(kicad_pcb
	(version 20260206)
	(generator "pcbnew")
	(generator_version "10.0")
	(general
		(thickness 1.6)
		(legacy_teardrops no)
	)
	(paper "A4")
	(layers
		(0 "F.Cu" signal "TOP")
		(4 "In1.Cu" signal "GND")
		(6 "In2.Cu" signal "IN1")
		(8 "In3.Cu" signal "GND1")
		(10 "In4.Cu" signal "IN2")
		(12 "In5.Cu" signal "GND2")
		(14 "In6.Cu" signal "IN3")
		(16 "In7.Cu" signal "GND3")
		(18 "In8.Cu" signal "VCC")
		(20 "In9.Cu" signal "VCC1")
		(22 "In10.Cu" signal "GND4")
		(24 "In11.Cu" signal "IN4")
		(26 "In12.Cu" signal "GND5")
		(28 "In13.Cu" signal "IN5")
		(30 "In14.Cu" signal "GND6")
		(32 "In15.Cu" signal "IN6")
		(34 "In16.Cu" signal "GND7")
		(2 "B.Cu" signal "BOTTOM")
		(9 "F.Adhes" user "F.Adhesive")
		(11 "B.Adhes" user "B.Adhesive")
		(13 "F.Paste" user "Package Geometry/Pastemask Top")
		(15 "B.Paste" user "Package Geometry/Pastemask Bottom")
		(5 "F.SilkS" user "Ref Des/Silkscreen Top")
		(7 "B.SilkS" user "Ref Des/Silkscreen Bottom")
		(1 "F.Mask" user "Board Geometry/Soldermask Top")
		(3 "B.Mask" user "Board Geometry/Soldermask Bottom")
		(17 "Dwgs.User" user "User.Drawings")
		(19 "Cmts.User" user "User.Comments")
		(21 "Eco1.User" user "User.Eco1")
		(23 "Eco2.User" user "User.Eco2")
		(25 "Edge.Cuts" user "Board Geometry/Outline")
		(27 "Margin" user)
		(31 "F.CrtYd" user "Package Geometry/Place Bound Top")
		(29 "B.CrtYd" user "Package Geometry/Place Bound Bottom")
		(35 "F.Fab" user "Ref Des/Assembly Top")
		(33 "B.Fab" user "Ref Des/Assembly Bottom")
	)
	(setup
		(pad_to_mask_clearance 0)
		(allow_soldermask_bridges_in_footprints no)
		(tenting
			(front yes)
			(back yes)
		)
		(covering
			(front no)
			(back no)
		)
		(plugging
			(front no)
			(back no)
		)
		(capping no)
		(filling no)
		(pcbplotparams
			(layerselection 0x00000000_00000000_55555555_5755f5ff)
			(plot_on_all_layers_selection 0x00000000_00000000_00000000_00000000)
			(disableapertmacros no)
			(usegerberextensions no)
			(usegerberattributes yes)
			(usegerberadvancedattributes yes)
			(creategerberjobfile yes)
			(dashed_line_dash_ratio 12)
			(dashed_line_gap_ratio 3)
			(svgprecision 4)
			(plotframeref no)
			(mode 1)
			(useauxorigin no)
			(pdf_front_fp_property_popups yes)
			(pdf_back_fp_property_popups yes)
			(pdf_metadata yes)
			(pdf_single_document no)
			(dxfpolygonmode yes)
			(dxfimperialunits yes)
			(dxfusepcbnewfont yes)
			(psnegative no)
			(psa4output no)
			(plot_black_and_white yes)
			(sketchpadsonfab no)
			(plotpadnumbers no)
			(hidednponfab no)
			(sketchdnponfab yes)
			(crossoutdnponfab yes)
			(subtractmaskfromsilk no)
			(outputformat 1)
			(mirror no)
			(drillshape 1)
			(scaleselection 1)
			(outputdirectory "")
		)
	)
	(gr_poly
		(pts
			(xy 91.67114 -232.942638) (xy 91.67114 -232.894886) (xy 91.470988 -232.894886) (xy 91.470988 -232.942638)
			(xy 91.571064 -233.04246)
		)
		(stroke
			(width 0)
			(type solid)
		)
		(fill yes)
		(layer "In4.Cu")
		(net "M_D_CPU1_SA_DQS_DP<6>")
	)
	(gr_poly
		(pts
			(xy 91.67114 -231.322626) (xy 91.67114 -231.278176) (xy 91.470988 -231.278176) (xy 91.470988 -231.322626)
			(xy 91.571064 -231.422702)
		)
		(stroke
			(width 0)
			(type solid)
		)
		(fill yes)
		(layer "In4.Cu")
		(net "M_D_CPU1_SA_DQ<11>")
	)
	(gr_poly
		(pts
			(xy 91.67114 -229.702614) (xy 91.67114 -229.658164) (xy 91.470988 -229.658164) (xy 91.470988 -229.702614)
			(xy 91.571064 -229.80269)
		)
		(stroke
			(width 0)
			(type solid)
		)
		(fill yes)
		(layer "In4.Cu")
		(net "M_D_CPU1_SA_DQ<7>")
	)
	(gr_poly
		(pts
			(xy 91.67114 -228.082856) (xy 91.67114 -228.035104) (xy 91.470988 -228.035104) (xy 91.470988 -228.082856)
			(xy 91.571064 -228.182678)
		)
		(stroke
			(width 0)
			(type solid)
		)
		(fill yes)
		(layer "In4.Cu")
		(net "M_D_CPU1_SA_DQS_DP<5>")
	)
	(gr_poly
		(pts
			(xy 91.67114 -226.46259) (xy 91.67114 -226.41814) (xy 91.470988 -226.41814) (xy 91.470988 -226.46259)
			(xy 91.571064 -226.562666)
		)
		(stroke
			(width 0)
			(type solid)
		)
		(fill yes)
		(layer "In4.Cu")
		(net "M_D_CPU1_SA_DQ<3>")
	)
	(gr_poly
		(pts
			(xy 91.971114 -292.918134) (xy 91.871038 -292.818058) (xy 91.770962 -292.918134) (xy 91.770962 -292.962584)
			(xy 91.971114 -292.962584)
		)
		(stroke
			(width 0)
			(type solid)
		)
		(fill yes)
		(layer "In4.Cu")
		(net "M_D_CPU1_SB_DQ<29>")
	)
	(gr_poly
		(pts
			(xy 91.971114 -291.297868) (xy 91.871038 -291.198046) (xy 91.770962 -291.297868) (xy 91.770962 -291.34562)
			(xy 91.971114 -291.34562)
		)
		(stroke
			(width 0)
			(type solid)
		)
		(fill yes)
		(layer "In4.Cu")
		(net "M_D_CPU1_SB_DQS_DN<8>")
	)
	(gr_poly
		(pts
			(xy 91.971114 -289.67811) (xy 91.871038 -289.578034) (xy 91.770962 -289.67811) (xy 91.770962 -289.72256)
			(xy 91.971114 -289.72256)
		)
		(stroke
			(width 0)
			(type solid)
		)
		(fill yes)
		(layer "In4.Cu")
		(net "M_D_CPU1_SB_DQ<25>")
	)
	(gr_poly
		(pts
			(xy 91.971114 -288.058098) (xy 91.871038 -287.958022) (xy 91.770962 -288.058098) (xy 91.770962 -288.102548)
			(xy 91.971114 -288.102548)
		)
		(stroke
			(width 0)
			(type solid)
		)
		(fill yes)
		(layer "In4.Cu")
		(net "M_D_CPU1_SB_DQ<21>")
	)
	(gr_poly
		(pts
			(xy 91.971114 -286.438086) (xy 91.871038 -286.33801) (xy 91.770962 -286.438086) (xy 91.770962 -286.485838)
			(xy 91.971114 -286.485838)
		)
		(stroke
			(width 0)
			(type solid)
		)
		(fill yes)
		(layer "In4.Cu")
		(net "M_D_CPU1_SB_DQS_DN<7>")
	)
	(gr_poly
		(pts
			(xy 91.971114 -284.818328) (xy 91.871038 -284.718252) (xy 91.770962 -284.818328) (xy 91.770962 -284.862778)
			(xy 91.971114 -284.862778)
		)
		(stroke
			(width 0)
			(type solid)
		)
		(fill yes)
		(layer "In4.Cu")
		(net "M_D_CPU1_SB_DQ<17>")
	)
	(gr_poly
		(pts
			(xy 91.971114 -283.198316) (xy 91.871038 -283.09824) (xy 91.770962 -283.198316) (xy 91.770962 -283.242766)
			(xy 91.971114 -283.242766)
		)
		(stroke
			(width 0)
			(type solid)
		)
		(fill yes)
		(layer "In4.Cu")
		(net "M_D_CPU1_SB_DQ<13>")
	)
	(gr_poly
		(pts
			(xy 91.971114 -281.57805) (xy 91.871038 -281.478228) (xy 91.770962 -281.57805) (xy 91.770962 -281.625802)
			(xy 91.971114 -281.625802)
		)
		(stroke
			(width 0)
			(type solid)
		)
		(fill yes)
		(layer "In4.Cu")
		(net "M_D_CPU1_SB_DQS_DN<6>")
	)
	(gr_poly
		(pts
			(xy 91.971114 -279.958292) (xy 91.871038 -279.858216) (xy 91.770962 -279.958292) (xy 91.770962 -280.002742)
			(xy 91.971114 -280.002742)
		)
		(stroke
			(width 0)
			(type solid)
		)
		(fill yes)
		(layer "In4.Cu")
		(net "M_D_CPU1_SB_DQ<9>")
	)
	(gr_poly
		(pts
			(xy 91.971114 -278.33828) (xy 91.871038 -278.238204) (xy 91.770962 -278.33828) (xy 91.770962 -278.38273)
			(xy 91.971114 -278.38273)
		)
		(stroke
			(width 0)
			(type solid)
		)
		(fill yes)
		(layer "In4.Cu")
		(net "M_D_CPU1_SB_DQ<5>")
	)
	(gr_poly
		(pts
			(xy 91.971114 -276.718014) (xy 91.871038 -276.618192) (xy 91.770962 -276.718014) (xy 91.770962 -276.765766)
			(xy 91.971114 -276.765766)
		)
		(stroke
			(width 0)
			(type solid)
		)
		(fill yes)
		(layer "In4.Cu")
		(net "M_D_CPU1_SB_DQS_DN<5>")
	)
	(gr_poly
		(pts
			(xy 91.971114 -275.098256) (xy 91.871038 -274.99818) (xy 91.770962 -275.098256) (xy 91.770962 -275.142706)
			(xy 91.971114 -275.142706)
		)
		(stroke
			(width 0)
			(type solid)
		)
		(fill yes)
		(layer "In4.Cu")
		(net "M_D_CPU1_SB_DQ<1>")
	)
	(gr_poly
		(pts
			(xy 91.971114 -273.478244) (xy 91.871038 -273.378168) (xy 91.770962 -273.478244) (xy 91.770962 -273.522694)
			(xy 91.971114 -273.522694)
		)
		(stroke
			(width 0)
			(type solid)
		)
		(fill yes)
		(layer "In4.Cu")
		(net "M_D_CPU1_SB_CB<1>")
	)
	(gr_poly
		(pts
			(xy 91.971114 -271.857978) (xy 91.871038 -271.758156) (xy 91.770962 -271.857978) (xy 91.770962 -271.90573)
			(xy 91.971114 -271.90573)
		)
		(stroke
			(width 0)
			(type solid)
		)
		(fill yes)
		(layer "In4.Cu")
		(net "M_D_CPU1_SB_DQS_DN<4>")
	)
	(gr_poly
		(pts
			(xy 91.971114 -270.23822) (xy 91.871038 -270.138144) (xy 91.770962 -270.23822) (xy 91.770962 -270.28267)
			(xy 91.971114 -270.28267)
		)
		(stroke
			(width 0)
			(type solid)
		)
		(fill yes)
		(layer "In4.Cu")
		(net "M_D_CPU1_SB_CB<5>")
	)
	(gr_poly
		(pts
			(xy 91.971114 -266.991846) (xy 91.871038 -266.89177) (xy 91.770962 -266.991846) (xy 91.770962 -267.036296)
			(xy 91.971114 -267.036296)
		)
		(stroke
			(width 0)
			(type solid)
		)
		(fill yes)
		(layer "In4.Cu")
		(net "M_D_CPU1_SA_RSP<0>")
	)
	(gr_poly
		(pts
			(xy 91.971114 -263.758172) (xy 91.871038 -263.658096) (xy 91.770962 -263.758172) (xy 91.770962 -263.802622)
			(xy 91.971114 -263.802622)
		)
		(stroke
			(width 0)
			(type solid)
		)
		(fill yes)
		(layer "In4.Cu")
		(net "M_D_CPU1_SB_CA<4>")
	)
	(gr_poly
		(pts
			(xy 91.971114 -262.13816) (xy 91.871038 -262.038084) (xy 91.770962 -262.13816) (xy 91.770962 -262.18261)
			(xy 91.971114 -262.18261)
		)
		(stroke
			(width 0)
			(type solid)
		)
		(fill yes)
		(layer "In4.Cu")
		(net "M_D_CPU1_SB_CA<0>")
	)
	(gr_poly
		(pts
			(xy 92.09278 -247.156986) (xy 92.088462 -247.109488) (xy 91.980258 -247.018556) (xy 91.889326 -247.127014)
			(xy 91.89339 -247.174512)
		)
		(stroke
			(width 0)
			(type solid)
		)
		(fill yes)
		(layer "In4.Cu")
		(net "M_D_CPU1_SA_DQS_DN<9>")
	)
	(gr_poly
		(pts
			(xy 92.09278 -242.29695) (xy 92.088462 -242.249452) (xy 91.980258 -242.15852) (xy 91.889326 -242.266978)
			(xy 91.89339 -242.314476)
		)
		(stroke
			(width 0)
			(type solid)
		)
		(fill yes)
		(layer "In4.Cu")
		(net "M_D_CPU1_SA_DQS_DN<8>")
	)
	(gr_poly
		(pts
			(xy 92.09278 -237.436914) (xy 92.088462 -237.389416) (xy 91.980258 -237.298484) (xy 91.889326 -237.406942)
			(xy 91.89339 -237.45444)
		)
		(stroke
			(width 0)
			(type solid)
		)
		(fill yes)
		(layer "In4.Cu")
		(net "M_D_CPU1_SA_DQS_DN<7>")
	)
	(gr_poly
		(pts
			(xy 92.09278 -232.576878) (xy 92.088462 -232.52938) (xy 91.980258 -232.438448) (xy 91.889326 -232.546906)
			(xy 91.89339 -232.594404)
		)
		(stroke
			(width 0)
			(type solid)
		)
		(fill yes)
		(layer "In4.Cu")
		(net "M_D_CPU1_SA_DQS_DN<6>")
	)
	(gr_poly
		(pts
			(xy 92.105226 -255.253236) (xy 92.101416 -255.20904) (xy 91.992958 -255.118108) (xy 91.902026 -255.226312)
			(xy 91.90609 -255.270508)
		)
		(stroke
			(width 0)
			(type solid)
		)
		(fill yes)
		(layer "In4.Cu")
		(net "M_D_CPU1_SA_CA<6>")
	)
	(gr_poly
		(pts
			(xy 92.105226 -253.633224) (xy 92.101416 -253.589028) (xy 91.992958 -253.498096) (xy 91.902026 -253.6063)
			(xy 91.90609 -253.650496)
		)
		(stroke
			(width 0)
			(type solid)
		)
		(fill yes)
		(layer "In4.Cu")
		(net "M_D_CPU1_SA_CA<2>")
	)
	(gr_poly
		(pts
			(xy 92.105226 -250.3932) (xy 92.101416 -250.349004) (xy 91.992958 -250.258072) (xy 91.902026 -250.366276)
			(xy 91.90609 -250.410472)
		)
		(stroke
			(width 0)
			(type solid)
		)
		(fill yes)
		(layer "In4.Cu")
		(net "M_D_CPU1_ALERT_R_N")
	)
	(gr_poly
		(pts
			(xy 92.105226 -248.773188) (xy 92.101416 -248.728738) (xy 91.992958 -248.63806) (xy 91.902026 -248.746264)
			(xy 91.90609 -248.79046)
		)
		(stroke
			(width 0)
			(type solid)
		)
		(fill yes)
		(layer "In4.Cu")
		(net "M_D_CPU1_SA_CB<5>")
	)
	(gr_poly
		(pts
			(xy 92.105226 -245.533164) (xy 92.101416 -245.488968) (xy 91.992958 -245.398036) (xy 91.902026 -245.50624)
			(xy 91.90609 -245.550436)
		)
		(stroke
			(width 0)
			(type solid)
		)
		(fill yes)
		(layer "In4.Cu")
		(net "M_D_CPU1_SA_CB<1>")
	)
	(gr_poly
		(pts
			(xy 92.105226 -243.913152) (xy 92.101416 -243.868702) (xy 91.992958 -243.778024) (xy 91.902026 -243.886228)
			(xy 91.90609 -243.930424)
		)
		(stroke
			(width 0)
			(type solid)
		)
		(fill yes)
		(layer "In4.Cu")
		(net "M_D_CPU1_SA_DQ<29>")
	)
	(gr_poly
		(pts
			(xy 92.105226 -240.673128) (xy 92.101416 -240.628932) (xy 91.992958 -240.538) (xy 91.902026 -240.646204)
			(xy 91.90609 -240.6904)
		)
		(stroke
			(width 0)
			(type solid)
		)
		(fill yes)
		(layer "In4.Cu")
		(net "M_D_CPU1_SA_DQ<25>")
	)
	(gr_poly
		(pts
			(xy 92.105226 -239.053116) (xy 92.101416 -239.00892) (xy 91.992958 -238.917988) (xy 91.902026 -239.026192)
			(xy 91.90609 -239.070388)
		)
		(stroke
			(width 0)
			(type solid)
		)
		(fill yes)
		(layer "In4.Cu")
		(net "M_D_CPU1_SA_DQ<21>")
	)
	(gr_poly
		(pts
			(xy 92.105226 -235.813092) (xy 92.101416 -235.768896) (xy 91.992958 -235.677964) (xy 91.902026 -235.786168)
			(xy 91.90609 -235.830364)
		)
		(stroke
			(width 0)
			(type solid)
		)
		(fill yes)
		(layer "In4.Cu")
		(net "M_D_CPU1_SA_DQ<17>")
	)
	(gr_poly
		(pts
			(xy 92.105226 -234.19308) (xy 92.101416 -234.148884) (xy 91.992958 -234.057952) (xy 91.902026 -234.166156)
			(xy 91.90609 -234.210352)
		)
		(stroke
			(width 0)
			(type solid)
		)
		(fill yes)
		(layer "In4.Cu")
		(net "M_D_CPU1_SA_DQ<13>")
	)
	(gr_poly
		(pts
			(xy 92.105226 -226.093274) (xy 92.101416 -226.048824) (xy 91.992958 -225.958146) (xy 91.902026 -226.06635)
			(xy 91.90609 -226.110546)
		)
		(stroke
			(width 0)
			(type solid)
		)
		(fill yes)
		(layer "In4.Cu")
		(net "M_D_CPU1_SA_DQ<1>")
	)
	(gr_poly
		(pts
			(xy 92.10548 -230.953056) (xy 92.10167 -230.90886) (xy 91.993212 -230.817928) (xy 91.90228 -230.926132)
			(xy 91.906344 -230.970328)
		)
		(stroke
			(width 0)
			(type solid)
		)
		(fill yes)
		(layer "In4.Cu")
		(net "M_D_CPU1_SA_DQ<9>")
	)
	(gr_poly
		(pts
			(xy 92.10548 -229.333044) (xy 92.10167 -229.288848) (xy 91.993212 -229.197916) (xy 91.90228 -229.30612)
			(xy 91.906344 -229.350316)
		)
		(stroke
			(width 0)
			(type solid)
		)
		(fill yes)
		(layer "In4.Cu")
		(net "M_D_CPU1_SA_DQ<5>")
	)
	(gr_poly
		(pts
			(xy 92.388436 -291.711126) (xy 92.392754 -291.663628) (xy 92.193364 -291.646356) (xy 92.1893 -291.6936)
			(xy 92.280232 -291.802058)
		)
		(stroke
			(width 0)
			(type solid)
		)
		(fill yes)
		(layer "In4.Cu")
		(net "M_D_CPU1_SB_DQS_DP<8>")
	)
	(gr_poly
		(pts
			(xy 92.388436 -286.85109) (xy 92.392754 -286.803592) (xy 92.193364 -286.78632) (xy 92.1893 -286.833564)
			(xy 92.280232 -286.942022)
		)
		(stroke
			(width 0)
			(type solid)
		)
		(fill yes)
		(layer "In4.Cu")
		(net "M_D_CPU1_SB_DQS_DP<7>")
	)
	(gr_poly
		(pts
			(xy 92.388436 -281.991308) (xy 92.392754 -281.94381) (xy 92.193364 -281.926284) (xy 92.1893 -281.973782)
			(xy 92.280232 -282.08224)
		)
		(stroke
			(width 0)
			(type solid)
		)
		(fill yes)
		(layer "In4.Cu")
		(net "M_D_CPU1_SB_DQS_DP<6>")
	)
	(gr_poly
		(pts
			(xy 92.388436 -277.131272) (xy 92.392754 -277.083774) (xy 92.193364 -277.066248) (xy 92.1893 -277.113746)
			(xy 92.280232 -277.222204)
		)
		(stroke
			(width 0)
			(type solid)
		)
		(fill yes)
		(layer "In4.Cu")
		(net "M_D_CPU1_SB_DQS_DP<5>")
	)
	(gr_poly
		(pts
			(xy 92.388436 -272.271236) (xy 92.392754 -272.223738) (xy 92.193364 -272.206212) (xy 92.1893 -272.25371)
			(xy 92.280232 -272.362168)
		)
		(stroke
			(width 0)
			(type solid)
		)
		(fill yes)
		(layer "In4.Cu")
		(net "M_D_CPU1_SB_DQS_DP<4>")
	)
	(gr_poly
		(pts
			(xy 92.40139 -290.091876) (xy 92.4052 -290.047426) (xy 92.206064 -290.030154) (xy 92.202 -290.07435)
			(xy 92.292932 -290.182554)
		)
		(stroke
			(width 0)
			(type solid)
		)
		(fill yes)
		(layer "In4.Cu")
		(net "M_D_CPU1_SB_DQ<27>")
	)
	(gr_poly
		(pts
			(xy 92.40139 -285.23184) (xy 92.4052 -285.187644) (xy 92.206064 -285.170372) (xy 92.202 -285.214568)
			(xy 92.292932 -285.322772)
		)
		(stroke
			(width 0)
			(type solid)
		)
		(fill yes)
		(layer "In4.Cu")
		(net "M_D_CPU1_SB_DQ<19>")
	)
	(gr_poly
		(pts
			(xy 92.40139 -283.611828) (xy 92.4052 -283.567632) (xy 92.206064 -283.55036) (xy 92.202 -283.594556)
			(xy 92.292932 -283.70276)
		)
		(stroke
			(width 0)
			(type solid)
		)
		(fill yes)
		(layer "In4.Cu")
		(net "M_D_CPU1_SB_DQ<15>")
	)
	(gr_poly
		(pts
			(xy 92.40139 -280.371804) (xy 92.4052 -280.327608) (xy 92.206064 -280.310336) (xy 92.202 -280.354532)
			(xy 92.292932 -280.462736)
		)
		(stroke
			(width 0)
			(type solid)
		)
		(fill yes)
		(layer "In4.Cu")
		(net "M_D_CPU1_SB_DQ<11>")
	)
	(gr_poly
		(pts
			(xy 92.40139 -278.751792) (xy 92.4052 -278.707596) (xy 92.206064 -278.690324) (xy 92.202 -278.73452)
			(xy 92.292932 -278.842724)
		)
		(stroke
			(width 0)
			(type solid)
		)
		(fill yes)
		(layer "In4.Cu")
		(net "M_D_CPU1_SB_DQ<7>")
	)
	(gr_poly
		(pts
			(xy 92.40139 -275.511768) (xy 92.4052 -275.467572) (xy 92.206064 -275.4503) (xy 92.202 -275.494496)
			(xy 92.292932 -275.6027)
		)
		(stroke
			(width 0)
			(type solid)
		)
		(fill yes)
		(layer "In4.Cu")
		(net "M_D_CPU1_SB_DQ<3>")
	)
	(gr_poly
		(pts
			(xy 92.40139 -273.891756) (xy 92.4052 -273.84756) (xy 92.206064 -273.830288) (xy 92.202 -273.874484)
			(xy 92.292932 -273.982688)
		)
		(stroke
			(width 0)
			(type solid)
		)
		(fill yes)
		(layer "In4.Cu")
		(net "M_D_CPU1_SB_CB<3>")
	)
	(gr_poly
		(pts
			(xy 92.40139 -270.651732) (xy 92.4052 -270.607536) (xy 92.206064 -270.590264) (xy 92.202 -270.63446)
			(xy 92.292932 -270.742664)
		)
		(stroke
			(width 0)
			(type solid)
		)
		(fill yes)
		(layer "In4.Cu")
		(net "M_D_CPU1_SB_CB<7>")
	)
	(gr_poly
		(pts
			(xy 92.40139 -265.791696) (xy 92.4052 -265.7475) (xy 92.206064 -265.730228) (xy 92.202 -265.774424)
			(xy 92.292932 -265.882628)
		)
		(stroke
			(width 0)
			(type solid)
		)
		(fill yes)
		(layer "In4.Cu")
		(net "M_D_CPU1_SB_CS_N<0>")
	)
	(gr_poly
		(pts
			(xy 92.40139 -264.171684) (xy 92.4052 -264.127488) (xy 92.206064 -264.110216) (xy 92.202 -264.154412)
			(xy 92.292932 -264.262616)
		)
		(stroke
			(width 0)
			(type solid)
		)
		(fill yes)
		(layer "In4.Cu")
		(net "M_D_CPU1_SB_CA<5>")
	)
	(gr_poly
		(pts
			(xy 92.40139 -262.551672) (xy 92.4052 -262.507476) (xy 92.206064 -262.490204) (xy 92.202 -262.5344)
			(xy 92.292932 -262.642604)
		)
		(stroke
			(width 0)
			(type solid)
		)
		(fill yes)
		(layer "In4.Cu")
		(net "M_D_CPU1_SB_CA<1>")
	)
	(gr_poly
		(pts
			(xy 92.401644 -288.471864) (xy 92.405454 -288.427668) (xy 92.206318 -288.410396) (xy 92.202254 -288.454592)
			(xy 92.293186 -288.562796)
		)
		(stroke
			(width 0)
			(type solid)
		)
		(fill yes)
		(layer "In4.Cu")
		(net "M_D_CPU1_SB_DQ<23>")
	)
	(gr_poly
		(pts
			(xy 131.653534 -230.926132) (xy 131.562602 -230.817928) (xy 131.454144 -230.90886) (xy 131.450334 -230.953056)
			(xy 131.64947 -230.970328)
		)
		(stroke
			(width 0)
			(type solid)
		)
		(fill yes)
		(layer "In4.Cu")
		(net "M_J_CPU1_SA_DQ<9>")
	)
	(gr_poly
		(pts
			(xy 131.653534 -229.30612) (xy 131.562602 -229.197916) (xy 131.454144 -229.288848) (xy 131.450334 -229.333044)
			(xy 131.64947 -229.350316)
		)
		(stroke
			(width 0)
			(type solid)
		)
		(fill yes)
		(layer "In4.Cu")
		(net "M_J_CPU1_SA_DQ<5>")
	)
	(gr_poly
		(pts
			(xy 131.653788 -255.226312) (xy 131.562856 -255.118108) (xy 131.454398 -255.20904) (xy 131.450588 -255.253236)
			(xy 131.649724 -255.270508)
		)
		(stroke
			(width 0)
			(type solid)
		)
		(fill yes)
		(layer "In4.Cu")
		(net "M_J_CPU1_SA_CA<6>")
	)
	(gr_poly
		(pts
			(xy 131.653788 -253.6063) (xy 131.562856 -253.498096) (xy 131.454398 -253.589028) (xy 131.450588 -253.633224)
			(xy 131.649724 -253.650496)
		)
		(stroke
			(width 0)
			(type solid)
		)
		(fill yes)
		(layer "In4.Cu")
		(net "M_J_CPU1_SA_CA<2>")
	)
	(gr_poly
		(pts
			(xy 131.653788 -251.986288) (xy 131.562856 -251.878084) (xy 131.454398 -251.969016) (xy 131.450588 -252.013212)
			(xy 131.649724 -252.030484)
		)
		(stroke
			(width 0)
			(type solid)
		)
		(fill yes)
		(layer "In4.Cu")
		(net "M_J_CPU1_SA_CS_N<1>")
	)
	(gr_poly
		(pts
			(xy 131.653788 -250.366276) (xy 131.562856 -250.258072) (xy 131.454398 -250.349004) (xy 131.450588 -250.3932)
			(xy 131.649724 -250.410472)
		)
		(stroke
			(width 0)
			(type solid)
		)
		(fill yes)
		(layer "In4.Cu")
		(net "M_J_CPU1_ALERT_R_N")
	)
	(gr_poly
		(pts
			(xy 131.653788 -248.746264) (xy 131.562856 -248.63806) (xy 131.454398 -248.728738) (xy 131.450588 -248.773188)
			(xy 131.649724 -248.79046)
		)
		(stroke
			(width 0)
			(type solid)
		)
		(fill yes)
		(layer "In4.Cu")
		(net "M_J_CPU1_SA_CB<5>")
	)
	(gr_poly
		(pts
			(xy 131.653788 -245.50624) (xy 131.562856 -245.398036) (xy 131.454398 -245.488968) (xy 131.450588 -245.533164)
			(xy 131.649724 -245.550436)
		)
		(stroke
			(width 0)
			(type solid)
		)
		(fill yes)
		(layer "In4.Cu")
		(net "M_J_CPU1_SA_CB<1>")
	)
	(gr_poly
		(pts
			(xy 131.653788 -243.886228) (xy 131.562856 -243.778024) (xy 131.454398 -243.868702) (xy 131.450588 -243.913152)
			(xy 131.649724 -243.930424)
		)
		(stroke
			(width 0)
			(type solid)
		)
		(fill yes)
		(layer "In4.Cu")
		(net "M_J_CPU1_SA_DQ<29>")
	)
	(gr_poly
		(pts
			(xy 131.653788 -240.646204) (xy 131.562856 -240.538) (xy 131.454398 -240.628932) (xy 131.450588 -240.673128)
			(xy 131.649724 -240.6904)
		)
		(stroke
			(width 0)
			(type solid)
		)
		(fill yes)
		(layer "In4.Cu")
		(net "M_J_CPU1_SA_DQ<25>")
	)
	(gr_poly
		(pts
			(xy 131.653788 -239.026192) (xy 131.562856 -238.917988) (xy 131.454398 -239.00892) (xy 131.450588 -239.053116)
			(xy 131.649724 -239.070388)
		)
		(stroke
			(width 0)
			(type solid)
		)
		(fill yes)
		(layer "In4.Cu")
		(net "M_J_CPU1_SA_DQ<21>")
	)
	(gr_poly
		(pts
			(xy 131.653788 -235.786168) (xy 131.562856 -235.677964) (xy 131.454398 -235.768896) (xy 131.450588 -235.813092)
			(xy 131.649724 -235.830364)
		)
		(stroke
			(width 0)
			(type solid)
		)
		(fill yes)
		(layer "In4.Cu")
		(net "M_J_CPU1_SA_DQ<17>")
	)
	(gr_poly
		(pts
			(xy 131.653788 -234.166156) (xy 131.562856 -234.057952) (xy 131.454398 -234.148884) (xy 131.450588 -234.19308)
			(xy 131.649724 -234.210352)
		)
		(stroke
			(width 0)
			(type solid)
		)
		(fill yes)
		(layer "In4.Cu")
		(net "M_J_CPU1_SA_DQ<13>")
	)
	(gr_poly
		(pts
			(xy 131.653788 -226.06635) (xy 131.562856 -225.958146) (xy 131.454398 -226.048824) (xy 131.450588 -226.093274)
			(xy 131.649724 -226.110546)
		)
		(stroke
			(width 0)
			(type solid)
		)
		(fill yes)
		(layer "In4.Cu")
		(net "M_J_CPU1_SA_DQ<1>")
	)
	(gr_poly
		(pts
			(xy 131.655566 -242.265962) (xy 131.564634 -242.157758) (xy 131.456176 -242.24869) (xy 131.452112 -242.296188)
			(xy 131.651248 -242.31346)
		)
		(stroke
			(width 0)
			(type solid)
		)
		(fill yes)
		(layer "In4.Cu")
		(net "M_J_CPU1_SA_DQS_DN<8>")
	)
	(gr_poly
		(pts
			(xy 131.655566 -227.686108) (xy 131.564634 -227.577904) (xy 131.456176 -227.668836) (xy 131.452112 -227.716334)
			(xy 131.651248 -227.733606)
		)
		(stroke
			(width 0)
			(type solid)
		)
		(fill yes)
		(layer "In4.Cu")
		(net "M_J_CPU1_SA_DQS_DN<5>")
	)
	(gr_poly
		(pts
			(xy 131.666488 -247.127014) (xy 131.575556 -247.018556) (xy 131.467352 -247.109488) (xy 131.463034 -247.156986)
			(xy 131.662424 -247.174512)
		)
		(stroke
			(width 0)
			(type solid)
		)
		(fill yes)
		(layer "In4.Cu")
		(net "M_J_CPU1_SA_DQS_DN<9>")
	)
	(gr_poly
		(pts
			(xy 131.666488 -237.406942) (xy 131.575556 -237.298484) (xy 131.467352 -237.389416) (xy 131.463034 -237.436914)
			(xy 131.662424 -237.45444)
		)
		(stroke
			(width 0)
			(type solid)
		)
		(fill yes)
		(layer "In4.Cu")
		(net "M_J_CPU1_SA_DQS_DN<7>")
	)
	(gr_poly
		(pts
			(xy 131.666488 -232.546906) (xy 131.575556 -232.438448) (xy 131.467352 -232.52938) (xy 131.463034 -232.576878)
			(xy 131.662424 -232.594404)
		)
		(stroke
			(width 0)
			(type solid)
		)
		(fill yes)
		(layer "In4.Cu")
		(net "M_J_CPU1_SA_DQS_DN<6>")
	)
	(gr_poly
		(pts
			(xy 131.953508 -288.454592) (xy 131.949444 -288.410396) (xy 131.750308 -288.427668) (xy 131.754118 -288.471864)
			(xy 131.862576 -288.562796)
		)
		(stroke
			(width 0)
			(type solid)
		)
		(fill yes)
		(layer "In4.Cu")
		(net "M_J_CPU1_SB_DQ<23>")
	)
	(gr_poly
		(pts
			(xy 131.953762 -290.07435) (xy 131.949698 -290.030154) (xy 131.750562 -290.047426) (xy 131.754372 -290.091876)
			(xy 131.86283 -290.182554)
		)
		(stroke
			(width 0)
			(type solid)
		)
		(fill yes)
		(layer "In4.Cu")
		(net "M_J_CPU1_SB_DQ<27>")
	)
	(gr_poly
		(pts
			(xy 131.953762 -285.214568) (xy 131.949698 -285.170372) (xy 131.750562 -285.187644) (xy 131.754372 -285.23184)
			(xy 131.86283 -285.322772)
		)
		(stroke
			(width 0)
			(type solid)
		)
		(fill yes)
		(layer "In4.Cu")
		(net "M_J_CPU1_SB_DQ<19>")
	)
	(gr_poly
		(pts
			(xy 131.953762 -283.594556) (xy 131.949698 -283.55036) (xy 131.750562 -283.567632) (xy 131.754372 -283.611828)
			(xy 131.86283 -283.70276)
		)
		(stroke
			(width 0)
			(type solid)
		)
		(fill yes)
		(layer "In4.Cu")
		(net "M_J_CPU1_SB_DQ<15>")
	)
	(gr_poly
		(pts
			(xy 131.953762 -280.354532) (xy 131.949698 -280.310336) (xy 131.750562 -280.327608) (xy 131.754372 -280.371804)
			(xy 131.86283 -280.462736)
		)
		(stroke
			(width 0)
			(type solid)
		)
		(fill yes)
		(layer "In4.Cu")
		(net "M_J_CPU1_SB_DQ<11>")
	)
	(gr_poly
		(pts
			(xy 131.953762 -278.73452) (xy 131.949698 -278.690324) (xy 131.750562 -278.707596) (xy 131.754372 -278.751792)
			(xy 131.86283 -278.842724)
		)
		(stroke
			(width 0)
			(type solid)
		)
		(fill yes)
		(layer "In4.Cu")
		(net "M_J_CPU1_SB_DQ<7>")
	)
	(gr_poly
		(pts
			(xy 131.953762 -275.494496) (xy 131.949698 -275.4503) (xy 131.750562 -275.467572) (xy 131.754372 -275.511768)
			(xy 131.86283 -275.6027)
		)
		(stroke
			(width 0)
			(type solid)
		)
		(fill yes)
		(layer "In4.Cu")
		(net "M_J_CPU1_SB_DQ<3>")
	)
	(gr_poly
		(pts
			(xy 131.953762 -273.874484) (xy 131.949698 -273.830288) (xy 131.750562 -273.84756) (xy 131.754372 -273.891756)
			(xy 131.86283 -273.982688)
		)
		(stroke
			(width 0)
			(type solid)
		)
		(fill yes)
		(layer "In4.Cu")
		(net "M_J_CPU1_SB_CB<3>")
	)
	(gr_poly
		(pts
			(xy 131.953762 -270.63446) (xy 131.949698 -270.590264) (xy 131.750562 -270.607536) (xy 131.754372 -270.651732)
			(xy 131.86283 -270.742664)
		)
		(stroke
			(width 0)
			(type solid)
		)
		(fill yes)
		(layer "In4.Cu")
		(net "M_J_CPU1_SB_CB<7>")
	)
	(gr_poly
		(pts
			(xy 131.953762 -265.774424) (xy 131.949698 -265.730228) (xy 131.750562 -265.7475) (xy 131.754372 -265.791696)
			(xy 131.86283 -265.882628)
		)
		(stroke
			(width 0)
			(type solid)
		)
		(fill yes)
		(layer "In4.Cu")
		(net "M_J_CPU1_SB_CS_N<0>")
	)
	(gr_poly
		(pts
			(xy 131.953762 -264.154412) (xy 131.949698 -264.110216) (xy 131.750562 -264.127488) (xy 131.754372 -264.171684)
			(xy 131.86283 -264.262616)
		)
		(stroke
			(width 0)
			(type solid)
		)
		(fill yes)
		(layer "In4.Cu")
		(net "M_J_CPU1_SB_CA<5>")
	)
	(gr_poly
		(pts
			(xy 131.953762 -262.5344) (xy 131.949698 -262.490204) (xy 131.750562 -262.507476) (xy 131.754372 -262.551672)
			(xy 131.86283 -262.642604)
		)
		(stroke
			(width 0)
			(type solid)
		)
		(fill yes)
		(layer "In4.Cu")
		(net "M_J_CPU1_SB_CA<1>")
	)
	(gr_poly
		(pts
			(xy 131.95554 -286.83458) (xy 131.951222 -286.787082) (xy 131.752086 -286.804608) (xy 131.75615 -286.851852)
			(xy 131.864608 -286.942784)
		)
		(stroke
			(width 0)
			(type solid)
		)
		(fill yes)
		(layer "In4.Cu")
		(net "M_J_CPU1_SB_DQS_DP<7>")
	)
	(gr_poly
		(pts
			(xy 131.95554 -272.254726) (xy 131.951222 -272.207228) (xy 131.752086 -272.2245) (xy 131.75615 -272.271998)
			(xy 131.864608 -272.36293)
		)
		(stroke
			(width 0)
			(type solid)
		)
		(fill yes)
		(layer "In4.Cu")
		(net "M_J_CPU1_SB_DQS_DP<4>")
	)
	(gr_poly
		(pts
			(xy 131.966462 -291.6936) (xy 131.962398 -291.646356) (xy 131.763008 -291.663628) (xy 131.767326 -291.711126)
			(xy 131.87553 -291.802058)
		)
		(stroke
			(width 0)
			(type solid)
		)
		(fill yes)
		(layer "In4.Cu")
		(net "M_J_CPU1_SB_DQS_DP<8>")
	)
	(gr_poly
		(pts
			(xy 131.966462 -281.973782) (xy 131.962398 -281.926284) (xy 131.763008 -281.94381) (xy 131.767326 -281.991308)
			(xy 131.87553 -282.08224)
		)
		(stroke
			(width 0)
			(type solid)
		)
		(fill yes)
		(layer "In4.Cu")
		(net "M_J_CPU1_SB_DQS_DP<6>")
	)
	(gr_poly
		(pts
			(xy 131.966462 -277.113746) (xy 131.962398 -277.066248) (xy 131.763008 -277.083774) (xy 131.767326 -277.131272)
			(xy 131.87553 -277.222204)
		)
		(stroke
			(width 0)
			(type solid)
		)
		(fill yes)
		(layer "In4.Cu")
		(net "M_J_CPU1_SB_DQS_DP<5>")
	)
	(gr_poly
		(pts
			(xy 132.084826 -255.622552) (xy 132.084826 -255.578102) (xy 131.884674 -255.578102) (xy 131.884674 -255.622552)
			(xy 131.98475 -255.722628)
		)
		(stroke
			(width 0)
			(type solid)
		)
		(fill yes)
		(layer "In4.Cu")
		(net "M_J_CPU1_SA_PAR")
	)
	(gr_poly
		(pts
			(xy 132.084826 -254.00254) (xy 132.084826 -253.95809) (xy 131.884674 -253.95809) (xy 131.884674 -254.00254)
			(xy 131.98475 -254.102616)
		)
		(stroke
			(width 0)
			(type solid)
		)
		(fill yes)
		(layer "In4.Cu")
		(net "M_J_CPU1_SA_CA<3>")
	)
	(gr_poly
		(pts
			(xy 132.084826 -250.762516) (xy 132.084826 -250.718066) (xy 131.884674 -250.718066) (xy 131.884674 -250.762516)
			(xy 131.98475 -250.862592)
		)
		(stroke
			(width 0)
			(type solid)
		)
		(fill yes)
		(layer "In4.Cu")
		(net "M_J_CPU1_RESET_N")
	)
	(gr_poly
		(pts
			(xy 132.084826 -249.142504) (xy 132.084826 -249.098054) (xy 131.884674 -249.098054) (xy 131.884674 -249.142504)
			(xy 131.98475 -249.24258)
		)
		(stroke
			(width 0)
			(type solid)
		)
		(fill yes)
		(layer "In4.Cu")
		(net "M_J_CPU1_SA_CB<7>")
	)
	(gr_poly
		(pts
			(xy 132.084826 -247.522746) (xy 132.084826 -247.474994) (xy 131.884674 -247.474994) (xy 131.884674 -247.522746)
			(xy 131.98475 -247.622568)
		)
		(stroke
			(width 0)
			(type solid)
		)
		(fill yes)
		(layer "In4.Cu")
		(net "M_J_CPU1_SA_DQS_DP<9>")
	)
	(gr_poly
		(pts
			(xy 132.084826 -245.90248) (xy 132.084826 -245.85803) (xy 131.884674 -245.85803) (xy 131.884674 -245.90248)
			(xy 131.98475 -246.002556)
		)
		(stroke
			(width 0)
			(type solid)
		)
		(fill yes)
		(layer "In4.Cu")
		(net "M_J_CPU1_SA_CB<3>")
	)
	(gr_poly
		(pts
			(xy 132.084826 -244.282468) (xy 132.084826 -244.238018) (xy 131.884674 -244.238018) (xy 131.884674 -244.282468)
			(xy 131.98475 -244.382544)
		)
		(stroke
			(width 0)
			(type solid)
		)
		(fill yes)
		(layer "In4.Cu")
		(net "M_J_CPU1_SA_DQ<31>")
	)
	(gr_poly
		(pts
			(xy 132.084826 -242.66271) (xy 132.084826 -242.614958) (xy 131.884674 -242.614958) (xy 131.884674 -242.66271)
			(xy 131.98475 -242.762532)
		)
		(stroke
			(width 0)
			(type solid)
		)
		(fill yes)
		(layer "In4.Cu")
		(net "M_J_CPU1_SA_DQS_DP<8>")
	)
	(gr_poly
		(pts
			(xy 132.084826 -241.042444) (xy 132.084826 -240.997994) (xy 131.884674 -240.997994) (xy 131.884674 -241.042444)
			(xy 131.98475 -241.14252)
		)
		(stroke
			(width 0)
			(type solid)
		)
		(fill yes)
		(layer "In4.Cu")
		(net "M_J_CPU1_SA_DQ<27>")
	)
	(gr_poly
		(pts
			(xy 132.084826 -239.422432) (xy 132.084826 -239.377982) (xy 131.884674 -239.377982) (xy 131.884674 -239.422432)
			(xy 131.98475 -239.522508)
		)
		(stroke
			(width 0)
			(type solid)
		)
		(fill yes)
		(layer "In4.Cu")
		(net "M_J_CPU1_SA_DQ<23>")
	)
	(gr_poly
		(pts
			(xy 132.084826 -237.802674) (xy 132.084826 -237.754922) (xy 131.884674 -237.754922) (xy 131.884674 -237.802674)
			(xy 131.98475 -237.902496)
		)
		(stroke
			(width 0)
			(type solid)
		)
		(fill yes)
		(layer "In4.Cu")
		(net "M_J_CPU1_SA_DQS_DP<7>")
	)
	(gr_poly
		(pts
			(xy 132.084826 -236.182408) (xy 132.084826 -236.137958) (xy 131.884674 -236.137958) (xy 131.884674 -236.182408)
			(xy 131.98475 -236.282484)
		)
		(stroke
			(width 0)
			(type solid)
		)
		(fill yes)
		(layer "In4.Cu")
		(net "M_J_CPU1_SA_DQ<19>")
	)
	(gr_poly
		(pts
			(xy 132.084826 -234.562396) (xy 132.084826 -234.517946) (xy 131.884674 -234.517946) (xy 131.884674 -234.562396)
			(xy 131.98475 -234.662472)
		)
		(stroke
			(width 0)
			(type solid)
		)
		(fill yes)
		(layer "In4.Cu")
		(net "M_J_CPU1_SA_DQ<15>")
	)
	(gr_poly
		(pts
			(xy 132.084826 -232.942638) (xy 132.084826 -232.894886) (xy 131.884674 -232.894886) (xy 131.884674 -232.942638)
			(xy 131.98475 -233.04246)
		)
		(stroke
			(width 0)
			(type solid)
		)
		(fill yes)
		(layer "In4.Cu")
		(net "M_J_CPU1_SA_DQS_DP<6>")
	)
	(gr_poly
		(pts
			(xy 132.084826 -231.322626) (xy 132.084826 -231.278176) (xy 131.884674 -231.278176) (xy 131.884674 -231.322626)
			(xy 131.98475 -231.422702)
		)
		(stroke
			(width 0)
			(type solid)
		)
		(fill yes)
		(layer "In4.Cu")
		(net "M_J_CPU1_SA_DQ<11>")
	)
	(gr_poly
		(pts
			(xy 132.084826 -229.702614) (xy 132.084826 -229.658164) (xy 131.884674 -229.658164) (xy 131.884674 -229.702614)
			(xy 131.98475 -229.80269)
		)
		(stroke
			(width 0)
			(type solid)
		)
		(fill yes)
		(layer "In4.Cu")
		(net "M_J_CPU1_SA_DQ<7>")
	)
	(gr_poly
		(pts
			(xy 132.084826 -228.082856) (xy 132.084826 -228.035104) (xy 131.884674 -228.035104) (xy 131.884674 -228.082856)
			(xy 131.98475 -228.182678)
		)
		(stroke
			(width 0)
			(type solid)
		)
		(fill yes)
		(layer "In4.Cu")
		(net "M_J_CPU1_SA_DQS_DP<5>")
	)
	(gr_poly
		(pts
			(xy 132.084826 -226.46259) (xy 132.084826 -226.41814) (xy 131.884674 -226.41814) (xy 131.884674 -226.46259)
			(xy 131.98475 -226.562666)
		)
		(stroke
			(width 0)
			(type solid)
		)
		(fill yes)
		(layer "In4.Cu")
		(net "M_J_CPU1_SA_DQ<3>")
	)
	(gr_poly
		(pts
			(xy 132.3848 -291.297868) (xy 132.284724 -291.198046) (xy 132.184648 -291.297868) (xy 132.184648 -291.34562)
			(xy 132.3848 -291.34562)
		)
		(stroke
			(width 0)
			(type solid)
		)
		(fill yes)
		(layer "In4.Cu")
		(net "M_J_CPU1_SB_DQS_DN<8>")
	)
	(gr_poly
		(pts
			(xy 132.3848 -289.67811) (xy 132.284724 -289.578034) (xy 132.184648 -289.67811) (xy 132.184648 -289.72256)
			(xy 132.3848 -289.72256)
		)
		(stroke
			(width 0)
			(type solid)
		)
		(fill yes)
		(layer "In4.Cu")
		(net "M_J_CPU1_SB_DQ<25>")
	)
	(gr_poly
		(pts
			(xy 132.3848 -288.058098) (xy 132.284724 -287.958022) (xy 132.184648 -288.058098) (xy 132.184648 -288.102548)
			(xy 132.3848 -288.102548)
		)
		(stroke
			(width 0)
			(type solid)
		)
		(fill yes)
		(layer "In4.Cu")
		(net "M_J_CPU1_SB_DQ<21>")
	)
	(gr_poly
		(pts
			(xy 132.3848 -286.438086) (xy 132.284724 -286.33801) (xy 132.184648 -286.438086) (xy 132.184648 -286.485838)
			(xy 132.3848 -286.485838)
		)
		(stroke
			(width 0)
			(type solid)
		)
		(fill yes)
		(layer "In4.Cu")
		(net "M_J_CPU1_SB_DQS_DN<7>")
	)
	(gr_poly
		(pts
			(xy 132.3848 -284.818328) (xy 132.284724 -284.718252) (xy 132.184648 -284.818328) (xy 132.184648 -284.862778)
			(xy 132.3848 -284.862778)
		)
		(stroke
			(width 0)
			(type solid)
		)
		(fill yes)
		(layer "In4.Cu")
		(net "M_J_CPU1_SB_DQ<17>")
	)
	(gr_poly
		(pts
			(xy 132.3848 -283.198316) (xy 132.284724 -283.09824) (xy 132.184648 -283.198316) (xy 132.184648 -283.242766)
			(xy 132.3848 -283.242766)
		)
		(stroke
			(width 0)
			(type solid)
		)
		(fill yes)
		(layer "In4.Cu")
		(net "M_J_CPU1_SB_DQ<13>")
	)
	(gr_poly
		(pts
			(xy 132.3848 -281.57805) (xy 132.284724 -281.478228) (xy 132.184648 -281.57805) (xy 132.184648 -281.625802)
			(xy 132.3848 -281.625802)
		)
		(stroke
			(width 0)
			(type solid)
		)
		(fill yes)
		(layer "In4.Cu")
		(net "M_J_CPU1_SB_DQS_DN<6>")
	)
	(gr_poly
		(pts
			(xy 132.3848 -279.958292) (xy 132.284724 -279.858216) (xy 132.184648 -279.958292) (xy 132.184648 -280.002742)
			(xy 132.3848 -280.002742)
		)
		(stroke
			(width 0)
			(type solid)
		)
		(fill yes)
		(layer "In4.Cu")
		(net "M_J_CPU1_SB_DQ<9>")
	)
	(gr_poly
		(pts
			(xy 132.3848 -278.33828) (xy 132.284724 -278.238204) (xy 132.184648 -278.33828) (xy 132.184648 -278.38273)
			(xy 132.3848 -278.38273)
		)
		(stroke
			(width 0)
			(type solid)
		)
		(fill yes)
		(layer "In4.Cu")
		(net "M_J_CPU1_SB_DQ<5>")
	)
	(gr_poly
		(pts
			(xy 132.3848 -276.718014) (xy 132.284724 -276.618192) (xy 132.184648 -276.718014) (xy 132.184648 -276.765766)
			(xy 132.3848 -276.765766)
		)
		(stroke
			(width 0)
			(type solid)
		)
		(fill yes)
		(layer "In4.Cu")
		(net "M_J_CPU1_SB_DQS_DN<5>")
	)
	(gr_poly
		(pts
			(xy 132.3848 -275.098256) (xy 132.284724 -274.99818) (xy 132.184648 -275.098256) (xy 132.184648 -275.142706)
			(xy 132.3848 -275.142706)
		)
		(stroke
			(width 0)
			(type solid)
		)
		(fill yes)
		(layer "In4.Cu")
		(net "M_J_CPU1_SB_DQ<1>")
	)
	(gr_poly
		(pts
			(xy 132.3848 -273.478244) (xy 132.284724 -273.378168) (xy 132.184648 -273.478244) (xy 132.184648 -273.522694)
			(xy 132.3848 -273.522694)
		)
		(stroke
			(width 0)
			(type solid)
		)
		(fill yes)
		(layer "In4.Cu")
		(net "M_J_CPU1_SB_CB<1>")
	)
	(gr_poly
		(pts
			(xy 132.3848 -271.857978) (xy 132.284724 -271.758156) (xy 132.184648 -271.857978) (xy 132.184648 -271.90573)
			(xy 132.3848 -271.90573)
		)
		(stroke
			(width 0)
			(type solid)
		)
		(fill yes)
		(layer "In4.Cu")
		(net "M_J_CPU1_SB_DQS_DN<4>")
	)
	(gr_poly
		(pts
			(xy 132.3848 -270.23822) (xy 132.284724 -270.138144) (xy 132.184648 -270.23822) (xy 132.184648 -270.28267)
			(xy 132.3848 -270.28267)
		)
		(stroke
			(width 0)
			(type solid)
		)
		(fill yes)
		(layer "In4.Cu")
		(net "M_J_CPU1_SB_CB<5>")
	)
	(gr_poly
		(pts
			(xy 132.3848 -266.998196) (xy 132.284724 -266.89812) (xy 132.184648 -266.998196) (xy 132.184648 -267.042646)
			(xy 132.3848 -267.042646)
		)
		(stroke
			(width 0)
			(type solid)
		)
		(fill yes)
		(layer "In4.Cu")
		(net "M_J_CPU1_SA_RSP<0>")
	)
	(gr_poly
		(pts
			(xy 132.3848 -265.378184) (xy 132.284724 -265.278108) (xy 132.184648 -265.378184) (xy 132.184648 -265.422634)
			(xy 132.3848 -265.422634)
		)
		(stroke
			(width 0)
			(type solid)
		)
		(fill yes)
		(layer "In4.Cu")
		(net "M_J_CPU1_SB_PAR")
	)
	(gr_poly
		(pts
			(xy 132.3848 -263.758172) (xy 132.284724 -263.658096) (xy 132.184648 -263.758172) (xy 132.184648 -263.802622)
			(xy 132.3848 -263.802622)
		)
		(stroke
			(width 0)
			(type solid)
		)
		(fill yes)
		(layer "In4.Cu")
		(net "M_J_CPU1_SB_CA<4>")
	)
	(gr_poly
		(pts
			(xy 132.3848 -262.13816) (xy 132.284724 -262.038084) (xy 132.184648 -262.13816) (xy 132.184648 -262.18261)
			(xy 132.3848 -262.18261)
		)
		(stroke
			(width 0)
			(type solid)
		)
		(fill yes)
		(layer "In4.Cu")
		(net "M_J_CPU1_SB_CA<0>")
	)
	(gr_poly
		(pts
			(xy 132.554726 -255.216406) (xy 132.45465 -255.11633) (xy 132.354574 -255.216406) (xy 132.354574 -255.260856)
			(xy 132.554726 -255.260856)
		)
		(stroke
			(width 0)
			(type solid)
		)
		(fill yes)
		(layer "In4.Cu")
		(net "M_J_CPU1_SA_CA<6>")
	)
	(gr_poly
		(pts
			(xy 132.554726 -253.596394) (xy 132.45465 -253.496318) (xy 132.354574 -253.596394) (xy 132.354574 -253.640844)
			(xy 132.554726 -253.640844)
		)
		(stroke
			(width 0)
			(type solid)
		)
		(fill yes)
		(layer "In4.Cu")
		(net "M_J_CPU1_SA_CA<2>")
	)
	(gr_poly
		(pts
			(xy 132.554726 -251.976382) (xy 132.45465 -251.876306) (xy 132.354574 -251.976382) (xy 132.354574 -252.020832)
			(xy 132.554726 -252.020832)
		)
		(stroke
			(width 0)
			(type solid)
		)
		(fill yes)
		(layer "In4.Cu")
		(net "M_J_CPU1_SA_CS_N<1>")
	)
	(gr_poly
		(pts
			(xy 132.554726 -250.35637) (xy 132.45465 -250.256294) (xy 132.354574 -250.35637) (xy 132.354574 -250.40082)
			(xy 132.554726 -250.40082)
		)
		(stroke
			(width 0)
			(type solid)
		)
		(fill yes)
		(layer "In4.Cu")
		(net "M_J_CPU1_ALERT_R_N")
	)
	(gr_poly
		(pts
			(xy 132.554726 -248.736358) (xy 132.45465 -248.636282) (xy 132.354574 -248.736358) (xy 132.354574 -248.780808)
			(xy 132.554726 -248.780808)
		)
		(stroke
			(width 0)
			(type solid)
		)
		(fill yes)
		(layer "In4.Cu")
		(net "M_J_CPU1_SA_CB<5>")
	)
	(gr_poly
		(pts
			(xy 132.554726 -247.116092) (xy 132.45465 -247.01627) (xy 132.354574 -247.116092) (xy 132.354574 -247.163844)
			(xy 132.554726 -247.163844)
		)
		(stroke
			(width 0)
			(type solid)
		)
		(fill yes)
		(layer "In4.Cu")
		(net "M_J_CPU1_SA_DQS_DN<9>")
	)
	(gr_poly
		(pts
			(xy 132.554726 -245.496334) (xy 132.45465 -245.396258) (xy 132.354574 -245.496334) (xy 132.354574 -245.540784)
			(xy 132.554726 -245.540784)
		)
		(stroke
			(width 0)
			(type solid)
		)
		(fill yes)
		(layer "In4.Cu")
		(net "M_J_CPU1_SA_CB<1>")
	)
	(gr_poly
		(pts
			(xy 132.554726 -243.876322) (xy 132.45465 -243.776246) (xy 132.354574 -243.876322) (xy 132.354574 -243.920772)
			(xy 132.554726 -243.920772)
		)
		(stroke
			(width 0)
			(type solid)
		)
		(fill yes)
		(layer "In4.Cu")
		(net "M_J_CPU1_SA_DQ<29>")
	)
	(gr_poly
		(pts
			(xy 132.554726 -242.256056) (xy 132.45465 -242.156234) (xy 132.354574 -242.256056) (xy 132.354574 -242.303808)
			(xy 132.554726 -242.303808)
		)
		(stroke
			(width 0)
			(type solid)
		)
		(fill yes)
		(layer "In4.Cu")
		(net "M_J_CPU1_SA_DQS_DN<8>")
	)
	(gr_poly
		(pts
			(xy 132.554726 -240.636298) (xy 132.45465 -240.536222) (xy 132.354574 -240.636298) (xy 132.354574 -240.680748)
			(xy 132.554726 -240.680748)
		)
		(stroke
			(width 0)
			(type solid)
		)
		(fill yes)
		(layer "In4.Cu")
		(net "M_J_CPU1_SA_DQ<25>")
	)
	(gr_poly
		(pts
			(xy 132.554726 -239.016286) (xy 132.45465 -238.91621) (xy 132.354574 -239.016286) (xy 132.354574 -239.060736)
			(xy 132.554726 -239.060736)
		)
		(stroke
			(width 0)
			(type solid)
		)
		(fill yes)
		(layer "In4.Cu")
		(net "M_J_CPU1_SA_DQ<21>")
	)
	(gr_poly
		(pts
			(xy 132.554726 -237.39602) (xy 132.45465 -237.296198) (xy 132.354574 -237.39602) (xy 132.354574 -237.443772)
			(xy 132.554726 -237.443772)
		)
		(stroke
			(width 0)
			(type solid)
		)
		(fill yes)
		(layer "In4.Cu")
		(net "M_J_CPU1_SA_DQS_DN<7>")
	)
	(gr_poly
		(pts
			(xy 132.554726 -235.776262) (xy 132.45465 -235.676186) (xy 132.354574 -235.776262) (xy 132.354574 -235.820712)
			(xy 132.554726 -235.820712)
		)
		(stroke
			(width 0)
			(type solid)
		)
		(fill yes)
		(layer "In4.Cu")
		(net "M_J_CPU1_SA_DQ<17>")
	)
	(gr_poly
		(pts
			(xy 132.554726 -234.15625) (xy 132.45465 -234.056174) (xy 132.354574 -234.15625) (xy 132.354574 -234.2007)
			(xy 132.554726 -234.2007)
		)
		(stroke
			(width 0)
			(type solid)
		)
		(fill yes)
		(layer "In4.Cu")
		(net "M_J_CPU1_SA_DQ<13>")
	)
	(gr_poly
		(pts
			(xy 132.554726 -232.535984) (xy 132.45465 -232.436162) (xy 132.354574 -232.535984) (xy 132.354574 -232.583736)
			(xy 132.554726 -232.583736)
		)
		(stroke
			(width 0)
			(type solid)
		)
		(fill yes)
		(layer "In4.Cu")
		(net "M_J_CPU1_SA_DQS_DN<6>")
	)
	(gr_poly
		(pts
			(xy 132.554726 -230.916226) (xy 132.45465 -230.81615) (xy 132.354574 -230.916226) (xy 132.354574 -230.960676)
			(xy 132.554726 -230.960676)
		)
		(stroke
			(width 0)
			(type solid)
		)
		(fill yes)
		(layer "In4.Cu")
		(net "M_J_CPU1_SA_DQ<9>")
	)
	(gr_poly
		(pts
			(xy 132.554726 -229.296214) (xy 132.45465 -229.196138) (xy 132.354574 -229.296214) (xy 132.354574 -229.340664)
			(xy 132.554726 -229.340664)
		)
		(stroke
			(width 0)
			(type solid)
		)
		(fill yes)
		(layer "In4.Cu")
		(net "M_J_CPU1_SA_DQ<5>")
	)
	(gr_poly
		(pts
			(xy 132.554726 -227.676202) (xy 132.45465 -227.57638) (xy 132.354574 -227.676202) (xy 132.354574 -227.723954)
			(xy 132.554726 -227.723954)
		)
		(stroke
			(width 0)
			(type solid)
		)
		(fill yes)
		(layer "In4.Cu")
		(net "M_J_CPU1_SA_DQS_DN<5>")
	)
	(gr_poly
		(pts
			(xy 132.554726 -226.056444) (xy 132.45465 -225.956368) (xy 132.354574 -226.056444) (xy 132.354574 -226.100894)
			(xy 132.554726 -226.100894)
		)
		(stroke
			(width 0)
			(type solid)
		)
		(fill yes)
		(layer "In4.Cu")
		(net "M_J_CPU1_SA_DQ<1>")
	)
	(gr_poly
		(pts
			(xy 132.854954 -291.704522) (xy 132.854954 -291.65677) (xy 132.654802 -291.65677) (xy 132.654802 -291.704522)
			(xy 132.754878 -291.804344)
		)
		(stroke
			(width 0)
			(type solid)
		)
		(fill yes)
		(layer "In4.Cu")
		(net "M_J_CPU1_SB_DQS_DP<8>")
	)
	(gr_poly
		(pts
			(xy 132.854954 -290.084256) (xy 132.854954 -290.039806) (xy 132.654802 -290.039806) (xy 132.654802 -290.084256)
			(xy 132.754878 -290.184332)
		)
		(stroke
			(width 0)
			(type solid)
		)
		(fill yes)
		(layer "In4.Cu")
		(net "M_J_CPU1_SB_DQ<27>")
	)
	(gr_poly
		(pts
			(xy 132.854954 -288.464498) (xy 132.854954 -288.420048) (xy 132.654802 -288.420048) (xy 132.654802 -288.464498)
			(xy 132.754878 -288.564574)
		)
		(stroke
			(width 0)
			(type solid)
		)
		(fill yes)
		(layer "In4.Cu")
		(net "M_J_CPU1_SB_DQ<23>")
	)
	(gr_poly
		(pts
			(xy 132.854954 -286.844486) (xy 132.854954 -286.796734) (xy 132.654802 -286.796734) (xy 132.654802 -286.844486)
			(xy 132.754878 -286.944562)
		)
		(stroke
			(width 0)
			(type solid)
		)
		(fill yes)
		(layer "In4.Cu")
		(net "M_J_CPU1_SB_DQS_DP<7>")
	)
	(gr_poly
		(pts
			(xy 132.854954 -285.224474) (xy 132.854954 -285.180024) (xy 132.654802 -285.180024) (xy 132.654802 -285.224474)
			(xy 132.754878 -285.32455)
		)
		(stroke
			(width 0)
			(type solid)
		)
		(fill yes)
		(layer "In4.Cu")
		(net "M_J_CPU1_SB_DQ<19>")
	)
	(gr_poly
		(pts
			(xy 132.854954 -283.604462) (xy 132.854954 -283.560012) (xy 132.654802 -283.560012) (xy 132.654802 -283.604462)
			(xy 132.754878 -283.704538)
		)
		(stroke
			(width 0)
			(type solid)
		)
		(fill yes)
		(layer "In4.Cu")
		(net "M_J_CPU1_SB_DQ<15>")
	)
	(gr_poly
		(pts
			(xy 132.854954 -281.984704) (xy 132.854954 -281.936952) (xy 132.654802 -281.936952) (xy 132.654802 -281.984704)
			(xy 132.754878 -282.084526)
		)
		(stroke
			(width 0)
			(type solid)
		)
		(fill yes)
		(layer "In4.Cu")
		(net "M_J_CPU1_SB_DQS_DP<6>")
	)
	(gr_poly
		(pts
			(xy 132.854954 -280.364438) (xy 132.854954 -280.319988) (xy 132.654802 -280.319988) (xy 132.654802 -280.364438)
			(xy 132.754878 -280.464514)
		)
		(stroke
			(width 0)
			(type solid)
		)
		(fill yes)
		(layer "In4.Cu")
		(net "M_J_CPU1_SB_DQ<11>")
	)
	(gr_poly
		(pts
			(xy 132.854954 -278.744426) (xy 132.854954 -278.699976) (xy 132.654802 -278.699976) (xy 132.654802 -278.744426)
			(xy 132.754878 -278.844502)
		)
		(stroke
			(width 0)
			(type solid)
		)
		(fill yes)
		(layer "In4.Cu")
		(net "M_J_CPU1_SB_DQ<7>")
	)
	(gr_poly
		(pts
			(xy 132.854954 -277.124668) (xy 132.854954 -277.076916) (xy 132.654802 -277.076916) (xy 132.654802 -277.124668)
			(xy 132.754878 -277.22449)
		)
		(stroke
			(width 0)
			(type solid)
		)
		(fill yes)
		(layer "In4.Cu")
		(net "M_J_CPU1_SB_DQS_DP<5>")
	)
	(gr_poly
		(pts
			(xy 132.854954 -275.504402) (xy 132.854954 -275.459952) (xy 132.654802 -275.459952) (xy 132.654802 -275.504402)
			(xy 132.754878 -275.604478)
		)
		(stroke
			(width 0)
			(type solid)
		)
		(fill yes)
		(layer "In4.Cu")
		(net "M_J_CPU1_SB_DQ<3>")
	)
	(gr_poly
		(pts
			(xy 132.854954 -273.88439) (xy 132.854954 -273.83994) (xy 132.654802 -273.83994) (xy 132.654802 -273.88439)
			(xy 132.754878 -273.984466)
		)
		(stroke
			(width 0)
			(type solid)
		)
		(fill yes)
		(layer "In4.Cu")
		(net "M_J_CPU1_SB_CB<3>")
	)
	(gr_poly
		(pts
			(xy 132.854954 -272.264632) (xy 132.854954 -272.21688) (xy 132.654802 -272.21688) (xy 132.654802 -272.264632)
			(xy 132.754878 -272.364454)
		)
		(stroke
			(width 0)
			(type solid)
		)
		(fill yes)
		(layer "In4.Cu")
		(net "M_J_CPU1_SB_DQS_DP<4>")
	)
	(gr_poly
		(pts
			(xy 132.854954 -270.644366) (xy 132.854954 -270.599916) (xy 132.654802 -270.599916) (xy 132.654802 -270.644366)
			(xy 132.754878 -270.744442)
		)
		(stroke
			(width 0)
			(type solid)
		)
		(fill yes)
		(layer "In4.Cu")
		(net "M_J_CPU1_SB_CB<7>")
	)
	(gr_poly
		(pts
			(xy 132.854954 -265.78433) (xy 132.854954 -265.73988) (xy 132.654802 -265.73988) (xy 132.654802 -265.78433)
			(xy 132.754878 -265.884406)
		)
		(stroke
			(width 0)
			(type solid)
		)
		(fill yes)
		(layer "In4.Cu")
		(net "M_J_CPU1_SB_CS_N<0>")
	)
	(gr_poly
		(pts
			(xy 132.854954 -264.164318) (xy 132.854954 -264.119868) (xy 132.654802 -264.119868) (xy 132.654802 -264.164318)
			(xy 132.754878 -264.264394)
		)
		(stroke
			(width 0)
			(type solid)
		)
		(fill yes)
		(layer "In4.Cu")
		(net "M_J_CPU1_SB_CA<5>")
	)
	(gr_poly
		(pts
			(xy 132.854954 -262.544306) (xy 132.854954 -262.499856) (xy 132.654802 -262.499856) (xy 132.654802 -262.544306)
			(xy 132.754878 -262.644382)
		)
		(stroke
			(width 0)
			(type solid)
		)
		(fill yes)
		(layer "In4.Cu")
		(net "M_J_CPU1_SB_CA<1>")
	)
	(gr_poly
		(pts
			(xy 133.02488 -255.622552) (xy 133.02488 -255.578102) (xy 132.824728 -255.578102) (xy 132.824728 -255.622552)
			(xy 132.924804 -255.722628)
		)
		(stroke
			(width 0)
			(type solid)
		)
		(fill yes)
		(layer "In4.Cu")
		(net "M_J_CPU1_SA_PAR")
	)
	(gr_poly
		(pts
			(xy 133.02488 -254.00254) (xy 133.02488 -253.95809) (xy 132.824728 -253.95809) (xy 132.824728 -254.00254)
			(xy 132.924804 -254.102616)
		)
		(stroke
			(width 0)
			(type solid)
		)
		(fill yes)
		(layer "In4.Cu")
		(net "M_J_CPU1_SA_CA<3>")
	)
	(gr_poly
		(pts
			(xy 133.02488 -250.762516) (xy 133.02488 -250.718066) (xy 132.824728 -250.718066) (xy 132.824728 -250.762516)
			(xy 132.924804 -250.862592)
		)
		(stroke
			(width 0)
			(type solid)
		)
		(fill yes)
		(layer "In4.Cu")
		(net "M_J_CPU1_RESET_N")
	)
	(gr_poly
		(pts
			(xy 133.02488 -249.142504) (xy 133.02488 -249.098054) (xy 132.824728 -249.098054) (xy 132.824728 -249.142504)
			(xy 132.924804 -249.24258)
		)
		(stroke
			(width 0)
			(type solid)
		)
		(fill yes)
		(layer "In4.Cu")
		(net "M_J_CPU1_SA_CB<7>")
	)
	(gr_poly
		(pts
			(xy 133.02488 -247.522746) (xy 133.02488 -247.474994) (xy 132.824728 -247.474994) (xy 132.824728 -247.522746)
			(xy 132.924804 -247.622568)
		)
		(stroke
			(width 0)
			(type solid)
		)
		(fill yes)
		(layer "In4.Cu")
		(net "M_J_CPU1_SA_DQS_DP<9>")
	)
	(gr_poly
		(pts
			(xy 133.02488 -245.90248) (xy 133.02488 -245.85803) (xy 132.824728 -245.85803) (xy 132.824728 -245.90248)
			(xy 132.924804 -246.002556)
		)
		(stroke
			(width 0)
			(type solid)
		)
		(fill yes)
		(layer "In4.Cu")
		(net "M_J_CPU1_SA_CB<3>")
	)
	(gr_poly
		(pts
			(xy 133.02488 -244.282468) (xy 133.02488 -244.238018) (xy 132.824728 -244.238018) (xy 132.824728 -244.282468)
			(xy 132.924804 -244.382544)
		)
		(stroke
			(width 0)
			(type solid)
		)
		(fill yes)
		(layer "In4.Cu")
		(net "M_J_CPU1_SA_DQ<31>")
	)
	(gr_poly
		(pts
			(xy 133.02488 -242.66271) (xy 133.02488 -242.614958) (xy 132.824728 -242.614958) (xy 132.824728 -242.66271)
			(xy 132.924804 -242.762532)
		)
		(stroke
			(width 0)
			(type solid)
		)
		(fill yes)
		(layer "In4.Cu")
		(net "M_J_CPU1_SA_DQS_DP<8>")
	)
	(gr_poly
		(pts
			(xy 133.02488 -241.042444) (xy 133.02488 -240.997994) (xy 132.824728 -240.997994) (xy 132.824728 -241.042444)
			(xy 132.924804 -241.14252)
		)
		(stroke
			(width 0)
			(type solid)
		)
		(fill yes)
		(layer "In4.Cu")
		(net "M_J_CPU1_SA_DQ<27>")
	)
	(gr_poly
		(pts
			(xy 133.02488 -239.422432) (xy 133.02488 -239.377982) (xy 132.824728 -239.377982) (xy 132.824728 -239.422432)
			(xy 132.924804 -239.522508)
		)
		(stroke
			(width 0)
			(type solid)
		)
		(fill yes)
		(layer "In4.Cu")
		(net "M_J_CPU1_SA_DQ<23>")
	)
	(gr_poly
		(pts
			(xy 133.02488 -237.802674) (xy 133.02488 -237.754922) (xy 132.824728 -237.754922) (xy 132.824728 -237.802674)
			(xy 132.924804 -237.902496)
		)
		(stroke
			(width 0)
			(type solid)
		)
		(fill yes)
		(layer "In4.Cu")
		(net "M_J_CPU1_SA_DQS_DP<7>")
	)
	(gr_poly
		(pts
			(xy 133.02488 -236.182408) (xy 133.02488 -236.137958) (xy 132.824728 -236.137958) (xy 132.824728 -236.182408)
			(xy 132.924804 -236.282484)
		)
		(stroke
			(width 0)
			(type solid)
		)
		(fill yes)
		(layer "In4.Cu")
		(net "M_J_CPU1_SA_DQ<19>")
	)
	(gr_poly
		(pts
			(xy 133.02488 -234.562396) (xy 133.02488 -234.517946) (xy 132.824728 -234.517946) (xy 132.824728 -234.562396)
			(xy 132.924804 -234.662472)
		)
		(stroke
			(width 0)
			(type solid)
		)
		(fill yes)
		(layer "In4.Cu")
		(net "M_J_CPU1_SA_DQ<15>")
	)
	(gr_poly
		(pts
			(xy 133.02488 -232.942638) (xy 133.02488 -232.894886) (xy 132.824728 -232.894886) (xy 132.824728 -232.942638)
			(xy 132.924804 -233.04246)
		)
		(stroke
			(width 0)
			(type solid)
		)
		(fill yes)
		(layer "In4.Cu")
		(net "M_J_CPU1_SA_DQS_DP<6>")
	)
	(gr_poly
		(pts
			(xy 133.02488 -231.322626) (xy 133.02488 -231.278176) (xy 132.824728 -231.278176) (xy 132.824728 -231.322626)
			(xy 132.924804 -231.422702)
		)
		(stroke
			(width 0)
			(type solid)
		)
		(fill yes)
		(layer "In4.Cu")
		(net "M_J_CPU1_SA_DQ<11>")
	)
	(gr_poly
		(pts
			(xy 133.02488 -229.702614) (xy 133.02488 -229.658164) (xy 132.824728 -229.658164) (xy 132.824728 -229.702614)
			(xy 132.924804 -229.80269)
		)
		(stroke
			(width 0)
			(type solid)
		)
		(fill yes)
		(layer "In4.Cu")
		(net "M_J_CPU1_SA_DQ<7>")
	)
	(gr_poly
		(pts
			(xy 133.02488 -228.082856) (xy 133.02488 -228.035104) (xy 132.824728 -228.035104) (xy 132.824728 -228.082856)
			(xy 132.924804 -228.182678)
		)
		(stroke
			(width 0)
			(type solid)
		)
		(fill yes)
		(layer "In4.Cu")
		(net "M_J_CPU1_SA_DQS_DP<5>")
	)
	(gr_poly
		(pts
			(xy 133.02488 -226.46259) (xy 133.02488 -226.41814) (xy 132.824728 -226.41814) (xy 132.824728 -226.46259)
			(xy 132.924804 -226.562666)
		)
		(stroke
			(width 0)
			(type solid)
		)
		(fill yes)
		(layer "In4.Cu")
		(net "M_J_CPU1_SA_DQ<3>")
	)
	(gr_poly
		(pts
			(xy 133.063742 -254.416306) (xy 132.97281 -254.308102) (xy 132.864352 -254.399034) (xy 132.860542 -254.44323)
			(xy 133.059678 -254.460502)
		)
		(stroke
			(width 0)
			(type solid)
		)
		(fill yes)
		(layer "In4.Cu")
		(net "M_J_CPU1_SA_CA<4>")
	)
	(gr_poly
		(pts
			(xy 133.063742 -252.796294) (xy 132.97281 -252.68809) (xy 132.864352 -252.778768) (xy 132.860542 -252.823218)
			(xy 133.059678 -252.84049)
		)
		(stroke
			(width 0)
			(type solid)
		)
		(fill yes)
		(layer "In4.Cu")
		(net "M_J_CPU1_SA_CA<0>")
	)
	(gr_poly
		(pts
			(xy 133.063742 -251.176282) (xy 132.97281 -251.068078) (xy 132.864352 -251.158756) (xy 132.860542 -251.203206)
			(xy 133.059678 -251.220478)
		)
		(stroke
			(width 0)
			(type solid)
		)
		(fill yes)
		(layer "In4.Cu")
		(net "M_J_CPU1_SA_CS_N<0>")
	)
	(gr_poly
		(pts
			(xy 133.063742 -247.936258) (xy 132.97281 -247.828054) (xy 132.864352 -247.918732) (xy 132.860542 -247.963182)
			(xy 133.059678 -247.980454)
		)
		(stroke
			(width 0)
			(type solid)
		)
		(fill yes)
		(layer "In4.Cu")
		(net "M_J_CPU1_SA_CB<4>")
	)
	(gr_poly
		(pts
			(xy 133.063742 -244.696234) (xy 132.97281 -244.58803) (xy 132.864352 -244.678708) (xy 132.860542 -244.723158)
			(xy 133.059678 -244.74043)
		)
		(stroke
			(width 0)
			(type solid)
		)
		(fill yes)
		(layer "In4.Cu")
		(net "M_J_CPU1_SA_CB<0>")
	)
	(gr_poly
		(pts
			(xy 133.063742 -243.076222) (xy 132.97281 -242.968018) (xy 132.864352 -243.058696) (xy 132.860542 -243.103146)
			(xy 133.059678 -243.120418)
		)
		(stroke
			(width 0)
			(type solid)
		)
		(fill yes)
		(layer "In4.Cu")
		(net "M_J_CPU1_SA_DQ<28>")
	)
	(gr_poly
		(pts
			(xy 133.063742 -239.836198) (xy 132.97281 -239.727994) (xy 132.864352 -239.818672) (xy 132.860542 -239.863122)
			(xy 133.059678 -239.880394)
		)
		(stroke
			(width 0)
			(type solid)
		)
		(fill yes)
		(layer "In4.Cu")
		(net "M_J_CPU1_SA_DQ<24>")
	)
	(gr_poly
		(pts
			(xy 133.063742 -238.216186) (xy 132.97281 -238.107982) (xy 132.864352 -238.19866) (xy 132.860542 -238.24311)
			(xy 133.059678 -238.260382)
		)
		(stroke
			(width 0)
			(type solid)
		)
		(fill yes)
		(layer "In4.Cu")
		(net "M_J_CPU1_SA_DQ<20>")
	)
	(gr_poly
		(pts
			(xy 133.063742 -234.976162) (xy 132.97281 -234.867958) (xy 132.864352 -234.958636) (xy 132.860542 -235.003086)
			(xy 133.059678 -235.020358)
		)
		(stroke
			(width 0)
			(type solid)
		)
		(fill yes)
		(layer "In4.Cu")
		(net "M_J_CPU1_SA_DQ<16>")
	)
	(gr_poly
		(pts
			(xy 133.063742 -233.35615) (xy 132.97281 -233.247946) (xy 132.864352 -233.338624) (xy 132.860542 -233.383074)
			(xy 133.059678 -233.400346)
		)
		(stroke
			(width 0)
			(type solid)
		)
		(fill yes)
		(layer "In4.Cu")
		(net "M_J_CPU1_SA_DQ<12>")
	)
	(gr_poly
		(pts
			(xy 133.063742 -230.116126) (xy 132.97281 -230.007922) (xy 132.864352 -230.098854) (xy 132.860542 -230.14305)
			(xy 133.059678 -230.160576)
		)
		(stroke
			(width 0)
			(type solid)
		)
		(fill yes)
		(layer "In4.Cu")
		(net "M_J_CPU1_SA_DQ<8>")
	)
	(gr_poly
		(pts
			(xy 133.063742 -228.496368) (xy 132.97281 -228.388164) (xy 132.864352 -228.479096) (xy 132.860542 -228.523292)
			(xy 133.059678 -228.540564)
		)
		(stroke
			(width 0)
			(type solid)
		)
		(fill yes)
		(layer "In4.Cu")
		(net "M_J_CPU1_SA_DQ<4>")
	)
	(gr_poly
		(pts
			(xy 133.063742 -225.256344) (xy 132.97281 -225.14814) (xy 132.864352 -225.239072) (xy 132.860542 -225.283268)
			(xy 133.059678 -225.30054)
		)
		(stroke
			(width 0)
			(type solid)
		)
		(fill yes)
		(layer "In4.Cu")
		(net "M_J_CPU1_SA_DQ<0>")
	)
	(gr_poly
		(pts
			(xy 133.06552 -256.036064) (xy 132.974588 -255.92786) (xy 132.86613 -256.018792) (xy 132.862066 -256.06629)
			(xy 133.061202 -256.083562)
		)
		(stroke
			(width 0)
			(type solid)
		)
		(fill yes)
		(layer "In4.Cu")
		(net "M_J_CPU1_CLK_DP<0>")
	)
	(gr_poly
		(pts
			(xy 133.06552 -231.735884) (xy 132.974588 -231.62768) (xy 132.86613 -231.718612) (xy 132.862066 -231.76611)
			(xy 133.061202 -231.783382)
		)
		(stroke
			(width 0)
			(type solid)
		)
		(fill yes)
		(layer "In4.Cu")
		(net "M_J_CPU1_SA_DQS_DP<1>")
	)
	(gr_poly
		(pts
			(xy 133.06552 -226.876102) (xy 132.974588 -226.767898) (xy 132.86613 -226.85883) (xy 132.862066 -226.906328)
			(xy 133.061202 -226.9236)
		)
		(stroke
			(width 0)
			(type solid)
		)
		(fill yes)
		(layer "In4.Cu")
		(net "M_J_CPU1_SA_DQS_DP<0>")
	)
	(gr_poly
		(pts
			(xy 133.076442 -246.317008) (xy 132.98551 -246.20855) (xy 132.877306 -246.299482) (xy 132.872988 -246.34698)
			(xy 133.072378 -246.364252)
		)
		(stroke
			(width 0)
			(type solid)
		)
		(fill yes)
		(layer "In4.Cu")
		(net "M_J_CPU1_SA_DQS_DP<4>")
	)
	(gr_poly
		(pts
			(xy 133.076442 -241.456972) (xy 132.98551 -241.348514) (xy 132.877306 -241.439446) (xy 132.872988 -241.486944)
			(xy 133.072378 -241.50447)
		)
		(stroke
			(width 0)
			(type solid)
		)
		(fill yes)
		(layer "In4.Cu")
		(net "M_J_CPU1_SA_DQS_DP<3>")
	)
	(gr_poly
		(pts
			(xy 133.076442 -236.596936) (xy 132.98551 -236.488478) (xy 132.877306 -236.57941) (xy 132.872988 -236.626908)
			(xy 133.072378 -236.644434)
		)
		(stroke
			(width 0)
			(type solid)
		)
		(fill yes)
		(layer "In4.Cu")
		(net "M_J_CPU1_SA_DQS_DP<2>")
	)
	(gr_poly
		(pts
			(xy 133.324854 -292.918134) (xy 133.224778 -292.818058) (xy 133.124702 -292.918134) (xy 133.124702 -292.962584)
			(xy 133.324854 -292.962584)
		)
		(stroke
			(width 0)
			(type solid)
		)
		(fill yes)
		(layer "In4.Cu")
		(net "M_J_CPU1_SB_DQ<29>")
	)
	(gr_poly
		(pts
			(xy 133.324854 -291.297868) (xy 133.224778 -291.198046) (xy 133.124702 -291.297868) (xy 133.124702 -291.34562)
			(xy 133.324854 -291.34562)
		)
		(stroke
			(width 0)
			(type solid)
		)
		(fill yes)
		(layer "In4.Cu")
		(net "M_J_CPU1_SB_DQS_DN<8>")
	)
	(gr_poly
		(pts
			(xy 133.324854 -289.67811) (xy 133.224778 -289.578034) (xy 133.124702 -289.67811) (xy 133.124702 -289.72256)
			(xy 133.324854 -289.72256)
		)
		(stroke
			(width 0)
			(type solid)
		)
		(fill yes)
		(layer "In4.Cu")
		(net "M_J_CPU1_SB_DQ<25>")
	)
	(gr_poly
		(pts
			(xy 133.324854 -288.058098) (xy 133.224778 -287.958022) (xy 133.124702 -288.058098) (xy 133.124702 -288.102548)
			(xy 133.324854 -288.102548)
		)
		(stroke
			(width 0)
			(type solid)
		)
		(fill yes)
		(layer "In4.Cu")
		(net "M_J_CPU1_SB_DQ<21>")
	)
	(gr_poly
		(pts
			(xy 133.324854 -286.438086) (xy 133.224778 -286.33801) (xy 133.124702 -286.438086) (xy 133.124702 -286.485838)
			(xy 133.324854 -286.485838)
		)
		(stroke
			(width 0)
			(type solid)
		)
		(fill yes)
		(layer "In4.Cu")
		(net "M_J_CPU1_SB_DQS_DN<7>")
	)
	(gr_poly
		(pts
			(xy 133.324854 -284.818328) (xy 133.224778 -284.718252) (xy 133.124702 -284.818328) (xy 133.124702 -284.862778)
			(xy 133.324854 -284.862778)
		)
		(stroke
			(width 0)
			(type solid)
		)
		(fill yes)
		(layer "In4.Cu")
		(net "M_J_CPU1_SB_DQ<17>")
	)
	(gr_poly
		(pts
			(xy 133.324854 -283.198316) (xy 133.224778 -283.09824) (xy 133.124702 -283.198316) (xy 133.124702 -283.242766)
			(xy 133.324854 -283.242766)
		)
		(stroke
			(width 0)
			(type solid)
		)
		(fill yes)
		(layer "In4.Cu")
		(net "M_J_CPU1_SB_DQ<13>")
	)
	(gr_poly
		(pts
			(xy 133.324854 -281.57805) (xy 133.224778 -281.478228) (xy 133.124702 -281.57805) (xy 133.124702 -281.625802)
			(xy 133.324854 -281.625802)
		)
		(stroke
			(width 0)
			(type solid)
		)
		(fill yes)
		(layer "In4.Cu")
		(net "M_J_CPU1_SB_DQS_DN<6>")
	)
	(gr_poly
		(pts
			(xy 133.324854 -279.958292) (xy 133.224778 -279.858216) (xy 133.124702 -279.958292) (xy 133.124702 -280.002742)
			(xy 133.324854 -280.002742)
		)
		(stroke
			(width 0)
			(type solid)
		)
		(fill yes)
		(layer "In4.Cu")
		(net "M_J_CPU1_SB_DQ<9>")
	)
	(gr_poly
		(pts
			(xy 133.324854 -278.33828) (xy 133.224778 -278.238204) (xy 133.124702 -278.33828) (xy 133.124702 -278.38273)
			(xy 133.324854 -278.38273)
		)
		(stroke
			(width 0)
			(type solid)
		)
		(fill yes)
		(layer "In4.Cu")
		(net "M_J_CPU1_SB_DQ<5>")
	)
	(gr_poly
		(pts
			(xy 133.324854 -276.718014) (xy 133.224778 -276.618192) (xy 133.124702 -276.718014) (xy 133.124702 -276.765766)
			(xy 133.324854 -276.765766)
		)
		(stroke
			(width 0)
			(type solid)
		)
		(fill yes)
		(layer "In4.Cu")
		(net "M_J_CPU1_SB_DQS_DN<5>")
	)
	(gr_poly
		(pts
			(xy 133.324854 -275.098256) (xy 133.224778 -274.99818) (xy 133.124702 -275.098256) (xy 133.124702 -275.142706)
			(xy 133.324854 -275.142706)
		)
		(stroke
			(width 0)
			(type solid)
		)
		(fill yes)
		(layer "In4.Cu")
		(net "M_J_CPU1_SB_DQ<1>")
	)
	(gr_poly
		(pts
			(xy 133.324854 -273.478244) (xy 133.224778 -273.378168) (xy 133.124702 -273.478244) (xy 133.124702 -273.522694)
			(xy 133.324854 -273.522694)
		)
		(stroke
			(width 0)
			(type solid)
		)
		(fill yes)
		(layer "In4.Cu")
		(net "M_J_CPU1_SB_CB<1>")
	)
	(gr_poly
		(pts
			(xy 133.324854 -271.857978) (xy 133.224778 -271.758156) (xy 133.124702 -271.857978) (xy 133.124702 -271.90573)
			(xy 133.324854 -271.90573)
		)
		(stroke
			(width 0)
			(type solid)
		)
		(fill yes)
		(layer "In4.Cu")
		(net "M_J_CPU1_SB_DQS_DN<4>")
	)
	(gr_poly
		(pts
			(xy 133.324854 -270.23822) (xy 133.224778 -270.138144) (xy 133.124702 -270.23822) (xy 133.124702 -270.28267)
			(xy 133.324854 -270.28267)
		)
		(stroke
			(width 0)
			(type solid)
		)
		(fill yes)
		(layer "In4.Cu")
		(net "M_J_CPU1_SB_CB<5>")
	)
	(gr_poly
		(pts
			(xy 133.324854 -266.998196) (xy 133.224778 -266.89812) (xy 133.124702 -266.998196) (xy 133.124702 -267.042646)
			(xy 133.324854 -267.042646)
		)
		(stroke
			(width 0)
			(type solid)
		)
		(fill yes)
		(layer "In4.Cu")
		(net "M_J_CPU1_SA_RSP<0>")
	)
	(gr_poly
		(pts
			(xy 133.324854 -265.378184) (xy 133.224778 -265.278108) (xy 133.124702 -265.378184) (xy 133.124702 -265.422634)
			(xy 133.324854 -265.422634)
		)
		(stroke
			(width 0)
			(type solid)
		)
		(fill yes)
		(layer "In4.Cu")
		(net "M_J_CPU1_SB_PAR")
	)
	(gr_poly
		(pts
			(xy 133.324854 -263.758172) (xy 133.224778 -263.658096) (xy 133.124702 -263.758172) (xy 133.124702 -263.802622)
			(xy 133.324854 -263.802622)
		)
		(stroke
			(width 0)
			(type solid)
		)
		(fill yes)
		(layer "In4.Cu")
		(net "M_J_CPU1_SB_CA<4>")
	)
	(gr_poly
		(pts
			(xy 133.324854 -262.13816) (xy 133.224778 -262.038084) (xy 133.124702 -262.13816) (xy 133.124702 -262.18261)
			(xy 133.324854 -262.18261)
		)
		(stroke
			(width 0)
			(type solid)
		)
		(fill yes)
		(layer "In4.Cu")
		(net "M_J_CPU1_SB_CA<0>")
	)
	(gr_poly
		(pts
			(xy 133.363462 -292.504368) (xy 133.359652 -292.460172) (xy 133.160262 -292.477444) (xy 133.164326 -292.521894)
			(xy 133.27253 -292.612826)
		)
		(stroke
			(width 0)
			(type solid)
		)
		(fill yes)
		(layer "In4.Cu")
		(net "M_J_CPU1_SB_DQ<30>")
	)
	(gr_poly
		(pts
			(xy 133.363462 -289.264344) (xy 133.359652 -289.220148) (xy 133.160262 -289.23742) (xy 133.164326 -289.28187)
			(xy 133.27253 -289.372802)
		)
		(stroke
			(width 0)
			(type solid)
		)
		(fill yes)
		(layer "In4.Cu")
		(net "M_J_CPU1_SB_DQ<26>")
	)
	(gr_poly
		(pts
			(xy 133.363462 -287.644586) (xy 133.359652 -287.60039) (xy 133.160262 -287.617662) (xy 133.164326 -287.662112)
			(xy 133.27253 -287.753044)
		)
		(stroke
			(width 0)
			(type solid)
		)
		(fill yes)
		(layer "In4.Cu")
		(net "M_J_CPU1_SB_DQ<22>")
	)
	(gr_poly
		(pts
			(xy 133.363462 -284.404562) (xy 133.359652 -284.360366) (xy 133.160262 -284.377638) (xy 133.164326 -284.422088)
			(xy 133.27253 -284.51302)
		)
		(stroke
			(width 0)
			(type solid)
		)
		(fill yes)
		(layer "In4.Cu")
		(net "M_J_CPU1_SB_DQ<18>")
	)
	(gr_poly
		(pts
			(xy 133.363462 -282.78455) (xy 133.359652 -282.740354) (xy 133.160262 -282.757626) (xy 133.164326 -282.802076)
			(xy 133.27253 -282.893008)
		)
		(stroke
			(width 0)
			(type solid)
		)
		(fill yes)
		(layer "In4.Cu")
		(net "M_J_CPU1_SB_DQ<14>")
	)
	(gr_poly
		(pts
			(xy 133.363462 -279.544526) (xy 133.359652 -279.50033) (xy 133.160262 -279.517602) (xy 133.164326 -279.562052)
			(xy 133.27253 -279.652984)
		)
		(stroke
			(width 0)
			(type solid)
		)
		(fill yes)
		(layer "In4.Cu")
		(net "M_J_CPU1_SB_DQ<10>")
	)
	(gr_poly
		(pts
			(xy 133.363462 -277.924514) (xy 133.359652 -277.880318) (xy 133.160262 -277.89759) (xy 133.164326 -277.94204)
			(xy 133.27253 -278.032972)
		)
		(stroke
			(width 0)
			(type solid)
		)
		(fill yes)
		(layer "In4.Cu")
		(net "M_J_CPU1_SB_DQ<6>")
	)
	(gr_poly
		(pts
			(xy 133.363462 -274.68449) (xy 133.359652 -274.640294) (xy 133.160262 -274.657566) (xy 133.164326 -274.702016)
			(xy 133.27253 -274.792948)
		)
		(stroke
			(width 0)
			(type solid)
		)
		(fill yes)
		(layer "In4.Cu")
		(net "M_J_CPU1_SB_DQ<2>")
	)
	(gr_poly
		(pts
			(xy 133.363462 -273.064478) (xy 133.359652 -273.020282) (xy 133.160262 -273.037554) (xy 133.164326 -273.082004)
			(xy 133.27253 -273.172936)
		)
		(stroke
			(width 0)
			(type solid)
		)
		(fill yes)
		(layer "In4.Cu")
		(net "M_J_CPU1_SB_CB<2>")
	)
	(gr_poly
		(pts
			(xy 133.363462 -269.824454) (xy 133.359652 -269.780258) (xy 133.160262 -269.79753) (xy 133.164326 -269.84198)
			(xy 133.27253 -269.932912)
		)
		(stroke
			(width 0)
			(type solid)
		)
		(fill yes)
		(layer "In4.Cu")
		(net "M_J_CPU1_SB_CB<6>")
	)
	(gr_poly
		(pts
			(xy 133.363462 -266.58443) (xy 133.359652 -266.540234) (xy 133.160262 -266.557506) (xy 133.164326 -266.601956)
			(xy 133.27253 -266.692888)
		)
		(stroke
			(width 0)
			(type solid)
		)
		(fill yes)
		(layer "In4.Cu")
		(net "M_J_CPU1_SB_CS_N<1>")
	)
	(gr_poly
		(pts
			(xy 133.363462 -263.344406) (xy 133.359652 -263.30021) (xy 133.160262 -263.317482) (xy 133.164326 -263.361932)
			(xy 133.27253 -263.452864)
		)
		(stroke
			(width 0)
			(type solid)
		)
		(fill yes)
		(layer "In4.Cu")
		(net "M_J_CPU1_SB_CA<3>")
	)
	(gr_poly
		(pts
			(xy 133.376162 -290.883594) (xy 133.372098 -290.836096) (xy 133.172708 -290.853622) (xy 133.177026 -290.90112)
			(xy 133.28523 -290.992052)
		)
		(stroke
			(width 0)
			(type solid)
		)
		(fill yes)
		(layer "In4.Cu")
		(net "M_J_CPU1_SB_DQS_DN<3>")
	)
	(gr_poly
		(pts
			(xy 133.376162 -286.023812) (xy 133.372098 -285.976568) (xy 133.172708 -285.99384) (xy 133.177026 -286.041338)
			(xy 133.28523 -286.13227)
		)
		(stroke
			(width 0)
			(type solid)
		)
		(fill yes)
		(layer "In4.Cu")
		(net "M_J_CPU1_SB_DQS_DN<2>")
	)
	(gr_poly
		(pts
			(xy 133.376162 -281.163776) (xy 133.372098 -281.116532) (xy 133.172708 -281.133804) (xy 133.177026 -281.181302)
			(xy 133.28523 -281.272234)
		)
		(stroke
			(width 0)
			(type solid)
		)
		(fill yes)
		(layer "In4.Cu")
		(net "M_J_CPU1_SB_DQS_DN<1>")
	)
	(gr_poly
		(pts
			(xy 133.376162 -276.30374) (xy 133.372098 -276.256496) (xy 133.172708 -276.273768) (xy 133.177026 -276.321266)
			(xy 133.28523 -276.412198)
		)
		(stroke
			(width 0)
			(type solid)
		)
		(fill yes)
		(layer "In4.Cu")
		(net "M_J_CPU1_SB_DQS_DN<0>")
	)
	(gr_poly
		(pts
			(xy 133.376162 -271.443704) (xy 133.372098 -271.39646) (xy 133.172708 -271.413732) (xy 133.177026 -271.46123)
			(xy 133.28523 -271.552162)
		)
		(stroke
			(width 0)
			(type solid)
		)
		(fill yes)
		(layer "In4.Cu")
		(net "M_J_CPU1_SB_DQS_DN<9>")
	)
	(gr_poly
		(pts
			(xy 133.49478 -256.432812) (xy 133.49478 -256.38506) (xy 133.294628 -256.38506) (xy 133.294628 -256.432812)
			(xy 133.394704 -256.532634)
		)
		(stroke
			(width 0)
			(type solid)
		)
		(fill yes)
		(layer "In4.Cu")
		(net "M_J_CPU1_CLK_DN<0>")
	)
	(gr_poly
		(pts
			(xy 133.49478 -255.216406) (xy 133.394704 -255.11633) (xy 133.294628 -255.216406) (xy 133.294628 -255.260856)
			(xy 133.49478 -255.260856)
		)
		(stroke
			(width 0)
			(type solid)
		)
		(fill yes)
		(layer "In4.Cu")
		(net "M_J_CPU1_SA_CA<6>")
	)
	(gr_poly
		(pts
			(xy 133.49478 -254.812546) (xy 133.49478 -254.768096) (xy 133.294628 -254.768096) (xy 133.294628 -254.812546)
			(xy 133.394704 -254.912622)
		)
		(stroke
			(width 0)
			(type solid)
		)
		(fill yes)
		(layer "In4.Cu")
		(net "M_J_CPU1_SA_CA<5>")
	)
	(gr_poly
		(pts
			(xy 133.49478 -253.596394) (xy 133.394704 -253.496318) (xy 133.294628 -253.596394) (xy 133.294628 -253.640844)
			(xy 133.49478 -253.640844)
		)
		(stroke
			(width 0)
			(type solid)
		)
		(fill yes)
		(layer "In4.Cu")
		(net "M_J_CPU1_SA_CA<2>")
	)
	(gr_poly
		(pts
			(xy 133.49478 -253.192534) (xy 133.49478 -253.148084) (xy 133.294628 -253.148084) (xy 133.294628 -253.192534)
			(xy 133.394704 -253.29261)
		)
		(stroke
			(width 0)
			(type solid)
		)
		(fill yes)
		(layer "In4.Cu")
		(net "M_J_CPU1_SA_CA<1>")
	)
	(gr_poly
		(pts
			(xy 133.49478 -251.976382) (xy 133.394704 -251.876306) (xy 133.294628 -251.976382) (xy 133.294628 -252.020832)
			(xy 133.49478 -252.020832)
		)
		(stroke
			(width 0)
			(type solid)
		)
		(fill yes)
		(layer "In4.Cu")
		(net "M_J_CPU1_SA_CS_N<1>")
	)
	(gr_poly
		(pts
			(xy 133.49478 -250.35637) (xy 133.394704 -250.256294) (xy 133.294628 -250.35637) (xy 133.294628 -250.40082)
			(xy 133.49478 -250.40082)
		)
		(stroke
			(width 0)
			(type solid)
		)
		(fill yes)
		(layer "In4.Cu")
		(net "M_J_CPU1_ALERT_R_N")
	)
	(gr_poly
		(pts
			(xy 133.49478 -248.736358) (xy 133.394704 -248.636282) (xy 133.294628 -248.736358) (xy 133.294628 -248.780808)
			(xy 133.49478 -248.780808)
		)
		(stroke
			(width 0)
			(type solid)
		)
		(fill yes)
		(layer "In4.Cu")
		(net "M_J_CPU1_SA_CB<5>")
	)
	(gr_poly
		(pts
			(xy 133.49478 -248.332498) (xy 133.49478 -248.288048) (xy 133.294628 -248.288048) (xy 133.294628 -248.332498)
			(xy 133.394704 -248.432574)
		)
		(stroke
			(width 0)
			(type solid)
		)
		(fill yes)
		(layer "In4.Cu")
		(net "M_J_CPU1_SA_CB<6>")
	)
	(gr_poly
		(pts
			(xy 133.49478 -247.116092) (xy 133.394704 -247.01627) (xy 133.294628 -247.116092) (xy 133.294628 -247.163844)
			(xy 133.49478 -247.163844)
		)
		(stroke
			(width 0)
			(type solid)
		)
		(fill yes)
		(layer "In4.Cu")
		(net "M_J_CPU1_SA_DQS_DN<9>")
	)
	(gr_poly
		(pts
			(xy 133.49478 -246.71274) (xy 133.49478 -246.664988) (xy 133.294628 -246.664988) (xy 133.294628 -246.71274)
			(xy 133.394704 -246.812562)
		)
		(stroke
			(width 0)
			(type solid)
		)
		(fill yes)
		(layer "In4.Cu")
		(net "M_J_CPU1_SA_DQS_DN<4>")
	)
	(gr_poly
		(pts
			(xy 133.49478 -245.496334) (xy 133.394704 -245.396258) (xy 133.294628 -245.496334) (xy 133.294628 -245.540784)
			(xy 133.49478 -245.540784)
		)
		(stroke
			(width 0)
			(type solid)
		)
		(fill yes)
		(layer "In4.Cu")
		(net "M_J_CPU1_SA_CB<1>")
	)
	(gr_poly
		(pts
			(xy 133.49478 -245.092474) (xy 133.49478 -245.048024) (xy 133.294628 -245.048024) (xy 133.294628 -245.092474)
			(xy 133.394704 -245.19255)
		)
		(stroke
			(width 0)
			(type solid)
		)
		(fill yes)
		(layer "In4.Cu")
		(net "M_J_CPU1_SA_CB<2>")
	)
	(gr_poly
		(pts
			(xy 133.49478 -243.876322) (xy 133.394704 -243.776246) (xy 133.294628 -243.876322) (xy 133.294628 -243.920772)
			(xy 133.49478 -243.920772)
		)
		(stroke
			(width 0)
			(type solid)
		)
		(fill yes)
		(layer "In4.Cu")
		(net "M_J_CPU1_SA_DQ<29>")
	)
	(gr_poly
		(pts
			(xy 133.49478 -243.472462) (xy 133.49478 -243.428012) (xy 133.294628 -243.428012) (xy 133.294628 -243.472462)
			(xy 133.394704 -243.572538)
		)
		(stroke
			(width 0)
			(type solid)
		)
		(fill yes)
		(layer "In4.Cu")
		(net "M_J_CPU1_SA_DQ<30>")
	)
	(gr_poly
		(pts
			(xy 133.49478 -242.256056) (xy 133.394704 -242.156234) (xy 133.294628 -242.256056) (xy 133.294628 -242.303808)
			(xy 133.49478 -242.303808)
		)
		(stroke
			(width 0)
			(type solid)
		)
		(fill yes)
		(layer "In4.Cu")
		(net "M_J_CPU1_SA_DQS_DN<8>")
	)
	(gr_poly
		(pts
			(xy 133.49478 -241.852704) (xy 133.49478 -241.804952) (xy 133.294628 -241.804952) (xy 133.294628 -241.852704)
			(xy 133.394704 -241.952526)
		)
		(stroke
			(width 0)
			(type solid)
		)
		(fill yes)
		(layer "In4.Cu")
		(net "M_J_CPU1_SA_DQS_DN<3>")
	)
	(gr_poly
		(pts
			(xy 133.49478 -240.636298) (xy 133.394704 -240.536222) (xy 133.294628 -240.636298) (xy 133.294628 -240.680748)
			(xy 133.49478 -240.680748)
		)
		(stroke
			(width 0)
			(type solid)
		)
		(fill yes)
		(layer "In4.Cu")
		(net "M_J_CPU1_SA_DQ<25>")
	)
	(gr_poly
		(pts
			(xy 133.49478 -240.232438) (xy 133.49478 -240.187988) (xy 133.294628 -240.187988) (xy 133.294628 -240.232438)
			(xy 133.394704 -240.332514)
		)
		(stroke
			(width 0)
			(type solid)
		)
		(fill yes)
		(layer "In4.Cu")
		(net "M_J_CPU1_SA_DQ<26>")
	)
	(gr_poly
		(pts
			(xy 133.49478 -239.016286) (xy 133.394704 -238.91621) (xy 133.294628 -239.016286) (xy 133.294628 -239.060736)
			(xy 133.49478 -239.060736)
		)
		(stroke
			(width 0)
			(type solid)
		)
		(fill yes)
		(layer "In4.Cu")
		(net "M_J_CPU1_SA_DQ<21>")
	)
	(gr_poly
		(pts
			(xy 133.49478 -238.612426) (xy 133.49478 -238.567976) (xy 133.294628 -238.567976) (xy 133.294628 -238.612426)
			(xy 133.394704 -238.712502)
		)
		(stroke
			(width 0)
			(type solid)
		)
		(fill yes)
		(layer "In4.Cu")
		(net "M_J_CPU1_SA_DQ<22>")
	)
	(gr_poly
		(pts
			(xy 133.49478 -237.39602) (xy 133.394704 -237.296198) (xy 133.294628 -237.39602) (xy 133.294628 -237.443772)
			(xy 133.49478 -237.443772)
		)
		(stroke
			(width 0)
			(type solid)
		)
		(fill yes)
		(layer "In4.Cu")
		(net "M_J_CPU1_SA_DQS_DN<7>")
	)
	(gr_poly
		(pts
			(xy 133.49478 -236.992668) (xy 133.49478 -236.944916) (xy 133.294628 -236.944916) (xy 133.294628 -236.992668)
			(xy 133.394704 -237.09249)
		)
		(stroke
			(width 0)
			(type solid)
		)
		(fill yes)
		(layer "In4.Cu")
		(net "M_J_CPU1_SA_DQS_DN<2>")
	)
	(gr_poly
		(pts
			(xy 133.49478 -235.776262) (xy 133.394704 -235.676186) (xy 133.294628 -235.776262) (xy 133.294628 -235.820712)
			(xy 133.49478 -235.820712)
		)
		(stroke
			(width 0)
			(type solid)
		)
		(fill yes)
		(layer "In4.Cu")
		(net "M_J_CPU1_SA_DQ<17>")
	)
	(gr_poly
		(pts
			(xy 133.49478 -235.372402) (xy 133.49478 -235.327952) (xy 133.294628 -235.327952) (xy 133.294628 -235.372402)
			(xy 133.394704 -235.472478)
		)
		(stroke
			(width 0)
			(type solid)
		)
		(fill yes)
		(layer "In4.Cu")
		(net "M_J_CPU1_SA_DQ<18>")
	)
	(gr_poly
		(pts
			(xy 133.49478 -234.15625) (xy 133.394704 -234.056174) (xy 133.294628 -234.15625) (xy 133.294628 -234.2007)
			(xy 133.49478 -234.2007)
		)
		(stroke
			(width 0)
			(type solid)
		)
		(fill yes)
		(layer "In4.Cu")
		(net "M_J_CPU1_SA_DQ<13>")
	)
	(gr_poly
		(pts
			(xy 133.49478 -233.75239) (xy 133.49478 -233.70794) (xy 133.294628 -233.70794) (xy 133.294628 -233.75239)
			(xy 133.394704 -233.852466)
		)
		(stroke
			(width 0)
			(type solid)
		)
		(fill yes)
		(layer "In4.Cu")
		(net "M_J_CPU1_SA_DQ<14>")
	)
	(gr_poly
		(pts
			(xy 133.49478 -232.535984) (xy 133.394704 -232.436162) (xy 133.294628 -232.535984) (xy 133.294628 -232.583736)
			(xy 133.49478 -232.583736)
		)
		(stroke
			(width 0)
			(type solid)
		)
		(fill yes)
		(layer "In4.Cu")
		(net "M_J_CPU1_SA_DQS_DN<6>")
	)
	(gr_poly
		(pts
			(xy 133.49478 -232.132632) (xy 133.49478 -232.08488) (xy 133.294628 -232.08488) (xy 133.294628 -232.132632)
			(xy 133.394704 -232.232454)
		)
		(stroke
			(width 0)
			(type solid)
		)
		(fill yes)
		(layer "In4.Cu")
		(net "M_J_CPU1_SA_DQS_DN<1>")
	)
	(gr_poly
		(pts
			(xy 133.49478 -230.916226) (xy 133.394704 -230.81615) (xy 133.294628 -230.916226) (xy 133.294628 -230.960676)
			(xy 133.49478 -230.960676)
		)
		(stroke
			(width 0)
			(type solid)
		)
		(fill yes)
		(layer "In4.Cu")
		(net "M_J_CPU1_SA_DQ<9>")
	)
	(gr_poly
		(pts
			(xy 133.49478 -230.51262) (xy 133.49478 -230.46817) (xy 133.294628 -230.46817) (xy 133.294628 -230.51262)
			(xy 133.394704 -230.612696)
		)
		(stroke
			(width 0)
			(type solid)
		)
		(fill yes)
		(layer "In4.Cu")
		(net "M_J_CPU1_SA_DQ<10>")
	)
	(gr_poly
		(pts
			(xy 133.49478 -229.296214) (xy 133.394704 -229.196138) (xy 133.294628 -229.296214) (xy 133.294628 -229.340664)
			(xy 133.49478 -229.340664)
		)
		(stroke
			(width 0)
			(type solid)
		)
		(fill yes)
		(layer "In4.Cu")
		(net "M_J_CPU1_SA_DQ<5>")
	)
	(gr_poly
		(pts
			(xy 133.49478 -228.892608) (xy 133.49478 -228.848158) (xy 133.294628 -228.848158) (xy 133.294628 -228.892608)
			(xy 133.394704 -228.992684)
		)
		(stroke
			(width 0)
			(type solid)
		)
		(fill yes)
		(layer "In4.Cu")
		(net "M_J_CPU1_SA_DQ<6>")
	)
	(gr_poly
		(pts
			(xy 133.49478 -227.676202) (xy 133.394704 -227.57638) (xy 133.294628 -227.676202) (xy 133.294628 -227.723954)
			(xy 133.49478 -227.723954)
		)
		(stroke
			(width 0)
			(type solid)
		)
		(fill yes)
		(layer "In4.Cu")
		(net "M_J_CPU1_SA_DQS_DN<5>")
	)
	(gr_poly
		(pts
			(xy 133.49478 -227.27285) (xy 133.49478 -227.225098) (xy 133.294628 -227.225098) (xy 133.294628 -227.27285)
			(xy 133.394704 -227.372672)
		)
		(stroke
			(width 0)
			(type solid)
		)
		(fill yes)
		(layer "In4.Cu")
		(net "M_J_CPU1_SA_DQS_DN<0>")
	)
	(gr_poly
		(pts
			(xy 133.49478 -226.056444) (xy 133.394704 -225.956368) (xy 133.294628 -226.056444) (xy 133.294628 -226.100894)
			(xy 133.49478 -226.100894)
		)
		(stroke
			(width 0)
			(type solid)
		)
		(fill yes)
		(layer "In4.Cu")
		(net "M_J_CPU1_SA_DQ<1>")
	)
	(gr_poly
		(pts
			(xy 133.49478 -225.652584) (xy 133.49478 -225.608134) (xy 133.294628 -225.608134) (xy 133.294628 -225.652584)
			(xy 133.394704 -225.75266)
		)
		(stroke
			(width 0)
			(type solid)
		)
		(fill yes)
		(layer "In4.Cu")
		(net "M_J_CPU1_SA_DQ<2>")
	)
	(gr_poly
		(pts
			(xy 133.794754 -292.108128) (xy 133.694678 -292.008052) (xy 133.594602 -292.108128) (xy 133.594602 -292.152578)
			(xy 133.794754 -292.152578)
		)
		(stroke
			(width 0)
			(type solid)
		)
		(fill yes)
		(layer "In4.Cu")
		(net "M_J_CPU1_SB_DQ<28>")
	)
	(gr_poly
		(pts
			(xy 133.794754 -291.704522) (xy 133.794754 -291.65677) (xy 133.594602 -291.65677) (xy 133.594602 -291.704522)
			(xy 133.694678 -291.804344)
		)
		(stroke
			(width 0)
			(type solid)
		)
		(fill yes)
		(layer "In4.Cu")
		(net "M_J_CPU1_SB_DQS_DP<8>")
	)
	(gr_poly
		(pts
			(xy 133.794754 -290.487862) (xy 133.694678 -290.38804) (xy 133.594602 -290.487862) (xy 133.594602 -290.535614)
			(xy 133.794754 -290.535614)
		)
		(stroke
			(width 0)
			(type solid)
		)
		(fill yes)
		(layer "In4.Cu")
		(net "M_J_CPU1_SB_DQS_DP<3>")
	)
	(gr_poly
		(pts
			(xy 133.794754 -290.084256) (xy 133.794754 -290.039806) (xy 133.594602 -290.039806) (xy 133.594602 -290.084256)
			(xy 133.694678 -290.184332)
		)
		(stroke
			(width 0)
			(type solid)
		)
		(fill yes)
		(layer "In4.Cu")
		(net "M_J_CPU1_SB_DQ<27>")
	)
	(gr_poly
		(pts
			(xy 133.794754 -288.868104) (xy 133.694678 -288.768028) (xy 133.594602 -288.868104) (xy 133.594602 -288.912554)
			(xy 133.794754 -288.912554)
		)
		(stroke
			(width 0)
			(type solid)
		)
		(fill yes)
		(layer "In4.Cu")
		(net "M_J_CPU1_SB_DQ<24>")
	)
	(gr_poly
		(pts
			(xy 133.794754 -288.464498) (xy 133.794754 -288.420048) (xy 133.594602 -288.420048) (xy 133.594602 -288.464498)
			(xy 133.694678 -288.564574)
		)
		(stroke
			(width 0)
			(type solid)
		)
		(fill yes)
		(layer "In4.Cu")
		(net "M_J_CPU1_SB_DQ<23>")
	)
	(gr_poly
		(pts
			(xy 133.794754 -287.248092) (xy 133.694678 -287.148016) (xy 133.594602 -287.248092) (xy 133.594602 -287.292542)
			(xy 133.794754 -287.292542)
		)
		(stroke
			(width 0)
			(type solid)
		)
		(fill yes)
		(layer "In4.Cu")
		(net "M_J_CPU1_SB_DQ<20>")
	)
	(gr_poly
		(pts
			(xy 133.794754 -286.844486) (xy 133.794754 -286.796734) (xy 133.594602 -286.796734) (xy 133.594602 -286.844486)
			(xy 133.694678 -286.944562)
		)
		(stroke
			(width 0)
			(type solid)
		)
		(fill yes)
		(layer "In4.Cu")
		(net "M_J_CPU1_SB_DQS_DP<7>")
	)
	(gr_poly
		(pts
			(xy 133.794754 -285.62808) (xy 133.694678 -285.528258) (xy 133.594602 -285.62808) (xy 133.594602 -285.675832)
			(xy 133.794754 -285.675832)
		)
		(stroke
			(width 0)
			(type solid)
		)
		(fill yes)
		(layer "In4.Cu")
		(net "M_J_CPU1_SB_DQS_DP<2>")
	)
	(gr_poly
		(pts
			(xy 133.794754 -285.224474) (xy 133.794754 -285.180024) (xy 133.594602 -285.180024) (xy 133.594602 -285.224474)
			(xy 133.694678 -285.32455)
		)
		(stroke
			(width 0)
			(type solid)
		)
		(fill yes)
		(layer "In4.Cu")
		(net "M_J_CPU1_SB_DQ<19>")
	)
	(gr_poly
		(pts
			(xy 133.794754 -284.008322) (xy 133.694678 -283.908246) (xy 133.594602 -284.008322) (xy 133.594602 -284.052772)
			(xy 133.794754 -284.052772)
		)
		(stroke
			(width 0)
			(type solid)
		)
		(fill yes)
		(layer "In4.Cu")
		(net "M_J_CPU1_SB_DQ<16>")
	)
	(gr_poly
		(pts
			(xy 133.794754 -283.604462) (xy 133.794754 -283.560012) (xy 133.594602 -283.560012) (xy 133.594602 -283.604462)
			(xy 133.694678 -283.704538)
		)
		(stroke
			(width 0)
			(type solid)
		)
		(fill yes)
		(layer "In4.Cu")
		(net "M_J_CPU1_SB_DQ<15>")
	)
	(gr_poly
		(pts
			(xy 133.794754 -282.38831) (xy 133.694678 -282.288234) (xy 133.594602 -282.38831) (xy 133.594602 -282.43276)
			(xy 133.794754 -282.43276)
		)
		(stroke
			(width 0)
			(type solid)
		)
		(fill yes)
		(layer "In4.Cu")
		(net "M_J_CPU1_SB_DQ<12>")
	)
	(gr_poly
		(pts
			(xy 133.794754 -281.984704) (xy 133.794754 -281.936952) (xy 133.594602 -281.936952) (xy 133.594602 -281.984704)
			(xy 133.694678 -282.084526)
		)
		(stroke
			(width 0)
			(type solid)
		)
		(fill yes)
		(layer "In4.Cu")
		(net "M_J_CPU1_SB_DQS_DP<6>")
	)
	(gr_poly
		(pts
			(xy 133.794754 -280.768044) (xy 133.694678 -280.668222) (xy 133.594602 -280.768044) (xy 133.594602 -280.815796)
			(xy 133.794754 -280.815796)
		)
		(stroke
			(width 0)
			(type solid)
		)
		(fill yes)
		(layer "In4.Cu")
		(net "M_J_CPU1_SB_DQS_DP<1>")
	)
	(gr_poly
		(pts
			(xy 133.794754 -280.364438) (xy 133.794754 -280.319988) (xy 133.594602 -280.319988) (xy 133.594602 -280.364438)
			(xy 133.694678 -280.464514)
		)
		(stroke
			(width 0)
			(type solid)
		)
		(fill yes)
		(layer "In4.Cu")
		(net "M_J_CPU1_SB_DQ<11>")
	)
	(gr_poly
		(pts
			(xy 133.794754 -279.148286) (xy 133.694678 -279.04821) (xy 133.594602 -279.148286) (xy 133.594602 -279.192736)
			(xy 133.794754 -279.192736)
		)
		(stroke
			(width 0)
			(type solid)
		)
		(fill yes)
		(layer "In4.Cu")
		(net "M_J_CPU1_SB_DQ<8>")
	)
	(gr_poly
		(pts
			(xy 133.794754 -278.744426) (xy 133.794754 -278.699976) (xy 133.594602 -278.699976) (xy 133.594602 -278.744426)
			(xy 133.694678 -278.844502)
		)
		(stroke
			(width 0)
			(type solid)
		)
		(fill yes)
		(layer "In4.Cu")
		(net "M_J_CPU1_SB_DQ<7>")
	)
	(gr_poly
		(pts
			(xy 133.794754 -277.528274) (xy 133.694678 -277.428198) (xy 133.594602 -277.528274) (xy 133.594602 -277.572724)
			(xy 133.794754 -277.572724)
		)
		(stroke
			(width 0)
			(type solid)
		)
		(fill yes)
		(layer "In4.Cu")
		(net "M_J_CPU1_SB_DQ<4>")
	)
	(gr_poly
		(pts
			(xy 133.794754 -277.124668) (xy 133.794754 -277.076916) (xy 133.594602 -277.076916) (xy 133.594602 -277.124668)
			(xy 133.694678 -277.22449)
		)
		(stroke
			(width 0)
			(type solid)
		)
		(fill yes)
		(layer "In4.Cu")
		(net "M_J_CPU1_SB_DQS_DP<5>")
	)
	(gr_poly
		(pts
			(xy 133.794754 -275.908008) (xy 133.694678 -275.808186) (xy 133.594602 -275.908008) (xy 133.594602 -275.95576)
			(xy 133.794754 -275.95576)
		)
		(stroke
			(width 0)
			(type solid)
		)
		(fill yes)
		(layer "In4.Cu")
		(net "M_J_CPU1_SB_DQS_DP<0>")
	)
	(gr_poly
		(pts
			(xy 133.794754 -275.504402) (xy 133.794754 -275.459952) (xy 133.594602 -275.459952) (xy 133.594602 -275.504402)
			(xy 133.694678 -275.604478)
		)
		(stroke
			(width 0)
			(type solid)
		)
		(fill yes)
		(layer "In4.Cu")
		(net "M_J_CPU1_SB_DQ<3>")
	)
	(gr_poly
		(pts
			(xy 133.794754 -274.28825) (xy 133.694678 -274.188174) (xy 133.594602 -274.28825) (xy 133.594602 -274.3327)
			(xy 133.794754 -274.3327)
		)
		(stroke
			(width 0)
			(type solid)
		)
		(fill yes)
		(layer "In4.Cu")
		(net "M_J_CPU1_SB_DQ<0>")
	)
	(gr_poly
		(pts
			(xy 133.794754 -273.88439) (xy 133.794754 -273.83994) (xy 133.594602 -273.83994) (xy 133.594602 -273.88439)
			(xy 133.694678 -273.984466)
		)
		(stroke
			(width 0)
			(type solid)
		)
		(fill yes)
		(layer "In4.Cu")
		(net "M_J_CPU1_SB_CB<3>")
	)
	(gr_poly
		(pts
			(xy 133.794754 -272.668238) (xy 133.694678 -272.568162) (xy 133.594602 -272.668238) (xy 133.594602 -272.712688)
			(xy 133.794754 -272.712688)
		)
		(stroke
			(width 0)
			(type solid)
		)
		(fill yes)
		(layer "In4.Cu")
		(net "M_J_CPU1_SB_CB<0>")
	)
	(gr_poly
		(pts
			(xy 133.794754 -272.264632) (xy 133.794754 -272.21688) (xy 133.594602 -272.21688) (xy 133.594602 -272.264632)
			(xy 133.694678 -272.364454)
		)
		(stroke
			(width 0)
			(type solid)
		)
		(fill yes)
		(layer "In4.Cu")
		(net "M_J_CPU1_SB_DQS_DP<4>")
	)
	(gr_poly
		(pts
			(xy 133.794754 -271.047972) (xy 133.694678 -270.94815) (xy 133.594602 -271.047972) (xy 133.594602 -271.095724)
			(xy 133.794754 -271.095724)
		)
		(stroke
			(width 0)
			(type solid)
		)
		(fill yes)
		(layer "In4.Cu")
		(net "M_J_CPU1_SB_DQS_DP<9>")
	)
	(gr_poly
		(pts
			(xy 133.794754 -270.644366) (xy 133.794754 -270.599916) (xy 133.594602 -270.599916) (xy 133.594602 -270.644366)
			(xy 133.694678 -270.744442)
		)
		(stroke
			(width 0)
			(type solid)
		)
		(fill yes)
		(layer "In4.Cu")
		(net "M_J_CPU1_SB_CB<7>")
	)
	(gr_poly
		(pts
			(xy 133.794754 -269.428214) (xy 133.694678 -269.328138) (xy 133.594602 -269.428214) (xy 133.594602 -269.472664)
			(xy 133.794754 -269.472664)
		)
		(stroke
			(width 0)
			(type solid)
		)
		(fill yes)
		(layer "In4.Cu")
		(net "M_J_CPU1_SB_CB<4>")
	)
	(gr_poly
		(pts
			(xy 133.794754 -267.808202) (xy 133.694678 -267.708126) (xy 133.594602 -267.808202) (xy 133.594602 -267.852652)
			(xy 133.794754 -267.852652)
		)
		(stroke
			(width 0)
			(type solid)
		)
		(fill yes)
		(layer "In4.Cu")
		(net "M_J_CPU1_SB_RSP<0>")
	)
	(gr_poly
		(pts
			(xy 133.794754 -265.78433) (xy 133.794754 -265.73988) (xy 133.594602 -265.73988) (xy 133.594602 -265.78433)
			(xy 133.694678 -265.884406)
		)
		(stroke
			(width 0)
			(type solid)
		)
		(fill yes)
		(layer "In4.Cu")
		(net "M_J_CPU1_SB_CS_N<0>")
	)
	(gr_poly
		(pts
			(xy 133.794754 -264.568178) (xy 133.694678 -264.468102) (xy 133.594602 -264.568178) (xy 133.594602 -264.612628)
			(xy 133.794754 -264.612628)
		)
		(stroke
			(width 0)
			(type solid)
		)
		(fill yes)
		(layer "In4.Cu")
		(net "M_J_CPU1_SB_CA<6>")
	)
	(gr_poly
		(pts
			(xy 133.794754 -264.164318) (xy 133.794754 -264.119868) (xy 133.594602 -264.119868) (xy 133.594602 -264.164318)
			(xy 133.694678 -264.264394)
		)
		(stroke
			(width 0)
			(type solid)
		)
		(fill yes)
		(layer "In4.Cu")
		(net "M_J_CPU1_SB_CA<5>")
	)
	(gr_poly
		(pts
			(xy 133.794754 -262.948166) (xy 133.694678 -262.84809) (xy 133.594602 -262.948166) (xy 133.594602 -262.992616)
			(xy 133.794754 -262.992616)
		)
		(stroke
			(width 0)
			(type solid)
		)
		(fill yes)
		(layer "In4.Cu")
		(net "M_J_CPU1_SB_CA<2>")
	)
	(gr_poly
		(pts
			(xy 133.794754 -262.544306) (xy 133.794754 -262.499856) (xy 133.594602 -262.499856) (xy 133.594602 -262.544306)
			(xy 133.694678 -262.644382)
		)
		(stroke
			(width 0)
			(type solid)
		)
		(fill yes)
		(layer "In4.Cu")
		(net "M_J_CPU1_SB_CA<1>")
	)
	(gr_poly
		(pts
			(xy 133.964934 -256.026158) (xy 133.864858 -255.926336) (xy 133.764782 -256.026158) (xy 133.764782 -256.07391)
			(xy 133.964934 -256.07391)
		)
		(stroke
			(width 0)
			(type solid)
		)
		(fill yes)
		(layer "In4.Cu")
		(net "M_J_CPU1_CLK_DP<0>")
	)
	(gr_poly
		(pts
			(xy 133.964934 -255.622552) (xy 133.964934 -255.578102) (xy 133.764782 -255.578102) (xy 133.764782 -255.622552)
			(xy 133.864858 -255.722628)
		)
		(stroke
			(width 0)
			(type solid)
		)
		(fill yes)
		(layer "In4.Cu")
		(net "M_J_CPU1_SA_PAR")
	)
	(gr_poly
		(pts
			(xy 133.964934 -254.4064) (xy 133.864858 -254.306324) (xy 133.764782 -254.4064) (xy 133.764782 -254.45085)
			(xy 133.964934 -254.45085)
		)
		(stroke
			(width 0)
			(type solid)
		)
		(fill yes)
		(layer "In4.Cu")
		(net "M_J_CPU1_SA_CA<4>")
	)
	(gr_poly
		(pts
			(xy 133.964934 -254.00254) (xy 133.964934 -253.95809) (xy 133.764782 -253.95809) (xy 133.764782 -254.00254)
			(xy 133.864858 -254.102616)
		)
		(stroke
			(width 0)
			(type solid)
		)
		(fill yes)
		(layer "In4.Cu")
		(net "M_J_CPU1_SA_CA<3>")
	)
	(gr_poly
		(pts
			(xy 133.964934 -252.786388) (xy 133.864858 -252.686312) (xy 133.764782 -252.786388) (xy 133.764782 -252.830838)
			(xy 133.964934 -252.830838)
		)
		(stroke
			(width 0)
			(type solid)
		)
		(fill yes)
		(layer "In4.Cu")
		(net "M_J_CPU1_SA_CA<0>")
	)
	(gr_poly
		(pts
			(xy 133.964934 -251.166376) (xy 133.864858 -251.0663) (xy 133.764782 -251.166376) (xy 133.764782 -251.210826)
			(xy 133.964934 -251.210826)
		)
		(stroke
			(width 0)
			(type solid)
		)
		(fill yes)
		(layer "In4.Cu")
		(net "M_J_CPU1_SA_CS_N<0>")
	)
	(gr_poly
		(pts
			(xy 133.964934 -250.762516) (xy 133.964934 -250.718066) (xy 133.764782 -250.718066) (xy 133.764782 -250.762516)
			(xy 133.864858 -250.862592)
		)
		(stroke
			(width 0)
			(type solid)
		)
		(fill yes)
		(layer "In4.Cu")
		(net "M_J_CPU1_RESET_N")
	)
	(gr_poly
		(pts
			(xy 133.964934 -249.142504) (xy 133.964934 -249.098054) (xy 133.764782 -249.098054) (xy 133.764782 -249.142504)
			(xy 133.864858 -249.24258)
		)
		(stroke
			(width 0)
			(type solid)
		)
		(fill yes)
		(layer "In4.Cu")
		(net "M_J_CPU1_SA_CB<7>")
	)
	(gr_poly
		(pts
			(xy 133.964934 -247.926352) (xy 133.864858 -247.826276) (xy 133.764782 -247.926352) (xy 133.764782 -247.970802)
			(xy 133.964934 -247.970802)
		)
		(stroke
			(width 0)
			(type solid)
		)
		(fill yes)
		(layer "In4.Cu")
		(net "M_J_CPU1_SA_CB<4>")
	)
	(gr_poly
		(pts
			(xy 133.964934 -247.522746) (xy 133.964934 -247.474994) (xy 133.764782 -247.474994) (xy 133.764782 -247.522746)
			(xy 133.864858 -247.622568)
		)
		(stroke
			(width 0)
			(type solid)
		)
		(fill yes)
		(layer "In4.Cu")
		(net "M_J_CPU1_SA_DQS_DP<9>")
	)
	(gr_poly
		(pts
			(xy 133.964934 -246.306086) (xy 133.864858 -246.206264) (xy 133.764782 -246.306086) (xy 133.764782 -246.353838)
			(xy 133.964934 -246.353838)
		)
		(stroke
			(width 0)
			(type solid)
		)
		(fill yes)
		(layer "In4.Cu")
		(net "M_J_CPU1_SA_DQS_DP<4>")
	)
	(gr_poly
		(pts
			(xy 133.964934 -245.90248) (xy 133.964934 -245.85803) (xy 133.764782 -245.85803) (xy 133.764782 -245.90248)
			(xy 133.864858 -246.002556)
		)
		(stroke
			(width 0)
			(type solid)
		)
		(fill yes)
		(layer "In4.Cu")
		(net "M_J_CPU1_SA_CB<3>")
	)
	(gr_poly
		(pts
			(xy 133.964934 -244.686328) (xy 133.864858 -244.586252) (xy 133.764782 -244.686328) (xy 133.764782 -244.730778)
			(xy 133.964934 -244.730778)
		)
		(stroke
			(width 0)
			(type solid)
		)
		(fill yes)
		(layer "In4.Cu")
		(net "M_J_CPU1_SA_CB<0>")
	)
	(gr_poly
		(pts
			(xy 133.964934 -244.282468) (xy 133.964934 -244.238018) (xy 133.764782 -244.238018) (xy 133.764782 -244.282468)
			(xy 133.864858 -244.382544)
		)
		(stroke
			(width 0)
			(type solid)
		)
		(fill yes)
		(layer "In4.Cu")
		(net "M_J_CPU1_SA_DQ<31>")
	)
	(gr_poly
		(pts
			(xy 133.964934 -243.066316) (xy 133.864858 -242.96624) (xy 133.764782 -243.066316) (xy 133.764782 -243.110766)
			(xy 133.964934 -243.110766)
		)
		(stroke
			(width 0)
			(type solid)
		)
		(fill yes)
		(layer "In4.Cu")
		(net "M_J_CPU1_SA_DQ<28>")
	)
	(gr_poly
		(pts
			(xy 133.964934 -242.66271) (xy 133.964934 -242.614958) (xy 133.764782 -242.614958) (xy 133.764782 -242.66271)
			(xy 133.864858 -242.762532)
		)
		(stroke
			(width 0)
			(type solid)
		)
		(fill yes)
		(layer "In4.Cu")
		(net "M_J_CPU1_SA_DQS_DP<8>")
	)
	(gr_poly
		(pts
			(xy 133.964934 -241.44605) (xy 133.864858 -241.346228) (xy 133.764782 -241.44605) (xy 133.764782 -241.493802)
			(xy 133.964934 -241.493802)
		)
		(stroke
			(width 0)
			(type solid)
		)
		(fill yes)
		(layer "In4.Cu")
		(net "M_J_CPU1_SA_DQS_DP<3>")
	)
	(gr_poly
		(pts
			(xy 133.964934 -241.042444) (xy 133.964934 -240.997994) (xy 133.764782 -240.997994) (xy 133.764782 -241.042444)
			(xy 133.864858 -241.14252)
		)
		(stroke
			(width 0)
			(type solid)
		)
		(fill yes)
		(layer "In4.Cu")
		(net "M_J_CPU1_SA_DQ<27>")
	)
	(gr_poly
		(pts
			(xy 133.964934 -239.826292) (xy 133.864858 -239.726216) (xy 133.764782 -239.826292) (xy 133.764782 -239.870742)
			(xy 133.964934 -239.870742)
		)
		(stroke
			(width 0)
			(type solid)
		)
		(fill yes)
		(layer "In4.Cu")
		(net "M_J_CPU1_SA_DQ<24>")
	)
	(gr_poly
		(pts
			(xy 133.964934 -239.422432) (xy 133.964934 -239.377982) (xy 133.764782 -239.377982) (xy 133.764782 -239.422432)
			(xy 133.864858 -239.522508)
		)
		(stroke
			(width 0)
			(type solid)
		)
		(fill yes)
		(layer "In4.Cu")
		(net "M_J_CPU1_SA_DQ<23>")
	)
	(gr_poly
		(pts
			(xy 133.964934 -238.20628) (xy 133.864858 -238.106204) (xy 133.764782 -238.20628) (xy 133.764782 -238.25073)
			(xy 133.964934 -238.25073)
		)
		(stroke
			(width 0)
			(type solid)
		)
		(fill yes)
		(layer "In4.Cu")
		(net "M_J_CPU1_SA_DQ<20>")
	)
	(gr_poly
		(pts
			(xy 133.964934 -237.802674) (xy 133.964934 -237.754922) (xy 133.764782 -237.754922) (xy 133.764782 -237.802674)
			(xy 133.864858 -237.902496)
		)
		(stroke
			(width 0)
			(type solid)
		)
		(fill yes)
		(layer "In4.Cu")
		(net "M_J_CPU1_SA_DQS_DP<7>")
	)
	(gr_poly
		(pts
			(xy 133.964934 -236.586014) (xy 133.864858 -236.486192) (xy 133.764782 -236.586014) (xy 133.764782 -236.633766)
			(xy 133.964934 -236.633766)
		)
		(stroke
			(width 0)
			(type solid)
		)
		(fill yes)
		(layer "In4.Cu")
		(net "M_J_CPU1_SA_DQS_DP<2>")
	)
	(gr_poly
		(pts
			(xy 133.964934 -236.182408) (xy 133.964934 -236.137958) (xy 133.764782 -236.137958) (xy 133.764782 -236.182408)
			(xy 133.864858 -236.282484)
		)
		(stroke
			(width 0)
			(type solid)
		)
		(fill yes)
		(layer "In4.Cu")
		(net "M_J_CPU1_SA_DQ<19>")
	)
	(gr_poly
		(pts
			(xy 133.964934 -234.966256) (xy 133.864858 -234.86618) (xy 133.764782 -234.966256) (xy 133.764782 -235.010706)
			(xy 133.964934 -235.010706)
		)
		(stroke
			(width 0)
			(type solid)
		)
		(fill yes)
		(layer "In4.Cu")
		(net "M_J_CPU1_SA_DQ<16>")
	)
	(gr_poly
		(pts
			(xy 133.964934 -234.562396) (xy 133.964934 -234.517946) (xy 133.764782 -234.517946) (xy 133.764782 -234.562396)
			(xy 133.864858 -234.662472)
		)
		(stroke
			(width 0)
			(type solid)
		)
		(fill yes)
		(layer "In4.Cu")
		(net "M_J_CPU1_SA_DQ<15>")
	)
	(gr_poly
		(pts
			(xy 133.964934 -233.346244) (xy 133.864858 -233.246168) (xy 133.764782 -233.346244) (xy 133.764782 -233.390694)
			(xy 133.964934 -233.390694)
		)
		(stroke
			(width 0)
			(type solid)
		)
		(fill yes)
		(layer "In4.Cu")
		(net "M_J_CPU1_SA_DQ<12>")
	)
	(gr_poly
		(pts
			(xy 133.964934 -232.942638) (xy 133.964934 -232.894886) (xy 133.764782 -232.894886) (xy 133.764782 -232.942638)
			(xy 133.864858 -233.04246)
		)
		(stroke
			(width 0)
			(type solid)
		)
		(fill yes)
		(layer "In4.Cu")
		(net "M_J_CPU1_SA_DQS_DP<6>")
	)
	(gr_poly
		(pts
			(xy 133.964934 -231.725978) (xy 133.864858 -231.626156) (xy 133.764782 -231.725978) (xy 133.764782 -231.77373)
			(xy 133.964934 -231.77373)
		)
		(stroke
			(width 0)
			(type solid)
		)
		(fill yes)
		(layer "In4.Cu")
		(net "M_J_CPU1_SA_DQS_DP<1>")
	)
	(gr_poly
		(pts
			(xy 133.964934 -231.322626) (xy 133.964934 -231.278176) (xy 133.764782 -231.278176) (xy 133.764782 -231.322626)
			(xy 133.864858 -231.422702)
		)
		(stroke
			(width 0)
			(type solid)
		)
		(fill yes)
		(layer "In4.Cu")
		(net "M_J_CPU1_SA_DQ<11>")
	)
	(gr_poly
		(pts
			(xy 133.964934 -230.10622) (xy 133.864858 -230.006144) (xy 133.764782 -230.10622) (xy 133.764782 -230.15067)
			(xy 133.964934 -230.15067)
		)
		(stroke
			(width 0)
			(type solid)
		)
		(fill yes)
		(layer "In4.Cu")
		(net "M_J_CPU1_SA_DQ<8>")
	)
	(gr_poly
		(pts
			(xy 133.964934 -229.702614) (xy 133.964934 -229.658164) (xy 133.764782 -229.658164) (xy 133.764782 -229.702614)
			(xy 133.864858 -229.80269)
		)
		(stroke
			(width 0)
			(type solid)
		)
		(fill yes)
		(layer "In4.Cu")
		(net "M_J_CPU1_SA_DQ<7>")
	)
	(gr_poly
		(pts
			(xy 133.964934 -228.486462) (xy 133.864858 -228.386386) (xy 133.764782 -228.486462) (xy 133.764782 -228.530912)
			(xy 133.964934 -228.530912)
		)
		(stroke
			(width 0)
			(type solid)
		)
		(fill yes)
		(layer "In4.Cu")
		(net "M_J_CPU1_SA_DQ<4>")
	)
	(gr_poly
		(pts
			(xy 133.964934 -228.082856) (xy 133.964934 -228.035104) (xy 133.764782 -228.035104) (xy 133.764782 -228.082856)
			(xy 133.864858 -228.182678)
		)
		(stroke
			(width 0)
			(type solid)
		)
		(fill yes)
		(layer "In4.Cu")
		(net "M_J_CPU1_SA_DQS_DP<5>")
	)
	(gr_poly
		(pts
			(xy 133.964934 -226.866196) (xy 133.864858 -226.766374) (xy 133.764782 -226.866196) (xy 133.764782 -226.913948)
			(xy 133.964934 -226.913948)
		)
		(stroke
			(width 0)
			(type solid)
		)
		(fill yes)
		(layer "In4.Cu")
		(net "M_J_CPU1_SA_DQS_DP<0>")
	)
	(gr_poly
		(pts
			(xy 133.964934 -226.46259) (xy 133.964934 -226.41814) (xy 133.764782 -226.41814) (xy 133.764782 -226.46259)
			(xy 133.864858 -226.562666)
		)
		(stroke
			(width 0)
			(type solid)
		)
		(fill yes)
		(layer "In4.Cu")
		(net "M_J_CPU1_SA_DQ<3>")
	)
	(gr_poly
		(pts
			(xy 133.964934 -225.246438) (xy 133.864858 -225.146362) (xy 133.764782 -225.246438) (xy 133.764782 -225.290888)
			(xy 133.964934 -225.290888)
		)
		(stroke
			(width 0)
			(type solid)
		)
		(fill yes)
		(layer "In4.Cu")
		(net "M_J_CPU1_SA_DQ<0>")
	)
	(gr_poly
		(pts
			(xy 134.264908 -292.918134) (xy 134.164832 -292.818058) (xy 134.064756 -292.918134) (xy 134.064756 -292.962584)
			(xy 134.264908 -292.962584)
		)
		(stroke
			(width 0)
			(type solid)
		)
		(fill yes)
		(layer "In4.Cu")
		(net "M_J_CPU1_SB_DQ<29>")
	)
	(gr_poly
		(pts
			(xy 134.264908 -292.514274) (xy 134.264908 -292.469824) (xy 134.064756 -292.469824) (xy 134.064756 -292.514274)
			(xy 134.164832 -292.61435)
		)
		(stroke
			(width 0)
			(type solid)
		)
		(fill yes)
		(layer "In4.Cu")
		(net "M_J_CPU1_SB_DQ<30>")
	)
	(gr_poly
		(pts
			(xy 134.264908 -291.297868) (xy 134.164832 -291.198046) (xy 134.064756 -291.297868) (xy 134.064756 -291.34562)
			(xy 134.264908 -291.34562)
		)
		(stroke
			(width 0)
			(type solid)
		)
		(fill yes)
		(layer "In4.Cu")
		(net "M_J_CPU1_SB_DQS_DN<8>")
	)
	(gr_poly
		(pts
			(xy 134.264908 -290.894516) (xy 134.264908 -290.846764) (xy 134.064756 -290.846764) (xy 134.064756 -290.894516)
			(xy 134.164832 -290.994338)
		)
		(stroke
			(width 0)
			(type solid)
		)
		(fill yes)
		(layer "In4.Cu")
		(net "M_J_CPU1_SB_DQS_DN<3>")
	)
	(gr_poly
		(pts
			(xy 134.264908 -289.67811) (xy 134.164832 -289.578034) (xy 134.064756 -289.67811) (xy 134.064756 -289.72256)
			(xy 134.264908 -289.72256)
		)
		(stroke
			(width 0)
			(type solid)
		)
		(fill yes)
		(layer "In4.Cu")
		(net "M_J_CPU1_SB_DQ<25>")
	)
	(gr_poly
		(pts
			(xy 134.264908 -289.27425) (xy 134.264908 -289.2298) (xy 134.064756 -289.2298) (xy 134.064756 -289.27425)
			(xy 134.164832 -289.374326)
		)
		(stroke
			(width 0)
			(type solid)
		)
		(fill yes)
		(layer "In4.Cu")
		(net "M_J_CPU1_SB_DQ<26>")
	)
	(gr_poly
		(pts
			(xy 134.264908 -288.058098) (xy 134.164832 -287.958022) (xy 134.064756 -288.058098) (xy 134.064756 -288.102548)
			(xy 134.264908 -288.102548)
		)
		(stroke
			(width 0)
			(type solid)
		)
		(fill yes)
		(layer "In4.Cu")
		(net "M_J_CPU1_SB_DQ<21>")
	)
	(gr_poly
		(pts
			(xy 134.264908 -287.654492) (xy 134.264908 -287.610042) (xy 134.064756 -287.610042) (xy 134.064756 -287.654492)
			(xy 134.164832 -287.754568)
		)
		(stroke
			(width 0)
			(type solid)
		)
		(fill yes)
		(layer "In4.Cu")
		(net "M_J_CPU1_SB_DQ<22>")
	)
	(gr_poly
		(pts
			(xy 134.264908 -286.438086) (xy 134.164832 -286.33801) (xy 134.064756 -286.438086) (xy 134.064756 -286.485838)
			(xy 134.264908 -286.485838)
		)
		(stroke
			(width 0)
			(type solid)
		)
		(fill yes)
		(layer "In4.Cu")
		(net "M_J_CPU1_SB_DQS_DN<7>")
	)
	(gr_poly
		(pts
			(xy 134.264908 -286.034734) (xy 134.264908 -285.986982) (xy 134.064756 -285.986982) (xy 134.064756 -286.034734)
			(xy 134.164832 -286.134556)
		)
		(stroke
			(width 0)
			(type solid)
		)
		(fill yes)
		(layer "In4.Cu")
		(net "M_J_CPU1_SB_DQS_DN<2>")
	)
	(gr_poly
		(pts
			(xy 134.264908 -284.818328) (xy 134.164832 -284.718252) (xy 134.064756 -284.818328) (xy 134.064756 -284.862778)
			(xy 134.264908 -284.862778)
		)
		(stroke
			(width 0)
			(type solid)
		)
		(fill yes)
		(layer "In4.Cu")
		(net "M_J_CPU1_SB_DQ<17>")
	)
	(gr_poly
		(pts
			(xy 134.264908 -284.414468) (xy 134.264908 -284.370018) (xy 134.064756 -284.370018) (xy 134.064756 -284.414468)
			(xy 134.164832 -284.514544)
		)
		(stroke
			(width 0)
			(type solid)
		)
		(fill yes)
		(layer "In4.Cu")
		(net "M_J_CPU1_SB_DQ<18>")
	)
	(gr_poly
		(pts
			(xy 134.264908 -283.198316) (xy 134.164832 -283.09824) (xy 134.064756 -283.198316) (xy 134.064756 -283.242766)
			(xy 134.264908 -283.242766)
		)
		(stroke
			(width 0)
			(type solid)
		)
		(fill yes)
		(layer "In4.Cu")
		(net "M_J_CPU1_SB_DQ<13>")
	)
	(gr_poly
		(pts
			(xy 134.264908 -282.794456) (xy 134.264908 -282.750006) (xy 134.064756 -282.750006) (xy 134.064756 -282.794456)
			(xy 134.164832 -282.894532)
		)
		(stroke
			(width 0)
			(type solid)
		)
		(fill yes)
		(layer "In4.Cu")
		(net "M_J_CPU1_SB_DQ<14>")
	)
	(gr_poly
		(pts
			(xy 134.264908 -281.57805) (xy 134.164832 -281.478228) (xy 134.064756 -281.57805) (xy 134.064756 -281.625802)
			(xy 134.264908 -281.625802)
		)
		(stroke
			(width 0)
			(type solid)
		)
		(fill yes)
		(layer "In4.Cu")
		(net "M_J_CPU1_SB_DQS_DN<6>")
	)
	(gr_poly
		(pts
			(xy 134.264908 -281.174698) (xy 134.264908 -281.126946) (xy 134.064756 -281.126946) (xy 134.064756 -281.174698)
			(xy 134.164832 -281.27452)
		)
		(stroke
			(width 0)
			(type solid)
		)
		(fill yes)
		(layer "In4.Cu")
		(net "M_J_CPU1_SB_DQS_DN<1>")
	)
	(gr_poly
		(pts
			(xy 134.264908 -279.958292) (xy 134.164832 -279.858216) (xy 134.064756 -279.958292) (xy 134.064756 -280.002742)
			(xy 134.264908 -280.002742)
		)
		(stroke
			(width 0)
			(type solid)
		)
		(fill yes)
		(layer "In4.Cu")
		(net "M_J_CPU1_SB_DQ<9>")
	)
	(gr_poly
		(pts
			(xy 134.264908 -279.554432) (xy 134.264908 -279.509982) (xy 134.064756 -279.509982) (xy 134.064756 -279.554432)
			(xy 134.164832 -279.654508)
		)
		(stroke
			(width 0)
			(type solid)
		)
		(fill yes)
		(layer "In4.Cu")
		(net "M_J_CPU1_SB_DQ<10>")
	)
	(gr_poly
		(pts
			(xy 134.264908 -278.33828) (xy 134.164832 -278.238204) (xy 134.064756 -278.33828) (xy 134.064756 -278.38273)
			(xy 134.264908 -278.38273)
		)
		(stroke
			(width 0)
			(type solid)
		)
		(fill yes)
		(layer "In4.Cu")
		(net "M_J_CPU1_SB_DQ<5>")
	)
	(gr_poly
		(pts
			(xy 134.264908 -277.93442) (xy 134.264908 -277.88997) (xy 134.064756 -277.88997) (xy 134.064756 -277.93442)
			(xy 134.164832 -278.034496)
		)
		(stroke
			(width 0)
			(type solid)
		)
		(fill yes)
		(layer "In4.Cu")
		(net "M_J_CPU1_SB_DQ<6>")
	)
	(gr_poly
		(pts
			(xy 134.264908 -276.718014) (xy 134.164832 -276.618192) (xy 134.064756 -276.718014) (xy 134.064756 -276.765766)
			(xy 134.264908 -276.765766)
		)
		(stroke
			(width 0)
			(type solid)
		)
		(fill yes)
		(layer "In4.Cu")
		(net "M_J_CPU1_SB_DQS_DN<5>")
	)
	(gr_poly
		(pts
			(xy 134.264908 -276.314662) (xy 134.264908 -276.26691) (xy 134.064756 -276.26691) (xy 134.064756 -276.314662)
			(xy 134.164832 -276.414484)
		)
		(stroke
			(width 0)
			(type solid)
		)
		(fill yes)
		(layer "In4.Cu")
		(net "M_J_CPU1_SB_DQS_DN<0>")
	)
	(gr_poly
		(pts
			(xy 134.264908 -275.098256) (xy 134.164832 -274.99818) (xy 134.064756 -275.098256) (xy 134.064756 -275.142706)
			(xy 134.264908 -275.142706)
		)
		(stroke
			(width 0)
			(type solid)
		)
		(fill yes)
		(layer "In4.Cu")
		(net "M_J_CPU1_SB_DQ<1>")
	)
	(gr_poly
		(pts
			(xy 134.264908 -274.694396) (xy 134.264908 -274.649946) (xy 134.064756 -274.649946) (xy 134.064756 -274.694396)
			(xy 134.164832 -274.794472)
		)
		(stroke
			(width 0)
			(type solid)
		)
		(fill yes)
		(layer "In4.Cu")
		(net "M_J_CPU1_SB_DQ<2>")
	)
	(gr_poly
		(pts
			(xy 134.264908 -273.478244) (xy 134.164832 -273.378168) (xy 134.064756 -273.478244) (xy 134.064756 -273.522694)
			(xy 134.264908 -273.522694)
		)
		(stroke
			(width 0)
			(type solid)
		)
		(fill yes)
		(layer "In4.Cu")
		(net "M_J_CPU1_SB_CB<1>")
	)
	(gr_poly
		(pts
			(xy 134.264908 -273.074384) (xy 134.264908 -273.029934) (xy 134.064756 -273.029934) (xy 134.064756 -273.074384)
			(xy 134.164832 -273.17446)
		)
		(stroke
			(width 0)
			(type solid)
		)
		(fill yes)
		(layer "In4.Cu")
		(net "M_J_CPU1_SB_CB<2>")
	)
	(gr_poly
		(pts
			(xy 134.264908 -271.857978) (xy 134.164832 -271.758156) (xy 134.064756 -271.857978) (xy 134.064756 -271.90573)
			(xy 134.264908 -271.90573)
		)
		(stroke
			(width 0)
			(type solid)
		)
		(fill yes)
		(layer "In4.Cu")
		(net "M_J_CPU1_SB_DQS_DN<4>")
	)
	(gr_poly
		(pts
			(xy 134.264908 -271.454626) (xy 134.264908 -271.406874) (xy 134.064756 -271.406874) (xy 134.064756 -271.454626)
			(xy 134.164832 -271.554448)
		)
		(stroke
			(width 0)
			(type solid)
		)
		(fill yes)
		(layer "In4.Cu")
		(net "M_J_CPU1_SB_DQS_DN<9>")
	)
	(gr_poly
		(pts
			(xy 134.264908 -270.23822) (xy 134.164832 -270.138144) (xy 134.064756 -270.23822) (xy 134.064756 -270.28267)
			(xy 134.264908 -270.28267)
		)
		(stroke
			(width 0)
			(type solid)
		)
		(fill yes)
		(layer "In4.Cu")
		(net "M_J_CPU1_SB_CB<5>")
	)
	(gr_poly
		(pts
			(xy 134.264908 -269.83436) (xy 134.264908 -269.78991) (xy 134.064756 -269.78991) (xy 134.064756 -269.83436)
			(xy 134.164832 -269.934436)
		)
		(stroke
			(width 0)
			(type solid)
		)
		(fill yes)
		(layer "In4.Cu")
		(net "M_J_CPU1_SB_CB<6>")
	)
	(gr_poly
		(pts
			(xy 134.264908 -266.998196) (xy 134.164832 -266.89812) (xy 134.064756 -266.998196) (xy 134.064756 -267.042646)
			(xy 134.264908 -267.042646)
		)
		(stroke
			(width 0)
			(type solid)
		)
		(fill yes)
		(layer "In4.Cu")
		(net "M_J_CPU1_SA_RSP<0>")
	)
	(gr_poly
		(pts
			(xy 134.264908 -266.594336) (xy 134.264908 -266.549886) (xy 134.064756 -266.549886) (xy 134.064756 -266.594336)
			(xy 134.164832 -266.694412)
		)
		(stroke
			(width 0)
			(type solid)
		)
		(fill yes)
		(layer "In4.Cu")
		(net "M_J_CPU1_SB_CS_N<1>")
	)
	(gr_poly
		(pts
			(xy 134.264908 -265.378184) (xy 134.164832 -265.278108) (xy 134.064756 -265.378184) (xy 134.064756 -265.422634)
			(xy 134.264908 -265.422634)
		)
		(stroke
			(width 0)
			(type solid)
		)
		(fill yes)
		(layer "In4.Cu")
		(net "M_J_CPU1_SB_PAR")
	)
	(gr_poly
		(pts
			(xy 134.264908 -263.758172) (xy 134.164832 -263.658096) (xy 134.064756 -263.758172) (xy 134.064756 -263.802622)
			(xy 134.264908 -263.802622)
		)
		(stroke
			(width 0)
			(type solid)
		)
		(fill yes)
		(layer "In4.Cu")
		(net "M_J_CPU1_SB_CA<4>")
	)
	(gr_poly
		(pts
			(xy 134.264908 -263.354312) (xy 134.264908 -263.309862) (xy 134.064756 -263.309862) (xy 134.064756 -263.354312)
			(xy 134.164832 -263.454388)
		)
		(stroke
			(width 0)
			(type solid)
		)
		(fill yes)
		(layer "In4.Cu")
		(net "M_J_CPU1_SB_CA<3>")
	)
	(gr_poly
		(pts
			(xy 134.264908 -262.13816) (xy 134.164832 -262.038084) (xy 134.064756 -262.13816) (xy 134.064756 -262.18261)
			(xy 134.264908 -262.18261)
		)
		(stroke
			(width 0)
			(type solid)
		)
		(fill yes)
		(layer "In4.Cu")
		(net "M_J_CPU1_SB_CA<0>")
	)
	(gr_poly
		(pts
			(xy 134.434834 -256.432812) (xy 134.434834 -256.38506) (xy 134.234682 -256.38506) (xy 134.234682 -256.432812)
			(xy 134.334758 -256.532634)
		)
		(stroke
			(width 0)
			(type solid)
		)
		(fill yes)
		(layer "In4.Cu")
		(net "M_J_CPU1_CLK_DN<0>")
	)
	(gr_poly
		(pts
			(xy 134.434834 -255.216406) (xy 134.334758 -255.11633) (xy 134.234682 -255.216406) (xy 134.234682 -255.260856)
			(xy 134.434834 -255.260856)
		)
		(stroke
			(width 0)
			(type solid)
		)
		(fill yes)
		(layer "In4.Cu")
		(net "M_J_CPU1_SA_CA<6>")
	)
	(gr_poly
		(pts
			(xy 134.434834 -254.812546) (xy 134.434834 -254.768096) (xy 134.234682 -254.768096) (xy 134.234682 -254.812546)
			(xy 134.334758 -254.912622)
		)
		(stroke
			(width 0)
			(type solid)
		)
		(fill yes)
		(layer "In4.Cu")
		(net "M_J_CPU1_SA_CA<5>")
	)
	(gr_poly
		(pts
			(xy 134.434834 -253.596394) (xy 134.334758 -253.496318) (xy 134.234682 -253.596394) (xy 134.234682 -253.640844)
			(xy 134.434834 -253.640844)
		)
		(stroke
			(width 0)
			(type solid)
		)
		(fill yes)
		(layer "In4.Cu")
		(net "M_J_CPU1_SA_CA<2>")
	)
	(gr_poly
		(pts
			(xy 134.434834 -253.192534) (xy 134.434834 -253.148084) (xy 134.234682 -253.148084) (xy 134.234682 -253.192534)
			(xy 134.334758 -253.29261)
		)
		(stroke
			(width 0)
			(type solid)
		)
		(fill yes)
		(layer "In4.Cu")
		(net "M_J_CPU1_SA_CA<1>")
	)
	(gr_poly
		(pts
			(xy 134.434834 -251.976382) (xy 134.334758 -251.876306) (xy 134.234682 -251.976382) (xy 134.234682 -252.020832)
			(xy 134.434834 -252.020832)
		)
		(stroke
			(width 0)
			(type solid)
		)
		(fill yes)
		(layer "In4.Cu")
		(net "M_J_CPU1_SA_CS_N<1>")
	)
	(gr_poly
		(pts
			(xy 134.434834 -250.35637) (xy 134.334758 -250.256294) (xy 134.234682 -250.35637) (xy 134.234682 -250.40082)
			(xy 134.434834 -250.40082)
		)
		(stroke
			(width 0)
			(type solid)
		)
		(fill yes)
		(layer "In4.Cu")
		(net "M_J_CPU1_ALERT_R_N")
	)
	(gr_poly
		(pts
			(xy 134.434834 -248.736358) (xy 134.334758 -248.636282) (xy 134.234682 -248.736358) (xy 134.234682 -248.780808)
			(xy 134.434834 -248.780808)
		)
		(stroke
			(width 0)
			(type solid)
		)
		(fill yes)
		(layer "In4.Cu")
		(net "M_J_CPU1_SA_CB<5>")
	)
	(gr_poly
		(pts
			(xy 134.434834 -248.332498) (xy 134.434834 -248.288048) (xy 134.234682 -248.288048) (xy 134.234682 -248.332498)
			(xy 134.334758 -248.432574)
		)
		(stroke
			(width 0)
			(type solid)
		)
		(fill yes)
		(layer "In4.Cu")
		(net "M_J_CPU1_SA_CB<6>")
	)
	(gr_poly
		(pts
			(xy 134.434834 -247.116092) (xy 134.334758 -247.01627) (xy 134.234682 -247.116092) (xy 134.234682 -247.163844)
			(xy 134.434834 -247.163844)
		)
		(stroke
			(width 0)
			(type solid)
		)
		(fill yes)
		(layer "In4.Cu")
		(net "M_J_CPU1_SA_DQS_DN<9>")
	)
	(gr_poly
		(pts
			(xy 134.434834 -246.71274) (xy 134.434834 -246.664988) (xy 134.234682 -246.664988) (xy 134.234682 -246.71274)
			(xy 134.334758 -246.812562)
		)
		(stroke
			(width 0)
			(type solid)
		)
		(fill yes)
		(layer "In4.Cu")
		(net "M_J_CPU1_SA_DQS_DN<4>")
	)
	(gr_poly
		(pts
			(xy 134.434834 -245.496334) (xy 134.334758 -245.396258) (xy 134.234682 -245.496334) (xy 134.234682 -245.540784)
			(xy 134.434834 -245.540784)
		)
		(stroke
			(width 0)
			(type solid)
		)
		(fill yes)
		(layer "In4.Cu")
		(net "M_J_CPU1_SA_CB<1>")
	)
	(gr_poly
		(pts
			(xy 134.434834 -245.092474) (xy 134.434834 -245.048024) (xy 134.234682 -245.048024) (xy 134.234682 -245.092474)
			(xy 134.334758 -245.19255)
		)
		(stroke
			(width 0)
			(type solid)
		)
		(fill yes)
		(layer "In4.Cu")
		(net "M_J_CPU1_SA_CB<2>")
	)
	(gr_poly
		(pts
			(xy 134.434834 -243.876322) (xy 134.334758 -243.776246) (xy 134.234682 -243.876322) (xy 134.234682 -243.920772)
			(xy 134.434834 -243.920772)
		)
		(stroke
			(width 0)
			(type solid)
		)
		(fill yes)
		(layer "In4.Cu")
		(net "M_J_CPU1_SA_DQ<29>")
	)
	(gr_poly
		(pts
			(xy 134.434834 -243.472462) (xy 134.434834 -243.428012) (xy 134.234682 -243.428012) (xy 134.234682 -243.472462)
			(xy 134.334758 -243.572538)
		)
		(stroke
			(width 0)
			(type solid)
		)
		(fill yes)
		(layer "In4.Cu")
		(net "M_J_CPU1_SA_DQ<30>")
	)
	(gr_poly
		(pts
			(xy 134.434834 -242.256056) (xy 134.334758 -242.156234) (xy 134.234682 -242.256056) (xy 134.234682 -242.303808)
			(xy 134.434834 -242.303808)
		)
		(stroke
			(width 0)
			(type solid)
		)
		(fill yes)
		(layer "In4.Cu")
		(net "M_J_CPU1_SA_DQS_DN<8>")
	)
	(gr_poly
		(pts
			(xy 134.434834 -241.852704) (xy 134.434834 -241.804952) (xy 134.234682 -241.804952) (xy 134.234682 -241.852704)
			(xy 134.334758 -241.952526)
		)
		(stroke
			(width 0)
			(type solid)
		)
		(fill yes)
		(layer "In4.Cu")
		(net "M_J_CPU1_SA_DQS_DN<3>")
	)
	(gr_poly
		(pts
			(xy 134.434834 -240.636298) (xy 134.334758 -240.536222) (xy 134.234682 -240.636298) (xy 134.234682 -240.680748)
			(xy 134.434834 -240.680748)
		)
		(stroke
			(width 0)
			(type solid)
		)
		(fill yes)
		(layer "In4.Cu")
		(net "M_J_CPU1_SA_DQ<25>")
	)
	(gr_poly
		(pts
			(xy 134.434834 -240.232438) (xy 134.434834 -240.187988) (xy 134.234682 -240.187988) (xy 134.234682 -240.232438)
			(xy 134.334758 -240.332514)
		)
		(stroke
			(width 0)
			(type solid)
		)
		(fill yes)
		(layer "In4.Cu")
		(net "M_J_CPU1_SA_DQ<26>")
	)
	(gr_poly
		(pts
			(xy 134.434834 -239.016286) (xy 134.334758 -238.91621) (xy 134.234682 -239.016286) (xy 134.234682 -239.060736)
			(xy 134.434834 -239.060736)
		)
		(stroke
			(width 0)
			(type solid)
		)
		(fill yes)
		(layer "In4.Cu")
		(net "M_J_CPU1_SA_DQ<21>")
	)
	(gr_poly
		(pts
			(xy 134.434834 -238.612426) (xy 134.434834 -238.567976) (xy 134.234682 -238.567976) (xy 134.234682 -238.612426)
			(xy 134.334758 -238.712502)
		)
		(stroke
			(width 0)
			(type solid)
		)
		(fill yes)
		(layer "In4.Cu")
		(net "M_J_CPU1_SA_DQ<22>")
	)
	(gr_poly
		(pts
			(xy 134.434834 -237.39602) (xy 134.334758 -237.296198) (xy 134.234682 -237.39602) (xy 134.234682 -237.443772)
			(xy 134.434834 -237.443772)
		)
		(stroke
			(width 0)
			(type solid)
		)
		(fill yes)
		(layer "In4.Cu")
		(net "M_J_CPU1_SA_DQS_DN<7>")
	)
	(gr_poly
		(pts
			(xy 134.434834 -236.992668) (xy 134.434834 -236.944916) (xy 134.234682 -236.944916) (xy 134.234682 -236.992668)
			(xy 134.334758 -237.09249)
		)
		(stroke
			(width 0)
			(type solid)
		)
		(fill yes)
		(layer "In4.Cu")
		(net "M_J_CPU1_SA_DQS_DN<2>")
	)
	(gr_poly
		(pts
			(xy 134.434834 -235.776262) (xy 134.334758 -235.676186) (xy 134.234682 -235.776262) (xy 134.234682 -235.820712)
			(xy 134.434834 -235.820712)
		)
		(stroke
			(width 0)
			(type solid)
		)
		(fill yes)
		(layer "In4.Cu")
		(net "M_J_CPU1_SA_DQ<17>")
	)
	(gr_poly
		(pts
			(xy 134.434834 -235.372402) (xy 134.434834 -235.327952) (xy 134.234682 -235.327952) (xy 134.234682 -235.372402)
			(xy 134.334758 -235.472478)
		)
		(stroke
			(width 0)
			(type solid)
		)
		(fill yes)
		(layer "In4.Cu")
		(net "M_J_CPU1_SA_DQ<18>")
	)
	(gr_poly
		(pts
			(xy 134.434834 -234.15625) (xy 134.334758 -234.056174) (xy 134.234682 -234.15625) (xy 134.234682 -234.2007)
			(xy 134.434834 -234.2007)
		)
		(stroke
			(width 0)
			(type solid)
		)
		(fill yes)
		(layer "In4.Cu")
		(net "M_J_CPU1_SA_DQ<13>")
	)
	(gr_poly
		(pts
			(xy 134.434834 -233.75239) (xy 134.434834 -233.70794) (xy 134.234682 -233.70794) (xy 134.234682 -233.75239)
			(xy 134.334758 -233.852466)
		)
		(stroke
			(width 0)
			(type solid)
		)
		(fill yes)
		(layer "In4.Cu")
		(net "M_J_CPU1_SA_DQ<14>")
	)
	(gr_poly
		(pts
			(xy 134.434834 -232.535984) (xy 134.334758 -232.436162) (xy 134.234682 -232.535984) (xy 134.234682 -232.583736)
			(xy 134.434834 -232.583736)
		)
		(stroke
			(width 0)
			(type solid)
		)
		(fill yes)
		(layer "In4.Cu")
		(net "M_J_CPU1_SA_DQS_DN<6>")
	)
	(gr_poly
		(pts
			(xy 134.434834 -232.132632) (xy 134.434834 -232.08488) (xy 134.234682 -232.08488) (xy 134.234682 -232.132632)
			(xy 134.334758 -232.232454)
		)
		(stroke
			(width 0)
			(type solid)
		)
		(fill yes)
		(layer "In4.Cu")
		(net "M_J_CPU1_SA_DQS_DN<1>")
	)
	(gr_poly
		(pts
			(xy 134.434834 -230.916226) (xy 134.334758 -230.81615) (xy 134.234682 -230.916226) (xy 134.234682 -230.960676)
			(xy 134.434834 -230.960676)
		)
		(stroke
			(width 0)
			(type solid)
		)
		(fill yes)
		(layer "In4.Cu")
		(net "M_J_CPU1_SA_DQ<9>")
	)
	(gr_poly
		(pts
			(xy 134.434834 -230.51262) (xy 134.434834 -230.46817) (xy 134.234682 -230.46817) (xy 134.234682 -230.51262)
			(xy 134.334758 -230.612696)
		)
		(stroke
			(width 0)
			(type solid)
		)
		(fill yes)
		(layer "In4.Cu")
		(net "M_J_CPU1_SA_DQ<10>")
	)
	(gr_poly
		(pts
			(xy 134.434834 -229.296214) (xy 134.334758 -229.196138) (xy 134.234682 -229.296214) (xy 134.234682 -229.340664)
			(xy 134.434834 -229.340664)
		)
		(stroke
			(width 0)
			(type solid)
		)
		(fill yes)
		(layer "In4.Cu")
		(net "M_J_CPU1_SA_DQ<5>")
	)
	(gr_poly
		(pts
			(xy 134.434834 -228.892608) (xy 134.434834 -228.848158) (xy 134.234682 -228.848158) (xy 134.234682 -228.892608)
			(xy 134.334758 -228.992684)
		)
		(stroke
			(width 0)
			(type solid)
		)
		(fill yes)
		(layer "In4.Cu")
		(net "M_J_CPU1_SA_DQ<6>")
	)
	(gr_poly
		(pts
			(xy 134.434834 -227.676202) (xy 134.334758 -227.57638) (xy 134.234682 -227.676202) (xy 134.234682 -227.723954)
			(xy 134.434834 -227.723954)
		)
		(stroke
			(width 0)
			(type solid)
		)
		(fill yes)
		(layer "In4.Cu")
		(net "M_J_CPU1_SA_DQS_DN<5>")
	)
	(gr_poly
		(pts
			(xy 134.434834 -227.27285) (xy 134.434834 -227.225098) (xy 134.234682 -227.225098) (xy 134.234682 -227.27285)
			(xy 134.334758 -227.372672)
		)
		(stroke
			(width 0)
			(type solid)
		)
		(fill yes)
		(layer "In4.Cu")
		(net "M_J_CPU1_SA_DQS_DN<0>")
	)
	(gr_poly
		(pts
			(xy 134.434834 -226.056444) (xy 134.334758 -225.956368) (xy 134.234682 -226.056444) (xy 134.234682 -226.100894)
			(xy 134.434834 -226.100894)
		)
		(stroke
			(width 0)
			(type solid)
		)
		(fill yes)
		(layer "In4.Cu")
		(net "M_J_CPU1_SA_DQ<1>")
	)
	(gr_poly
		(pts
			(xy 134.434834 -225.652584) (xy 134.434834 -225.608134) (xy 134.234682 -225.608134) (xy 134.234682 -225.652584)
			(xy 134.334758 -225.75266)
		)
		(stroke
			(width 0)
			(type solid)
		)
		(fill yes)
		(layer "In4.Cu")
		(net "M_J_CPU1_SA_DQ<2>")
	)
	(gr_poly
		(pts
			(xy 134.734808 -293.32428) (xy 134.734808 -293.27983) (xy 134.534656 -293.27983) (xy 134.534656 -293.32428)
			(xy 134.634732 -293.424356)
		)
		(stroke
			(width 0)
			(type solid)
		)
		(fill yes)
		(layer "In4.Cu")
		(net "M_J_CPU1_SB_DQ<31>")
	)
	(gr_poly
		(pts
			(xy 134.734808 -292.108128) (xy 134.634732 -292.008052) (xy 134.534656 -292.108128) (xy 134.534656 -292.152578)
			(xy 134.734808 -292.152578)
		)
		(stroke
			(width 0)
			(type solid)
		)
		(fill yes)
		(layer "In4.Cu")
		(net "M_J_CPU1_SB_DQ<28>")
	)
	(gr_poly
		(pts
			(xy 134.734808 -291.704522) (xy 134.734808 -291.65677) (xy 134.534656 -291.65677) (xy 134.534656 -291.704522)
			(xy 134.634732 -291.804344)
		)
		(stroke
			(width 0)
			(type solid)
		)
		(fill yes)
		(layer "In4.Cu")
		(net "M_J_CPU1_SB_DQS_DP<8>")
	)
	(gr_poly
		(pts
			(xy 134.734808 -290.487862) (xy 134.634732 -290.38804) (xy 134.534656 -290.487862) (xy 134.534656 -290.535614)
			(xy 134.734808 -290.535614)
		)
		(stroke
			(width 0)
			(type solid)
		)
		(fill yes)
		(layer "In4.Cu")
		(net "M_J_CPU1_SB_DQS_DP<3>")
	)
	(gr_poly
		(pts
			(xy 134.734808 -290.084256) (xy 134.734808 -290.039806) (xy 134.534656 -290.039806) (xy 134.534656 -290.084256)
			(xy 134.634732 -290.184332)
		)
		(stroke
			(width 0)
			(type solid)
		)
		(fill yes)
		(layer "In4.Cu")
		(net "M_J_CPU1_SB_DQ<27>")
	)
	(gr_poly
		(pts
			(xy 134.734808 -288.868104) (xy 134.634732 -288.768028) (xy 134.534656 -288.868104) (xy 134.534656 -288.912554)
			(xy 134.734808 -288.912554)
		)
		(stroke
			(width 0)
			(type solid)
		)
		(fill yes)
		(layer "In4.Cu")
		(net "M_J_CPU1_SB_DQ<24>")
	)
	(gr_poly
		(pts
			(xy 134.734808 -288.464498) (xy 134.734808 -288.420048) (xy 134.534656 -288.420048) (xy 134.534656 -288.464498)
			(xy 134.634732 -288.564574)
		)
		(stroke
			(width 0)
			(type solid)
		)
		(fill yes)
		(layer "In4.Cu")
		(net "M_J_CPU1_SB_DQ<23>")
	)
	(gr_poly
		(pts
			(xy 134.734808 -287.248092) (xy 134.634732 -287.148016) (xy 134.534656 -287.248092) (xy 134.534656 -287.292542)
			(xy 134.734808 -287.292542)
		)
		(stroke
			(width 0)
			(type solid)
		)
		(fill yes)
		(layer "In4.Cu")
		(net "M_J_CPU1_SB_DQ<20>")
	)
	(gr_poly
		(pts
			(xy 134.734808 -286.844486) (xy 134.734808 -286.796734) (xy 134.534656 -286.796734) (xy 134.534656 -286.844486)
			(xy 134.634732 -286.944562)
		)
		(stroke
			(width 0)
			(type solid)
		)
		(fill yes)
		(layer "In4.Cu")
		(net "M_J_CPU1_SB_DQS_DP<7>")
	)
	(gr_poly
		(pts
			(xy 134.734808 -285.62808) (xy 134.634732 -285.528258) (xy 134.534656 -285.62808) (xy 134.534656 -285.675832)
			(xy 134.734808 -285.675832)
		)
		(stroke
			(width 0)
			(type solid)
		)
		(fill yes)
		(layer "In4.Cu")
		(net "M_J_CPU1_SB_DQS_DP<2>")
	)
	(gr_poly
		(pts
			(xy 134.734808 -285.224474) (xy 134.734808 -285.180024) (xy 134.534656 -285.180024) (xy 134.534656 -285.224474)
			(xy 134.634732 -285.32455)
		)
		(stroke
			(width 0)
			(type solid)
		)
		(fill yes)
		(layer "In4.Cu")
		(net "M_J_CPU1_SB_DQ<19>")
	)
	(gr_poly
		(pts
			(xy 134.734808 -284.008322) (xy 134.634732 -283.908246) (xy 134.534656 -284.008322) (xy 134.534656 -284.052772)
			(xy 134.734808 -284.052772)
		)
		(stroke
			(width 0)
			(type solid)
		)
		(fill yes)
		(layer "In4.Cu")
		(net "M_J_CPU1_SB_DQ<16>")
	)
	(gr_poly
		(pts
			(xy 134.734808 -283.604462) (xy 134.734808 -283.560012) (xy 134.534656 -283.560012) (xy 134.534656 -283.604462)
			(xy 134.634732 -283.704538)
		)
		(stroke
			(width 0)
			(type solid)
		)
		(fill yes)
		(layer "In4.Cu")
		(net "M_J_CPU1_SB_DQ<15>")
	)
	(gr_poly
		(pts
			(xy 134.734808 -282.38831) (xy 134.634732 -282.288234) (xy 134.534656 -282.38831) (xy 134.534656 -282.43276)
			(xy 134.734808 -282.43276)
		)
		(stroke
			(width 0)
			(type solid)
		)
		(fill yes)
		(layer "In4.Cu")
		(net "M_J_CPU1_SB_DQ<12>")
	)
	(gr_poly
		(pts
			(xy 134.734808 -281.984704) (xy 134.734808 -281.936952) (xy 134.534656 -281.936952) (xy 134.534656 -281.984704)
			(xy 134.634732 -282.084526)
		)
		(stroke
			(width 0)
			(type solid)
		)
		(fill yes)
		(layer "In4.Cu")
		(net "M_J_CPU1_SB_DQS_DP<6>")
	)
	(gr_poly
		(pts
			(xy 134.734808 -280.768044) (xy 134.634732 -280.668222) (xy 134.534656 -280.768044) (xy 134.534656 -280.815796)
			(xy 134.734808 -280.815796)
		)
		(stroke
			(width 0)
			(type solid)
		)
		(fill yes)
		(layer "In4.Cu")
		(net "M_J_CPU1_SB_DQS_DP<1>")
	)
	(gr_poly
		(pts
			(xy 134.734808 -280.364438) (xy 134.734808 -280.319988) (xy 134.534656 -280.319988) (xy 134.534656 -280.364438)
			(xy 134.634732 -280.464514)
		)
		(stroke
			(width 0)
			(type solid)
		)
		(fill yes)
		(layer "In4.Cu")
		(net "M_J_CPU1_SB_DQ<11>")
	)
	(gr_poly
		(pts
			(xy 134.734808 -279.148286) (xy 134.634732 -279.04821) (xy 134.534656 -279.148286) (xy 134.534656 -279.192736)
			(xy 134.734808 -279.192736)
		)
		(stroke
			(width 0)
			(type solid)
		)
		(fill yes)
		(layer "In4.Cu")
		(net "M_J_CPU1_SB_DQ<8>")
	)
	(gr_poly
		(pts
			(xy 134.734808 -278.744426) (xy 134.734808 -278.699976) (xy 134.534656 -278.699976) (xy 134.534656 -278.744426)
			(xy 134.634732 -278.844502)
		)
		(stroke
			(width 0)
			(type solid)
		)
		(fill yes)
		(layer "In4.Cu")
		(net "M_J_CPU1_SB_DQ<7>")
	)
	(gr_poly
		(pts
			(xy 134.734808 -277.528274) (xy 134.634732 -277.428198) (xy 134.534656 -277.528274) (xy 134.534656 -277.572724)
			(xy 134.734808 -277.572724)
		)
		(stroke
			(width 0)
			(type solid)
		)
		(fill yes)
		(layer "In4.Cu")
		(net "M_J_CPU1_SB_DQ<4>")
	)
	(gr_poly
		(pts
			(xy 134.734808 -277.124668) (xy 134.734808 -277.076916) (xy 134.534656 -277.076916) (xy 134.534656 -277.124668)
			(xy 134.634732 -277.22449)
		)
		(stroke
			(width 0)
			(type solid)
		)
		(fill yes)
		(layer "In4.Cu")
		(net "M_J_CPU1_SB_DQS_DP<5>")
	)
	(gr_poly
		(pts
			(xy 134.734808 -275.908008) (xy 134.634732 -275.808186) (xy 134.534656 -275.908008) (xy 134.534656 -275.95576)
			(xy 134.734808 -275.95576)
		)
		(stroke
			(width 0)
			(type solid)
		)
		(fill yes)
		(layer "In4.Cu")
		(net "M_J_CPU1_SB_DQS_DP<0>")
	)
	(gr_poly
		(pts
			(xy 134.734808 -275.504402) (xy 134.734808 -275.459952) (xy 134.534656 -275.459952) (xy 134.534656 -275.504402)
			(xy 134.634732 -275.604478)
		)
		(stroke
			(width 0)
			(type solid)
		)
		(fill yes)
		(layer "In4.Cu")
		(net "M_J_CPU1_SB_DQ<3>")
	)
	(gr_poly
		(pts
			(xy 134.734808 -274.28825) (xy 134.634732 -274.188174) (xy 134.534656 -274.28825) (xy 134.534656 -274.3327)
			(xy 134.734808 -274.3327)
		)
		(stroke
			(width 0)
			(type solid)
		)
		(fill yes)
		(layer "In4.Cu")
		(net "M_J_CPU1_SB_DQ<0>")
	)
	(gr_poly
		(pts
			(xy 134.734808 -273.88439) (xy 134.734808 -273.83994) (xy 134.534656 -273.83994) (xy 134.534656 -273.88439)
			(xy 134.634732 -273.984466)
		)
		(stroke
			(width 0)
			(type solid)
		)
		(fill yes)
		(layer "In4.Cu")
		(net "M_J_CPU1_SB_CB<3>")
	)
	(gr_poly
		(pts
			(xy 134.734808 -272.668238) (xy 134.634732 -272.568162) (xy 134.534656 -272.668238) (xy 134.534656 -272.712688)
			(xy 134.734808 -272.712688)
		)
		(stroke
			(width 0)
			(type solid)
		)
		(fill yes)
		(layer "In4.Cu")
		(net "M_J_CPU1_SB_CB<0>")
	)
	(gr_poly
		(pts
			(xy 134.734808 -272.264632) (xy 134.734808 -272.21688) (xy 134.534656 -272.21688) (xy 134.534656 -272.264632)
			(xy 134.634732 -272.364454)
		)
		(stroke
			(width 0)
			(type solid)
		)
		(fill yes)
		(layer "In4.Cu")
		(net "M_J_CPU1_SB_DQS_DP<4>")
	)
	(gr_poly
		(pts
			(xy 134.734808 -271.047972) (xy 134.634732 -270.94815) (xy 134.534656 -271.047972) (xy 134.534656 -271.095724)
			(xy 134.734808 -271.095724)
		)
		(stroke
			(width 0)
			(type solid)
		)
		(fill yes)
		(layer "In4.Cu")
		(net "M_J_CPU1_SB_DQS_DP<9>")
	)
	(gr_poly
		(pts
			(xy 134.734808 -270.644366) (xy 134.734808 -270.599916) (xy 134.534656 -270.599916) (xy 134.534656 -270.644366)
			(xy 134.634732 -270.744442)
		)
		(stroke
			(width 0)
			(type solid)
		)
		(fill yes)
		(layer "In4.Cu")
		(net "M_J_CPU1_SB_CB<7>")
	)
	(gr_poly
		(pts
			(xy 134.734808 -269.428214) (xy 134.634732 -269.328138) (xy 134.534656 -269.428214) (xy 134.534656 -269.472664)
			(xy 134.734808 -269.472664)
		)
		(stroke
			(width 0)
			(type solid)
		)
		(fill yes)
		(layer "In4.Cu")
		(net "M_J_CPU1_SB_CB<4>")
	)
	(gr_poly
		(pts
			(xy 134.734808 -267.808202) (xy 134.634732 -267.708126) (xy 134.534656 -267.808202) (xy 134.534656 -267.852652)
			(xy 134.734808 -267.852652)
		)
		(stroke
			(width 0)
			(type solid)
		)
		(fill yes)
		(layer "In4.Cu")
		(net "M_J_CPU1_SB_RSP<0>")
	)
	(gr_poly
		(pts
			(xy 134.734808 -265.78433) (xy 134.734808 -265.73988) (xy 134.534656 -265.73988) (xy 134.534656 -265.78433)
			(xy 134.634732 -265.884406)
		)
		(stroke
			(width 0)
			(type solid)
		)
		(fill yes)
		(layer "In4.Cu")
		(net "M_J_CPU1_SB_CS_N<0>")
	)
	(gr_poly
		(pts
			(xy 134.734808 -264.568178) (xy 134.634732 -264.468102) (xy 134.534656 -264.568178) (xy 134.534656 -264.612628)
			(xy 134.734808 -264.612628)
		)
		(stroke
			(width 0)
			(type solid)
		)
		(fill yes)
		(layer "In4.Cu")
		(net "M_J_CPU1_SB_CA<6>")
	)
	(gr_poly
		(pts
			(xy 134.734808 -264.164318) (xy 134.734808 -264.119868) (xy 134.534656 -264.119868) (xy 134.534656 -264.164318)
			(xy 134.634732 -264.264394)
		)
		(stroke
			(width 0)
			(type solid)
		)
		(fill yes)
		(layer "In4.Cu")
		(net "M_J_CPU1_SB_CA<5>")
	)
	(gr_poly
		(pts
			(xy 134.734808 -262.948166) (xy 134.634732 -262.84809) (xy 134.534656 -262.948166) (xy 134.534656 -262.992616)
			(xy 134.734808 -262.992616)
		)
		(stroke
			(width 0)
			(type solid)
		)
		(fill yes)
		(layer "In4.Cu")
		(net "M_J_CPU1_SB_CA<2>")
	)
	(gr_poly
		(pts
			(xy 134.734808 -262.544306) (xy 134.734808 -262.499856) (xy 134.534656 -262.499856) (xy 134.534656 -262.544306)
			(xy 134.634732 -262.644382)
		)
		(stroke
			(width 0)
			(type solid)
		)
		(fill yes)
		(layer "In4.Cu")
		(net "M_J_CPU1_SB_CA<1>")
	)
	(gr_poly
		(pts
			(xy 134.904734 -256.026158) (xy 134.804658 -255.926336) (xy 134.704582 -256.026158) (xy 134.704582 -256.07391)
			(xy 134.904734 -256.07391)
		)
		(stroke
			(width 0)
			(type solid)
		)
		(fill yes)
		(layer "In4.Cu")
		(net "M_J_CPU1_CLK_DP<0>")
	)
	(gr_poly
		(pts
			(xy 134.904734 -255.622552) (xy 134.904734 -255.578102) (xy 134.704582 -255.578102) (xy 134.704582 -255.622552)
			(xy 134.804658 -255.722628)
		)
		(stroke
			(width 0)
			(type solid)
		)
		(fill yes)
		(layer "In4.Cu")
		(net "M_J_CPU1_SA_PAR")
	)
	(gr_poly
		(pts
			(xy 134.904734 -254.4064) (xy 134.804658 -254.306324) (xy 134.704582 -254.4064) (xy 134.704582 -254.45085)
			(xy 134.904734 -254.45085)
		)
		(stroke
			(width 0)
			(type solid)
		)
		(fill yes)
		(layer "In4.Cu")
		(net "M_J_CPU1_SA_CA<4>")
	)
	(gr_poly
		(pts
			(xy 134.904734 -254.00254) (xy 134.904734 -253.95809) (xy 134.704582 -253.95809) (xy 134.704582 -254.00254)
			(xy 134.804658 -254.102616)
		)
		(stroke
			(width 0)
			(type solid)
		)
		(fill yes)
		(layer "In4.Cu")
		(net "M_J_CPU1_SA_CA<3>")
	)
	(gr_poly
		(pts
			(xy 134.904734 -252.786388) (xy 134.804658 -252.686312) (xy 134.704582 -252.786388) (xy 134.704582 -252.830838)
			(xy 134.904734 -252.830838)
		)
		(stroke
			(width 0)
			(type solid)
		)
		(fill yes)
		(layer "In4.Cu")
		(net "M_J_CPU1_SA_CA<0>")
	)
	(gr_poly
		(pts
			(xy 134.904734 -251.166376) (xy 134.804658 -251.0663) (xy 134.704582 -251.166376) (xy 134.704582 -251.210826)
			(xy 134.904734 -251.210826)
		)
		(stroke
			(width 0)
			(type solid)
		)
		(fill yes)
		(layer "In4.Cu")
		(net "M_J_CPU1_SA_CS_N<0>")
	)
	(gr_poly
		(pts
			(xy 134.904734 -250.762516) (xy 134.904734 -250.718066) (xy 134.704582 -250.718066) (xy 134.704582 -250.762516)
			(xy 134.804658 -250.862592)
		)
		(stroke
			(width 0)
			(type solid)
		)
		(fill yes)
		(layer "In4.Cu")
		(net "M_J_CPU1_RESET_N")
	)
	(gr_poly
		(pts
			(xy 134.904734 -249.142504) (xy 134.904734 -249.098054) (xy 134.704582 -249.098054) (xy 134.704582 -249.142504)
			(xy 134.804658 -249.24258)
		)
		(stroke
			(width 0)
			(type solid)
		)
		(fill yes)
		(layer "In4.Cu")
		(net "M_J_CPU1_SA_CB<7>")
	)
	(gr_poly
		(pts
			(xy 134.904734 -247.926352) (xy 134.804658 -247.826276) (xy 134.704582 -247.926352) (xy 134.704582 -247.970802)
			(xy 134.904734 -247.970802)
		)
		(stroke
			(width 0)
			(type solid)
		)
		(fill yes)
		(layer "In4.Cu")
		(net "M_J_CPU1_SA_CB<4>")
	)
	(gr_poly
		(pts
			(xy 134.904734 -247.522746) (xy 134.904734 -247.474994) (xy 134.704582 -247.474994) (xy 134.704582 -247.522746)
			(xy 134.804658 -247.622568)
		)
		(stroke
			(width 0)
			(type solid)
		)
		(fill yes)
		(layer "In4.Cu")
		(net "M_J_CPU1_SA_DQS_DP<9>")
	)
	(gr_poly
		(pts
			(xy 134.904734 -246.306086) (xy 134.804658 -246.206264) (xy 134.704582 -246.306086) (xy 134.704582 -246.353838)
			(xy 134.904734 -246.353838)
		)
		(stroke
			(width 0)
			(type solid)
		)
		(fill yes)
		(layer "In4.Cu")
		(net "M_J_CPU1_SA_DQS_DP<4>")
	)
	(gr_poly
		(pts
			(xy 134.904734 -245.90248) (xy 134.904734 -245.85803) (xy 134.704582 -245.85803) (xy 134.704582 -245.90248)
			(xy 134.804658 -246.002556)
		)
		(stroke
			(width 0)
			(type solid)
		)
		(fill yes)
		(layer "In4.Cu")
		(net "M_J_CPU1_SA_CB<3>")
	)
	(gr_poly
		(pts
			(xy 134.904734 -244.686328) (xy 134.804658 -244.586252) (xy 134.704582 -244.686328) (xy 134.704582 -244.730778)
			(xy 134.904734 -244.730778)
		)
		(stroke
			(width 0)
			(type solid)
		)
		(fill yes)
		(layer "In4.Cu")
		(net "M_J_CPU1_SA_CB<0>")
	)
	(gr_poly
		(pts
			(xy 134.904734 -244.282468) (xy 134.904734 -244.238018) (xy 134.704582 -244.238018) (xy 134.704582 -244.282468)
			(xy 134.804658 -244.382544)
		)
		(stroke
			(width 0)
			(type solid)
		)
		(fill yes)
		(layer "In4.Cu")
		(net "M_J_CPU1_SA_DQ<31>")
	)
	(gr_poly
		(pts
			(xy 134.904734 -243.066316) (xy 134.804658 -242.96624) (xy 134.704582 -243.066316) (xy 134.704582 -243.110766)
			(xy 134.904734 -243.110766)
		)
		(stroke
			(width 0)
			(type solid)
		)
		(fill yes)
		(layer "In4.Cu")
		(net "M_J_CPU1_SA_DQ<28>")
	)
	(gr_poly
		(pts
			(xy 134.904734 -242.66271) (xy 134.904734 -242.614958) (xy 134.704582 -242.614958) (xy 134.704582 -242.66271)
			(xy 134.804658 -242.762532)
		)
		(stroke
			(width 0)
			(type solid)
		)
		(fill yes)
		(layer "In4.Cu")
		(net "M_J_CPU1_SA_DQS_DP<8>")
	)
	(gr_poly
		(pts
			(xy 134.904734 -241.44605) (xy 134.804658 -241.346228) (xy 134.704582 -241.44605) (xy 134.704582 -241.493802)
			(xy 134.904734 -241.493802)
		)
		(stroke
			(width 0)
			(type solid)
		)
		(fill yes)
		(layer "In4.Cu")
		(net "M_J_CPU1_SA_DQS_DP<3>")
	)
	(gr_poly
		(pts
			(xy 134.904734 -241.042444) (xy 134.904734 -240.997994) (xy 134.704582 -240.997994) (xy 134.704582 -241.042444)
			(xy 134.804658 -241.14252)
		)
		(stroke
			(width 0)
			(type solid)
		)
		(fill yes)
		(layer "In4.Cu")
		(net "M_J_CPU1_SA_DQ<27>")
	)
	(gr_poly
		(pts
			(xy 134.904734 -239.826292) (xy 134.804658 -239.726216) (xy 134.704582 -239.826292) (xy 134.704582 -239.870742)
			(xy 134.904734 -239.870742)
		)
		(stroke
			(width 0)
			(type solid)
		)
		(fill yes)
		(layer "In4.Cu")
		(net "M_J_CPU1_SA_DQ<24>")
	)
	(gr_poly
		(pts
			(xy 134.904734 -239.422432) (xy 134.904734 -239.377982) (xy 134.704582 -239.377982) (xy 134.704582 -239.422432)
			(xy 134.804658 -239.522508)
		)
		(stroke
			(width 0)
			(type solid)
		)
		(fill yes)
		(layer "In4.Cu")
		(net "M_J_CPU1_SA_DQ<23>")
	)
	(gr_poly
		(pts
			(xy 134.904734 -238.20628) (xy 134.804658 -238.106204) (xy 134.704582 -238.20628) (xy 134.704582 -238.25073)
			(xy 134.904734 -238.25073)
		)
		(stroke
			(width 0)
			(type solid)
		)
		(fill yes)
		(layer "In4.Cu")
		(net "M_J_CPU1_SA_DQ<20>")
	)
	(gr_poly
		(pts
			(xy 134.904734 -237.802674) (xy 134.904734 -237.754922) (xy 134.704582 -237.754922) (xy 134.704582 -237.802674)
			(xy 134.804658 -237.902496)
		)
		(stroke
			(width 0)
			(type solid)
		)
		(fill yes)
		(layer "In4.Cu")
		(net "M_J_CPU1_SA_DQS_DP<7>")
	)
	(gr_poly
		(pts
			(xy 134.904734 -236.586014) (xy 134.804658 -236.486192) (xy 134.704582 -236.586014) (xy 134.704582 -236.633766)
			(xy 134.904734 -236.633766)
		)
		(stroke
			(width 0)
			(type solid)
		)
		(fill yes)
		(layer "In4.Cu")
		(net "M_J_CPU1_SA_DQS_DP<2>")
	)
	(gr_poly
		(pts
			(xy 134.904734 -236.182408) (xy 134.904734 -236.137958) (xy 134.704582 -236.137958) (xy 134.704582 -236.182408)
			(xy 134.804658 -236.282484)
		)
		(stroke
			(width 0)
			(type solid)
		)
		(fill yes)
		(layer "In4.Cu")
		(net "M_J_CPU1_SA_DQ<19>")
	)
	(gr_poly
		(pts
			(xy 134.904734 -234.966256) (xy 134.804658 -234.86618) (xy 134.704582 -234.966256) (xy 134.704582 -235.010706)
			(xy 134.904734 -235.010706)
		)
		(stroke
			(width 0)
			(type solid)
		)
		(fill yes)
		(layer "In4.Cu")
		(net "M_J_CPU1_SA_DQ<16>")
	)
	(gr_poly
		(pts
			(xy 134.904734 -234.562396) (xy 134.904734 -234.517946) (xy 134.704582 -234.517946) (xy 134.704582 -234.562396)
			(xy 134.804658 -234.662472)
		)
		(stroke
			(width 0)
			(type solid)
		)
		(fill yes)
		(layer "In4.Cu")
		(net "M_J_CPU1_SA_DQ<15>")
	)
	(gr_poly
		(pts
			(xy 134.904734 -233.346244) (xy 134.804658 -233.246168) (xy 134.704582 -233.346244) (xy 134.704582 -233.390694)
			(xy 134.904734 -233.390694)
		)
		(stroke
			(width 0)
			(type solid)
		)
		(fill yes)
		(layer "In4.Cu")
		(net "M_J_CPU1_SA_DQ<12>")
	)
	(gr_poly
		(pts
			(xy 134.904734 -232.942638) (xy 134.904734 -232.894886) (xy 134.704582 -232.894886) (xy 134.704582 -232.942638)
			(xy 134.804658 -233.04246)
		)
		(stroke
			(width 0)
			(type solid)
		)
		(fill yes)
		(layer "In4.Cu")
		(net "M_J_CPU1_SA_DQS_DP<6>")
	)
	(gr_poly
		(pts
			(xy 134.904734 -231.725978) (xy 134.804658 -231.626156) (xy 134.704582 -231.725978) (xy 134.704582 -231.77373)
			(xy 134.904734 -231.77373)
		)
		(stroke
			(width 0)
			(type solid)
		)
		(fill yes)
		(layer "In4.Cu")
		(net "M_J_CPU1_SA_DQS_DP<1>")
	)
	(gr_poly
		(pts
			(xy 134.904734 -231.322626) (xy 134.904734 -231.278176) (xy 134.704582 -231.278176) (xy 134.704582 -231.322626)
			(xy 134.804658 -231.422702)
		)
		(stroke
			(width 0)
			(type solid)
		)
		(fill yes)
		(layer "In4.Cu")
		(net "M_J_CPU1_SA_DQ<11>")
	)
	(gr_poly
		(pts
			(xy 134.904734 -230.10622) (xy 134.804658 -230.006144) (xy 134.704582 -230.10622) (xy 134.704582 -230.15067)
			(xy 134.904734 -230.15067)
		)
		(stroke
			(width 0)
			(type solid)
		)
		(fill yes)
		(layer "In4.Cu")
		(net "M_J_CPU1_SA_DQ<8>")
	)
	(gr_poly
		(pts
			(xy 134.904734 -229.702614) (xy 134.904734 -229.658164) (xy 134.704582 -229.658164) (xy 134.704582 -229.702614)
			(xy 134.804658 -229.80269)
		)
		(stroke
			(width 0)
			(type solid)
		)
		(fill yes)
		(layer "In4.Cu")
		(net "M_J_CPU1_SA_DQ<7>")
	)
	(gr_poly
		(pts
			(xy 134.904734 -228.486462) (xy 134.804658 -228.386386) (xy 134.704582 -228.486462) (xy 134.704582 -228.530912)
			(xy 134.904734 -228.530912)
		)
		(stroke
			(width 0)
			(type solid)
		)
		(fill yes)
		(layer "In4.Cu")
		(net "M_J_CPU1_SA_DQ<4>")
	)
	(gr_poly
		(pts
			(xy 134.904734 -228.082856) (xy 134.904734 -228.035104) (xy 134.704582 -228.035104) (xy 134.704582 -228.082856)
			(xy 134.804658 -228.182678)
		)
		(stroke
			(width 0)
			(type solid)
		)
		(fill yes)
		(layer "In4.Cu")
		(net "M_J_CPU1_SA_DQS_DP<5>")
	)
	(gr_poly
		(pts
			(xy 134.904734 -226.866196) (xy 134.804658 -226.766374) (xy 134.704582 -226.866196) (xy 134.704582 -226.913948)
			(xy 134.904734 -226.913948)
		)
		(stroke
			(width 0)
			(type solid)
		)
		(fill yes)
		(layer "In4.Cu")
		(net "M_J_CPU1_SA_DQS_DP<0>")
	)
	(gr_poly
		(pts
			(xy 134.904734 -226.46259) (xy 134.904734 -226.41814) (xy 134.704582 -226.41814) (xy 134.704582 -226.46259)
			(xy 134.804658 -226.562666)
		)
		(stroke
			(width 0)
			(type solid)
		)
		(fill yes)
		(layer "In4.Cu")
		(net "M_J_CPU1_SA_DQ<3>")
	)
	(gr_poly
		(pts
			(xy 134.904734 -225.246438) (xy 134.804658 -225.146362) (xy 134.704582 -225.246438) (xy 134.704582 -225.290888)
			(xy 134.904734 -225.290888)
		)
		(stroke
			(width 0)
			(type solid)
		)
		(fill yes)
		(layer "In4.Cu")
		(net "M_J_CPU1_SA_DQ<0>")
	)
	(gr_poly
		(pts
			(xy 135.204708 -292.918134) (xy 135.104632 -292.818058) (xy 135.004556 -292.918134) (xy 135.004556 -292.962584)
			(xy 135.204708 -292.962584)
		)
		(stroke
			(width 0)
			(type solid)
		)
		(fill yes)
		(layer "In4.Cu")
		(net "M_J_CPU1_SB_DQ<29>")
	)
	(gr_poly
		(pts
			(xy 135.204708 -292.514274) (xy 135.204708 -292.469824) (xy 135.004556 -292.469824) (xy 135.004556 -292.514274)
			(xy 135.104632 -292.61435)
		)
		(stroke
			(width 0)
			(type solid)
		)
		(fill yes)
		(layer "In4.Cu")
		(net "M_J_CPU1_SB_DQ<30>")
	)
	(gr_poly
		(pts
			(xy 135.204708 -291.297868) (xy 135.104632 -291.198046) (xy 135.004556 -291.297868) (xy 135.004556 -291.34562)
			(xy 135.204708 -291.34562)
		)
		(stroke
			(width 0)
			(type solid)
		)
		(fill yes)
		(layer "In4.Cu")
		(net "M_J_CPU1_SB_DQS_DN<8>")
	)
	(gr_poly
		(pts
			(xy 135.204708 -290.894516) (xy 135.204708 -290.846764) (xy 135.004556 -290.846764) (xy 135.004556 -290.894516)
			(xy 135.104632 -290.994338)
		)
		(stroke
			(width 0)
			(type solid)
		)
		(fill yes)
		(layer "In4.Cu")
		(net "M_J_CPU1_SB_DQS_DN<3>")
	)
	(gr_poly
		(pts
			(xy 135.204708 -289.67811) (xy 135.104632 -289.578034) (xy 135.004556 -289.67811) (xy 135.004556 -289.72256)
			(xy 135.204708 -289.72256)
		)
		(stroke
			(width 0)
			(type solid)
		)
		(fill yes)
		(layer "In4.Cu")
		(net "M_J_CPU1_SB_DQ<25>")
	)
	(gr_poly
		(pts
			(xy 135.204708 -289.27425) (xy 135.204708 -289.2298) (xy 135.004556 -289.2298) (xy 135.004556 -289.27425)
			(xy 135.104632 -289.374326)
		)
		(stroke
			(width 0)
			(type solid)
		)
		(fill yes)
		(layer "In4.Cu")
		(net "M_J_CPU1_SB_DQ<26>")
	)
	(gr_poly
		(pts
			(xy 135.204708 -288.058098) (xy 135.104632 -287.958022) (xy 135.004556 -288.058098) (xy 135.004556 -288.102548)
			(xy 135.204708 -288.102548)
		)
		(stroke
			(width 0)
			(type solid)
		)
		(fill yes)
		(layer "In4.Cu")
		(net "M_J_CPU1_SB_DQ<21>")
	)
	(gr_poly
		(pts
			(xy 135.204708 -287.654492) (xy 135.204708 -287.610042) (xy 135.004556 -287.610042) (xy 135.004556 -287.654492)
			(xy 135.104632 -287.754568)
		)
		(stroke
			(width 0)
			(type solid)
		)
		(fill yes)
		(layer "In4.Cu")
		(net "M_J_CPU1_SB_DQ<22>")
	)
	(gr_poly
		(pts
			(xy 135.204708 -286.438086) (xy 135.104632 -286.33801) (xy 135.004556 -286.438086) (xy 135.004556 -286.485838)
			(xy 135.204708 -286.485838)
		)
		(stroke
			(width 0)
			(type solid)
		)
		(fill yes)
		(layer "In4.Cu")
		(net "M_J_CPU1_SB_DQS_DN<7>")
	)
	(gr_poly
		(pts
			(xy 135.204708 -286.034734) (xy 135.204708 -285.986982) (xy 135.004556 -285.986982) (xy 135.004556 -286.034734)
			(xy 135.104632 -286.134556)
		)
		(stroke
			(width 0)
			(type solid)
		)
		(fill yes)
		(layer "In4.Cu")
		(net "M_J_CPU1_SB_DQS_DN<2>")
	)
	(gr_poly
		(pts
			(xy 135.204708 -284.818328) (xy 135.104632 -284.718252) (xy 135.004556 -284.818328) (xy 135.004556 -284.862778)
			(xy 135.204708 -284.862778)
		)
		(stroke
			(width 0)
			(type solid)
		)
		(fill yes)
		(layer "In4.Cu")
		(net "M_J_CPU1_SB_DQ<17>")
	)
	(gr_poly
		(pts
			(xy 135.204708 -284.414468) (xy 135.204708 -284.370018) (xy 135.004556 -284.370018) (xy 135.004556 -284.414468)
			(xy 135.104632 -284.514544)
		)
		(stroke
			(width 0)
			(type solid)
		)
		(fill yes)
		(layer "In4.Cu")
		(net "M_J_CPU1_SB_DQ<18>")
	)
	(gr_poly
		(pts
			(xy 135.204708 -283.198316) (xy 135.104632 -283.09824) (xy 135.004556 -283.198316) (xy 135.004556 -283.242766)
			(xy 135.204708 -283.242766)
		)
		(stroke
			(width 0)
			(type solid)
		)
		(fill yes)
		(layer "In4.Cu")
		(net "M_J_CPU1_SB_DQ<13>")
	)
	(gr_poly
		(pts
			(xy 135.204708 -282.794456) (xy 135.204708 -282.750006) (xy 135.004556 -282.750006) (xy 135.004556 -282.794456)
			(xy 135.104632 -282.894532)
		)
		(stroke
			(width 0)
			(type solid)
		)
		(fill yes)
		(layer "In4.Cu")
		(net "M_J_CPU1_SB_DQ<14>")
	)
	(gr_poly
		(pts
			(xy 135.204708 -281.57805) (xy 135.104632 -281.478228) (xy 135.004556 -281.57805) (xy 135.004556 -281.625802)
			(xy 135.204708 -281.625802)
		)
		(stroke
			(width 0)
			(type solid)
		)
		(fill yes)
		(layer "In4.Cu")
		(net "M_J_CPU1_SB_DQS_DN<6>")
	)
	(gr_poly
		(pts
			(xy 135.204708 -281.174698) (xy 135.204708 -281.126946) (xy 135.004556 -281.126946) (xy 135.004556 -281.174698)
			(xy 135.104632 -281.27452)
		)
		(stroke
			(width 0)
			(type solid)
		)
		(fill yes)
		(layer "In4.Cu")
		(net "M_J_CPU1_SB_DQS_DN<1>")
	)
	(gr_poly
		(pts
			(xy 135.204708 -279.958292) (xy 135.104632 -279.858216) (xy 135.004556 -279.958292) (xy 135.004556 -280.002742)
			(xy 135.204708 -280.002742)
		)
		(stroke
			(width 0)
			(type solid)
		)
		(fill yes)
		(layer "In4.Cu")
		(net "M_J_CPU1_SB_DQ<9>")
	)
	(gr_poly
		(pts
			(xy 135.204708 -279.554432) (xy 135.204708 -279.509982) (xy 135.004556 -279.509982) (xy 135.004556 -279.554432)
			(xy 135.104632 -279.654508)
		)
		(stroke
			(width 0)
			(type solid)
		)
		(fill yes)
		(layer "In4.Cu")
		(net "M_J_CPU1_SB_DQ<10>")
	)
	(gr_poly
		(pts
			(xy 135.204708 -278.33828) (xy 135.104632 -278.238204) (xy 135.004556 -278.33828) (xy 135.004556 -278.38273)
			(xy 135.204708 -278.38273)
		)
		(stroke
			(width 0)
			(type solid)
		)
		(fill yes)
		(layer "In4.Cu")
		(net "M_J_CPU1_SB_DQ<5>")
	)
	(gr_poly
		(pts
			(xy 135.204708 -277.93442) (xy 135.204708 -277.88997) (xy 135.004556 -277.88997) (xy 135.004556 -277.93442)
			(xy 135.104632 -278.034496)
		)
		(stroke
			(width 0)
			(type solid)
		)
		(fill yes)
		(layer "In4.Cu")
		(net "M_J_CPU1_SB_DQ<6>")
	)
	(gr_poly
		(pts
			(xy 135.204708 -276.718014) (xy 135.104632 -276.618192) (xy 135.004556 -276.718014) (xy 135.004556 -276.765766)
			(xy 135.204708 -276.765766)
		)
		(stroke
			(width 0)
			(type solid)
		)
		(fill yes)
		(layer "In4.Cu")
		(net "M_J_CPU1_SB_DQS_DN<5>")
	)
	(gr_poly
		(pts
			(xy 135.204708 -276.314662) (xy 135.204708 -276.26691) (xy 135.004556 -276.26691) (xy 135.004556 -276.314662)
			(xy 135.104632 -276.414484)
		)
		(stroke
			(width 0)
			(type solid)
		)
		(fill yes)
		(layer "In4.Cu")
		(net "M_J_CPU1_SB_DQS_DN<0>")
	)
	(gr_poly
		(pts
			(xy 135.204708 -275.098256) (xy 135.104632 -274.99818) (xy 135.004556 -275.098256) (xy 135.004556 -275.142706)
			(xy 135.204708 -275.142706)
		)
		(stroke
			(width 0)
			(type solid)
		)
		(fill yes)
		(layer "In4.Cu")
		(net "M_J_CPU1_SB_DQ<1>")
	)
	(gr_poly
		(pts
			(xy 135.204708 -274.694396) (xy 135.204708 -274.649946) (xy 135.004556 -274.649946) (xy 135.004556 -274.694396)
			(xy 135.104632 -274.794472)
		)
		(stroke
			(width 0)
			(type solid)
		)
		(fill yes)
		(layer "In4.Cu")
		(net "M_J_CPU1_SB_DQ<2>")
	)
	(gr_poly
		(pts
			(xy 135.204708 -273.478244) (xy 135.104632 -273.378168) (xy 135.004556 -273.478244) (xy 135.004556 -273.522694)
			(xy 135.204708 -273.522694)
		)
		(stroke
			(width 0)
			(type solid)
		)
		(fill yes)
		(layer "In4.Cu")
		(net "M_J_CPU1_SB_CB<1>")
	)
	(gr_poly
		(pts
			(xy 135.204708 -273.074384) (xy 135.204708 -273.029934) (xy 135.004556 -273.029934) (xy 135.004556 -273.074384)
			(xy 135.104632 -273.17446)
		)
		(stroke
			(width 0)
			(type solid)
		)
		(fill yes)
		(layer "In4.Cu")
		(net "M_J_CPU1_SB_CB<2>")
	)
	(gr_poly
		(pts
			(xy 135.204708 -271.857978) (xy 135.104632 -271.758156) (xy 135.004556 -271.857978) (xy 135.004556 -271.90573)
			(xy 135.204708 -271.90573)
		)
		(stroke
			(width 0)
			(type solid)
		)
		(fill yes)
		(layer "In4.Cu")
		(net "M_J_CPU1_SB_DQS_DN<4>")
	)
	(gr_poly
		(pts
			(xy 135.204708 -271.454626) (xy 135.204708 -271.406874) (xy 135.004556 -271.406874) (xy 135.004556 -271.454626)
			(xy 135.104632 -271.554448)
		)
		(stroke
			(width 0)
			(type solid)
		)
		(fill yes)
		(layer "In4.Cu")
		(net "M_J_CPU1_SB_DQS_DN<9>")
	)
	(gr_poly
		(pts
			(xy 135.204708 -270.23822) (xy 135.104632 -270.138144) (xy 135.004556 -270.23822) (xy 135.004556 -270.28267)
			(xy 135.204708 -270.28267)
		)
		(stroke
			(width 0)
			(type solid)
		)
		(fill yes)
		(layer "In4.Cu")
		(net "M_J_CPU1_SB_CB<5>")
	)
	(gr_poly
		(pts
			(xy 135.204708 -269.83436) (xy 135.204708 -269.78991) (xy 135.004556 -269.78991) (xy 135.004556 -269.83436)
			(xy 135.104632 -269.934436)
		)
		(stroke
			(width 0)
			(type solid)
		)
		(fill yes)
		(layer "In4.Cu")
		(net "M_J_CPU1_SB_CB<6>")
	)
	(gr_poly
		(pts
			(xy 135.204708 -266.998196) (xy 135.104632 -266.89812) (xy 135.004556 -266.998196) (xy 135.004556 -267.042646)
			(xy 135.204708 -267.042646)
		)
		(stroke
			(width 0)
			(type solid)
		)
		(fill yes)
		(layer "In4.Cu")
		(net "M_J_CPU1_SA_RSP<0>")
	)
	(gr_poly
		(pts
			(xy 135.204708 -266.594336) (xy 135.204708 -266.549886) (xy 135.004556 -266.549886) (xy 135.004556 -266.594336)
			(xy 135.104632 -266.694412)
		)
		(stroke
			(width 0)
			(type solid)
		)
		(fill yes)
		(layer "In4.Cu")
		(net "M_J_CPU1_SB_CS_N<1>")
	)
	(gr_poly
		(pts
			(xy 135.204708 -265.378184) (xy 135.104632 -265.278108) (xy 135.004556 -265.378184) (xy 135.004556 -265.422634)
			(xy 135.204708 -265.422634)
		)
		(stroke
			(width 0)
			(type solid)
		)
		(fill yes)
		(layer "In4.Cu")
		(net "M_J_CPU1_SB_PAR")
	)
	(gr_poly
		(pts
			(xy 135.204708 -263.758172) (xy 135.104632 -263.658096) (xy 135.004556 -263.758172) (xy 135.004556 -263.802622)
			(xy 135.204708 -263.802622)
		)
		(stroke
			(width 0)
			(type solid)
		)
		(fill yes)
		(layer "In4.Cu")
		(net "M_J_CPU1_SB_CA<4>")
	)
	(gr_poly
		(pts
			(xy 135.204708 -263.354312) (xy 135.204708 -263.309862) (xy 135.004556 -263.309862) (xy 135.004556 -263.354312)
			(xy 135.104632 -263.454388)
		)
		(stroke
			(width 0)
			(type solid)
		)
		(fill yes)
		(layer "In4.Cu")
		(net "M_J_CPU1_SB_CA<3>")
	)
	(gr_poly
		(pts
			(xy 135.204708 -262.13816) (xy 135.104632 -262.038084) (xy 135.004556 -262.13816) (xy 135.004556 -262.18261)
			(xy 135.204708 -262.18261)
		)
		(stroke
			(width 0)
			(type solid)
		)
		(fill yes)
		(layer "In4.Cu")
		(net "M_J_CPU1_SB_CA<0>")
	)
	(gr_poly
		(pts
			(xy 135.374888 -256.432812) (xy 135.374888 -256.38506) (xy 135.174736 -256.38506) (xy 135.174736 -256.432812)
			(xy 135.274812 -256.532634)
		)
		(stroke
			(width 0)
			(type solid)
		)
		(fill yes)
		(layer "In4.Cu")
		(net "M_J_CPU1_CLK_DN<0>")
	)
	(gr_poly
		(pts
			(xy 135.374888 -255.216406) (xy 135.274812 -255.11633) (xy 135.174736 -255.216406) (xy 135.174736 -255.260856)
			(xy 135.374888 -255.260856)
		)
		(stroke
			(width 0)
			(type solid)
		)
		(fill yes)
		(layer "In4.Cu")
		(net "M_J_CPU1_SA_CA<6>")
	)
	(gr_poly
		(pts
			(xy 135.374888 -254.812546) (xy 135.374888 -254.768096) (xy 135.174736 -254.768096) (xy 135.174736 -254.812546)
			(xy 135.274812 -254.912622)
		)
		(stroke
			(width 0)
			(type solid)
		)
		(fill yes)
		(layer "In4.Cu")
		(net "M_J_CPU1_SA_CA<5>")
	)
	(gr_poly
		(pts
			(xy 135.374888 -253.596394) (xy 135.274812 -253.496318) (xy 135.174736 -253.596394) (xy 135.174736 -253.640844)
			(xy 135.374888 -253.640844)
		)
		(stroke
			(width 0)
			(type solid)
		)
		(fill yes)
		(layer "In4.Cu")
		(net "M_J_CPU1_SA_CA<2>")
	)
	(gr_poly
		(pts
			(xy 135.374888 -253.192534) (xy 135.374888 -253.148084) (xy 135.174736 -253.148084) (xy 135.174736 -253.192534)
			(xy 135.274812 -253.29261)
		)
		(stroke
			(width 0)
			(type solid)
		)
		(fill yes)
		(layer "In4.Cu")
		(net "M_J_CPU1_SA_CA<1>")
	)
	(gr_poly
		(pts
			(xy 135.374888 -251.976382) (xy 135.274812 -251.876306) (xy 135.174736 -251.976382) (xy 135.174736 -252.020832)
			(xy 135.374888 -252.020832)
		)
		(stroke
			(width 0)
			(type solid)
		)
		(fill yes)
		(layer "In4.Cu")
		(net "M_J_CPU1_SA_CS_N<1>")
	)
	(gr_poly
		(pts
			(xy 135.374888 -250.35637) (xy 135.274812 -250.256294) (xy 135.174736 -250.35637) (xy 135.174736 -250.40082)
			(xy 135.374888 -250.40082)
		)
		(stroke
			(width 0)
			(type solid)
		)
		(fill yes)
		(layer "In4.Cu")
		(net "M_J_CPU1_ALERT_R_N")
	)
	(gr_poly
		(pts
			(xy 135.374888 -248.736358) (xy 135.274812 -248.636282) (xy 135.174736 -248.736358) (xy 135.174736 -248.780808)
			(xy 135.374888 -248.780808)
		)
		(stroke
			(width 0)
			(type solid)
		)
		(fill yes)
		(layer "In4.Cu")
		(net "M_J_CPU1_SA_CB<5>")
	)
	(gr_poly
		(pts
			(xy 135.374888 -248.332498) (xy 135.374888 -248.288048) (xy 135.174736 -248.288048) (xy 135.174736 -248.332498)
			(xy 135.274812 -248.432574)
		)
		(stroke
			(width 0)
			(type solid)
		)
		(fill yes)
		(layer "In4.Cu")
		(net "M_J_CPU1_SA_CB<6>")
	)
	(gr_poly
		(pts
			(xy 135.374888 -247.116092) (xy 135.274812 -247.01627) (xy 135.174736 -247.116092) (xy 135.174736 -247.163844)
			(xy 135.374888 -247.163844)
		)
		(stroke
			(width 0)
			(type solid)
		)
		(fill yes)
		(layer "In4.Cu")
		(net "M_J_CPU1_SA_DQS_DN<9>")
	)
	(gr_poly
		(pts
			(xy 135.374888 -246.71274) (xy 135.374888 -246.664988) (xy 135.174736 -246.664988) (xy 135.174736 -246.71274)
			(xy 135.274812 -246.812562)
		)
		(stroke
			(width 0)
			(type solid)
		)
		(fill yes)
		(layer "In4.Cu")
		(net "M_J_CPU1_SA_DQS_DN<4>")
	)
	(gr_poly
		(pts
			(xy 135.374888 -245.496334) (xy 135.274812 -245.396258) (xy 135.174736 -245.496334) (xy 135.174736 -245.540784)
			(xy 135.374888 -245.540784)
		)
		(stroke
			(width 0)
			(type solid)
		)
		(fill yes)
		(layer "In4.Cu")
		(net "M_J_CPU1_SA_CB<1>")
	)
	(gr_poly
		(pts
			(xy 135.374888 -245.092474) (xy 135.374888 -245.048024) (xy 135.174736 -245.048024) (xy 135.174736 -245.092474)
			(xy 135.274812 -245.19255)
		)
		(stroke
			(width 0)
			(type solid)
		)
		(fill yes)
		(layer "In4.Cu")
		(net "M_J_CPU1_SA_CB<2>")
	)
	(gr_poly
		(pts
			(xy 135.374888 -243.876322) (xy 135.274812 -243.776246) (xy 135.174736 -243.876322) (xy 135.174736 -243.920772)
			(xy 135.374888 -243.920772)
		)
		(stroke
			(width 0)
			(type solid)
		)
		(fill yes)
		(layer "In4.Cu")
		(net "M_J_CPU1_SA_DQ<29>")
	)
	(gr_poly
		(pts
			(xy 135.374888 -243.472462) (xy 135.374888 -243.428012) (xy 135.174736 -243.428012) (xy 135.174736 -243.472462)
			(xy 135.274812 -243.572538)
		)
		(stroke
			(width 0)
			(type solid)
		)
		(fill yes)
		(layer "In4.Cu")
		(net "M_J_CPU1_SA_DQ<30>")
	)
	(gr_poly
		(pts
			(xy 135.374888 -242.256056) (xy 135.274812 -242.156234) (xy 135.174736 -242.256056) (xy 135.174736 -242.303808)
			(xy 135.374888 -242.303808)
		)
		(stroke
			(width 0)
			(type solid)
		)
		(fill yes)
		(layer "In4.Cu")
		(net "M_J_CPU1_SA_DQS_DN<8>")
	)
	(gr_poly
		(pts
			(xy 135.374888 -241.852704) (xy 135.374888 -241.804952) (xy 135.174736 -241.804952) (xy 135.174736 -241.852704)
			(xy 135.274812 -241.952526)
		)
		(stroke
			(width 0)
			(type solid)
		)
		(fill yes)
		(layer "In4.Cu")
		(net "M_J_CPU1_SA_DQS_DN<3>")
	)
	(gr_poly
		(pts
			(xy 135.374888 -240.636298) (xy 135.274812 -240.536222) (xy 135.174736 -240.636298) (xy 135.174736 -240.680748)
			(xy 135.374888 -240.680748)
		)
		(stroke
			(width 0)
			(type solid)
		)
		(fill yes)
		(layer "In4.Cu")
		(net "M_J_CPU1_SA_DQ<25>")
	)
	(gr_poly
		(pts
			(xy 135.374888 -240.232438) (xy 135.374888 -240.187988) (xy 135.174736 -240.187988) (xy 135.174736 -240.232438)
			(xy 135.274812 -240.332514)
		)
		(stroke
			(width 0)
			(type solid)
		)
		(fill yes)
		(layer "In4.Cu")
		(net "M_J_CPU1_SA_DQ<26>")
	)
	(gr_poly
		(pts
			(xy 135.374888 -239.016286) (xy 135.274812 -238.91621) (xy 135.174736 -239.016286) (xy 135.174736 -239.060736)
			(xy 135.374888 -239.060736)
		)
		(stroke
			(width 0)
			(type solid)
		)
		(fill yes)
		(layer "In4.Cu")
		(net "M_J_CPU1_SA_DQ<21>")
	)
	(gr_poly
		(pts
			(xy 135.374888 -238.612426) (xy 135.374888 -238.567976) (xy 135.174736 -238.567976) (xy 135.174736 -238.612426)
			(xy 135.274812 -238.712502)
		)
		(stroke
			(width 0)
			(type solid)
		)
		(fill yes)
		(layer "In4.Cu")
		(net "M_J_CPU1_SA_DQ<22>")
	)
	(gr_poly
		(pts
			(xy 135.374888 -237.39602) (xy 135.274812 -237.296198) (xy 135.174736 -237.39602) (xy 135.174736 -237.443772)
			(xy 135.374888 -237.443772)
		)
		(stroke
			(width 0)
			(type solid)
		)
		(fill yes)
		(layer "In4.Cu")
		(net "M_J_CPU1_SA_DQS_DN<7>")
	)
	(gr_poly
		(pts
			(xy 135.374888 -236.992668) (xy 135.374888 -236.944916) (xy 135.174736 -236.944916) (xy 135.174736 -236.992668)
			(xy 135.274812 -237.09249)
		)
		(stroke
			(width 0)
			(type solid)
		)
		(fill yes)
		(layer "In4.Cu")
		(net "M_J_CPU1_SA_DQS_DN<2>")
	)
	(gr_poly
		(pts
			(xy 135.374888 -235.776262) (xy 135.274812 -235.676186) (xy 135.174736 -235.776262) (xy 135.174736 -235.820712)
			(xy 135.374888 -235.820712)
		)
		(stroke
			(width 0)
			(type solid)
		)
		(fill yes)
		(layer "In4.Cu")
		(net "M_J_CPU1_SA_DQ<17>")
	)
	(gr_poly
		(pts
			(xy 135.374888 -235.372402) (xy 135.374888 -235.327952) (xy 135.174736 -235.327952) (xy 135.174736 -235.372402)
			(xy 135.274812 -235.472478)
		)
		(stroke
			(width 0)
			(type solid)
		)
		(fill yes)
		(layer "In4.Cu")
		(net "M_J_CPU1_SA_DQ<18>")
	)
	(gr_poly
		(pts
			(xy 135.374888 -234.15625) (xy 135.274812 -234.056174) (xy 135.174736 -234.15625) (xy 135.174736 -234.2007)
			(xy 135.374888 -234.2007)
		)
		(stroke
			(width 0)
			(type solid)
		)
		(fill yes)
		(layer "In4.Cu")
		(net "M_J_CPU1_SA_DQ<13>")
	)
	(gr_poly
		(pts
			(xy 135.374888 -233.75239) (xy 135.374888 -233.70794) (xy 135.174736 -233.70794) (xy 135.174736 -233.75239)
			(xy 135.274812 -233.852466)
		)
		(stroke
			(width 0)
			(type solid)
		)
		(fill yes)
		(layer "In4.Cu")
		(net "M_J_CPU1_SA_DQ<14>")
	)
	(gr_poly
		(pts
			(xy 135.374888 -232.535984) (xy 135.274812 -232.436162) (xy 135.174736 -232.535984) (xy 135.174736 -232.583736)
			(xy 135.374888 -232.583736)
		)
		(stroke
			(width 0)
			(type solid)
		)
		(fill yes)
		(layer "In4.Cu")
		(net "M_J_CPU1_SA_DQS_DN<6>")
	)
	(gr_poly
		(pts
			(xy 135.374888 -232.132632) (xy 135.374888 -232.08488) (xy 135.174736 -232.08488) (xy 135.174736 -232.132632)
			(xy 135.274812 -232.232454)
		)
		(stroke
			(width 0)
			(type solid)
		)
		(fill yes)
		(layer "In4.Cu")
		(net "M_J_CPU1_SA_DQS_DN<1>")
	)
	(gr_poly
		(pts
			(xy 135.374888 -230.916226) (xy 135.274812 -230.81615) (xy 135.174736 -230.916226) (xy 135.174736 -230.960676)
			(xy 135.374888 -230.960676)
		)
		(stroke
			(width 0)
			(type solid)
		)
		(fill yes)
		(layer "In4.Cu")
		(net "M_J_CPU1_SA_DQ<9>")
	)
	(gr_poly
		(pts
			(xy 135.374888 -230.51262) (xy 135.374888 -230.46817) (xy 135.174736 -230.46817) (xy 135.174736 -230.51262)
			(xy 135.274812 -230.612696)
		)
		(stroke
			(width 0)
			(type solid)
		)
		(fill yes)
		(layer "In4.Cu")
		(net "M_J_CPU1_SA_DQ<10>")
	)
	(gr_poly
		(pts
			(xy 135.374888 -229.296214) (xy 135.274812 -229.196138) (xy 135.174736 -229.296214) (xy 135.174736 -229.340664)
			(xy 135.374888 -229.340664)
		)
		(stroke
			(width 0)
			(type solid)
		)
		(fill yes)
		(layer "In4.Cu")
		(net "M_J_CPU1_SA_DQ<5>")
	)
	(gr_poly
		(pts
			(xy 135.374888 -228.892608) (xy 135.374888 -228.848158) (xy 135.174736 -228.848158) (xy 135.174736 -228.892608)
			(xy 135.274812 -228.992684)
		)
		(stroke
			(width 0)
			(type solid)
		)
		(fill yes)
		(layer "In4.Cu")
		(net "M_J_CPU1_SA_DQ<6>")
	)
	(gr_poly
		(pts
			(xy 135.374888 -227.676202) (xy 135.274812 -227.57638) (xy 135.174736 -227.676202) (xy 135.174736 -227.723954)
			(xy 135.374888 -227.723954)
		)
		(stroke
			(width 0)
			(type solid)
		)
		(fill yes)
		(layer "In4.Cu")
		(net "M_J_CPU1_SA_DQS_DN<5>")
	)
	(gr_poly
		(pts
			(xy 135.374888 -227.27285) (xy 135.374888 -227.225098) (xy 135.174736 -227.225098) (xy 135.174736 -227.27285)
			(xy 135.274812 -227.372672)
		)
		(stroke
			(width 0)
			(type solid)
		)
		(fill yes)
		(layer "In4.Cu")
		(net "M_J_CPU1_SA_DQS_DN<0>")
	)
	(gr_poly
		(pts
			(xy 135.374888 -226.056444) (xy 135.274812 -225.956368) (xy 135.174736 -226.056444) (xy 135.174736 -226.100894)
			(xy 135.374888 -226.100894)
		)
		(stroke
			(width 0)
			(type solid)
		)
		(fill yes)
		(layer "In4.Cu")
		(net "M_J_CPU1_SA_DQ<1>")
	)
	(gr_poly
		(pts
			(xy 135.374888 -225.652584) (xy 135.374888 -225.608134) (xy 135.174736 -225.608134) (xy 135.174736 -225.652584)
			(xy 135.274812 -225.75266)
		)
		(stroke
			(width 0)
			(type solid)
		)
		(fill yes)
		(layer "In4.Cu")
		(net "M_J_CPU1_SA_DQ<2>")
	)
	(gr_poly
		(pts
			(xy 135.674862 -293.32428) (xy 135.674862 -293.27983) (xy 135.47471 -293.27983) (xy 135.47471 -293.32428)
			(xy 135.574786 -293.424356)
		)
		(stroke
			(width 0)
			(type solid)
		)
		(fill yes)
		(layer "In4.Cu")
		(net "M_J_CPU1_SB_DQ<31>")
	)
	(gr_poly
		(pts
			(xy 135.674862 -292.108128) (xy 135.574786 -292.008052) (xy 135.47471 -292.108128) (xy 135.47471 -292.152578)
			(xy 135.674862 -292.152578)
		)
		(stroke
			(width 0)
			(type solid)
		)
		(fill yes)
		(layer "In4.Cu")
		(net "M_J_CPU1_SB_DQ<28>")
	)
	(gr_poly
		(pts
			(xy 135.674862 -291.704522) (xy 135.674862 -291.65677) (xy 135.47471 -291.65677) (xy 135.47471 -291.704522)
			(xy 135.574786 -291.804344)
		)
		(stroke
			(width 0)
			(type solid)
		)
		(fill yes)
		(layer "In4.Cu")
		(net "M_J_CPU1_SB_DQS_DP<8>")
	)
	(gr_poly
		(pts
			(xy 135.674862 -290.487862) (xy 135.574786 -290.38804) (xy 135.47471 -290.487862) (xy 135.47471 -290.535614)
			(xy 135.674862 -290.535614)
		)
		(stroke
			(width 0)
			(type solid)
		)
		(fill yes)
		(layer "In4.Cu")
		(net "M_J_CPU1_SB_DQS_DP<3>")
	)
	(gr_poly
		(pts
			(xy 135.674862 -290.084256) (xy 135.674862 -290.039806) (xy 135.47471 -290.039806) (xy 135.47471 -290.084256)
			(xy 135.574786 -290.184332)
		)
		(stroke
			(width 0)
			(type solid)
		)
		(fill yes)
		(layer "In4.Cu")
		(net "M_J_CPU1_SB_DQ<27>")
	)
	(gr_poly
		(pts
			(xy 135.674862 -288.868104) (xy 135.574786 -288.768028) (xy 135.47471 -288.868104) (xy 135.47471 -288.912554)
			(xy 135.674862 -288.912554)
		)
		(stroke
			(width 0)
			(type solid)
		)
		(fill yes)
		(layer "In4.Cu")
		(net "M_J_CPU1_SB_DQ<24>")
	)
	(gr_poly
		(pts
			(xy 135.674862 -288.464498) (xy 135.674862 -288.420048) (xy 135.47471 -288.420048) (xy 135.47471 -288.464498)
			(xy 135.574786 -288.564574)
		)
		(stroke
			(width 0)
			(type solid)
		)
		(fill yes)
		(layer "In4.Cu")
		(net "M_J_CPU1_SB_DQ<23>")
	)
	(gr_poly
		(pts
			(xy 135.674862 -287.248092) (xy 135.574786 -287.148016) (xy 135.47471 -287.248092) (xy 135.47471 -287.292542)
			(xy 135.674862 -287.292542)
		)
		(stroke
			(width 0)
			(type solid)
		)
		(fill yes)
		(layer "In4.Cu")
		(net "M_J_CPU1_SB_DQ<20>")
	)
	(gr_poly
		(pts
			(xy 135.674862 -286.844486) (xy 135.674862 -286.796734) (xy 135.47471 -286.796734) (xy 135.47471 -286.844486)
			(xy 135.574786 -286.944562)
		)
		(stroke
			(width 0)
			(type solid)
		)
		(fill yes)
		(layer "In4.Cu")
		(net "M_J_CPU1_SB_DQS_DP<7>")
	)
	(gr_poly
		(pts
			(xy 135.674862 -285.62808) (xy 135.574786 -285.528258) (xy 135.47471 -285.62808) (xy 135.47471 -285.675832)
			(xy 135.674862 -285.675832)
		)
		(stroke
			(width 0)
			(type solid)
		)
		(fill yes)
		(layer "In4.Cu")
		(net "M_J_CPU1_SB_DQS_DP<2>")
	)
	(gr_poly
		(pts
			(xy 135.674862 -285.224474) (xy 135.674862 -285.180024) (xy 135.47471 -285.180024) (xy 135.47471 -285.224474)
			(xy 135.574786 -285.32455)
		)
		(stroke
			(width 0)
			(type solid)
		)
		(fill yes)
		(layer "In4.Cu")
		(net "M_J_CPU1_SB_DQ<19>")
	)
	(gr_poly
		(pts
			(xy 135.674862 -284.008322) (xy 135.574786 -283.908246) (xy 135.47471 -284.008322) (xy 135.47471 -284.052772)
			(xy 135.674862 -284.052772)
		)
		(stroke
			(width 0)
			(type solid)
		)
		(fill yes)
		(layer "In4.Cu")
		(net "M_J_CPU1_SB_DQ<16>")
	)
	(gr_poly
		(pts
			(xy 135.674862 -283.604462) (xy 135.674862 -283.560012) (xy 135.47471 -283.560012) (xy 135.47471 -283.604462)
			(xy 135.574786 -283.704538)
		)
		(stroke
			(width 0)
			(type solid)
		)
		(fill yes)
		(layer "In4.Cu")
		(net "M_J_CPU1_SB_DQ<15>")
	)
	(gr_poly
		(pts
			(xy 135.674862 -282.38831) (xy 135.574786 -282.288234) (xy 135.47471 -282.38831) (xy 135.47471 -282.43276)
			(xy 135.674862 -282.43276)
		)
		(stroke
			(width 0)
			(type solid)
		)
		(fill yes)
		(layer "In4.Cu")
		(net "M_J_CPU1_SB_DQ<12>")
	)
	(gr_poly
		(pts
			(xy 135.674862 -281.984704) (xy 135.674862 -281.936952) (xy 135.47471 -281.936952) (xy 135.47471 -281.984704)
			(xy 135.574786 -282.084526)
		)
		(stroke
			(width 0)
			(type solid)
		)
		(fill yes)
		(layer "In4.Cu")
		(net "M_J_CPU1_SB_DQS_DP<6>")
	)
	(gr_poly
		(pts
			(xy 135.674862 -280.768044) (xy 135.574786 -280.668222) (xy 135.47471 -280.768044) (xy 135.47471 -280.815796)
			(xy 135.674862 -280.815796)
		)
		(stroke
			(width 0)
			(type solid)
		)
		(fill yes)
		(layer "In4.Cu")
		(net "M_J_CPU1_SB_DQS_DP<1>")
	)
	(gr_poly
		(pts
			(xy 135.674862 -280.364438) (xy 135.674862 -280.319988) (xy 135.47471 -280.319988) (xy 135.47471 -280.364438)
			(xy 135.574786 -280.464514)
		)
		(stroke
			(width 0)
			(type solid)
		)
		(fill yes)
		(layer "In4.Cu")
		(net "M_J_CPU1_SB_DQ<11>")
	)
	(gr_poly
		(pts
			(xy 135.674862 -279.148286) (xy 135.574786 -279.04821) (xy 135.47471 -279.148286) (xy 135.47471 -279.192736)
			(xy 135.674862 -279.192736)
		)
		(stroke
			(width 0)
			(type solid)
		)
		(fill yes)
		(layer "In4.Cu")
		(net "M_J_CPU1_SB_DQ<8>")
	)
	(gr_poly
		(pts
			(xy 135.674862 -278.744426) (xy 135.674862 -278.699976) (xy 135.47471 -278.699976) (xy 135.47471 -278.744426)
			(xy 135.574786 -278.844502)
		)
		(stroke
			(width 0)
			(type solid)
		)
		(fill yes)
		(layer "In4.Cu")
		(net "M_J_CPU1_SB_DQ<7>")
	)
	(gr_poly
		(pts
			(xy 135.674862 -277.528274) (xy 135.574786 -277.428198) (xy 135.47471 -277.528274) (xy 135.47471 -277.572724)
			(xy 135.674862 -277.572724)
		)
		(stroke
			(width 0)
			(type solid)
		)
		(fill yes)
		(layer "In4.Cu")
		(net "M_J_CPU1_SB_DQ<4>")
	)
	(gr_poly
		(pts
			(xy 135.674862 -277.124668) (xy 135.674862 -277.076916) (xy 135.47471 -277.076916) (xy 135.47471 -277.124668)
			(xy 135.574786 -277.22449)
		)
		(stroke
			(width 0)
			(type solid)
		)
		(fill yes)
		(layer "In4.Cu")
		(net "M_J_CPU1_SB_DQS_DP<5>")
	)
	(gr_poly
		(pts
			(xy 135.674862 -275.908008) (xy 135.574786 -275.808186) (xy 135.47471 -275.908008) (xy 135.47471 -275.95576)
			(xy 135.674862 -275.95576)
		)
		(stroke
			(width 0)
			(type solid)
		)
		(fill yes)
		(layer "In4.Cu")
		(net "M_J_CPU1_SB_DQS_DP<0>")
	)
	(gr_poly
		(pts
			(xy 135.674862 -275.504402) (xy 135.674862 -275.459952) (xy 135.47471 -275.459952) (xy 135.47471 -275.504402)
			(xy 135.574786 -275.604478)
		)
		(stroke
			(width 0)
			(type solid)
		)
		(fill yes)
		(layer "In4.Cu")
		(net "M_J_CPU1_SB_DQ<3>")
	)
	(gr_poly
		(pts
			(xy 135.674862 -274.28825) (xy 135.574786 -274.188174) (xy 135.47471 -274.28825) (xy 135.47471 -274.3327)
			(xy 135.674862 -274.3327)
		)
		(stroke
			(width 0)
			(type solid)
		)
		(fill yes)
		(layer "In4.Cu")
		(net "M_J_CPU1_SB_DQ<0>")
	)
	(gr_poly
		(pts
			(xy 135.674862 -273.88439) (xy 135.674862 -273.83994) (xy 135.47471 -273.83994) (xy 135.47471 -273.88439)
			(xy 135.574786 -273.984466)
		)
		(stroke
			(width 0)
			(type solid)
		)
		(fill yes)
		(layer "In4.Cu")
		(net "M_J_CPU1_SB_CB<3>")
	)
	(gr_poly
		(pts
			(xy 135.674862 -272.668238) (xy 135.574786 -272.568162) (xy 135.47471 -272.668238) (xy 135.47471 -272.712688)
			(xy 135.674862 -272.712688)
		)
		(stroke
			(width 0)
			(type solid)
		)
		(fill yes)
		(layer "In4.Cu")
		(net "M_J_CPU1_SB_CB<0>")
	)
	(gr_poly
		(pts
			(xy 135.674862 -272.264632) (xy 135.674862 -272.21688) (xy 135.47471 -272.21688) (xy 135.47471 -272.264632)
			(xy 135.574786 -272.364454)
		)
		(stroke
			(width 0)
			(type solid)
		)
		(fill yes)
		(layer "In4.Cu")
		(net "M_J_CPU1_SB_DQS_DP<4>")
	)
	(gr_poly
		(pts
			(xy 135.674862 -271.047972) (xy 135.574786 -270.94815) (xy 135.47471 -271.047972) (xy 135.47471 -271.095724)
			(xy 135.674862 -271.095724)
		)
		(stroke
			(width 0)
			(type solid)
		)
		(fill yes)
		(layer "In4.Cu")
		(net "M_J_CPU1_SB_DQS_DP<9>")
	)
	(gr_poly
		(pts
			(xy 135.674862 -270.644366) (xy 135.674862 -270.599916) (xy 135.47471 -270.599916) (xy 135.47471 -270.644366)
			(xy 135.574786 -270.744442)
		)
		(stroke
			(width 0)
			(type solid)
		)
		(fill yes)
		(layer "In4.Cu")
		(net "M_J_CPU1_SB_CB<7>")
	)
	(gr_poly
		(pts
			(xy 135.674862 -269.428214) (xy 135.574786 -269.328138) (xy 135.47471 -269.428214) (xy 135.47471 -269.472664)
			(xy 135.674862 -269.472664)
		)
		(stroke
			(width 0)
			(type solid)
		)
		(fill yes)
		(layer "In4.Cu")
		(net "M_J_CPU1_SB_CB<4>")
	)
	(gr_poly
		(pts
			(xy 135.674862 -267.808202) (xy 135.574786 -267.708126) (xy 135.47471 -267.808202) (xy 135.47471 -267.852652)
			(xy 135.674862 -267.852652)
		)
		(stroke
			(width 0)
			(type solid)
		)
		(fill yes)
		(layer "In4.Cu")
		(net "M_J_CPU1_SB_RSP<0>")
	)
	(gr_poly
		(pts
			(xy 135.674862 -265.78433) (xy 135.674862 -265.73988) (xy 135.47471 -265.73988) (xy 135.47471 -265.78433)
			(xy 135.574786 -265.884406)
		)
		(stroke
			(width 0)
			(type solid)
		)
		(fill yes)
		(layer "In4.Cu")
		(net "M_J_CPU1_SB_CS_N<0>")
	)
	(gr_poly
		(pts
			(xy 135.674862 -264.568178) (xy 135.574786 -264.468102) (xy 135.47471 -264.568178) (xy 135.47471 -264.612628)
			(xy 135.674862 -264.612628)
		)
		(stroke
			(width 0)
			(type solid)
		)
		(fill yes)
		(layer "In4.Cu")
		(net "M_J_CPU1_SB_CA<6>")
	)
	(gr_poly
		(pts
			(xy 135.674862 -264.164318) (xy 135.674862 -264.119868) (xy 135.47471 -264.119868) (xy 135.47471 -264.164318)
			(xy 135.574786 -264.264394)
		)
		(stroke
			(width 0)
			(type solid)
		)
		(fill yes)
		(layer "In4.Cu")
		(net "M_J_CPU1_SB_CA<5>")
	)
	(gr_poly
		(pts
			(xy 135.674862 -262.948166) (xy 135.574786 -262.84809) (xy 135.47471 -262.948166) (xy 135.47471 -262.992616)
			(xy 135.674862 -262.992616)
		)
		(stroke
			(width 0)
			(type solid)
		)
		(fill yes)
		(layer "In4.Cu")
		(net "M_J_CPU1_SB_CA<2>")
	)
	(gr_poly
		(pts
			(xy 135.674862 -262.544306) (xy 135.674862 -262.499856) (xy 135.47471 -262.499856) (xy 135.47471 -262.544306)
			(xy 135.574786 -262.644382)
		)
		(stroke
			(width 0)
			(type solid)
		)
		(fill yes)
		(layer "In4.Cu")
		(net "M_J_CPU1_SB_CA<1>")
	)
	(gr_poly
		(pts
			(xy 135.844788 -256.026158) (xy 135.744712 -255.926336) (xy 135.644636 -256.026158) (xy 135.644636 -256.07391)
			(xy 135.844788 -256.07391)
		)
		(stroke
			(width 0)
			(type solid)
		)
		(fill yes)
		(layer "In4.Cu")
		(net "M_J_CPU1_CLK_DP<0>")
	)
	(gr_poly
		(pts
			(xy 135.844788 -255.622552) (xy 135.844788 -255.578102) (xy 135.644636 -255.578102) (xy 135.644636 -255.622552)
			(xy 135.744712 -255.722628)
		)
		(stroke
			(width 0)
			(type solid)
		)
		(fill yes)
		(layer "In4.Cu")
		(net "M_J_CPU1_SA_PAR")
	)
	(gr_poly
		(pts
			(xy 135.844788 -254.4064) (xy 135.744712 -254.306324) (xy 135.644636 -254.4064) (xy 135.644636 -254.45085)
			(xy 135.844788 -254.45085)
		)
		(stroke
			(width 0)
			(type solid)
		)
		(fill yes)
		(layer "In4.Cu")
		(net "M_J_CPU1_SA_CA<4>")
	)
	(gr_poly
		(pts
			(xy 135.844788 -254.00254) (xy 135.844788 -253.95809) (xy 135.644636 -253.95809) (xy 135.644636 -254.00254)
			(xy 135.744712 -254.102616)
		)
		(stroke
			(width 0)
			(type solid)
		)
		(fill yes)
		(layer "In4.Cu")
		(net "M_J_CPU1_SA_CA<3>")
	)
	(gr_poly
		(pts
			(xy 135.844788 -252.786388) (xy 135.744712 -252.686312) (xy 135.644636 -252.786388) (xy 135.644636 -252.830838)
			(xy 135.844788 -252.830838)
		)
		(stroke
			(width 0)
			(type solid)
		)
		(fill yes)
		(layer "In4.Cu")
		(net "M_J_CPU1_SA_CA<0>")
	)
	(gr_poly
		(pts
			(xy 135.844788 -251.166376) (xy 135.744712 -251.0663) (xy 135.644636 -251.166376) (xy 135.644636 -251.210826)
			(xy 135.844788 -251.210826)
		)
		(stroke
			(width 0)
			(type solid)
		)
		(fill yes)
		(layer "In4.Cu")
		(net "M_J_CPU1_SA_CS_N<0>")
	)
	(gr_poly
		(pts
			(xy 135.844788 -250.762516) (xy 135.844788 -250.718066) (xy 135.644636 -250.718066) (xy 135.644636 -250.762516)
			(xy 135.744712 -250.862592)
		)
		(stroke
			(width 0)
			(type solid)
		)
		(fill yes)
		(layer "In4.Cu")
		(net "M_J_CPU1_RESET_N")
	)
	(gr_poly
		(pts
			(xy 135.844788 -249.142504) (xy 135.844788 -249.098054) (xy 135.644636 -249.098054) (xy 135.644636 -249.142504)
			(xy 135.744712 -249.24258)
		)
		(stroke
			(width 0)
			(type solid)
		)
		(fill yes)
		(layer "In4.Cu")
		(net "M_J_CPU1_SA_CB<7>")
	)
	(gr_poly
		(pts
			(xy 135.844788 -247.926352) (xy 135.744712 -247.826276) (xy 135.644636 -247.926352) (xy 135.644636 -247.970802)
			(xy 135.844788 -247.970802)
		)
		(stroke
			(width 0)
			(type solid)
		)
		(fill yes)
		(layer "In4.Cu")
		(net "M_J_CPU1_SA_CB<4>")
	)
	(gr_poly
		(pts
			(xy 135.844788 -247.522746) (xy 135.844788 -247.474994) (xy 135.644636 -247.474994) (xy 135.644636 -247.522746)
			(xy 135.744712 -247.622568)
		)
		(stroke
			(width 0)
			(type solid)
		)
		(fill yes)
		(layer "In4.Cu")
		(net "M_J_CPU1_SA_DQS_DP<9>")
	)
	(gr_poly
		(pts
			(xy 135.844788 -246.306086) (xy 135.744712 -246.206264) (xy 135.644636 -246.306086) (xy 135.644636 -246.353838)
			(xy 135.844788 -246.353838)
		)
		(stroke
			(width 0)
			(type solid)
		)
		(fill yes)
		(layer "In4.Cu")
		(net "M_J_CPU1_SA_DQS_DP<4>")
	)
	(gr_poly
		(pts
			(xy 135.844788 -245.90248) (xy 135.844788 -245.85803) (xy 135.644636 -245.85803) (xy 135.644636 -245.90248)
			(xy 135.744712 -246.002556)
		)
		(stroke
			(width 0)
			(type solid)
		)
		(fill yes)
		(layer "In4.Cu")
		(net "M_J_CPU1_SA_CB<3>")
	)
	(gr_poly
		(pts
			(xy 135.844788 -244.686328) (xy 135.744712 -244.586252) (xy 135.644636 -244.686328) (xy 135.644636 -244.730778)
			(xy 135.844788 -244.730778)
		)
		(stroke
			(width 0)
			(type solid)
		)
		(fill yes)
		(layer "In4.Cu")
		(net "M_J_CPU1_SA_CB<0>")
	)
	(gr_poly
		(pts
			(xy 135.844788 -244.282468) (xy 135.844788 -244.238018) (xy 135.644636 -244.238018) (xy 135.644636 -244.282468)
			(xy 135.744712 -244.382544)
		)
		(stroke
			(width 0)
			(type solid)
		)
		(fill yes)
		(layer "In4.Cu")
		(net "M_J_CPU1_SA_DQ<31>")
	)
	(gr_poly
		(pts
			(xy 135.844788 -243.066316) (xy 135.744712 -242.96624) (xy 135.644636 -243.066316) (xy 135.644636 -243.110766)
			(xy 135.844788 -243.110766)
		)
		(stroke
			(width 0)
			(type solid)
		)
		(fill yes)
		(layer "In4.Cu")
		(net "M_J_CPU1_SA_DQ<28>")
	)
	(gr_poly
		(pts
			(xy 135.844788 -242.66271) (xy 135.844788 -242.614958) (xy 135.644636 -242.614958) (xy 135.644636 -242.66271)
			(xy 135.744712 -242.762532)
		)
		(stroke
			(width 0)
			(type solid)
		)
		(fill yes)
		(layer "In4.Cu")
		(net "M_J_CPU1_SA_DQS_DP<8>")
	)
	(gr_poly
		(pts
			(xy 135.844788 -241.44605) (xy 135.744712 -241.346228) (xy 135.644636 -241.44605) (xy 135.644636 -241.493802)
			(xy 135.844788 -241.493802)
		)
		(stroke
			(width 0)
			(type solid)
		)
		(fill yes)
		(layer "In4.Cu")
		(net "M_J_CPU1_SA_DQS_DP<3>")
	)
	(gr_poly
		(pts
			(xy 135.844788 -241.042444) (xy 135.844788 -240.997994) (xy 135.644636 -240.997994) (xy 135.644636 -241.042444)
			(xy 135.744712 -241.14252)
		)
		(stroke
			(width 0)
			(type solid)
		)
		(fill yes)
		(layer "In4.Cu")
		(net "M_J_CPU1_SA_DQ<27>")
	)
	(gr_poly
		(pts
			(xy 135.844788 -239.826292) (xy 135.744712 -239.726216) (xy 135.644636 -239.826292) (xy 135.644636 -239.870742)
			(xy 135.844788 -239.870742)
		)
		(stroke
			(width 0)
			(type solid)
		)
		(fill yes)
		(layer "In4.Cu")
		(net "M_J_CPU1_SA_DQ<24>")
	)
	(gr_poly
		(pts
			(xy 135.844788 -239.422432) (xy 135.844788 -239.377982) (xy 135.644636 -239.377982) (xy 135.644636 -239.422432)
			(xy 135.744712 -239.522508)
		)
		(stroke
			(width 0)
			(type solid)
		)
		(fill yes)
		(layer "In4.Cu")
		(net "M_J_CPU1_SA_DQ<23>")
	)
	(gr_poly
		(pts
			(xy 135.844788 -238.20628) (xy 135.744712 -238.106204) (xy 135.644636 -238.20628) (xy 135.644636 -238.25073)
			(xy 135.844788 -238.25073)
		)
		(stroke
			(width 0)
			(type solid)
		)
		(fill yes)
		(layer "In4.Cu")
		(net "M_J_CPU1_SA_DQ<20>")
	)
	(gr_poly
		(pts
			(xy 135.844788 -237.802674) (xy 135.844788 -237.754922) (xy 135.644636 -237.754922) (xy 135.644636 -237.802674)
			(xy 135.744712 -237.902496)
		)
		(stroke
			(width 0)
			(type solid)
		)
		(fill yes)
		(layer "In4.Cu")
		(net "M_J_CPU1_SA_DQS_DP<7>")
	)
	(gr_poly
		(pts
			(xy 135.844788 -236.586014) (xy 135.744712 -236.486192) (xy 135.644636 -236.586014) (xy 135.644636 -236.633766)
			(xy 135.844788 -236.633766)
		)
		(stroke
			(width 0)
			(type solid)
		)
		(fill yes)
		(layer "In4.Cu")
		(net "M_J_CPU1_SA_DQS_DP<2>")
	)
	(gr_poly
		(pts
			(xy 135.844788 -236.182408) (xy 135.844788 -236.137958) (xy 135.644636 -236.137958) (xy 135.644636 -236.182408)
			(xy 135.744712 -236.282484)
		)
		(stroke
			(width 0)
			(type solid)
		)
		(fill yes)
		(layer "In4.Cu")
		(net "M_J_CPU1_SA_DQ<19>")
	)
	(gr_poly
		(pts
			(xy 135.844788 -234.966256) (xy 135.744712 -234.86618) (xy 135.644636 -234.966256) (xy 135.644636 -235.010706)
			(xy 135.844788 -235.010706)
		)
		(stroke
			(width 0)
			(type solid)
		)
		(fill yes)
		(layer "In4.Cu")
		(net "M_J_CPU1_SA_DQ<16>")
	)
	(gr_poly
		(pts
			(xy 135.844788 -234.562396) (xy 135.844788 -234.517946) (xy 135.644636 -234.517946) (xy 135.644636 -234.562396)
			(xy 135.744712 -234.662472)
		)
		(stroke
			(width 0)
			(type solid)
		)
		(fill yes)
		(layer "In4.Cu")
		(net "M_J_CPU1_SA_DQ<15>")
	)
	(gr_poly
		(pts
			(xy 135.844788 -233.346244) (xy 135.744712 -233.246168) (xy 135.644636 -233.346244) (xy 135.644636 -233.390694)
			(xy 135.844788 -233.390694)
		)
		(stroke
			(width 0)
			(type solid)
		)
		(fill yes)
		(layer "In4.Cu")
		(net "M_J_CPU1_SA_DQ<12>")
	)
	(gr_poly
		(pts
			(xy 135.844788 -232.942638) (xy 135.844788 -232.894886) (xy 135.644636 -232.894886) (xy 135.644636 -232.942638)
			(xy 135.744712 -233.04246)
		)
		(stroke
			(width 0)
			(type solid)
		)
		(fill yes)
		(layer "In4.Cu")
		(net "M_J_CPU1_SA_DQS_DP<6>")
	)
	(gr_poly
		(pts
			(xy 135.844788 -231.725978) (xy 135.744712 -231.626156) (xy 135.644636 -231.725978) (xy 135.644636 -231.77373)
			(xy 135.844788 -231.77373)
		)
		(stroke
			(width 0)
			(type solid)
		)
		(fill yes)
		(layer "In4.Cu")
		(net "M_J_CPU1_SA_DQS_DP<1>")
	)
	(gr_poly
		(pts
			(xy 135.844788 -231.322626) (xy 135.844788 -231.278176) (xy 135.644636 -231.278176) (xy 135.644636 -231.322626)
			(xy 135.744712 -231.422702)
		)
		(stroke
			(width 0)
			(type solid)
		)
		(fill yes)
		(layer "In4.Cu")
		(net "M_J_CPU1_SA_DQ<11>")
	)
	(gr_poly
		(pts
			(xy 135.844788 -230.10622) (xy 135.744712 -230.006144) (xy 135.644636 -230.10622) (xy 135.644636 -230.15067)
			(xy 135.844788 -230.15067)
		)
		(stroke
			(width 0)
			(type solid)
		)
		(fill yes)
		(layer "In4.Cu")
		(net "M_J_CPU1_SA_DQ<8>")
	)
	(gr_poly
		(pts
			(xy 135.844788 -229.702614) (xy 135.844788 -229.658164) (xy 135.644636 -229.658164) (xy 135.644636 -229.702614)
			(xy 135.744712 -229.80269)
		)
		(stroke
			(width 0)
			(type solid)
		)
		(fill yes)
		(layer "In4.Cu")
		(net "M_J_CPU1_SA_DQ<7>")
	)
	(gr_poly
		(pts
			(xy 135.844788 -228.486462) (xy 135.744712 -228.386386) (xy 135.644636 -228.486462) (xy 135.644636 -228.530912)
			(xy 135.844788 -228.530912)
		)
		(stroke
			(width 0)
			(type solid)
		)
		(fill yes)
		(layer "In4.Cu")
		(net "M_J_CPU1_SA_DQ<4>")
	)
	(gr_poly
		(pts
			(xy 135.844788 -228.082856) (xy 135.844788 -228.035104) (xy 135.644636 -228.035104) (xy 135.644636 -228.082856)
			(xy 135.744712 -228.182678)
		)
		(stroke
			(width 0)
			(type solid)
		)
		(fill yes)
		(layer "In4.Cu")
		(net "M_J_CPU1_SA_DQS_DP<5>")
	)
	(gr_poly
		(pts
			(xy 135.844788 -226.866196) (xy 135.744712 -226.766374) (xy 135.644636 -226.866196) (xy 135.644636 -226.913948)
			(xy 135.844788 -226.913948)
		)
		(stroke
			(width 0)
			(type solid)
		)
		(fill yes)
		(layer "In4.Cu")
		(net "M_J_CPU1_SA_DQS_DP<0>")
	)
	(gr_poly
		(pts
			(xy 135.844788 -226.46259) (xy 135.844788 -226.41814) (xy 135.644636 -226.41814) (xy 135.644636 -226.46259)
			(xy 135.744712 -226.562666)
		)
		(stroke
			(width 0)
			(type solid)
		)
		(fill yes)
		(layer "In4.Cu")
		(net "M_J_CPU1_SA_DQ<3>")
	)
	(gr_poly
		(pts
			(xy 135.844788 -225.246438) (xy 135.744712 -225.146362) (xy 135.644636 -225.246438) (xy 135.644636 -225.290888)
			(xy 135.844788 -225.290888)
		)
		(stroke
			(width 0)
			(type solid)
		)
		(fill yes)
		(layer "In4.Cu")
		(net "M_J_CPU1_SA_DQ<0>")
	)
	(gr_poly
		(pts
			(xy 136.144762 -292.918134) (xy 136.044686 -292.818058) (xy 135.94461 -292.918134) (xy 135.94461 -292.962584)
			(xy 136.144762 -292.962584)
		)
		(stroke
			(width 0)
			(type solid)
		)
		(fill yes)
		(layer "In4.Cu")
		(net "M_J_CPU1_SB_DQ<29>")
	)
	(gr_poly
		(pts
			(xy 136.144762 -292.514274) (xy 136.144762 -292.469824) (xy 135.94461 -292.469824) (xy 135.94461 -292.514274)
			(xy 136.044686 -292.61435)
		)
		(stroke
			(width 0)
			(type solid)
		)
		(fill yes)
		(layer "In4.Cu")
		(net "M_J_CPU1_SB_DQ<30>")
	)
	(gr_poly
		(pts
			(xy 136.144762 -291.297868) (xy 136.044686 -291.198046) (xy 135.94461 -291.297868) (xy 135.94461 -291.34562)
			(xy 136.144762 -291.34562)
		)
		(stroke
			(width 0)
			(type solid)
		)
		(fill yes)
		(layer "In4.Cu")
		(net "M_J_CPU1_SB_DQS_DN<8>")
	)
	(gr_poly
		(pts
			(xy 136.144762 -290.894516) (xy 136.144762 -290.846764) (xy 135.94461 -290.846764) (xy 135.94461 -290.894516)
			(xy 136.044686 -290.994338)
		)
		(stroke
			(width 0)
			(type solid)
		)
		(fill yes)
		(layer "In4.Cu")
		(net "M_J_CPU1_SB_DQS_DN<3>")
	)
	(gr_poly
		(pts
			(xy 136.144762 -289.67811) (xy 136.044686 -289.578034) (xy 135.94461 -289.67811) (xy 135.94461 -289.72256)
			(xy 136.144762 -289.72256)
		)
		(stroke
			(width 0)
			(type solid)
		)
		(fill yes)
		(layer "In4.Cu")
		(net "M_J_CPU1_SB_DQ<25>")
	)
	(gr_poly
		(pts
			(xy 136.144762 -289.27425) (xy 136.144762 -289.2298) (xy 135.94461 -289.2298) (xy 135.94461 -289.27425)
			(xy 136.044686 -289.374326)
		)
		(stroke
			(width 0)
			(type solid)
		)
		(fill yes)
		(layer "In4.Cu")
		(net "M_J_CPU1_SB_DQ<26>")
	)
	(gr_poly
		(pts
			(xy 136.144762 -288.058098) (xy 136.044686 -287.958022) (xy 135.94461 -288.058098) (xy 135.94461 -288.102548)
			(xy 136.144762 -288.102548)
		)
		(stroke
			(width 0)
			(type solid)
		)
		(fill yes)
		(layer "In4.Cu")
		(net "M_J_CPU1_SB_DQ<21>")
	)
	(gr_poly
		(pts
			(xy 136.144762 -287.654492) (xy 136.144762 -287.610042) (xy 135.94461 -287.610042) (xy 135.94461 -287.654492)
			(xy 136.044686 -287.754568)
		)
		(stroke
			(width 0)
			(type solid)
		)
		(fill yes)
		(layer "In4.Cu")
		(net "M_J_CPU1_SB_DQ<22>")
	)
	(gr_poly
		(pts
			(xy 136.144762 -286.438086) (xy 136.044686 -286.33801) (xy 135.94461 -286.438086) (xy 135.94461 -286.485838)
			(xy 136.144762 -286.485838)
		)
		(stroke
			(width 0)
			(type solid)
		)
		(fill yes)
		(layer "In4.Cu")
		(net "M_J_CPU1_SB_DQS_DN<7>")
	)
	(gr_poly
		(pts
			(xy 136.144762 -286.034734) (xy 136.144762 -285.986982) (xy 135.94461 -285.986982) (xy 135.94461 -286.034734)
			(xy 136.044686 -286.134556)
		)
		(stroke
			(width 0)
			(type solid)
		)
		(fill yes)
		(layer "In4.Cu")
		(net "M_J_CPU1_SB_DQS_DN<2>")
	)
	(gr_poly
		(pts
			(xy 136.144762 -284.818328) (xy 136.044686 -284.718252) (xy 135.94461 -284.818328) (xy 135.94461 -284.862778)
			(xy 136.144762 -284.862778)
		)
		(stroke
			(width 0)
			(type solid)
		)
		(fill yes)
		(layer "In4.Cu")
		(net "M_J_CPU1_SB_DQ<17>")
	)
	(gr_poly
		(pts
			(xy 136.144762 -284.414468) (xy 136.144762 -284.370018) (xy 135.94461 -284.370018) (xy 135.94461 -284.414468)
			(xy 136.044686 -284.514544)
		)
		(stroke
			(width 0)
			(type solid)
		)
		(fill yes)
		(layer "In4.Cu")
		(net "M_J_CPU1_SB_DQ<18>")
	)
	(gr_poly
		(pts
			(xy 136.144762 -283.198316) (xy 136.044686 -283.09824) (xy 135.94461 -283.198316) (xy 135.94461 -283.242766)
			(xy 136.144762 -283.242766)
		)
		(stroke
			(width 0)
			(type solid)
		)
		(fill yes)
		(layer "In4.Cu")
		(net "M_J_CPU1_SB_DQ<13>")
	)
	(gr_poly
		(pts
			(xy 136.144762 -282.794456) (xy 136.144762 -282.750006) (xy 135.94461 -282.750006) (xy 135.94461 -282.794456)
			(xy 136.044686 -282.894532)
		)
		(stroke
			(width 0)
			(type solid)
		)
		(fill yes)
		(layer "In4.Cu")
		(net "M_J_CPU1_SB_DQ<14>")
	)
	(gr_poly
		(pts
			(xy 136.144762 -281.57805) (xy 136.044686 -281.478228) (xy 135.94461 -281.57805) (xy 135.94461 -281.625802)
			(xy 136.144762 -281.625802)
		)
		(stroke
			(width 0)
			(type solid)
		)
		(fill yes)
		(layer "In4.Cu")
		(net "M_J_CPU1_SB_DQS_DN<6>")
	)
	(gr_poly
		(pts
			(xy 136.144762 -281.174698) (xy 136.144762 -281.126946) (xy 135.94461 -281.126946) (xy 135.94461 -281.174698)
			(xy 136.044686 -281.27452)
		)
		(stroke
			(width 0)
			(type solid)
		)
		(fill yes)
		(layer "In4.Cu")
		(net "M_J_CPU1_SB_DQS_DN<1>")
	)
	(gr_poly
		(pts
			(xy 136.144762 -279.958292) (xy 136.044686 -279.858216) (xy 135.94461 -279.958292) (xy 135.94461 -280.002742)
			(xy 136.144762 -280.002742)
		)
		(stroke
			(width 0)
			(type solid)
		)
		(fill yes)
		(layer "In4.Cu")
		(net "M_J_CPU1_SB_DQ<9>")
	)
	(gr_poly
		(pts
			(xy 136.144762 -279.554432) (xy 136.144762 -279.509982) (xy 135.94461 -279.509982) (xy 135.94461 -279.554432)
			(xy 136.044686 -279.654508)
		)
		(stroke
			(width 0)
			(type solid)
		)
		(fill yes)
		(layer "In4.Cu")
		(net "M_J_CPU1_SB_DQ<10>")
	)
	(gr_poly
		(pts
			(xy 136.144762 -278.33828) (xy 136.044686 -278.238204) (xy 135.94461 -278.33828) (xy 135.94461 -278.38273)
			(xy 136.144762 -278.38273)
		)
		(stroke
			(width 0)
			(type solid)
		)
		(fill yes)
		(layer "In4.Cu")
		(net "M_J_CPU1_SB_DQ<5>")
	)
	(gr_poly
		(pts
			(xy 136.144762 -277.93442) (xy 136.144762 -277.88997) (xy 135.94461 -277.88997) (xy 135.94461 -277.93442)
			(xy 136.044686 -278.034496)
		)
		(stroke
			(width 0)
			(type solid)
		)
		(fill yes)
		(layer "In4.Cu")
		(net "M_J_CPU1_SB_DQ<6>")
	)
	(gr_poly
		(pts
			(xy 136.144762 -276.718014) (xy 136.044686 -276.618192) (xy 135.94461 -276.718014) (xy 135.94461 -276.765766)
			(xy 136.144762 -276.765766)
		)
		(stroke
			(width 0)
			(type solid)
		)
		(fill yes)
		(layer "In4.Cu")
		(net "M_J_CPU1_SB_DQS_DN<5>")
	)
	(gr_poly
		(pts
			(xy 136.144762 -276.314662) (xy 136.144762 -276.26691) (xy 135.94461 -276.26691) (xy 135.94461 -276.314662)
			(xy 136.044686 -276.414484)
		)
		(stroke
			(width 0)
			(type solid)
		)
		(fill yes)
		(layer "In4.Cu")
		(net "M_J_CPU1_SB_DQS_DN<0>")
	)
	(gr_poly
		(pts
			(xy 136.144762 -275.098256) (xy 136.044686 -274.99818) (xy 135.94461 -275.098256) (xy 135.94461 -275.142706)
			(xy 136.144762 -275.142706)
		)
		(stroke
			(width 0)
			(type solid)
		)
		(fill yes)
		(layer "In4.Cu")
		(net "M_J_CPU1_SB_DQ<1>")
	)
	(gr_poly
		(pts
			(xy 136.144762 -274.694396) (xy 136.144762 -274.649946) (xy 135.94461 -274.649946) (xy 135.94461 -274.694396)
			(xy 136.044686 -274.794472)
		)
		(stroke
			(width 0)
			(type solid)
		)
		(fill yes)
		(layer "In4.Cu")
		(net "M_J_CPU1_SB_DQ<2>")
	)
	(gr_poly
		(pts
			(xy 136.144762 -273.478244) (xy 136.044686 -273.378168) (xy 135.94461 -273.478244) (xy 135.94461 -273.522694)
			(xy 136.144762 -273.522694)
		)
		(stroke
			(width 0)
			(type solid)
		)
		(fill yes)
		(layer "In4.Cu")
		(net "M_J_CPU1_SB_CB<1>")
	)
	(gr_poly
		(pts
			(xy 136.144762 -273.074384) (xy 136.144762 -273.029934) (xy 135.94461 -273.029934) (xy 135.94461 -273.074384)
			(xy 136.044686 -273.17446)
		)
		(stroke
			(width 0)
			(type solid)
		)
		(fill yes)
		(layer "In4.Cu")
		(net "M_J_CPU1_SB_CB<2>")
	)
	(gr_poly
		(pts
			(xy 136.144762 -271.857978) (xy 136.044686 -271.758156) (xy 135.94461 -271.857978) (xy 135.94461 -271.90573)
			(xy 136.144762 -271.90573)
		)
		(stroke
			(width 0)
			(type solid)
		)
		(fill yes)
		(layer "In4.Cu")
		(net "M_J_CPU1_SB_DQS_DN<4>")
	)
	(gr_poly
		(pts
			(xy 136.144762 -271.454626) (xy 136.144762 -271.406874) (xy 135.94461 -271.406874) (xy 135.94461 -271.454626)
			(xy 136.044686 -271.554448)
		)
		(stroke
			(width 0)
			(type solid)
		)
		(fill yes)
		(layer "In4.Cu")
		(net "M_J_CPU1_SB_DQS_DN<9>")
	)
	(gr_poly
		(pts
			(xy 136.144762 -270.23822) (xy 136.044686 -270.138144) (xy 135.94461 -270.23822) (xy 135.94461 -270.28267)
			(xy 136.144762 -270.28267)
		)
		(stroke
			(width 0)
			(type solid)
		)
		(fill yes)
		(layer "In4.Cu")
		(net "M_J_CPU1_SB_CB<5>")
	)
	(gr_poly
		(pts
			(xy 136.144762 -269.83436) (xy 136.144762 -269.78991) (xy 135.94461 -269.78991) (xy 135.94461 -269.83436)
			(xy 136.044686 -269.934436)
		)
		(stroke
			(width 0)
			(type solid)
		)
		(fill yes)
		(layer "In4.Cu")
		(net "M_J_CPU1_SB_CB<6>")
	)
	(gr_poly
		(pts
			(xy 136.144762 -266.998196) (xy 136.044686 -266.89812) (xy 135.94461 -266.998196) (xy 135.94461 -267.042646)
			(xy 136.144762 -267.042646)
		)
		(stroke
			(width 0)
			(type solid)
		)
		(fill yes)
		(layer "In4.Cu")
		(net "M_J_CPU1_SA_RSP<0>")
	)
	(gr_poly
		(pts
			(xy 136.144762 -266.594336) (xy 136.144762 -266.549886) (xy 135.94461 -266.549886) (xy 135.94461 -266.594336)
			(xy 136.044686 -266.694412)
		)
		(stroke
			(width 0)
			(type solid)
		)
		(fill yes)
		(layer "In4.Cu")
		(net "M_J_CPU1_SB_CS_N<1>")
	)
	(gr_poly
		(pts
			(xy 136.144762 -265.378184) (xy 136.044686 -265.278108) (xy 135.94461 -265.378184) (xy 135.94461 -265.422634)
			(xy 136.144762 -265.422634)
		)
		(stroke
			(width 0)
			(type solid)
		)
		(fill yes)
		(layer "In4.Cu")
		(net "M_J_CPU1_SB_PAR")
	)
	(gr_poly
		(pts
			(xy 136.144762 -263.758172) (xy 136.044686 -263.658096) (xy 135.94461 -263.758172) (xy 135.94461 -263.802622)
			(xy 136.144762 -263.802622)
		)
		(stroke
			(width 0)
			(type solid)
		)
		(fill yes)
		(layer "In4.Cu")
		(net "M_J_CPU1_SB_CA<4>")
	)
	(gr_poly
		(pts
			(xy 136.144762 -263.354312) (xy 136.144762 -263.309862) (xy 135.94461 -263.309862) (xy 135.94461 -263.354312)
			(xy 136.044686 -263.454388)
		)
		(stroke
			(width 0)
			(type solid)
		)
		(fill yes)
		(layer "In4.Cu")
		(net "M_J_CPU1_SB_CA<3>")
	)
	(gr_poly
		(pts
			(xy 136.144762 -262.13816) (xy 136.044686 -262.038084) (xy 135.94461 -262.13816) (xy 135.94461 -262.18261)
			(xy 136.144762 -262.18261)
		)
		(stroke
			(width 0)
			(type solid)
		)
		(fill yes)
		(layer "In4.Cu")
		(net "M_J_CPU1_SB_CA<0>")
	)
	(gr_poly
		(pts
			(xy 136.314942 -256.432812) (xy 136.314942 -256.38506) (xy 136.11479 -256.38506) (xy 136.11479 -256.432812)
			(xy 136.214866 -256.532634)
		)
		(stroke
			(width 0)
			(type solid)
		)
		(fill yes)
		(layer "In4.Cu")
		(net "M_J_CPU1_CLK_DN<0>")
	)
	(gr_poly
		(pts
			(xy 136.314942 -255.216406) (xy 136.214866 -255.11633) (xy 136.11479 -255.216406) (xy 136.11479 -255.260856)
			(xy 136.314942 -255.260856)
		)
		(stroke
			(width 0)
			(type solid)
		)
		(fill yes)
		(layer "In4.Cu")
		(net "M_J_CPU1_SA_CA<6>")
	)
	(gr_poly
		(pts
			(xy 136.314942 -254.812546) (xy 136.314942 -254.768096) (xy 136.11479 -254.768096) (xy 136.11479 -254.812546)
			(xy 136.214866 -254.912622)
		)
		(stroke
			(width 0)
			(type solid)
		)
		(fill yes)
		(layer "In4.Cu")
		(net "M_J_CPU1_SA_CA<5>")
	)
	(gr_poly
		(pts
			(xy 136.314942 -253.596394) (xy 136.214866 -253.496318) (xy 136.11479 -253.596394) (xy 136.11479 -253.640844)
			(xy 136.314942 -253.640844)
		)
		(stroke
			(width 0)
			(type solid)
		)
		(fill yes)
		(layer "In4.Cu")
		(net "M_J_CPU1_SA_CA<2>")
	)
	(gr_poly
		(pts
			(xy 136.314942 -253.192534) (xy 136.314942 -253.148084) (xy 136.11479 -253.148084) (xy 136.11479 -253.192534)
			(xy 136.214866 -253.29261)
		)
		(stroke
			(width 0)
			(type solid)
		)
		(fill yes)
		(layer "In4.Cu")
		(net "M_J_CPU1_SA_CA<1>")
	)
	(gr_poly
		(pts
			(xy 136.314942 -251.976382) (xy 136.214866 -251.876306) (xy 136.11479 -251.976382) (xy 136.11479 -252.020832)
			(xy 136.314942 -252.020832)
		)
		(stroke
			(width 0)
			(type solid)
		)
		(fill yes)
		(layer "In4.Cu")
		(net "M_J_CPU1_SA_CS_N<1>")
	)
	(gr_poly
		(pts
			(xy 136.314942 -250.35637) (xy 136.214866 -250.256294) (xy 136.11479 -250.35637) (xy 136.11479 -250.40082)
			(xy 136.314942 -250.40082)
		)
		(stroke
			(width 0)
			(type solid)
		)
		(fill yes)
		(layer "In4.Cu")
		(net "M_J_CPU1_ALERT_R_N")
	)
	(gr_poly
		(pts
			(xy 136.314942 -248.736358) (xy 136.214866 -248.636282) (xy 136.11479 -248.736358) (xy 136.11479 -248.780808)
			(xy 136.314942 -248.780808)
		)
		(stroke
			(width 0)
			(type solid)
		)
		(fill yes)
		(layer "In4.Cu")
		(net "M_J_CPU1_SA_CB<5>")
	)
	(gr_poly
		(pts
			(xy 136.314942 -248.332498) (xy 136.314942 -248.288048) (xy 136.11479 -248.288048) (xy 136.11479 -248.332498)
			(xy 136.214866 -248.432574)
		)
		(stroke
			(width 0)
			(type solid)
		)
		(fill yes)
		(layer "In4.Cu")
		(net "M_J_CPU1_SA_CB<6>")
	)
	(gr_poly
		(pts
			(xy 136.314942 -247.116092) (xy 136.214866 -247.01627) (xy 136.11479 -247.116092) (xy 136.11479 -247.163844)
			(xy 136.314942 -247.163844)
		)
		(stroke
			(width 0)
			(type solid)
		)
		(fill yes)
		(layer "In4.Cu")
		(net "M_J_CPU1_SA_DQS_DN<9>")
	)
	(gr_poly
		(pts
			(xy 136.314942 -246.71274) (xy 136.314942 -246.664988) (xy 136.11479 -246.664988) (xy 136.11479 -246.71274)
			(xy 136.214866 -246.812562)
		)
		(stroke
			(width 0)
			(type solid)
		)
		(fill yes)
		(layer "In4.Cu")
		(net "M_J_CPU1_SA_DQS_DN<4>")
	)
	(gr_poly
		(pts
			(xy 136.314942 -245.496334) (xy 136.214866 -245.396258) (xy 136.11479 -245.496334) (xy 136.11479 -245.540784)
			(xy 136.314942 -245.540784)
		)
		(stroke
			(width 0)
			(type solid)
		)
		(fill yes)
		(layer "In4.Cu")
		(net "M_J_CPU1_SA_CB<1>")
	)
	(gr_poly
		(pts
			(xy 136.314942 -245.092474) (xy 136.314942 -245.048024) (xy 136.11479 -245.048024) (xy 136.11479 -245.092474)
			(xy 136.214866 -245.19255)
		)
		(stroke
			(width 0)
			(type solid)
		)
		(fill yes)
		(layer "In4.Cu")
		(net "M_J_CPU1_SA_CB<2>")
	)
	(gr_poly
		(pts
			(xy 136.314942 -243.876322) (xy 136.214866 -243.776246) (xy 136.11479 -243.876322) (xy 136.11479 -243.920772)
			(xy 136.314942 -243.920772)
		)
		(stroke
			(width 0)
			(type solid)
		)
		(fill yes)
		(layer "In4.Cu")
		(net "M_J_CPU1_SA_DQ<29>")
	)
	(gr_poly
		(pts
			(xy 136.314942 -243.472462) (xy 136.314942 -243.428012) (xy 136.11479 -243.428012) (xy 136.11479 -243.472462)
			(xy 136.214866 -243.572538)
		)
		(stroke
			(width 0)
			(type solid)
		)
		(fill yes)
		(layer "In4.Cu")
		(net "M_J_CPU1_SA_DQ<30>")
	)
	(gr_poly
		(pts
			(xy 136.314942 -242.256056) (xy 136.214866 -242.156234) (xy 136.11479 -242.256056) (xy 136.11479 -242.303808)
			(xy 136.314942 -242.303808)
		)
		(stroke
			(width 0)
			(type solid)
		)
		(fill yes)
		(layer "In4.Cu")
		(net "M_J_CPU1_SA_DQS_DN<8>")
	)
	(gr_poly
		(pts
			(xy 136.314942 -241.852704) (xy 136.314942 -241.804952) (xy 136.11479 -241.804952) (xy 136.11479 -241.852704)
			(xy 136.214866 -241.952526)
		)
		(stroke
			(width 0)
			(type solid)
		)
		(fill yes)
		(layer "In4.Cu")
		(net "M_J_CPU1_SA_DQS_DN<3>")
	)
	(gr_poly
		(pts
			(xy 136.314942 -240.636298) (xy 136.214866 -240.536222) (xy 136.11479 -240.636298) (xy 136.11479 -240.680748)
			(xy 136.314942 -240.680748)
		)
		(stroke
			(width 0)
			(type solid)
		)
		(fill yes)
		(layer "In4.Cu")
		(net "M_J_CPU1_SA_DQ<25>")
	)
	(gr_poly
		(pts
			(xy 136.314942 -240.232438) (xy 136.314942 -240.187988) (xy 136.11479 -240.187988) (xy 136.11479 -240.232438)
			(xy 136.214866 -240.332514)
		)
		(stroke
			(width 0)
			(type solid)
		)
		(fill yes)
		(layer "In4.Cu")
		(net "M_J_CPU1_SA_DQ<26>")
	)
	(gr_poly
		(pts
			(xy 136.314942 -239.016286) (xy 136.214866 -238.91621) (xy 136.11479 -239.016286) (xy 136.11479 -239.060736)
			(xy 136.314942 -239.060736)
		)
		(stroke
			(width 0)
			(type solid)
		)
		(fill yes)
		(layer "In4.Cu")
		(net "M_J_CPU1_SA_DQ<21>")
	)
	(gr_poly
		(pts
			(xy 136.314942 -238.612426) (xy 136.314942 -238.567976) (xy 136.11479 -238.567976) (xy 136.11479 -238.612426)
			(xy 136.214866 -238.712502)
		)
		(stroke
			(width 0)
			(type solid)
		)
		(fill yes)
		(layer "In4.Cu")
		(net "M_J_CPU1_SA_DQ<22>")
	)
	(gr_poly
		(pts
			(xy 136.314942 -237.39602) (xy 136.214866 -237.296198) (xy 136.11479 -237.39602) (xy 136.11479 -237.443772)
			(xy 136.314942 -237.443772)
		)
		(stroke
			(width 0)
			(type solid)
		)
		(fill yes)
		(layer "In4.Cu")
		(net "M_J_CPU1_SA_DQS_DN<7>")
	)
	(gr_poly
		(pts
			(xy 136.314942 -236.992668) (xy 136.314942 -236.944916) (xy 136.11479 -236.944916) (xy 136.11479 -236.992668)
			(xy 136.214866 -237.09249)
		)
		(stroke
			(width 0)
			(type solid)
		)
		(fill yes)
		(layer "In4.Cu")
		(net "M_J_CPU1_SA_DQS_DN<2>")
	)
	(gr_poly
		(pts
			(xy 136.314942 -235.776262) (xy 136.214866 -235.676186) (xy 136.11479 -235.776262) (xy 136.11479 -235.820712)
			(xy 136.314942 -235.820712)
		)
		(stroke
			(width 0)
			(type solid)
		)
		(fill yes)
		(layer "In4.Cu")
		(net "M_J_CPU1_SA_DQ<17>")
	)
	(gr_poly
		(pts
			(xy 136.314942 -235.372402) (xy 136.314942 -235.327952) (xy 136.11479 -235.327952) (xy 136.11479 -235.372402)
			(xy 136.214866 -235.472478)
		)
		(stroke
			(width 0)
			(type solid)
		)
		(fill yes)
		(layer "In4.Cu")
		(net "M_J_CPU1_SA_DQ<18>")
	)
	(gr_poly
		(pts
			(xy 136.314942 -234.15625) (xy 136.214866 -234.056174) (xy 136.11479 -234.15625) (xy 136.11479 -234.2007)
			(xy 136.314942 -234.2007)
		)
		(stroke
			(width 0)
			(type solid)
		)
		(fill yes)
		(layer "In4.Cu")
		(net "M_J_CPU1_SA_DQ<13>")
	)
	(gr_poly
		(pts
			(xy 136.314942 -233.75239) (xy 136.314942 -233.70794) (xy 136.11479 -233.70794) (xy 136.11479 -233.75239)
			(xy 136.214866 -233.852466)
		)
		(stroke
			(width 0)
			(type solid)
		)
		(fill yes)
		(layer "In4.Cu")
		(net "M_J_CPU1_SA_DQ<14>")
	)
	(gr_poly
		(pts
			(xy 136.314942 -232.535984) (xy 136.214866 -232.436162) (xy 136.11479 -232.535984) (xy 136.11479 -232.583736)
			(xy 136.314942 -232.583736)
		)
		(stroke
			(width 0)
			(type solid)
		)
		(fill yes)
		(layer "In4.Cu")
		(net "M_J_CPU1_SA_DQS_DN<6>")
	)
	(gr_poly
		(pts
			(xy 136.314942 -232.132632) (xy 136.314942 -232.08488) (xy 136.11479 -232.08488) (xy 136.11479 -232.132632)
			(xy 136.214866 -232.232454)
		)
		(stroke
			(width 0)
			(type solid)
		)
		(fill yes)
		(layer "In4.Cu")
		(net "M_J_CPU1_SA_DQS_DN<1>")
	)
	(gr_poly
		(pts
			(xy 136.314942 -230.916226) (xy 136.214866 -230.81615) (xy 136.11479 -230.916226) (xy 136.11479 -230.960676)
			(xy 136.314942 -230.960676)
		)
		(stroke
			(width 0)
			(type solid)
		)
		(fill yes)
		(layer "In4.Cu")
		(net "M_J_CPU1_SA_DQ<9>")
	)
	(gr_poly
		(pts
			(xy 136.314942 -230.51262) (xy 136.314942 -230.46817) (xy 136.11479 -230.46817) (xy 136.11479 -230.51262)
			(xy 136.214866 -230.612696)
		)
		(stroke
			(width 0)
			(type solid)
		)
		(fill yes)
		(layer "In4.Cu")
		(net "M_J_CPU1_SA_DQ<10>")
	)
	(gr_poly
		(pts
			(xy 136.314942 -229.296214) (xy 136.214866 -229.196138) (xy 136.11479 -229.296214) (xy 136.11479 -229.340664)
			(xy 136.314942 -229.340664)
		)
		(stroke
			(width 0)
			(type solid)
		)
		(fill yes)
		(layer "In4.Cu")
		(net "M_J_CPU1_SA_DQ<5>")
	)
	(gr_poly
		(pts
			(xy 136.314942 -228.892608) (xy 136.314942 -228.848158) (xy 136.11479 -228.848158) (xy 136.11479 -228.892608)
			(xy 136.214866 -228.992684)
		)
		(stroke
			(width 0)
			(type solid)
		)
		(fill yes)
		(layer "In4.Cu")
		(net "M_J_CPU1_SA_DQ<6>")
	)
	(gr_poly
		(pts
			(xy 136.314942 -227.676202) (xy 136.214866 -227.57638) (xy 136.11479 -227.676202) (xy 136.11479 -227.723954)
			(xy 136.314942 -227.723954)
		)
		(stroke
			(width 0)
			(type solid)
		)
		(fill yes)
		(layer "In4.Cu")
		(net "M_J_CPU1_SA_DQS_DN<5>")
	)
	(gr_poly
		(pts
			(xy 136.314942 -227.27285) (xy 136.314942 -227.225098) (xy 136.11479 -227.225098) (xy 136.11479 -227.27285)
			(xy 136.214866 -227.372672)
		)
		(stroke
			(width 0)
			(type solid)
		)
		(fill yes)
		(layer "In4.Cu")
		(net "M_J_CPU1_SA_DQS_DN<0>")
	)
	(gr_poly
		(pts
			(xy 136.314942 -226.056444) (xy 136.214866 -225.956368) (xy 136.11479 -226.056444) (xy 136.11479 -226.100894)
			(xy 136.314942 -226.100894)
		)
		(stroke
			(width 0)
			(type solid)
		)
		(fill yes)
		(layer "In4.Cu")
		(net "M_J_CPU1_SA_DQ<1>")
	)
	(gr_poly
		(pts
			(xy 136.314942 -225.652584) (xy 136.314942 -225.608134) (xy 136.11479 -225.608134) (xy 136.11479 -225.652584)
			(xy 136.214866 -225.75266)
		)
		(stroke
			(width 0)
			(type solid)
		)
		(fill yes)
		(layer "In4.Cu")
		(net "M_J_CPU1_SA_DQ<2>")
	)
	(gr_poly
		(pts
			(xy 136.614916 -293.32428) (xy 136.614916 -293.27983) (xy 136.414764 -293.27983) (xy 136.414764 -293.32428)
			(xy 136.51484 -293.424356)
		)
		(stroke
			(width 0)
			(type solid)
		)
		(fill yes)
		(layer "In4.Cu")
		(net "M_J_CPU1_SB_DQ<31>")
	)
	(gr_poly
		(pts
			(xy 136.614916 -292.108128) (xy 136.51484 -292.008052) (xy 136.414764 -292.108128) (xy 136.414764 -292.152578)
			(xy 136.614916 -292.152578)
		)
		(stroke
			(width 0)
			(type solid)
		)
		(fill yes)
		(layer "In4.Cu")
		(net "M_J_CPU1_SB_DQ<28>")
	)
	(gr_poly
		(pts
			(xy 136.614916 -291.704522) (xy 136.614916 -291.65677) (xy 136.414764 -291.65677) (xy 136.414764 -291.704522)
			(xy 136.51484 -291.804344)
		)
		(stroke
			(width 0)
			(type solid)
		)
		(fill yes)
		(layer "In4.Cu")
		(net "M_J_CPU1_SB_DQS_DP<8>")
	)
	(gr_poly
		(pts
			(xy 136.614916 -290.487862) (xy 136.51484 -290.38804) (xy 136.414764 -290.487862) (xy 136.414764 -290.535614)
			(xy 136.614916 -290.535614)
		)
		(stroke
			(width 0)
			(type solid)
		)
		(fill yes)
		(layer "In4.Cu")
		(net "M_J_CPU1_SB_DQS_DP<3>")
	)
	(gr_poly
		(pts
			(xy 136.614916 -290.084256) (xy 136.614916 -290.039806) (xy 136.414764 -290.039806) (xy 136.414764 -290.084256)
			(xy 136.51484 -290.184332)
		)
		(stroke
			(width 0)
			(type solid)
		)
		(fill yes)
		(layer "In4.Cu")
		(net "M_J_CPU1_SB_DQ<27>")
	)
	(gr_poly
		(pts
			(xy 136.614916 -288.868104) (xy 136.51484 -288.768028) (xy 136.414764 -288.868104) (xy 136.414764 -288.912554)
			(xy 136.614916 -288.912554)
		)
		(stroke
			(width 0)
			(type solid)
		)
		(fill yes)
		(layer "In4.Cu")
		(net "M_J_CPU1_SB_DQ<24>")
	)
	(gr_poly
		(pts
			(xy 136.614916 -288.464498) (xy 136.614916 -288.420048) (xy 136.414764 -288.420048) (xy 136.414764 -288.464498)
			(xy 136.51484 -288.564574)
		)
		(stroke
			(width 0)
			(type solid)
		)
		(fill yes)
		(layer "In4.Cu")
		(net "M_J_CPU1_SB_DQ<23>")
	)
	(gr_poly
		(pts
			(xy 136.614916 -287.248092) (xy 136.51484 -287.148016) (xy 136.414764 -287.248092) (xy 136.414764 -287.292542)
			(xy 136.614916 -287.292542)
		)
		(stroke
			(width 0)
			(type solid)
		)
		(fill yes)
		(layer "In4.Cu")
		(net "M_J_CPU1_SB_DQ<20>")
	)
	(gr_poly
		(pts
			(xy 136.614916 -286.844486) (xy 136.614916 -286.796734) (xy 136.414764 -286.796734) (xy 136.414764 -286.844486)
			(xy 136.51484 -286.944562)
		)
		(stroke
			(width 0)
			(type solid)
		)
		(fill yes)
		(layer "In4.Cu")
		(net "M_J_CPU1_SB_DQS_DP<7>")
	)
	(gr_poly
		(pts
			(xy 136.614916 -285.62808) (xy 136.51484 -285.528258) (xy 136.414764 -285.62808) (xy 136.414764 -285.675832)
			(xy 136.614916 -285.675832)
		)
		(stroke
			(width 0)
			(type solid)
		)
		(fill yes)
		(layer "In4.Cu")
		(net "M_J_CPU1_SB_DQS_DP<2>")
	)
	(gr_poly
		(pts
			(xy 136.614916 -285.224474) (xy 136.614916 -285.180024) (xy 136.414764 -285.180024) (xy 136.414764 -285.224474)
			(xy 136.51484 -285.32455)
		)
		(stroke
			(width 0)
			(type solid)
		)
		(fill yes)
		(layer "In4.Cu")
		(net "M_J_CPU1_SB_DQ<19>")
	)
	(gr_poly
		(pts
			(xy 136.614916 -284.008322) (xy 136.51484 -283.908246) (xy 136.414764 -284.008322) (xy 136.414764 -284.052772)
			(xy 136.614916 -284.052772)
		)
		(stroke
			(width 0)
			(type solid)
		)
		(fill yes)
		(layer "In4.Cu")
		(net "M_J_CPU1_SB_DQ<16>")
	)
	(gr_poly
		(pts
			(xy 136.614916 -283.604462) (xy 136.614916 -283.560012) (xy 136.414764 -283.560012) (xy 136.414764 -283.604462)
			(xy 136.51484 -283.704538)
		)
		(stroke
			(width 0)
			(type solid)
		)
		(fill yes)
		(layer "In4.Cu")
		(net "M_J_CPU1_SB_DQ<15>")
	)
	(gr_poly
		(pts
			(xy 136.614916 -282.38831) (xy 136.51484 -282.288234) (xy 136.414764 -282.38831) (xy 136.414764 -282.43276)
			(xy 136.614916 -282.43276)
		)
		(stroke
			(width 0)
			(type solid)
		)
		(fill yes)
		(layer "In4.Cu")
		(net "M_J_CPU1_SB_DQ<12>")
	)
	(gr_poly
		(pts
			(xy 136.614916 -281.984704) (xy 136.614916 -281.936952) (xy 136.414764 -281.936952) (xy 136.414764 -281.984704)
			(xy 136.51484 -282.084526)
		)
		(stroke
			(width 0)
			(type solid)
		)
		(fill yes)
		(layer "In4.Cu")
		(net "M_J_CPU1_SB_DQS_DP<6>")
	)
	(gr_poly
		(pts
			(xy 136.614916 -280.768044) (xy 136.51484 -280.668222) (xy 136.414764 -280.768044) (xy 136.414764 -280.815796)
			(xy 136.614916 -280.815796)
		)
		(stroke
			(width 0)
			(type solid)
		)
		(fill yes)
		(layer "In4.Cu")
		(net "M_J_CPU1_SB_DQS_DP<1>")
	)
	(gr_poly
		(pts
			(xy 136.614916 -280.364438) (xy 136.614916 -280.319988) (xy 136.414764 -280.319988) (xy 136.414764 -280.364438)
			(xy 136.51484 -280.464514)
		)
		(stroke
			(width 0)
			(type solid)
		)
		(fill yes)
		(layer "In4.Cu")
		(net "M_J_CPU1_SB_DQ<11>")
	)
	(gr_poly
		(pts
			(xy 136.614916 -279.148286) (xy 136.51484 -279.04821) (xy 136.414764 -279.148286) (xy 136.414764 -279.192736)
			(xy 136.614916 -279.192736)
		)
		(stroke
			(width 0)
			(type solid)
		)
		(fill yes)
		(layer "In4.Cu")
		(net "M_J_CPU1_SB_DQ<8>")
	)
	(gr_poly
		(pts
			(xy 136.614916 -278.744426) (xy 136.614916 -278.699976) (xy 136.414764 -278.699976) (xy 136.414764 -278.744426)
			(xy 136.51484 -278.844502)
		)
		(stroke
			(width 0)
			(type solid)
		)
		(fill yes)
		(layer "In4.Cu")
		(net "M_J_CPU1_SB_DQ<7>")
	)
	(gr_poly
		(pts
			(xy 136.614916 -277.528274) (xy 136.51484 -277.428198) (xy 136.414764 -277.528274) (xy 136.414764 -277.572724)
			(xy 136.614916 -277.572724)
		)
		(stroke
			(width 0)
			(type solid)
		)
		(fill yes)
		(layer "In4.Cu")
		(net "M_J_CPU1_SB_DQ<4>")
	)
	(gr_poly
		(pts
			(xy 136.614916 -277.124668) (xy 136.614916 -277.076916) (xy 136.414764 -277.076916) (xy 136.414764 -277.124668)
			(xy 136.51484 -277.22449)
		)
		(stroke
			(width 0)
			(type solid)
		)
		(fill yes)
		(layer "In4.Cu")
		(net "M_J_CPU1_SB_DQS_DP<5>")
	)
	(gr_poly
		(pts
			(xy 136.614916 -275.908008) (xy 136.51484 -275.808186) (xy 136.414764 -275.908008) (xy 136.414764 -275.95576)
			(xy 136.614916 -275.95576)
		)
		(stroke
			(width 0)
			(type solid)
		)
		(fill yes)
		(layer "In4.Cu")
		(net "M_J_CPU1_SB_DQS_DP<0>")
	)
	(gr_poly
		(pts
			(xy 136.614916 -275.504402) (xy 136.614916 -275.459952) (xy 136.414764 -275.459952) (xy 136.414764 -275.504402)
			(xy 136.51484 -275.604478)
		)
		(stroke
			(width 0)
			(type solid)
		)
		(fill yes)
		(layer "In4.Cu")
		(net "M_J_CPU1_SB_DQ<3>")
	)
	(gr_poly
		(pts
			(xy 136.614916 -274.28825) (xy 136.51484 -274.188174) (xy 136.414764 -274.28825) (xy 136.414764 -274.3327)
			(xy 136.614916 -274.3327)
		)
		(stroke
			(width 0)
			(type solid)
		)
		(fill yes)
		(layer "In4.Cu")
		(net "M_J_CPU1_SB_DQ<0>")
	)
	(gr_poly
		(pts
			(xy 136.614916 -273.88439) (xy 136.614916 -273.83994) (xy 136.414764 -273.83994) (xy 136.414764 -273.88439)
			(xy 136.51484 -273.984466)
		)
		(stroke
			(width 0)
			(type solid)
		)
		(fill yes)
		(layer "In4.Cu")
		(net "M_J_CPU1_SB_CB<3>")
	)
	(gr_poly
		(pts
			(xy 136.614916 -272.668238) (xy 136.51484 -272.568162) (xy 136.414764 -272.668238) (xy 136.414764 -272.712688)
			(xy 136.614916 -272.712688)
		)
		(stroke
			(width 0)
			(type solid)
		)
		(fill yes)
		(layer "In4.Cu")
		(net "M_J_CPU1_SB_CB<0>")
	)
	(gr_poly
		(pts
			(xy 136.614916 -272.264632) (xy 136.614916 -272.21688) (xy 136.414764 -272.21688) (xy 136.414764 -272.264632)
			(xy 136.51484 -272.364454)
		)
		(stroke
			(width 0)
			(type solid)
		)
		(fill yes)
		(layer "In4.Cu")
		(net "M_J_CPU1_SB_DQS_DP<4>")
	)
	(gr_poly
		(pts
			(xy 136.614916 -271.047972) (xy 136.51484 -270.94815) (xy 136.414764 -271.047972) (xy 136.414764 -271.095724)
			(xy 136.614916 -271.095724)
		)
		(stroke
			(width 0)
			(type solid)
		)
		(fill yes)
		(layer "In4.Cu")
		(net "M_J_CPU1_SB_DQS_DP<9>")
	)
	(gr_poly
		(pts
			(xy 136.614916 -270.644366) (xy 136.614916 -270.599916) (xy 136.414764 -270.599916) (xy 136.414764 -270.644366)
			(xy 136.51484 -270.744442)
		)
		(stroke
			(width 0)
			(type solid)
		)
		(fill yes)
		(layer "In4.Cu")
		(net "M_J_CPU1_SB_CB<7>")
	)
	(gr_poly
		(pts
			(xy 136.614916 -269.428214) (xy 136.51484 -269.328138) (xy 136.414764 -269.428214) (xy 136.414764 -269.472664)
			(xy 136.614916 -269.472664)
		)
		(stroke
			(width 0)
			(type solid)
		)
		(fill yes)
		(layer "In4.Cu")
		(net "M_J_CPU1_SB_CB<4>")
	)
	(gr_poly
		(pts
			(xy 136.614916 -267.808202) (xy 136.51484 -267.708126) (xy 136.414764 -267.808202) (xy 136.414764 -267.852652)
			(xy 136.614916 -267.852652)
		)
		(stroke
			(width 0)
			(type solid)
		)
		(fill yes)
		(layer "In4.Cu")
		(net "M_J_CPU1_SB_RSP<0>")
	)
	(gr_poly
		(pts
			(xy 136.614916 -265.78433) (xy 136.614916 -265.73988) (xy 136.414764 -265.73988) (xy 136.414764 -265.78433)
			(xy 136.51484 -265.884406)
		)
		(stroke
			(width 0)
			(type solid)
		)
		(fill yes)
		(layer "In4.Cu")
		(net "M_J_CPU1_SB_CS_N<0>")
	)
	(gr_poly
		(pts
			(xy 136.614916 -264.568178) (xy 136.51484 -264.468102) (xy 136.414764 -264.568178) (xy 136.414764 -264.612628)
			(xy 136.614916 -264.612628)
		)
		(stroke
			(width 0)
			(type solid)
		)
		(fill yes)
		(layer "In4.Cu")
		(net "M_J_CPU1_SB_CA<6>")
	)
	(gr_poly
		(pts
			(xy 136.614916 -264.164318) (xy 136.614916 -264.119868) (xy 136.414764 -264.119868) (xy 136.414764 -264.164318)
			(xy 136.51484 -264.264394)
		)
		(stroke
			(width 0)
			(type solid)
		)
		(fill yes)
		(layer "In4.Cu")
		(net "M_J_CPU1_SB_CA<5>")
	)
	(gr_poly
		(pts
			(xy 136.614916 -262.948166) (xy 136.51484 -262.84809) (xy 136.414764 -262.948166) (xy 136.414764 -262.992616)
			(xy 136.614916 -262.992616)
		)
		(stroke
			(width 0)
			(type solid)
		)
		(fill yes)
		(layer "In4.Cu")
		(net "M_J_CPU1_SB_CA<2>")
	)
	(gr_poly
		(pts
			(xy 136.614916 -262.544306) (xy 136.614916 -262.499856) (xy 136.414764 -262.499856) (xy 136.414764 -262.544306)
			(xy 136.51484 -262.644382)
		)
		(stroke
			(width 0)
			(type solid)
		)
		(fill yes)
		(layer "In4.Cu")
		(net "M_J_CPU1_SB_CA<1>")
	)
	(gr_poly
		(pts
			(xy 136.784842 -256.026158) (xy 136.684766 -255.926336) (xy 136.58469 -256.026158) (xy 136.58469 -256.07391)
			(xy 136.784842 -256.07391)
		)
		(stroke
			(width 0)
			(type solid)
		)
		(fill yes)
		(layer "In4.Cu")
		(net "M_J_CPU1_CLK_DP<0>")
	)
	(gr_poly
		(pts
			(xy 136.784842 -255.622552) (xy 136.784842 -255.578102) (xy 136.58469 -255.578102) (xy 136.58469 -255.622552)
			(xy 136.684766 -255.722628)
		)
		(stroke
			(width 0)
			(type solid)
		)
		(fill yes)
		(layer "In4.Cu")
		(net "M_J_CPU1_SA_PAR")
	)
	(gr_poly
		(pts
			(xy 136.784842 -254.4064) (xy 136.684766 -254.306324) (xy 136.58469 -254.4064) (xy 136.58469 -254.45085)
			(xy 136.784842 -254.45085)
		)
		(stroke
			(width 0)
			(type solid)
		)
		(fill yes)
		(layer "In4.Cu")
		(net "M_J_CPU1_SA_CA<4>")
	)
	(gr_poly
		(pts
			(xy 136.784842 -254.00254) (xy 136.784842 -253.95809) (xy 136.58469 -253.95809) (xy 136.58469 -254.00254)
			(xy 136.684766 -254.102616)
		)
		(stroke
			(width 0)
			(type solid)
		)
		(fill yes)
		(layer "In4.Cu")
		(net "M_J_CPU1_SA_CA<3>")
	)
	(gr_poly
		(pts
			(xy 136.784842 -252.786388) (xy 136.684766 -252.686312) (xy 136.58469 -252.786388) (xy 136.58469 -252.830838)
			(xy 136.784842 -252.830838)
		)
		(stroke
			(width 0)
			(type solid)
		)
		(fill yes)
		(layer "In4.Cu")
		(net "M_J_CPU1_SA_CA<0>")
	)
	(gr_poly
		(pts
			(xy 136.784842 -251.166376) (xy 136.684766 -251.0663) (xy 136.58469 -251.166376) (xy 136.58469 -251.210826)
			(xy 136.784842 -251.210826)
		)
		(stroke
			(width 0)
			(type solid)
		)
		(fill yes)
		(layer "In4.Cu")
		(net "M_J_CPU1_SA_CS_N<0>")
	)
	(gr_poly
		(pts
			(xy 136.784842 -250.762516) (xy 136.784842 -250.718066) (xy 136.58469 -250.718066) (xy 136.58469 -250.762516)
			(xy 136.684766 -250.862592)
		)
		(stroke
			(width 0)
			(type solid)
		)
		(fill yes)
		(layer "In4.Cu")
		(net "M_J_CPU1_RESET_N")
	)
	(gr_poly
		(pts
			(xy 136.784842 -249.142504) (xy 136.784842 -249.098054) (xy 136.58469 -249.098054) (xy 136.58469 -249.142504)
			(xy 136.684766 -249.24258)
		)
		(stroke
			(width 0)
			(type solid)
		)
		(fill yes)
		(layer "In4.Cu")
		(net "M_J_CPU1_SA_CB<7>")
	)
	(gr_poly
		(pts
			(xy 136.784842 -247.926352) (xy 136.684766 -247.826276) (xy 136.58469 -247.926352) (xy 136.58469 -247.970802)
			(xy 136.784842 -247.970802)
		)
		(stroke
			(width 0)
			(type solid)
		)
		(fill yes)
		(layer "In4.Cu")
		(net "M_J_CPU1_SA_CB<4>")
	)
	(gr_poly
		(pts
			(xy 136.784842 -247.522746) (xy 136.784842 -247.474994) (xy 136.58469 -247.474994) (xy 136.58469 -247.522746)
			(xy 136.684766 -247.622568)
		)
		(stroke
			(width 0)
			(type solid)
		)
		(fill yes)
		(layer "In4.Cu")
		(net "M_J_CPU1_SA_DQS_DP<9>")
	)
	(gr_poly
		(pts
			(xy 136.784842 -246.306086) (xy 136.684766 -246.206264) (xy 136.58469 -246.306086) (xy 136.58469 -246.353838)
			(xy 136.784842 -246.353838)
		)
		(stroke
			(width 0)
			(type solid)
		)
		(fill yes)
		(layer "In4.Cu")
		(net "M_J_CPU1_SA_DQS_DP<4>")
	)
	(gr_poly
		(pts
			(xy 136.784842 -245.90248) (xy 136.784842 -245.85803) (xy 136.58469 -245.85803) (xy 136.58469 -245.90248)
			(xy 136.684766 -246.002556)
		)
		(stroke
			(width 0)
			(type solid)
		)
		(fill yes)
		(layer "In4.Cu")
		(net "M_J_CPU1_SA_CB<3>")
	)
	(gr_poly
		(pts
			(xy 136.784842 -244.686328) (xy 136.684766 -244.586252) (xy 136.58469 -244.686328) (xy 136.58469 -244.730778)
			(xy 136.784842 -244.730778)
		)
		(stroke
			(width 0)
			(type solid)
		)
		(fill yes)
		(layer "In4.Cu")
		(net "M_J_CPU1_SA_CB<0>")
	)
	(gr_poly
		(pts
			(xy 136.784842 -244.282468) (xy 136.784842 -244.238018) (xy 136.58469 -244.238018) (xy 136.58469 -244.282468)
			(xy 136.684766 -244.382544)
		)
		(stroke
			(width 0)
			(type solid)
		)
		(fill yes)
		(layer "In4.Cu")
		(net "M_J_CPU1_SA_DQ<31>")
	)
	(gr_poly
		(pts
			(xy 136.784842 -243.066316) (xy 136.684766 -242.96624) (xy 136.58469 -243.066316) (xy 136.58469 -243.110766)
			(xy 136.784842 -243.110766)
		)
		(stroke
			(width 0)
			(type solid)
		)
		(fill yes)
		(layer "In4.Cu")
		(net "M_J_CPU1_SA_DQ<28>")
	)
	(gr_poly
		(pts
			(xy 136.784842 -242.66271) (xy 136.784842 -242.614958) (xy 136.58469 -242.614958) (xy 136.58469 -242.66271)
			(xy 136.684766 -242.762532)
		)
		(stroke
			(width 0)
			(type solid)
		)
		(fill yes)
		(layer "In4.Cu")
		(net "M_J_CPU1_SA_DQS_DP<8>")
	)
	(gr_poly
		(pts
			(xy 136.784842 -241.44605) (xy 136.684766 -241.346228) (xy 136.58469 -241.44605) (xy 136.58469 -241.493802)
			(xy 136.784842 -241.493802)
		)
		(stroke
			(width 0)
			(type solid)
		)
		(fill yes)
		(layer "In4.Cu")
		(net "M_J_CPU1_SA_DQS_DP<3>")
	)
	(gr_poly
		(pts
			(xy 136.784842 -241.042444) (xy 136.784842 -240.997994) (xy 136.58469 -240.997994) (xy 136.58469 -241.042444)
			(xy 136.684766 -241.14252)
		)
		(stroke
			(width 0)
			(type solid)
		)
		(fill yes)
		(layer "In4.Cu")
		(net "M_J_CPU1_SA_DQ<27>")
	)
	(gr_poly
		(pts
			(xy 136.784842 -239.826292) (xy 136.684766 -239.726216) (xy 136.58469 -239.826292) (xy 136.58469 -239.870742)
			(xy 136.784842 -239.870742)
		)
		(stroke
			(width 0)
			(type solid)
		)
		(fill yes)
		(layer "In4.Cu")
		(net "M_J_CPU1_SA_DQ<24>")
	)
	(gr_poly
		(pts
			(xy 136.784842 -239.422432) (xy 136.784842 -239.377982) (xy 136.58469 -239.377982) (xy 136.58469 -239.422432)
			(xy 136.684766 -239.522508)
		)
		(stroke
			(width 0)
			(type solid)
		)
		(fill yes)
		(layer "In4.Cu")
		(net "M_J_CPU1_SA_DQ<23>")
	)
	(gr_poly
		(pts
			(xy 136.784842 -238.20628) (xy 136.684766 -238.106204) (xy 136.58469 -238.20628) (xy 136.58469 -238.25073)
			(xy 136.784842 -238.25073)
		)
		(stroke
			(width 0)
			(type solid)
		)
		(fill yes)
		(layer "In4.Cu")
		(net "M_J_CPU1_SA_DQ<20>")
	)
	(gr_poly
		(pts
			(xy 136.784842 -237.802674) (xy 136.784842 -237.754922) (xy 136.58469 -237.754922) (xy 136.58469 -237.802674)
			(xy 136.684766 -237.902496)
		)
		(stroke
			(width 0)
			(type solid)
		)
		(fill yes)
		(layer "In4.Cu")
		(net "M_J_CPU1_SA_DQS_DP<7>")
	)
	(gr_poly
		(pts
			(xy 136.784842 -236.586014) (xy 136.684766 -236.486192) (xy 136.58469 -236.586014) (xy 136.58469 -236.633766)
			(xy 136.784842 -236.633766)
		)
		(stroke
			(width 0)
			(type solid)
		)
		(fill yes)
		(layer "In4.Cu")
		(net "M_J_CPU1_SA_DQS_DP<2>")
	)
	(gr_poly
		(pts
			(xy 136.784842 -236.182408) (xy 136.784842 -236.137958) (xy 136.58469 -236.137958) (xy 136.58469 -236.182408)
			(xy 136.684766 -236.282484)
		)
		(stroke
			(width 0)
			(type solid)
		)
		(fill yes)
		(layer "In4.Cu")
		(net "M_J_CPU1_SA_DQ<19>")
	)
	(gr_poly
		(pts
			(xy 136.784842 -234.966256) (xy 136.684766 -234.86618) (xy 136.58469 -234.966256) (xy 136.58469 -235.010706)
			(xy 136.784842 -235.010706)
		)
		(stroke
			(width 0)
			(type solid)
		)
		(fill yes)
		(layer "In4.Cu")
		(net "M_J_CPU1_SA_DQ<16>")
	)
	(gr_poly
		(pts
			(xy 136.784842 -234.562396) (xy 136.784842 -234.517946) (xy 136.58469 -234.517946) (xy 136.58469 -234.562396)
			(xy 136.684766 -234.662472)
		)
		(stroke
			(width 0)
			(type solid)
		)
		(fill yes)
		(layer "In4.Cu")
		(net "M_J_CPU1_SA_DQ<15>")
	)
	(gr_poly
		(pts
			(xy 136.784842 -233.346244) (xy 136.684766 -233.246168) (xy 136.58469 -233.346244) (xy 136.58469 -233.390694)
			(xy 136.784842 -233.390694)
		)
		(stroke
			(width 0)
			(type solid)
		)
		(fill yes)
		(layer "In4.Cu")
		(net "M_J_CPU1_SA_DQ<12>")
	)
	(gr_poly
		(pts
			(xy 136.784842 -232.942638) (xy 136.784842 -232.894886) (xy 136.58469 -232.894886) (xy 136.58469 -232.942638)
			(xy 136.684766 -233.04246)
		)
		(stroke
			(width 0)
			(type solid)
		)
		(fill yes)
		(layer "In4.Cu")
		(net "M_J_CPU1_SA_DQS_DP<6>")
	)
	(gr_poly
		(pts
			(xy 136.784842 -231.725978) (xy 136.684766 -231.626156) (xy 136.58469 -231.725978) (xy 136.58469 -231.77373)
			(xy 136.784842 -231.77373)
		)
		(stroke
			(width 0)
			(type solid)
		)
		(fill yes)
		(layer "In4.Cu")
		(net "M_J_CPU1_SA_DQS_DP<1>")
	)
	(gr_poly
		(pts
			(xy 136.784842 -231.322626) (xy 136.784842 -231.278176) (xy 136.58469 -231.278176) (xy 136.58469 -231.322626)
			(xy 136.684766 -231.422702)
		)
		(stroke
			(width 0)
			(type solid)
		)
		(fill yes)
		(layer "In4.Cu")
		(net "M_J_CPU1_SA_DQ<11>")
	)
	(gr_poly
		(pts
			(xy 136.784842 -230.10622) (xy 136.684766 -230.006144) (xy 136.58469 -230.10622) (xy 136.58469 -230.15067)
			(xy 136.784842 -230.15067)
		)
		(stroke
			(width 0)
			(type solid)
		)
		(fill yes)
		(layer "In4.Cu")
		(net "M_J_CPU1_SA_DQ<8>")
	)
	(gr_poly
		(pts
			(xy 136.784842 -229.702614) (xy 136.784842 -229.658164) (xy 136.58469 -229.658164) (xy 136.58469 -229.702614)
			(xy 136.684766 -229.80269)
		)
		(stroke
			(width 0)
			(type solid)
		)
		(fill yes)
		(layer "In4.Cu")
		(net "M_J_CPU1_SA_DQ<7>")
	)
	(gr_poly
		(pts
			(xy 136.784842 -228.486462) (xy 136.684766 -228.386386) (xy 136.58469 -228.486462) (xy 136.58469 -228.530912)
			(xy 136.784842 -228.530912)
		)
		(stroke
			(width 0)
			(type solid)
		)
		(fill yes)
		(layer "In4.Cu")
		(net "M_J_CPU1_SA_DQ<4>")
	)
	(gr_poly
		(pts
			(xy 136.784842 -228.082856) (xy 136.784842 -228.035104) (xy 136.58469 -228.035104) (xy 136.58469 -228.082856)
			(xy 136.684766 -228.182678)
		)
		(stroke
			(width 0)
			(type solid)
		)
		(fill yes)
		(layer "In4.Cu")
		(net "M_J_CPU1_SA_DQS_DP<5>")
	)
	(gr_poly
		(pts
			(xy 136.784842 -226.866196) (xy 136.684766 -226.766374) (xy 136.58469 -226.866196) (xy 136.58469 -226.913948)
			(xy 136.784842 -226.913948)
		)
		(stroke
			(width 0)
			(type solid)
		)
		(fill yes)
		(layer "In4.Cu")
		(net "M_J_CPU1_SA_DQS_DP<0>")
	)
	(gr_poly
		(pts
			(xy 136.784842 -226.46259) (xy 136.784842 -226.41814) (xy 136.58469 -226.41814) (xy 136.58469 -226.46259)
			(xy 136.684766 -226.562666)
		)
		(stroke
			(width 0)
			(type solid)
		)
		(fill yes)
		(layer "In4.Cu")
		(net "M_J_CPU1_SA_DQ<3>")
	)
	(gr_poly
		(pts
			(xy 136.784842 -225.246438) (xy 136.684766 -225.146362) (xy 136.58469 -225.246438) (xy 136.58469 -225.290888)
			(xy 136.784842 -225.290888)
		)
		(stroke
			(width 0)
			(type solid)
		)
		(fill yes)
		(layer "In4.Cu")
		(net "M_J_CPU1_SA_DQ<0>")
	)
	(gr_poly
		(pts
			(xy 137.084816 -292.918134) (xy 136.98474 -292.818058) (xy 136.884664 -292.918134) (xy 136.884664 -292.962584)
			(xy 137.084816 -292.962584)
		)
		(stroke
			(width 0)
			(type solid)
		)
		(fill yes)
		(layer "In4.Cu")
		(net "M_J_CPU1_SB_DQ<29>")
	)
	(gr_poly
		(pts
			(xy 137.084816 -292.514274) (xy 137.084816 -292.469824) (xy 136.884664 -292.469824) (xy 136.884664 -292.514274)
			(xy 136.98474 -292.61435)
		)
		(stroke
			(width 0)
			(type solid)
		)
		(fill yes)
		(layer "In4.Cu")
		(net "M_J_CPU1_SB_DQ<30>")
	)
	(gr_poly
		(pts
			(xy 137.084816 -291.297868) (xy 136.98474 -291.198046) (xy 136.884664 -291.297868) (xy 136.884664 -291.34562)
			(xy 137.084816 -291.34562)
		)
		(stroke
			(width 0)
			(type solid)
		)
		(fill yes)
		(layer "In4.Cu")
		(net "M_J_CPU1_SB_DQS_DN<8>")
	)
	(gr_poly
		(pts
			(xy 137.084816 -290.894516) (xy 137.084816 -290.846764) (xy 136.884664 -290.846764) (xy 136.884664 -290.894516)
			(xy 136.98474 -290.994338)
		)
		(stroke
			(width 0)
			(type solid)
		)
		(fill yes)
		(layer "In4.Cu")
		(net "M_J_CPU1_SB_DQS_DN<3>")
	)
	(gr_poly
		(pts
			(xy 137.084816 -289.67811) (xy 136.98474 -289.578034) (xy 136.884664 -289.67811) (xy 136.884664 -289.72256)
			(xy 137.084816 -289.72256)
		)
		(stroke
			(width 0)
			(type solid)
		)
		(fill yes)
		(layer "In4.Cu")
		(net "M_J_CPU1_SB_DQ<25>")
	)
	(gr_poly
		(pts
			(xy 137.084816 -289.27425) (xy 137.084816 -289.2298) (xy 136.884664 -289.2298) (xy 136.884664 -289.27425)
			(xy 136.98474 -289.374326)
		)
		(stroke
			(width 0)
			(type solid)
		)
		(fill yes)
		(layer "In4.Cu")
		(net "M_J_CPU1_SB_DQ<26>")
	)
	(gr_poly
		(pts
			(xy 137.084816 -288.058098) (xy 136.98474 -287.958022) (xy 136.884664 -288.058098) (xy 136.884664 -288.102548)
			(xy 137.084816 -288.102548)
		)
		(stroke
			(width 0)
			(type solid)
		)
		(fill yes)
		(layer "In4.Cu")
		(net "M_J_CPU1_SB_DQ<21>")
	)
	(gr_poly
		(pts
			(xy 137.084816 -287.654492) (xy 137.084816 -287.610042) (xy 136.884664 -287.610042) (xy 136.884664 -287.654492)
			(xy 136.98474 -287.754568)
		)
		(stroke
			(width 0)
			(type solid)
		)
		(fill yes)
		(layer "In4.Cu")
		(net "M_J_CPU1_SB_DQ<22>")
	)
	(gr_poly
		(pts
			(xy 137.084816 -286.438086) (xy 136.98474 -286.33801) (xy 136.884664 -286.438086) (xy 136.884664 -286.485838)
			(xy 137.084816 -286.485838)
		)
		(stroke
			(width 0)
			(type solid)
		)
		(fill yes)
		(layer "In4.Cu")
		(net "M_J_CPU1_SB_DQS_DN<7>")
	)
	(gr_poly
		(pts
			(xy 137.084816 -286.034734) (xy 137.084816 -285.986982) (xy 136.884664 -285.986982) (xy 136.884664 -286.034734)
			(xy 136.98474 -286.134556)
		)
		(stroke
			(width 0)
			(type solid)
		)
		(fill yes)
		(layer "In4.Cu")
		(net "M_J_CPU1_SB_DQS_DN<2>")
	)
	(gr_poly
		(pts
			(xy 137.084816 -284.818328) (xy 136.98474 -284.718252) (xy 136.884664 -284.818328) (xy 136.884664 -284.862778)
			(xy 137.084816 -284.862778)
		)
		(stroke
			(width 0)
			(type solid)
		)
		(fill yes)
		(layer "In4.Cu")
		(net "M_J_CPU1_SB_DQ<17>")
	)
	(gr_poly
		(pts
			(xy 137.084816 -284.414468) (xy 137.084816 -284.370018) (xy 136.884664 -284.370018) (xy 136.884664 -284.414468)
			(xy 136.98474 -284.514544)
		)
		(stroke
			(width 0)
			(type solid)
		)
		(fill yes)
		(layer "In4.Cu")
		(net "M_J_CPU1_SB_DQ<18>")
	)
	(gr_poly
		(pts
			(xy 137.084816 -283.198316) (xy 136.98474 -283.09824) (xy 136.884664 -283.198316) (xy 136.884664 -283.242766)
			(xy 137.084816 -283.242766)
		)
		(stroke
			(width 0)
			(type solid)
		)
		(fill yes)
		(layer "In4.Cu")
		(net "M_J_CPU1_SB_DQ<13>")
	)
	(gr_poly
		(pts
			(xy 137.084816 -282.794456) (xy 137.084816 -282.750006) (xy 136.884664 -282.750006) (xy 136.884664 -282.794456)
			(xy 136.98474 -282.894532)
		)
		(stroke
			(width 0)
			(type solid)
		)
		(fill yes)
		(layer "In4.Cu")
		(net "M_J_CPU1_SB_DQ<14>")
	)
	(gr_poly
		(pts
			(xy 137.084816 -281.57805) (xy 136.98474 -281.478228) (xy 136.884664 -281.57805) (xy 136.884664 -281.625802)
			(xy 137.084816 -281.625802)
		)
		(stroke
			(width 0)
			(type solid)
		)
		(fill yes)
		(layer "In4.Cu")
		(net "M_J_CPU1_SB_DQS_DN<6>")
	)
	(gr_poly
		(pts
			(xy 137.084816 -281.174698) (xy 137.084816 -281.126946) (xy 136.884664 -281.126946) (xy 136.884664 -281.174698)
			(xy 136.98474 -281.27452)
		)
		(stroke
			(width 0)
			(type solid)
		)
		(fill yes)
		(layer "In4.Cu")
		(net "M_J_CPU1_SB_DQS_DN<1>")
	)
	(gr_poly
		(pts
			(xy 137.084816 -279.958292) (xy 136.98474 -279.858216) (xy 136.884664 -279.958292) (xy 136.884664 -280.002742)
			(xy 137.084816 -280.002742)
		)
		(stroke
			(width 0)
			(type solid)
		)
		(fill yes)
		(layer "In4.Cu")
		(net "M_J_CPU1_SB_DQ<9>")
	)
	(gr_poly
		(pts
			(xy 137.084816 -279.554432) (xy 137.084816 -279.509982) (xy 136.884664 -279.509982) (xy 136.884664 -279.554432)
			(xy 136.98474 -279.654508)
		)
		(stroke
			(width 0)
			(type solid)
		)
		(fill yes)
		(layer "In4.Cu")
		(net "M_J_CPU1_SB_DQ<10>")
	)
	(gr_poly
		(pts
			(xy 137.084816 -278.33828) (xy 136.98474 -278.238204) (xy 136.884664 -278.33828) (xy 136.884664 -278.38273)
			(xy 137.084816 -278.38273)
		)
		(stroke
			(width 0)
			(type solid)
		)
		(fill yes)
		(layer "In4.Cu")
		(net "M_J_CPU1_SB_DQ<5>")
	)
	(gr_poly
		(pts
			(xy 137.084816 -277.93442) (xy 137.084816 -277.88997) (xy 136.884664 -277.88997) (xy 136.884664 -277.93442)
			(xy 136.98474 -278.034496)
		)
		(stroke
			(width 0)
			(type solid)
		)
		(fill yes)
		(layer "In4.Cu")
		(net "M_J_CPU1_SB_DQ<6>")
	)
	(gr_poly
		(pts
			(xy 137.084816 -276.718014) (xy 136.98474 -276.618192) (xy 136.884664 -276.718014) (xy 136.884664 -276.765766)
			(xy 137.084816 -276.765766)
		)
		(stroke
			(width 0)
			(type solid)
		)
		(fill yes)
		(layer "In4.Cu")
		(net "M_J_CPU1_SB_DQS_DN<5>")
	)
	(gr_poly
		(pts
			(xy 137.084816 -276.314662) (xy 137.084816 -276.26691) (xy 136.884664 -276.26691) (xy 136.884664 -276.314662)
			(xy 136.98474 -276.414484)
		)
		(stroke
			(width 0)
			(type solid)
		)
		(fill yes)
		(layer "In4.Cu")
		(net "M_J_CPU1_SB_DQS_DN<0>")
	)
	(gr_poly
		(pts
			(xy 137.084816 -275.098256) (xy 136.98474 -274.99818) (xy 136.884664 -275.098256) (xy 136.884664 -275.142706)
			(xy 137.084816 -275.142706)
		)
		(stroke
			(width 0)
			(type solid)
		)
		(fill yes)
		(layer "In4.Cu")
		(net "M_J_CPU1_SB_DQ<1>")
	)
	(gr_poly
		(pts
			(xy 137.084816 -274.694396) (xy 137.084816 -274.649946) (xy 136.884664 -274.649946) (xy 136.884664 -274.694396)
			(xy 136.98474 -274.794472)
		)
		(stroke
			(width 0)
			(type solid)
		)
		(fill yes)
		(layer "In4.Cu")
		(net "M_J_CPU1_SB_DQ<2>")
	)
	(gr_poly
		(pts
			(xy 137.084816 -273.478244) (xy 136.98474 -273.378168) (xy 136.884664 -273.478244) (xy 136.884664 -273.522694)
			(xy 137.084816 -273.522694)
		)
		(stroke
			(width 0)
			(type solid)
		)
		(fill yes)
		(layer "In4.Cu")
		(net "M_J_CPU1_SB_CB<1>")
	)
	(gr_poly
		(pts
			(xy 137.084816 -273.074384) (xy 137.084816 -273.029934) (xy 136.884664 -273.029934) (xy 136.884664 -273.074384)
			(xy 136.98474 -273.17446)
		)
		(stroke
			(width 0)
			(type solid)
		)
		(fill yes)
		(layer "In4.Cu")
		(net "M_J_CPU1_SB_CB<2>")
	)
	(gr_poly
		(pts
			(xy 137.084816 -271.857978) (xy 136.98474 -271.758156) (xy 136.884664 -271.857978) (xy 136.884664 -271.90573)
			(xy 137.084816 -271.90573)
		)
		(stroke
			(width 0)
			(type solid)
		)
		(fill yes)
		(layer "In4.Cu")
		(net "M_J_CPU1_SB_DQS_DN<4>")
	)
	(gr_poly
		(pts
			(xy 137.084816 -271.454626) (xy 137.084816 -271.406874) (xy 136.884664 -271.406874) (xy 136.884664 -271.454626)
			(xy 136.98474 -271.554448)
		)
		(stroke
			(width 0)
			(type solid)
		)
		(fill yes)
		(layer "In4.Cu")
		(net "M_J_CPU1_SB_DQS_DN<9>")
	)
	(gr_poly
		(pts
			(xy 137.084816 -270.23822) (xy 136.98474 -270.138144) (xy 136.884664 -270.23822) (xy 136.884664 -270.28267)
			(xy 137.084816 -270.28267)
		)
		(stroke
			(width 0)
			(type solid)
		)
		(fill yes)
		(layer "In4.Cu")
		(net "M_J_CPU1_SB_CB<5>")
	)
	(gr_poly
		(pts
			(xy 137.084816 -269.83436) (xy 137.084816 -269.78991) (xy 136.884664 -269.78991) (xy 136.884664 -269.83436)
			(xy 136.98474 -269.934436)
		)
		(stroke
			(width 0)
			(type solid)
		)
		(fill yes)
		(layer "In4.Cu")
		(net "M_J_CPU1_SB_CB<6>")
	)
	(gr_poly
		(pts
			(xy 137.084816 -266.998196) (xy 136.98474 -266.89812) (xy 136.884664 -266.998196) (xy 136.884664 -267.042646)
			(xy 137.084816 -267.042646)
		)
		(stroke
			(width 0)
			(type solid)
		)
		(fill yes)
		(layer "In4.Cu")
		(net "M_J_CPU1_SA_RSP<0>")
	)
	(gr_poly
		(pts
			(xy 137.084816 -266.594336) (xy 137.084816 -266.549886) (xy 136.884664 -266.549886) (xy 136.884664 -266.594336)
			(xy 136.98474 -266.694412)
		)
		(stroke
			(width 0)
			(type solid)
		)
		(fill yes)
		(layer "In4.Cu")
		(net "M_J_CPU1_SB_CS_N<1>")
	)
	(gr_poly
		(pts
			(xy 137.084816 -265.378184) (xy 136.98474 -265.278108) (xy 136.884664 -265.378184) (xy 136.884664 -265.422634)
			(xy 137.084816 -265.422634)
		)
		(stroke
			(width 0)
			(type solid)
		)
		(fill yes)
		(layer "In4.Cu")
		(net "M_J_CPU1_SB_PAR")
	)
	(gr_poly
		(pts
			(xy 137.084816 -263.758172) (xy 136.98474 -263.658096) (xy 136.884664 -263.758172) (xy 136.884664 -263.802622)
			(xy 137.084816 -263.802622)
		)
		(stroke
			(width 0)
			(type solid)
		)
		(fill yes)
		(layer "In4.Cu")
		(net "M_J_CPU1_SB_CA<4>")
	)
	(gr_poly
		(pts
			(xy 137.084816 -263.354312) (xy 137.084816 -263.309862) (xy 136.884664 -263.309862) (xy 136.884664 -263.354312)
			(xy 136.98474 -263.454388)
		)
		(stroke
			(width 0)
			(type solid)
		)
		(fill yes)
		(layer "In4.Cu")
		(net "M_J_CPU1_SB_CA<3>")
	)
	(gr_poly
		(pts
			(xy 137.084816 -262.13816) (xy 136.98474 -262.038084) (xy 136.884664 -262.13816) (xy 136.884664 -262.18261)
			(xy 137.084816 -262.18261)
		)
		(stroke
			(width 0)
			(type solid)
		)
		(fill yes)
		(layer "In4.Cu")
		(net "M_J_CPU1_SB_CA<0>")
	)
	(gr_poly
		(pts
			(xy 137.254742 -256.432812) (xy 137.254742 -256.38506) (xy 137.05459 -256.38506) (xy 137.05459 -256.432812)
			(xy 137.154666 -256.532634)
		)
		(stroke
			(width 0)
			(type solid)
		)
		(fill yes)
		(layer "In4.Cu")
		(net "M_J_CPU1_CLK_DN<0>")
	)
	(gr_poly
		(pts
			(xy 137.254742 -255.216406) (xy 137.154666 -255.11633) (xy 137.05459 -255.216406) (xy 137.05459 -255.260856)
			(xy 137.254742 -255.260856)
		)
		(stroke
			(width 0)
			(type solid)
		)
		(fill yes)
		(layer "In4.Cu")
		(net "M_J_CPU1_SA_CA<6>")
	)
	(gr_poly
		(pts
			(xy 137.254742 -254.812546) (xy 137.254742 -254.768096) (xy 137.05459 -254.768096) (xy 137.05459 -254.812546)
			(xy 137.154666 -254.912622)
		)
		(stroke
			(width 0)
			(type solid)
		)
		(fill yes)
		(layer "In4.Cu")
		(net "M_J_CPU1_SA_CA<5>")
	)
	(gr_poly
		(pts
			(xy 137.254742 -253.596394) (xy 137.154666 -253.496318) (xy 137.05459 -253.596394) (xy 137.05459 -253.640844)
			(xy 137.254742 -253.640844)
		)
		(stroke
			(width 0)
			(type solid)
		)
		(fill yes)
		(layer "In4.Cu")
		(net "M_J_CPU1_SA_CA<2>")
	)
	(gr_poly
		(pts
			(xy 137.254742 -253.192534) (xy 137.254742 -253.148084) (xy 137.05459 -253.148084) (xy 137.05459 -253.192534)
			(xy 137.154666 -253.29261)
		)
		(stroke
			(width 0)
			(type solid)
		)
		(fill yes)
		(layer "In4.Cu")
		(net "M_J_CPU1_SA_CA<1>")
	)
	(gr_poly
		(pts
			(xy 137.254742 -251.976382) (xy 137.154666 -251.876306) (xy 137.05459 -251.976382) (xy 137.05459 -252.020832)
			(xy 137.254742 -252.020832)
		)
		(stroke
			(width 0)
			(type solid)
		)
		(fill yes)
		(layer "In4.Cu")
		(net "M_J_CPU1_SA_CS_N<1>")
	)
	(gr_poly
		(pts
			(xy 137.254742 -250.35637) (xy 137.154666 -250.256294) (xy 137.05459 -250.35637) (xy 137.05459 -250.40082)
			(xy 137.254742 -250.40082)
		)
		(stroke
			(width 0)
			(type solid)
		)
		(fill yes)
		(layer "In4.Cu")
		(net "M_J_CPU1_ALERT_R_N")
	)
	(gr_poly
		(pts
			(xy 137.254742 -248.736358) (xy 137.154666 -248.636282) (xy 137.05459 -248.736358) (xy 137.05459 -248.780808)
			(xy 137.254742 -248.780808)
		)
		(stroke
			(width 0)
			(type solid)
		)
		(fill yes)
		(layer "In4.Cu")
		(net "M_J_CPU1_SA_CB<5>")
	)
	(gr_poly
		(pts
			(xy 137.254742 -248.332498) (xy 137.254742 -248.288048) (xy 137.05459 -248.288048) (xy 137.05459 -248.332498)
			(xy 137.154666 -248.432574)
		)
		(stroke
			(width 0)
			(type solid)
		)
		(fill yes)
		(layer "In4.Cu")
		(net "M_J_CPU1_SA_CB<6>")
	)
	(gr_poly
		(pts
			(xy 137.254742 -247.116092) (xy 137.154666 -247.01627) (xy 137.05459 -247.116092) (xy 137.05459 -247.163844)
			(xy 137.254742 -247.163844)
		)
		(stroke
			(width 0)
			(type solid)
		)
		(fill yes)
		(layer "In4.Cu")
		(net "M_J_CPU1_SA_DQS_DN<9>")
	)
	(gr_poly
		(pts
			(xy 137.254742 -246.71274) (xy 137.254742 -246.664988) (xy 137.05459 -246.664988) (xy 137.05459 -246.71274)
			(xy 137.154666 -246.812562)
		)
		(stroke
			(width 0)
			(type solid)
		)
		(fill yes)
		(layer "In4.Cu")
		(net "M_J_CPU1_SA_DQS_DN<4>")
	)
	(gr_poly
		(pts
			(xy 137.254742 -245.496334) (xy 137.154666 -245.396258) (xy 137.05459 -245.496334) (xy 137.05459 -245.540784)
			(xy 137.254742 -245.540784)
		)
		(stroke
			(width 0)
			(type solid)
		)
		(fill yes)
		(layer "In4.Cu")
		(net "M_J_CPU1_SA_CB<1>")
	)
	(gr_poly
		(pts
			(xy 137.254742 -245.092474) (xy 137.254742 -245.048024) (xy 137.05459 -245.048024) (xy 137.05459 -245.092474)
			(xy 137.154666 -245.19255)
		)
		(stroke
			(width 0)
			(type solid)
		)
		(fill yes)
		(layer "In4.Cu")
		(net "M_J_CPU1_SA_CB<2>")
	)
	(gr_poly
		(pts
			(xy 137.254742 -243.876322) (xy 137.154666 -243.776246) (xy 137.05459 -243.876322) (xy 137.05459 -243.920772)
			(xy 137.254742 -243.920772)
		)
		(stroke
			(width 0)
			(type solid)
		)
		(fill yes)
		(layer "In4.Cu")
		(net "M_J_CPU1_SA_DQ<29>")
	)
	(gr_poly
		(pts
			(xy 137.254742 -243.472462) (xy 137.254742 -243.428012) (xy 137.05459 -243.428012) (xy 137.05459 -243.472462)
			(xy 137.154666 -243.572538)
		)
		(stroke
			(width 0)
			(type solid)
		)
		(fill yes)
		(layer "In4.Cu")
		(net "M_J_CPU1_SA_DQ<30>")
	)
	(gr_poly
		(pts
			(xy 137.254742 -242.256056) (xy 137.154666 -242.156234) (xy 137.05459 -242.256056) (xy 137.05459 -242.303808)
			(xy 137.254742 -242.303808)
		)
		(stroke
			(width 0)
			(type solid)
		)
		(fill yes)
		(layer "In4.Cu")
		(net "M_J_CPU1_SA_DQS_DN<8>")
	)
	(gr_poly
		(pts
			(xy 137.254742 -241.852704) (xy 137.254742 -241.804952) (xy 137.05459 -241.804952) (xy 137.05459 -241.852704)
			(xy 137.154666 -241.952526)
		)
		(stroke
			(width 0)
			(type solid)
		)
		(fill yes)
		(layer "In4.Cu")
		(net "M_J_CPU1_SA_DQS_DN<3>")
	)
	(gr_poly
		(pts
			(xy 137.254742 -240.636298) (xy 137.154666 -240.536222) (xy 137.05459 -240.636298) (xy 137.05459 -240.680748)
			(xy 137.254742 -240.680748)
		)
		(stroke
			(width 0)
			(type solid)
		)
		(fill yes)
		(layer "In4.Cu")
		(net "M_J_CPU1_SA_DQ<25>")
	)
	(gr_poly
		(pts
			(xy 137.254742 -240.232438) (xy 137.254742 -240.187988) (xy 137.05459 -240.187988) (xy 137.05459 -240.232438)
			(xy 137.154666 -240.332514)
		)
		(stroke
			(width 0)
			(type solid)
		)
		(fill yes)
		(layer "In4.Cu")
		(net "M_J_CPU1_SA_DQ<26>")
	)
	(gr_poly
		(pts
			(xy 137.254742 -239.016286) (xy 137.154666 -238.91621) (xy 137.05459 -239.016286) (xy 137.05459 -239.060736)
			(xy 137.254742 -239.060736)
		)
		(stroke
			(width 0)
			(type solid)
		)
		(fill yes)
		(layer "In4.Cu")
		(net "M_J_CPU1_SA_DQ<21>")
	)
	(gr_poly
		(pts
			(xy 137.254742 -238.612426) (xy 137.254742 -238.567976) (xy 137.05459 -238.567976) (xy 137.05459 -238.612426)
			(xy 137.154666 -238.712502)
		)
		(stroke
			(width 0)
			(type solid)
		)
		(fill yes)
		(layer "In4.Cu")
		(net "M_J_CPU1_SA_DQ<22>")
	)
	(gr_poly
		(pts
			(xy 137.254742 -237.39602) (xy 137.154666 -237.296198) (xy 137.05459 -237.39602) (xy 137.05459 -237.443772)
			(xy 137.254742 -237.443772)
		)
		(stroke
			(width 0)
			(type solid)
		)
		(fill yes)
		(layer "In4.Cu")
		(net "M_J_CPU1_SA_DQS_DN<7>")
	)
	(gr_poly
		(pts
			(xy 137.254742 -236.992668) (xy 137.254742 -236.944916) (xy 137.05459 -236.944916) (xy 137.05459 -236.992668)
			(xy 137.154666 -237.09249)
		)
		(stroke
			(width 0)
			(type solid)
		)
		(fill yes)
		(layer "In4.Cu")
		(net "M_J_CPU1_SA_DQS_DN<2>")
	)
	(gr_poly
		(pts
			(xy 137.254742 -235.776262) (xy 137.154666 -235.676186) (xy 137.05459 -235.776262) (xy 137.05459 -235.820712)
			(xy 137.254742 -235.820712)
		)
		(stroke
			(width 0)
			(type solid)
		)
		(fill yes)
		(layer "In4.Cu")
		(net "M_J_CPU1_SA_DQ<17>")
	)
	(gr_poly
		(pts
			(xy 137.254742 -235.372402) (xy 137.254742 -235.327952) (xy 137.05459 -235.327952) (xy 137.05459 -235.372402)
			(xy 137.154666 -235.472478)
		)
		(stroke
			(width 0)
			(type solid)
		)
		(fill yes)
		(layer "In4.Cu")
		(net "M_J_CPU1_SA_DQ<18>")
	)
	(gr_poly
		(pts
			(xy 137.254742 -234.15625) (xy 137.154666 -234.056174) (xy 137.05459 -234.15625) (xy 137.05459 -234.2007)
			(xy 137.254742 -234.2007)
		)
		(stroke
			(width 0)
			(type solid)
		)
		(fill yes)
		(layer "In4.Cu")
		(net "M_J_CPU1_SA_DQ<13>")
	)
	(gr_poly
		(pts
			(xy 137.254742 -233.75239) (xy 137.254742 -233.70794) (xy 137.05459 -233.70794) (xy 137.05459 -233.75239)
			(xy 137.154666 -233.852466)
		)
		(stroke
			(width 0)
			(type solid)
		)
		(fill yes)
		(layer "In4.Cu")
		(net "M_J_CPU1_SA_DQ<14>")
	)
	(gr_poly
		(pts
			(xy 137.254742 -232.535984) (xy 137.154666 -232.436162) (xy 137.05459 -232.535984) (xy 137.05459 -232.583736)
			(xy 137.254742 -232.583736)
		)
		(stroke
			(width 0)
			(type solid)
		)
		(fill yes)
		(layer "In4.Cu")
		(net "M_J_CPU1_SA_DQS_DN<6>")
	)
	(gr_poly
		(pts
			(xy 137.254742 -232.132632) (xy 137.254742 -232.08488) (xy 137.05459 -232.08488) (xy 137.05459 -232.132632)
			(xy 137.154666 -232.232454)
		)
		(stroke
			(width 0)
			(type solid)
		)
		(fill yes)
		(layer "In4.Cu")
		(net "M_J_CPU1_SA_DQS_DN<1>")
	)
	(gr_poly
		(pts
			(xy 137.254742 -230.916226) (xy 137.154666 -230.81615) (xy 137.05459 -230.916226) (xy 137.05459 -230.960676)
			(xy 137.254742 -230.960676)
		)
		(stroke
			(width 0)
			(type solid)
		)
		(fill yes)
		(layer "In4.Cu")
		(net "M_J_CPU1_SA_DQ<9>")
	)
	(gr_poly
		(pts
			(xy 137.254742 -230.51262) (xy 137.254742 -230.46817) (xy 137.05459 -230.46817) (xy 137.05459 -230.51262)
			(xy 137.154666 -230.612696)
		)
		(stroke
			(width 0)
			(type solid)
		)
		(fill yes)
		(layer "In4.Cu")
		(net "M_J_CPU1_SA_DQ<10>")
	)
	(gr_poly
		(pts
			(xy 137.254742 -229.296214) (xy 137.154666 -229.196138) (xy 137.05459 -229.296214) (xy 137.05459 -229.340664)
			(xy 137.254742 -229.340664)
		)
		(stroke
			(width 0)
			(type solid)
		)
		(fill yes)
		(layer "In4.Cu")
		(net "M_J_CPU1_SA_DQ<5>")
	)
	(gr_poly
		(pts
			(xy 137.254742 -228.892608) (xy 137.254742 -228.848158) (xy 137.05459 -228.848158) (xy 137.05459 -228.892608)
			(xy 137.154666 -228.992684)
		)
		(stroke
			(width 0)
			(type solid)
		)
		(fill yes)
		(layer "In4.Cu")
		(net "M_J_CPU1_SA_DQ<6>")
	)
	(gr_poly
		(pts
			(xy 137.254742 -227.676202) (xy 137.154666 -227.57638) (xy 137.05459 -227.676202) (xy 137.05459 -227.723954)
			(xy 137.254742 -227.723954)
		)
		(stroke
			(width 0)
			(type solid)
		)
		(fill yes)
		(layer "In4.Cu")
		(net "M_J_CPU1_SA_DQS_DN<5>")
	)
	(gr_poly
		(pts
			(xy 137.254742 -227.27285) (xy 137.254742 -227.225098) (xy 137.05459 -227.225098) (xy 137.05459 -227.27285)
			(xy 137.154666 -227.372672)
		)
		(stroke
			(width 0)
			(type solid)
		)
		(fill yes)
		(layer "In4.Cu")
		(net "M_J_CPU1_SA_DQS_DN<0>")
	)
	(gr_poly
		(pts
			(xy 137.254742 -226.056444) (xy 137.154666 -225.956368) (xy 137.05459 -226.056444) (xy 137.05459 -226.100894)
			(xy 137.254742 -226.100894)
		)
		(stroke
			(width 0)
			(type solid)
		)
		(fill yes)
		(layer "In4.Cu")
		(net "M_J_CPU1_SA_DQ<1>")
	)
	(gr_poly
		(pts
			(xy 137.254742 -225.652584) (xy 137.254742 -225.608134) (xy 137.05459 -225.608134) (xy 137.05459 -225.652584)
			(xy 137.154666 -225.75266)
		)
		(stroke
			(width 0)
			(type solid)
		)
		(fill yes)
		(layer "In4.Cu")
		(net "M_J_CPU1_SA_DQ<2>")
	)
	(gr_poly
		(pts
			(xy 137.554716 -293.32428) (xy 137.554716 -293.27983) (xy 137.354564 -293.27983) (xy 137.354564 -293.32428)
			(xy 137.45464 -293.424356)
		)
		(stroke
			(width 0)
			(type solid)
		)
		(fill yes)
		(layer "In4.Cu")
		(net "M_J_CPU1_SB_DQ<31>")
	)
	(gr_poly
		(pts
			(xy 137.554716 -292.108128) (xy 137.45464 -292.008052) (xy 137.354564 -292.108128) (xy 137.354564 -292.152578)
			(xy 137.554716 -292.152578)
		)
		(stroke
			(width 0)
			(type solid)
		)
		(fill yes)
		(layer "In4.Cu")
		(net "M_J_CPU1_SB_DQ<28>")
	)
	(gr_poly
		(pts
			(xy 137.554716 -291.704522) (xy 137.554716 -291.65677) (xy 137.354564 -291.65677) (xy 137.354564 -291.704522)
			(xy 137.45464 -291.804344)
		)
		(stroke
			(width 0)
			(type solid)
		)
		(fill yes)
		(layer "In4.Cu")
		(net "M_J_CPU1_SB_DQS_DP<8>")
	)
	(gr_poly
		(pts
			(xy 137.554716 -290.487862) (xy 137.45464 -290.38804) (xy 137.354564 -290.487862) (xy 137.354564 -290.535614)
			(xy 137.554716 -290.535614)
		)
		(stroke
			(width 0)
			(type solid)
		)
		(fill yes)
		(layer "In4.Cu")
		(net "M_J_CPU1_SB_DQS_DP<3>")
	)
	(gr_poly
		(pts
			(xy 137.554716 -290.084256) (xy 137.554716 -290.039806) (xy 137.354564 -290.039806) (xy 137.354564 -290.084256)
			(xy 137.45464 -290.184332)
		)
		(stroke
			(width 0)
			(type solid)
		)
		(fill yes)
		(layer "In4.Cu")
		(net "M_J_CPU1_SB_DQ<27>")
	)
	(gr_poly
		(pts
			(xy 137.554716 -288.868104) (xy 137.45464 -288.768028) (xy 137.354564 -288.868104) (xy 137.354564 -288.912554)
			(xy 137.554716 -288.912554)
		)
		(stroke
			(width 0)
			(type solid)
		)
		(fill yes)
		(layer "In4.Cu")
		(net "M_J_CPU1_SB_DQ<24>")
	)
	(gr_poly
		(pts
			(xy 137.554716 -288.464498) (xy 137.554716 -288.420048) (xy 137.354564 -288.420048) (xy 137.354564 -288.464498)
			(xy 137.45464 -288.564574)
		)
		(stroke
			(width 0)
			(type solid)
		)
		(fill yes)
		(layer "In4.Cu")
		(net "M_J_CPU1_SB_DQ<23>")
	)
	(gr_poly
		(pts
			(xy 137.554716 -287.248092) (xy 137.45464 -287.148016) (xy 137.354564 -287.248092) (xy 137.354564 -287.292542)
			(xy 137.554716 -287.292542)
		)
		(stroke
			(width 0)
			(type solid)
		)
		(fill yes)
		(layer "In4.Cu")
		(net "M_J_CPU1_SB_DQ<20>")
	)
	(gr_poly
		(pts
			(xy 137.554716 -286.844486) (xy 137.554716 -286.796734) (xy 137.354564 -286.796734) (xy 137.354564 -286.844486)
			(xy 137.45464 -286.944562)
		)
		(stroke
			(width 0)
			(type solid)
		)
		(fill yes)
		(layer "In4.Cu")
		(net "M_J_CPU1_SB_DQS_DP<7>")
	)
	(gr_poly
		(pts
			(xy 137.554716 -285.62808) (xy 137.45464 -285.528258) (xy 137.354564 -285.62808) (xy 137.354564 -285.675832)
			(xy 137.554716 -285.675832)
		)
		(stroke
			(width 0)
			(type solid)
		)
		(fill yes)
		(layer "In4.Cu")
		(net "M_J_CPU1_SB_DQS_DP<2>")
	)
	(gr_poly
		(pts
			(xy 137.554716 -285.224474) (xy 137.554716 -285.180024) (xy 137.354564 -285.180024) (xy 137.354564 -285.224474)
			(xy 137.45464 -285.32455)
		)
		(stroke
			(width 0)
			(type solid)
		)
		(fill yes)
		(layer "In4.Cu")
		(net "M_J_CPU1_SB_DQ<19>")
	)
	(gr_poly
		(pts
			(xy 137.554716 -284.008322) (xy 137.45464 -283.908246) (xy 137.354564 -284.008322) (xy 137.354564 -284.052772)
			(xy 137.554716 -284.052772)
		)
		(stroke
			(width 0)
			(type solid)
		)
		(fill yes)
		(layer "In4.Cu")
		(net "M_J_CPU1_SB_DQ<16>")
	)
	(gr_poly
		(pts
			(xy 137.554716 -283.604462) (xy 137.554716 -283.560012) (xy 137.354564 -283.560012) (xy 137.354564 -283.604462)
			(xy 137.45464 -283.704538)
		)
		(stroke
			(width 0)
			(type solid)
		)
		(fill yes)
		(layer "In4.Cu")
		(net "M_J_CPU1_SB_DQ<15>")
	)
	(gr_poly
		(pts
			(xy 137.554716 -282.38831) (xy 137.45464 -282.288234) (xy 137.354564 -282.38831) (xy 137.354564 -282.43276)
			(xy 137.554716 -282.43276)
		)
		(stroke
			(width 0)
			(type solid)
		)
		(fill yes)
		(layer "In4.Cu")
		(net "M_J_CPU1_SB_DQ<12>")
	)
	(gr_poly
		(pts
			(xy 137.554716 -281.984704) (xy 137.554716 -281.936952) (xy 137.354564 -281.936952) (xy 137.354564 -281.984704)
			(xy 137.45464 -282.084526)
		)
		(stroke
			(width 0)
			(type solid)
		)
		(fill yes)
		(layer "In4.Cu")
		(net "M_J_CPU1_SB_DQS_DP<6>")
	)
	(gr_poly
		(pts
			(xy 137.554716 -280.768044) (xy 137.45464 -280.668222) (xy 137.354564 -280.768044) (xy 137.354564 -280.815796)
			(xy 137.554716 -280.815796)
		)
		(stroke
			(width 0)
			(type solid)
		)
		(fill yes)
		(layer "In4.Cu")
		(net "M_J_CPU1_SB_DQS_DP<1>")
	)
	(gr_poly
		(pts
			(xy 137.554716 -280.364438) (xy 137.554716 -280.319988) (xy 137.354564 -280.319988) (xy 137.354564 -280.364438)
			(xy 137.45464 -280.464514)
		)
		(stroke
			(width 0)
			(type solid)
		)
		(fill yes)
		(layer "In4.Cu")
		(net "M_J_CPU1_SB_DQ<11>")
	)
	(gr_poly
		(pts
			(xy 137.554716 -279.148286) (xy 137.45464 -279.04821) (xy 137.354564 -279.148286) (xy 137.354564 -279.192736)
			(xy 137.554716 -279.192736)
		)
		(stroke
			(width 0)
			(type solid)
		)
		(fill yes)
		(layer "In4.Cu")
		(net "M_J_CPU1_SB_DQ<8>")
	)
	(gr_poly
		(pts
			(xy 137.554716 -278.744426) (xy 137.554716 -278.699976) (xy 137.354564 -278.699976) (xy 137.354564 -278.744426)
			(xy 137.45464 -278.844502)
		)
		(stroke
			(width 0)
			(type solid)
		)
		(fill yes)
		(layer "In4.Cu")
		(net "M_J_CPU1_SB_DQ<7>")
	)
	(gr_poly
		(pts
			(xy 137.554716 -277.528274) (xy 137.45464 -277.428198) (xy 137.354564 -277.528274) (xy 137.354564 -277.572724)
			(xy 137.554716 -277.572724)
		)
		(stroke
			(width 0)
			(type solid)
		)
		(fill yes)
		(layer "In4.Cu")
		(net "M_J_CPU1_SB_DQ<4>")
	)
	(gr_poly
		(pts
			(xy 137.554716 -277.124668) (xy 137.554716 -277.076916) (xy 137.354564 -277.076916) (xy 137.354564 -277.124668)
			(xy 137.45464 -277.22449)
		)
		(stroke
			(width 0)
			(type solid)
		)
		(fill yes)
		(layer "In4.Cu")
		(net "M_J_CPU1_SB_DQS_DP<5>")
	)
	(gr_poly
		(pts
			(xy 137.554716 -275.908008) (xy 137.45464 -275.808186) (xy 137.354564 -275.908008) (xy 137.354564 -275.95576)
			(xy 137.554716 -275.95576)
		)
		(stroke
			(width 0)
			(type solid)
		)
		(fill yes)
		(layer "In4.Cu")
		(net "M_J_CPU1_SB_DQS_DP<0>")
	)
	(gr_poly
		(pts
			(xy 137.554716 -275.504402) (xy 137.554716 -275.459952) (xy 137.354564 -275.459952) (xy 137.354564 -275.504402)
			(xy 137.45464 -275.604478)
		)
		(stroke
			(width 0)
			(type solid)
		)
		(fill yes)
		(layer "In4.Cu")
		(net "M_J_CPU1_SB_DQ<3>")
	)
	(gr_poly
		(pts
			(xy 137.554716 -274.28825) (xy 137.45464 -274.188174) (xy 137.354564 -274.28825) (xy 137.354564 -274.3327)
			(xy 137.554716 -274.3327)
		)
		(stroke
			(width 0)
			(type solid)
		)
		(fill yes)
		(layer "In4.Cu")
		(net "M_J_CPU1_SB_DQ<0>")
	)
	(gr_poly
		(pts
			(xy 137.554716 -273.88439) (xy 137.554716 -273.83994) (xy 137.354564 -273.83994) (xy 137.354564 -273.88439)
			(xy 137.45464 -273.984466)
		)
		(stroke
			(width 0)
			(type solid)
		)
		(fill yes)
		(layer "In4.Cu")
		(net "M_J_CPU1_SB_CB<3>")
	)
	(gr_poly
		(pts
			(xy 137.554716 -272.668238) (xy 137.45464 -272.568162) (xy 137.354564 -272.668238) (xy 137.354564 -272.712688)
			(xy 137.554716 -272.712688)
		)
		(stroke
			(width 0)
			(type solid)
		)
		(fill yes)
		(layer "In4.Cu")
		(net "M_J_CPU1_SB_CB<0>")
	)
	(gr_poly
		(pts
			(xy 137.554716 -272.264632) (xy 137.554716 -272.21688) (xy 137.354564 -272.21688) (xy 137.354564 -272.264632)
			(xy 137.45464 -272.364454)
		)
		(stroke
			(width 0)
			(type solid)
		)
		(fill yes)
		(layer "In4.Cu")
		(net "M_J_CPU1_SB_DQS_DP<4>")
	)
	(gr_poly
		(pts
			(xy 137.554716 -271.047972) (xy 137.45464 -270.94815) (xy 137.354564 -271.047972) (xy 137.354564 -271.095724)
			(xy 137.554716 -271.095724)
		)
		(stroke
			(width 0)
			(type solid)
		)
		(fill yes)
		(layer "In4.Cu")
		(net "M_J_CPU1_SB_DQS_DP<9>")
	)
	(gr_poly
		(pts
			(xy 137.554716 -270.644366) (xy 137.554716 -270.599916) (xy 137.354564 -270.599916) (xy 137.354564 -270.644366)
			(xy 137.45464 -270.744442)
		)
		(stroke
			(width 0)
			(type solid)
		)
		(fill yes)
		(layer "In4.Cu")
		(net "M_J_CPU1_SB_CB<7>")
	)
	(gr_poly
		(pts
			(xy 137.554716 -269.428214) (xy 137.45464 -269.328138) (xy 137.354564 -269.428214) (xy 137.354564 -269.472664)
			(xy 137.554716 -269.472664)
		)
		(stroke
			(width 0)
			(type solid)
		)
		(fill yes)
		(layer "In4.Cu")
		(net "M_J_CPU1_SB_CB<4>")
	)
	(gr_poly
		(pts
			(xy 137.554716 -267.808202) (xy 137.45464 -267.708126) (xy 137.354564 -267.808202) (xy 137.354564 -267.852652)
			(xy 137.554716 -267.852652)
		)
		(stroke
			(width 0)
			(type solid)
		)
		(fill yes)
		(layer "In4.Cu")
		(net "M_J_CPU1_SB_RSP<0>")
	)
	(gr_poly
		(pts
			(xy 137.554716 -265.78433) (xy 137.554716 -265.73988) (xy 137.354564 -265.73988) (xy 137.354564 -265.78433)
			(xy 137.45464 -265.884406)
		)
		(stroke
			(width 0)
			(type solid)
		)
		(fill yes)
		(layer "In4.Cu")
		(net "M_J_CPU1_SB_CS_N<0>")
	)
	(gr_poly
		(pts
			(xy 137.554716 -264.568178) (xy 137.45464 -264.468102) (xy 137.354564 -264.568178) (xy 137.354564 -264.612628)
			(xy 137.554716 -264.612628)
		)
		(stroke
			(width 0)
			(type solid)
		)
		(fill yes)
		(layer "In4.Cu")
		(net "M_J_CPU1_SB_CA<6>")
	)
	(gr_poly
		(pts
			(xy 137.554716 -264.164318) (xy 137.554716 -264.119868) (xy 137.354564 -264.119868) (xy 137.354564 -264.164318)
			(xy 137.45464 -264.264394)
		)
		(stroke
			(width 0)
			(type solid)
		)
		(fill yes)
		(layer "In4.Cu")
		(net "M_J_CPU1_SB_CA<5>")
	)
	(gr_poly
		(pts
			(xy 137.554716 -262.948166) (xy 137.45464 -262.84809) (xy 137.354564 -262.948166) (xy 137.354564 -262.992616)
			(xy 137.554716 -262.992616)
		)
		(stroke
			(width 0)
			(type solid)
		)
		(fill yes)
		(layer "In4.Cu")
		(net "M_J_CPU1_SB_CA<2>")
	)
	(gr_poly
		(pts
			(xy 137.554716 -262.544306) (xy 137.554716 -262.499856) (xy 137.354564 -262.499856) (xy 137.354564 -262.544306)
			(xy 137.45464 -262.644382)
		)
		(stroke
			(width 0)
			(type solid)
		)
		(fill yes)
		(layer "In4.Cu")
		(net "M_J_CPU1_SB_CA<1>")
	)
	(gr_poly
		(pts
			(xy 137.724896 -256.026158) (xy 137.62482 -255.926336) (xy 137.524744 -256.026158) (xy 137.524744 -256.07391)
			(xy 137.724896 -256.07391)
		)
		(stroke
			(width 0)
			(type solid)
		)
		(fill yes)
		(layer "In4.Cu")
		(net "M_J_CPU1_CLK_DP<0>")
	)
	(gr_poly
		(pts
			(xy 137.724896 -255.622552) (xy 137.724896 -255.578102) (xy 137.524744 -255.578102) (xy 137.524744 -255.622552)
			(xy 137.62482 -255.722628)
		)
		(stroke
			(width 0)
			(type solid)
		)
		(fill yes)
		(layer "In4.Cu")
		(net "M_J_CPU1_SA_PAR")
	)
	(gr_poly
		(pts
			(xy 137.724896 -254.4064) (xy 137.62482 -254.306324) (xy 137.524744 -254.4064) (xy 137.524744 -254.45085)
			(xy 137.724896 -254.45085)
		)
		(stroke
			(width 0)
			(type solid)
		)
		(fill yes)
		(layer "In4.Cu")
		(net "M_J_CPU1_SA_CA<4>")
	)
	(gr_poly
		(pts
			(xy 137.724896 -254.00254) (xy 137.724896 -253.95809) (xy 137.524744 -253.95809) (xy 137.524744 -254.00254)
			(xy 137.62482 -254.102616)
		)
		(stroke
			(width 0)
			(type solid)
		)
		(fill yes)
		(layer "In4.Cu")
		(net "M_J_CPU1_SA_CA<3>")
	)
	(gr_poly
		(pts
			(xy 137.724896 -252.786388) (xy 137.62482 -252.686312) (xy 137.524744 -252.786388) (xy 137.524744 -252.830838)
			(xy 137.724896 -252.830838)
		)
		(stroke
			(width 0)
			(type solid)
		)
		(fill yes)
		(layer "In4.Cu")
		(net "M_J_CPU1_SA_CA<0>")
	)
	(gr_poly
		(pts
			(xy 137.724896 -251.166376) (xy 137.62482 -251.0663) (xy 137.524744 -251.166376) (xy 137.524744 -251.210826)
			(xy 137.724896 -251.210826)
		)
		(stroke
			(width 0)
			(type solid)
		)
		(fill yes)
		(layer "In4.Cu")
		(net "M_J_CPU1_SA_CS_N<0>")
	)
	(gr_poly
		(pts
			(xy 137.724896 -250.762516) (xy 137.724896 -250.718066) (xy 137.524744 -250.718066) (xy 137.524744 -250.762516)
			(xy 137.62482 -250.862592)
		)
		(stroke
			(width 0)
			(type solid)
		)
		(fill yes)
		(layer "In4.Cu")
		(net "M_J_CPU1_RESET_N")
	)
	(gr_poly
		(pts
			(xy 137.724896 -249.142504) (xy 137.724896 -249.098054) (xy 137.524744 -249.098054) (xy 137.524744 -249.142504)
			(xy 137.62482 -249.24258)
		)
		(stroke
			(width 0)
			(type solid)
		)
		(fill yes)
		(layer "In4.Cu")
		(net "M_J_CPU1_SA_CB<7>")
	)
	(gr_poly
		(pts
			(xy 137.724896 -247.926352) (xy 137.62482 -247.826276) (xy 137.524744 -247.926352) (xy 137.524744 -247.970802)
			(xy 137.724896 -247.970802)
		)
		(stroke
			(width 0)
			(type solid)
		)
		(fill yes)
		(layer "In4.Cu")
		(net "M_J_CPU1_SA_CB<4>")
	)
	(gr_poly
		(pts
			(xy 137.724896 -247.522746) (xy 137.724896 -247.474994) (xy 137.524744 -247.474994) (xy 137.524744 -247.522746)
			(xy 137.62482 -247.622568)
		)
		(stroke
			(width 0)
			(type solid)
		)
		(fill yes)
		(layer "In4.Cu")
		(net "M_J_CPU1_SA_DQS_DP<9>")
	)
	(gr_poly
		(pts
			(xy 137.724896 -246.306086) (xy 137.62482 -246.206264) (xy 137.524744 -246.306086) (xy 137.524744 -246.353838)
			(xy 137.724896 -246.353838)
		)
		(stroke
			(width 0)
			(type solid)
		)
		(fill yes)
		(layer "In4.Cu")
		(net "M_J_CPU1_SA_DQS_DP<4>")
	)
	(gr_poly
		(pts
			(xy 137.724896 -245.90248) (xy 137.724896 -245.85803) (xy 137.524744 -245.85803) (xy 137.524744 -245.90248)
			(xy 137.62482 -246.002556)
		)
		(stroke
			(width 0)
			(type solid)
		)
		(fill yes)
		(layer "In4.Cu")
		(net "M_J_CPU1_SA_CB<3>")
	)
	(gr_poly
		(pts
			(xy 137.724896 -244.686328) (xy 137.62482 -244.586252) (xy 137.524744 -244.686328) (xy 137.524744 -244.730778)
			(xy 137.724896 -244.730778)
		)
		(stroke
			(width 0)
			(type solid)
		)
		(fill yes)
		(layer "In4.Cu")
		(net "M_J_CPU1_SA_CB<0>")
	)
	(gr_poly
		(pts
			(xy 137.724896 -244.282468) (xy 137.724896 -244.238018) (xy 137.524744 -244.238018) (xy 137.524744 -244.282468)
			(xy 137.62482 -244.382544)
		)
		(stroke
			(width 0)
			(type solid)
		)
		(fill yes)
		(layer "In4.Cu")
		(net "M_J_CPU1_SA_DQ<31>")
	)
	(gr_poly
		(pts
			(xy 137.724896 -243.066316) (xy 137.62482 -242.96624) (xy 137.524744 -243.066316) (xy 137.524744 -243.110766)
			(xy 137.724896 -243.110766)
		)
		(stroke
			(width 0)
			(type solid)
		)
		(fill yes)
		(layer "In4.Cu")
		(net "M_J_CPU1_SA_DQ<28>")
	)
	(gr_poly
		(pts
			(xy 137.724896 -242.66271) (xy 137.724896 -242.614958) (xy 137.524744 -242.614958) (xy 137.524744 -242.66271)
			(xy 137.62482 -242.762532)
		)
		(stroke
			(width 0)
			(type solid)
		)
		(fill yes)
		(layer "In4.Cu")
		(net "M_J_CPU1_SA_DQS_DP<8>")
	)
	(gr_poly
		(pts
			(xy 137.724896 -241.44605) (xy 137.62482 -241.346228) (xy 137.524744 -241.44605) (xy 137.524744 -241.493802)
			(xy 137.724896 -241.493802)
		)
		(stroke
			(width 0)
			(type solid)
		)
		(fill yes)
		(layer "In4.Cu")
		(net "M_J_CPU1_SA_DQS_DP<3>")
	)
	(gr_poly
		(pts
			(xy 137.724896 -241.042444) (xy 137.724896 -240.997994) (xy 137.524744 -240.997994) (xy 137.524744 -241.042444)
			(xy 137.62482 -241.14252)
		)
		(stroke
			(width 0)
			(type solid)
		)
		(fill yes)
		(layer "In4.Cu")
		(net "M_J_CPU1_SA_DQ<27>")
	)
	(gr_poly
		(pts
			(xy 137.724896 -239.826292) (xy 137.62482 -239.726216) (xy 137.524744 -239.826292) (xy 137.524744 -239.870742)
			(xy 137.724896 -239.870742)
		)
		(stroke
			(width 0)
			(type solid)
		)
		(fill yes)
		(layer "In4.Cu")
		(net "M_J_CPU1_SA_DQ<24>")
	)
	(gr_poly
		(pts
			(xy 137.724896 -239.422432) (xy 137.724896 -239.377982) (xy 137.524744 -239.377982) (xy 137.524744 -239.422432)
			(xy 137.62482 -239.522508)
		)
		(stroke
			(width 0)
			(type solid)
		)
		(fill yes)
		(layer "In4.Cu")
		(net "M_J_CPU1_SA_DQ<23>")
	)
	(gr_poly
		(pts
			(xy 137.724896 -238.20628) (xy 137.62482 -238.106204) (xy 137.524744 -238.20628) (xy 137.524744 -238.25073)
			(xy 137.724896 -238.25073)
		)
		(stroke
			(width 0)
			(type solid)
		)
		(fill yes)
		(layer "In4.Cu")
		(net "M_J_CPU1_SA_DQ<20>")
	)
	(gr_poly
		(pts
			(xy 137.724896 -237.802674) (xy 137.724896 -237.754922) (xy 137.524744 -237.754922) (xy 137.524744 -237.802674)
			(xy 137.62482 -237.902496)
		)
		(stroke
			(width 0)
			(type solid)
		)
		(fill yes)
		(layer "In4.Cu")
		(net "M_J_CPU1_SA_DQS_DP<7>")
	)
	(gr_poly
		(pts
			(xy 137.724896 -236.586014) (xy 137.62482 -236.486192) (xy 137.524744 -236.586014) (xy 137.524744 -236.633766)
			(xy 137.724896 -236.633766)
		)
		(stroke
			(width 0)
			(type solid)
		)
		(fill yes)
		(layer "In4.Cu")
		(net "M_J_CPU1_SA_DQS_DP<2>")
	)
	(gr_poly
		(pts
			(xy 137.724896 -236.182408) (xy 137.724896 -236.137958) (xy 137.524744 -236.137958) (xy 137.524744 -236.182408)
			(xy 137.62482 -236.282484)
		)
		(stroke
			(width 0)
			(type solid)
		)
		(fill yes)
		(layer "In4.Cu")
		(net "M_J_CPU1_SA_DQ<19>")
	)
	(gr_poly
		(pts
			(xy 137.724896 -234.966256) (xy 137.62482 -234.86618) (xy 137.524744 -234.966256) (xy 137.524744 -235.010706)
			(xy 137.724896 -235.010706)
		)
		(stroke
			(width 0)
			(type solid)
		)
		(fill yes)
		(layer "In4.Cu")
		(net "M_J_CPU1_SA_DQ<16>")
	)
	(gr_poly
		(pts
			(xy 137.724896 -234.562396) (xy 137.724896 -234.517946) (xy 137.524744 -234.517946) (xy 137.524744 -234.562396)
			(xy 137.62482 -234.662472)
		)
		(stroke
			(width 0)
			(type solid)
		)
		(fill yes)
		(layer "In4.Cu")
		(net "M_J_CPU1_SA_DQ<15>")
	)
	(gr_poly
		(pts
			(xy 137.724896 -233.346244) (xy 137.62482 -233.246168) (xy 137.524744 -233.346244) (xy 137.524744 -233.390694)
			(xy 137.724896 -233.390694)
		)
		(stroke
			(width 0)
			(type solid)
		)
		(fill yes)
		(layer "In4.Cu")
		(net "M_J_CPU1_SA_DQ<12>")
	)
	(gr_poly
		(pts
			(xy 137.724896 -232.942638) (xy 137.724896 -232.894886) (xy 137.524744 -232.894886) (xy 137.524744 -232.942638)
			(xy 137.62482 -233.04246)
		)
		(stroke
			(width 0)
			(type solid)
		)
		(fill yes)
		(layer "In4.Cu")
		(net "M_J_CPU1_SA_DQS_DP<6>")
	)
	(gr_poly
		(pts
			(xy 137.724896 -231.725978) (xy 137.62482 -231.626156) (xy 137.524744 -231.725978) (xy 137.524744 -231.77373)
			(xy 137.724896 -231.77373)
		)
		(stroke
			(width 0)
			(type solid)
		)
		(fill yes)
		(layer "In4.Cu")
		(net "M_J_CPU1_SA_DQS_DP<1>")
	)
	(gr_poly
		(pts
			(xy 137.724896 -231.322626) (xy 137.724896 -231.278176) (xy 137.524744 -231.278176) (xy 137.524744 -231.322626)
			(xy 137.62482 -231.422702)
		)
		(stroke
			(width 0)
			(type solid)
		)
		(fill yes)
		(layer "In4.Cu")
		(net "M_J_CPU1_SA_DQ<11>")
	)
	(gr_poly
		(pts
			(xy 137.724896 -230.10622) (xy 137.62482 -230.006144) (xy 137.524744 -230.10622) (xy 137.524744 -230.15067)
			(xy 137.724896 -230.15067)
		)
		(stroke
			(width 0)
			(type solid)
		)
		(fill yes)
		(layer "In4.Cu")
		(net "M_J_CPU1_SA_DQ<8>")
	)
	(gr_poly
		(pts
			(xy 137.724896 -229.702614) (xy 137.724896 -229.658164) (xy 137.524744 -229.658164) (xy 137.524744 -229.702614)
			(xy 137.62482 -229.80269)
		)
		(stroke
			(width 0)
			(type solid)
		)
		(fill yes)
		(layer "In4.Cu")
		(net "M_J_CPU1_SA_DQ<7>")
	)
	(gr_poly
		(pts
			(xy 137.724896 -228.486462) (xy 137.62482 -228.386386) (xy 137.524744 -228.486462) (xy 137.524744 -228.530912)
			(xy 137.724896 -228.530912)
		)
		(stroke
			(width 0)
			(type solid)
		)
		(fill yes)
		(layer "In4.Cu")
		(net "M_J_CPU1_SA_DQ<4>")
	)
	(gr_poly
		(pts
			(xy 137.724896 -228.082856) (xy 137.724896 -228.035104) (xy 137.524744 -228.035104) (xy 137.524744 -228.082856)
			(xy 137.62482 -228.182678)
		)
		(stroke
			(width 0)
			(type solid)
		)
		(fill yes)
		(layer "In4.Cu")
		(net "M_J_CPU1_SA_DQS_DP<5>")
	)
	(gr_poly
		(pts
			(xy 137.724896 -226.866196) (xy 137.62482 -226.766374) (xy 137.524744 -226.866196) (xy 137.524744 -226.913948)
			(xy 137.724896 -226.913948)
		)
		(stroke
			(width 0)
			(type solid)
		)
		(fill yes)
		(layer "In4.Cu")
		(net "M_J_CPU1_SA_DQS_DP<0>")
	)
	(gr_poly
		(pts
			(xy 137.724896 -226.46259) (xy 137.724896 -226.41814) (xy 137.524744 -226.41814) (xy 137.524744 -226.46259)
			(xy 137.62482 -226.562666)
		)
		(stroke
			(width 0)
			(type solid)
		)
		(fill yes)
		(layer "In4.Cu")
		(net "M_J_CPU1_SA_DQ<3>")
	)
	(gr_poly
		(pts
			(xy 137.724896 -225.246438) (xy 137.62482 -225.146362) (xy 137.524744 -225.246438) (xy 137.524744 -225.290888)
			(xy 137.724896 -225.290888)
		)
		(stroke
			(width 0)
			(type solid)
		)
		(fill yes)
		(layer "In4.Cu")
		(net "M_J_CPU1_SA_DQ<0>")
	)
	(gr_poly
		(pts
			(xy 138.02487 -292.918134) (xy 137.924794 -292.818058) (xy 137.824718 -292.918134) (xy 137.824718 -292.962584)
			(xy 138.02487 -292.962584)
		)
		(stroke
			(width 0)
			(type solid)
		)
		(fill yes)
		(layer "In4.Cu")
		(net "M_J_CPU1_SB_DQ<29>")
	)
	(gr_poly
		(pts
			(xy 138.02487 -292.514274) (xy 138.02487 -292.469824) (xy 137.824718 -292.469824) (xy 137.824718 -292.514274)
			(xy 137.924794 -292.61435)
		)
		(stroke
			(width 0)
			(type solid)
		)
		(fill yes)
		(layer "In4.Cu")
		(net "M_J_CPU1_SB_DQ<30>")
	)
	(gr_poly
		(pts
			(xy 138.02487 -291.297868) (xy 137.924794 -291.198046) (xy 137.824718 -291.297868) (xy 137.824718 -291.34562)
			(xy 138.02487 -291.34562)
		)
		(stroke
			(width 0)
			(type solid)
		)
		(fill yes)
		(layer "In4.Cu")
		(net "M_J_CPU1_SB_DQS_DN<8>")
	)
	(gr_poly
		(pts
			(xy 138.02487 -290.894516) (xy 138.02487 -290.846764) (xy 137.824718 -290.846764) (xy 137.824718 -290.894516)
			(xy 137.924794 -290.994338)
		)
		(stroke
			(width 0)
			(type solid)
		)
		(fill yes)
		(layer "In4.Cu")
		(net "M_J_CPU1_SB_DQS_DN<3>")
	)
	(gr_poly
		(pts
			(xy 138.02487 -289.67811) (xy 137.924794 -289.578034) (xy 137.824718 -289.67811) (xy 137.824718 -289.72256)
			(xy 138.02487 -289.72256)
		)
		(stroke
			(width 0)
			(type solid)
		)
		(fill yes)
		(layer "In4.Cu")
		(net "M_J_CPU1_SB_DQ<25>")
	)
	(gr_poly
		(pts
			(xy 138.02487 -289.27425) (xy 138.02487 -289.2298) (xy 137.824718 -289.2298) (xy 137.824718 -289.27425)
			(xy 137.924794 -289.374326)
		)
		(stroke
			(width 0)
			(type solid)
		)
		(fill yes)
		(layer "In4.Cu")
		(net "M_J_CPU1_SB_DQ<26>")
	)
	(gr_poly
		(pts
			(xy 138.02487 -288.058098) (xy 137.924794 -287.958022) (xy 137.824718 -288.058098) (xy 137.824718 -288.102548)
			(xy 138.02487 -288.102548)
		)
		(stroke
			(width 0)
			(type solid)
		)
		(fill yes)
		(layer "In4.Cu")
		(net "M_J_CPU1_SB_DQ<21>")
	)
	(gr_poly
		(pts
			(xy 138.02487 -287.654492) (xy 138.02487 -287.610042) (xy 137.824718 -287.610042) (xy 137.824718 -287.654492)
			(xy 137.924794 -287.754568)
		)
		(stroke
			(width 0)
			(type solid)
		)
		(fill yes)
		(layer "In4.Cu")
		(net "M_J_CPU1_SB_DQ<22>")
	)
	(gr_poly
		(pts
			(xy 138.02487 -286.438086) (xy 137.924794 -286.33801) (xy 137.824718 -286.438086) (xy 137.824718 -286.485838)
			(xy 138.02487 -286.485838)
		)
		(stroke
			(width 0)
			(type solid)
		)
		(fill yes)
		(layer "In4.Cu")
		(net "M_J_CPU1_SB_DQS_DN<7>")
	)
	(gr_poly
		(pts
			(xy 138.02487 -286.034734) (xy 138.02487 -285.986982) (xy 137.824718 -285.986982) (xy 137.824718 -286.034734)
			(xy 137.924794 -286.134556)
		)
		(stroke
			(width 0)
			(type solid)
		)
		(fill yes)
		(layer "In4.Cu")
		(net "M_J_CPU1_SB_DQS_DN<2>")
	)
	(gr_poly
		(pts
			(xy 138.02487 -284.818328) (xy 137.924794 -284.718252) (xy 137.824718 -284.818328) (xy 137.824718 -284.862778)
			(xy 138.02487 -284.862778)
		)
		(stroke
			(width 0)
			(type solid)
		)
		(fill yes)
		(layer "In4.Cu")
		(net "M_J_CPU1_SB_DQ<17>")
	)
	(gr_poly
		(pts
			(xy 138.02487 -284.414468) (xy 138.02487 -284.370018) (xy 137.824718 -284.370018) (xy 137.824718 -284.414468)
			(xy 137.924794 -284.514544)
		)
		(stroke
			(width 0)
			(type solid)
		)
		(fill yes)
		(layer "In4.Cu")
		(net "M_J_CPU1_SB_DQ<18>")
	)
	(gr_poly
		(pts
			(xy 138.02487 -283.198316) (xy 137.924794 -283.09824) (xy 137.824718 -283.198316) (xy 137.824718 -283.242766)
			(xy 138.02487 -283.242766)
		)
		(stroke
			(width 0)
			(type solid)
		)
		(fill yes)
		(layer "In4.Cu")
		(net "M_J_CPU1_SB_DQ<13>")
	)
	(gr_poly
		(pts
			(xy 138.02487 -282.794456) (xy 138.02487 -282.750006) (xy 137.824718 -282.750006) (xy 137.824718 -282.794456)
			(xy 137.924794 -282.894532)
		)
		(stroke
			(width 0)
			(type solid)
		)
		(fill yes)
		(layer "In4.Cu")
		(net "M_J_CPU1_SB_DQ<14>")
	)
	(gr_poly
		(pts
			(xy 138.02487 -281.57805) (xy 137.924794 -281.478228) (xy 137.824718 -281.57805) (xy 137.824718 -281.625802)
			(xy 138.02487 -281.625802)
		)
		(stroke
			(width 0)
			(type solid)
		)
		(fill yes)
		(layer "In4.Cu")
		(net "M_J_CPU1_SB_DQS_DN<6>")
	)
	(gr_poly
		(pts
			(xy 138.02487 -281.174698) (xy 138.02487 -281.126946) (xy 137.824718 -281.126946) (xy 137.824718 -281.174698)
			(xy 137.924794 -281.27452)
		)
		(stroke
			(width 0)
			(type solid)
		)
		(fill yes)
		(layer "In4.Cu")
		(net "M_J_CPU1_SB_DQS_DN<1>")
	)
	(gr_poly
		(pts
			(xy 138.02487 -279.958292) (xy 137.924794 -279.858216) (xy 137.824718 -279.958292) (xy 137.824718 -280.002742)
			(xy 138.02487 -280.002742)
		)
		(stroke
			(width 0)
			(type solid)
		)
		(fill yes)
		(layer "In4.Cu")
		(net "M_J_CPU1_SB_DQ<9>")
	)
	(gr_poly
		(pts
			(xy 138.02487 -279.554432) (xy 138.02487 -279.509982) (xy 137.824718 -279.509982) (xy 137.824718 -279.554432)
			(xy 137.924794 -279.654508)
		)
		(stroke
			(width 0)
			(type solid)
		)
		(fill yes)
		(layer "In4.Cu")
		(net "M_J_CPU1_SB_DQ<10>")
	)
	(gr_poly
		(pts
			(xy 138.02487 -278.33828) (xy 137.924794 -278.238204) (xy 137.824718 -278.33828) (xy 137.824718 -278.38273)
			(xy 138.02487 -278.38273)
		)
		(stroke
			(width 0)
			(type solid)
		)
		(fill yes)
		(layer "In4.Cu")
		(net "M_J_CPU1_SB_DQ<5>")
	)
	(gr_poly
		(pts
			(xy 138.02487 -277.93442) (xy 138.02487 -277.88997) (xy 137.824718 -277.88997) (xy 137.824718 -277.93442)
			(xy 137.924794 -278.034496)
		)
		(stroke
			(width 0)
			(type solid)
		)
		(fill yes)
		(layer "In4.Cu")
		(net "M_J_CPU1_SB_DQ<6>")
	)
	(gr_poly
		(pts
			(xy 138.02487 -276.718014) (xy 137.924794 -276.618192) (xy 137.824718 -276.718014) (xy 137.824718 -276.765766)
			(xy 138.02487 -276.765766)
		)
		(stroke
			(width 0)
			(type solid)
		)
		(fill yes)
		(layer "In4.Cu")
		(net "M_J_CPU1_SB_DQS_DN<5>")
	)
	(gr_poly
		(pts
			(xy 138.02487 -276.314662) (xy 138.02487 -276.26691) (xy 137.824718 -276.26691) (xy 137.824718 -276.314662)
			(xy 137.924794 -276.414484)
		)
		(stroke
			(width 0)
			(type solid)
		)
		(fill yes)
		(layer "In4.Cu")
		(net "M_J_CPU1_SB_DQS_DN<0>")
	)
	(gr_poly
		(pts
			(xy 138.02487 -275.098256) (xy 137.924794 -274.99818) (xy 137.824718 -275.098256) (xy 137.824718 -275.142706)
			(xy 138.02487 -275.142706)
		)
		(stroke
			(width 0)
			(type solid)
		)
		(fill yes)
		(layer "In4.Cu")
		(net "M_J_CPU1_SB_DQ<1>")
	)
	(gr_poly
		(pts
			(xy 138.02487 -274.694396) (xy 138.02487 -274.649946) (xy 137.824718 -274.649946) (xy 137.824718 -274.694396)
			(xy 137.924794 -274.794472)
		)
		(stroke
			(width 0)
			(type solid)
		)
		(fill yes)
		(layer "In4.Cu")
		(net "M_J_CPU1_SB_DQ<2>")
	)
	(gr_poly
		(pts
			(xy 138.02487 -273.478244) (xy 137.924794 -273.378168) (xy 137.824718 -273.478244) (xy 137.824718 -273.522694)
			(xy 138.02487 -273.522694)
		)
		(stroke
			(width 0)
			(type solid)
		)
		(fill yes)
		(layer "In4.Cu")
		(net "M_J_CPU1_SB_CB<1>")
	)
	(gr_poly
		(pts
			(xy 138.02487 -273.074384) (xy 138.02487 -273.029934) (xy 137.824718 -273.029934) (xy 137.824718 -273.074384)
			(xy 137.924794 -273.17446)
		)
		(stroke
			(width 0)
			(type solid)
		)
		(fill yes)
		(layer "In4.Cu")
		(net "M_J_CPU1_SB_CB<2>")
	)
	(gr_poly
		(pts
			(xy 138.02487 -271.857978) (xy 137.924794 -271.758156) (xy 137.824718 -271.857978) (xy 137.824718 -271.90573)
			(xy 138.02487 -271.90573)
		)
		(stroke
			(width 0)
			(type solid)
		)
		(fill yes)
		(layer "In4.Cu")
		(net "M_J_CPU1_SB_DQS_DN<4>")
	)
	(gr_poly
		(pts
			(xy 138.02487 -271.454626) (xy 138.02487 -271.406874) (xy 137.824718 -271.406874) (xy 137.824718 -271.454626)
			(xy 137.924794 -271.554448)
		)
		(stroke
			(width 0)
			(type solid)
		)
		(fill yes)
		(layer "In4.Cu")
		(net "M_J_CPU1_SB_DQS_DN<9>")
	)
	(gr_poly
		(pts
			(xy 138.02487 -270.23822) (xy 137.924794 -270.138144) (xy 137.824718 -270.23822) (xy 137.824718 -270.28267)
			(xy 138.02487 -270.28267)
		)
		(stroke
			(width 0)
			(type solid)
		)
		(fill yes)
		(layer "In4.Cu")
		(net "M_J_CPU1_SB_CB<5>")
	)
	(gr_poly
		(pts
			(xy 138.02487 -269.83436) (xy 138.02487 -269.78991) (xy 137.824718 -269.78991) (xy 137.824718 -269.83436)
			(xy 137.924794 -269.934436)
		)
		(stroke
			(width 0)
			(type solid)
		)
		(fill yes)
		(layer "In4.Cu")
		(net "M_J_CPU1_SB_CB<6>")
	)
	(gr_poly
		(pts
			(xy 138.02487 -266.998196) (xy 137.924794 -266.89812) (xy 137.824718 -266.998196) (xy 137.824718 -267.042646)
			(xy 138.02487 -267.042646)
		)
		(stroke
			(width 0)
			(type solid)
		)
		(fill yes)
		(layer "In4.Cu")
		(net "M_J_CPU1_SA_RSP<0>")
	)
	(gr_poly
		(pts
			(xy 138.02487 -266.594336) (xy 138.02487 -266.549886) (xy 137.824718 -266.549886) (xy 137.824718 -266.594336)
			(xy 137.924794 -266.694412)
		)
		(stroke
			(width 0)
			(type solid)
		)
		(fill yes)
		(layer "In4.Cu")
		(net "M_J_CPU1_SB_CS_N<1>")
	)
	(gr_poly
		(pts
			(xy 138.02487 -265.378184) (xy 137.924794 -265.278108) (xy 137.824718 -265.378184) (xy 137.824718 -265.422634)
			(xy 138.02487 -265.422634)
		)
		(stroke
			(width 0)
			(type solid)
		)
		(fill yes)
		(layer "In4.Cu")
		(net "M_J_CPU1_SB_PAR")
	)
	(gr_poly
		(pts
			(xy 138.02487 -263.758172) (xy 137.924794 -263.658096) (xy 137.824718 -263.758172) (xy 137.824718 -263.802622)
			(xy 138.02487 -263.802622)
		)
		(stroke
			(width 0)
			(type solid)
		)
		(fill yes)
		(layer "In4.Cu")
		(net "M_J_CPU1_SB_CA<4>")
	)
	(gr_poly
		(pts
			(xy 138.02487 -263.354312) (xy 138.02487 -263.309862) (xy 137.824718 -263.309862) (xy 137.824718 -263.354312)
			(xy 137.924794 -263.454388)
		)
		(stroke
			(width 0)
			(type solid)
		)
		(fill yes)
		(layer "In4.Cu")
		(net "M_J_CPU1_SB_CA<3>")
	)
	(gr_poly
		(pts
			(xy 138.02487 -262.13816) (xy 137.924794 -262.038084) (xy 137.824718 -262.13816) (xy 137.824718 -262.18261)
			(xy 138.02487 -262.18261)
		)
		(stroke
			(width 0)
			(type solid)
		)
		(fill yes)
		(layer "In4.Cu")
		(net "M_J_CPU1_SB_CA<0>")
	)
	(gr_poly
		(pts
			(xy 138.194796 -256.432812) (xy 138.194796 -256.38506) (xy 137.994644 -256.38506) (xy 137.994644 -256.432812)
			(xy 138.09472 -256.532634)
		)
		(stroke
			(width 0)
			(type solid)
		)
		(fill yes)
		(layer "In4.Cu")
		(net "M_J_CPU1_CLK_DN<0>")
	)
	(gr_poly
		(pts
			(xy 138.194796 -255.216406) (xy 138.09472 -255.11633) (xy 137.994644 -255.216406) (xy 137.994644 -255.260856)
			(xy 138.194796 -255.260856)
		)
		(stroke
			(width 0)
			(type solid)
		)
		(fill yes)
		(layer "In4.Cu")
		(net "M_J_CPU1_SA_CA<6>")
	)
	(gr_poly
		(pts
			(xy 138.194796 -254.812546) (xy 138.194796 -254.768096) (xy 137.994644 -254.768096) (xy 137.994644 -254.812546)
			(xy 138.09472 -254.912622)
		)
		(stroke
			(width 0)
			(type solid)
		)
		(fill yes)
		(layer "In4.Cu")
		(net "M_J_CPU1_SA_CA<5>")
	)
	(gr_poly
		(pts
			(xy 138.194796 -253.596394) (xy 138.09472 -253.496318) (xy 137.994644 -253.596394) (xy 137.994644 -253.640844)
			(xy 138.194796 -253.640844)
		)
		(stroke
			(width 0)
			(type solid)
		)
		(fill yes)
		(layer "In4.Cu")
		(net "M_J_CPU1_SA_CA<2>")
	)
	(gr_poly
		(pts
			(xy 138.194796 -253.192534) (xy 138.194796 -253.148084) (xy 137.994644 -253.148084) (xy 137.994644 -253.192534)
			(xy 138.09472 -253.29261)
		)
		(stroke
			(width 0)
			(type solid)
		)
		(fill yes)
		(layer "In4.Cu")
		(net "M_J_CPU1_SA_CA<1>")
	)
	(gr_poly
		(pts
			(xy 138.194796 -251.976382) (xy 138.09472 -251.876306) (xy 137.994644 -251.976382) (xy 137.994644 -252.020832)
			(xy 138.194796 -252.020832)
		)
		(stroke
			(width 0)
			(type solid)
		)
		(fill yes)
		(layer "In4.Cu")
		(net "M_J_CPU1_SA_CS_N<1>")
	)
	(gr_poly
		(pts
			(xy 138.194796 -250.35637) (xy 138.09472 -250.256294) (xy 137.994644 -250.35637) (xy 137.994644 -250.40082)
			(xy 138.194796 -250.40082)
		)
		(stroke
			(width 0)
			(type solid)
		)
		(fill yes)
		(layer "In4.Cu")
		(net "M_J_CPU1_ALERT_R_N")
	)
	(gr_poly
		(pts
			(xy 138.194796 -248.736358) (xy 138.09472 -248.636282) (xy 137.994644 -248.736358) (xy 137.994644 -248.780808)
			(xy 138.194796 -248.780808)
		)
		(stroke
			(width 0)
			(type solid)
		)
		(fill yes)
		(layer "In4.Cu")
		(net "M_J_CPU1_SA_CB<5>")
	)
	(gr_poly
		(pts
			(xy 138.194796 -248.332498) (xy 138.194796 -248.288048) (xy 137.994644 -248.288048) (xy 137.994644 -248.332498)
			(xy 138.09472 -248.432574)
		)
		(stroke
			(width 0)
			(type solid)
		)
		(fill yes)
		(layer "In4.Cu")
		(net "M_J_CPU1_SA_CB<6>")
	)
	(gr_poly
		(pts
			(xy 138.194796 -247.116092) (xy 138.09472 -247.01627) (xy 137.994644 -247.116092) (xy 137.994644 -247.163844)
			(xy 138.194796 -247.163844)
		)
		(stroke
			(width 0)
			(type solid)
		)
		(fill yes)
		(layer "In4.Cu")
		(net "M_J_CPU1_SA_DQS_DN<9>")
	)
	(gr_poly
		(pts
			(xy 138.194796 -246.71274) (xy 138.194796 -246.664988) (xy 137.994644 -246.664988) (xy 137.994644 -246.71274)
			(xy 138.09472 -246.812562)
		)
		(stroke
			(width 0)
			(type solid)
		)
		(fill yes)
		(layer "In4.Cu")
		(net "M_J_CPU1_SA_DQS_DN<4>")
	)
	(gr_poly
		(pts
			(xy 138.194796 -245.496334) (xy 138.09472 -245.396258) (xy 137.994644 -245.496334) (xy 137.994644 -245.540784)
			(xy 138.194796 -245.540784)
		)
		(stroke
			(width 0)
			(type solid)
		)
		(fill yes)
		(layer "In4.Cu")
		(net "M_J_CPU1_SA_CB<1>")
	)
	(gr_poly
		(pts
			(xy 138.194796 -245.092474) (xy 138.194796 -245.048024) (xy 137.994644 -245.048024) (xy 137.994644 -245.092474)
			(xy 138.09472 -245.19255)
		)
		(stroke
			(width 0)
			(type solid)
		)
		(fill yes)
		(layer "In4.Cu")
		(net "M_J_CPU1_SA_CB<2>")
	)
	(gr_poly
		(pts
			(xy 138.194796 -243.876322) (xy 138.09472 -243.776246) (xy 137.994644 -243.876322) (xy 137.994644 -243.920772)
			(xy 138.194796 -243.920772)
		)
		(stroke
			(width 0)
			(type solid)
		)
		(fill yes)
		(layer "In4.Cu")
		(net "M_J_CPU1_SA_DQ<29>")
	)
	(gr_poly
		(pts
			(xy 138.194796 -243.472462) (xy 138.194796 -243.428012) (xy 137.994644 -243.428012) (xy 137.994644 -243.472462)
			(xy 138.09472 -243.572538)
		)
		(stroke
			(width 0)
			(type solid)
		)
		(fill yes)
		(layer "In4.Cu")
		(net "M_J_CPU1_SA_DQ<30>")
	)
	(gr_poly
		(pts
			(xy 138.194796 -242.256056) (xy 138.09472 -242.156234) (xy 137.994644 -242.256056) (xy 137.994644 -242.303808)
			(xy 138.194796 -242.303808)
		)
		(stroke
			(width 0)
			(type solid)
		)
		(fill yes)
		(layer "In4.Cu")
		(net "M_J_CPU1_SA_DQS_DN<8>")
	)
	(gr_poly
		(pts
			(xy 138.194796 -241.852704) (xy 138.194796 -241.804952) (xy 137.994644 -241.804952) (xy 137.994644 -241.852704)
			(xy 138.09472 -241.952526)
		)
		(stroke
			(width 0)
			(type solid)
		)
		(fill yes)
		(layer "In4.Cu")
		(net "M_J_CPU1_SA_DQS_DN<3>")
	)
	(gr_poly
		(pts
			(xy 138.194796 -240.636298) (xy 138.09472 -240.536222) (xy 137.994644 -240.636298) (xy 137.994644 -240.680748)
			(xy 138.194796 -240.680748)
		)
		(stroke
			(width 0)
			(type solid)
		)
		(fill yes)
		(layer "In4.Cu")
		(net "M_J_CPU1_SA_DQ<25>")
	)
	(gr_poly
		(pts
			(xy 138.194796 -240.232438) (xy 138.194796 -240.187988) (xy 137.994644 -240.187988) (xy 137.994644 -240.232438)
			(xy 138.09472 -240.332514)
		)
		(stroke
			(width 0)
			(type solid)
		)
		(fill yes)
		(layer "In4.Cu")
		(net "M_J_CPU1_SA_DQ<26>")
	)
	(gr_poly
		(pts
			(xy 138.194796 -239.016286) (xy 138.09472 -238.91621) (xy 137.994644 -239.016286) (xy 137.994644 -239.060736)
			(xy 138.194796 -239.060736)
		)
		(stroke
			(width 0)
			(type solid)
		)
		(fill yes)
		(layer "In4.Cu")
		(net "M_J_CPU1_SA_DQ<21>")
	)
	(gr_poly
		(pts
			(xy 138.194796 -238.612426) (xy 138.194796 -238.567976) (xy 137.994644 -238.567976) (xy 137.994644 -238.612426)
			(xy 138.09472 -238.712502)
		)
		(stroke
			(width 0)
			(type solid)
		)
		(fill yes)
		(layer "In4.Cu")
		(net "M_J_CPU1_SA_DQ<22>")
	)
	(gr_poly
		(pts
			(xy 138.194796 -237.39602) (xy 138.09472 -237.296198) (xy 137.994644 -237.39602) (xy 137.994644 -237.443772)
			(xy 138.194796 -237.443772)
		)
		(stroke
			(width 0)
			(type solid)
		)
		(fill yes)
		(layer "In4.Cu")
		(net "M_J_CPU1_SA_DQS_DN<7>")
	)
	(gr_poly
		(pts
			(xy 138.194796 -236.992668) (xy 138.194796 -236.944916) (xy 137.994644 -236.944916) (xy 137.994644 -236.992668)
			(xy 138.09472 -237.09249)
		)
		(stroke
			(width 0)
			(type solid)
		)
		(fill yes)
		(layer "In4.Cu")
		(net "M_J_CPU1_SA_DQS_DN<2>")
	)
	(gr_poly
		(pts
			(xy 138.194796 -235.776262) (xy 138.09472 -235.676186) (xy 137.994644 -235.776262) (xy 137.994644 -235.820712)
			(xy 138.194796 -235.820712)
		)
		(stroke
			(width 0)
			(type solid)
		)
		(fill yes)
		(layer "In4.Cu")
		(net "M_J_CPU1_SA_DQ<17>")
	)
	(gr_poly
		(pts
			(xy 138.194796 -235.372402) (xy 138.194796 -235.327952) (xy 137.994644 -235.327952) (xy 137.994644 -235.372402)
			(xy 138.09472 -235.472478)
		)
		(stroke
			(width 0)
			(type solid)
		)
		(fill yes)
		(layer "In4.Cu")
		(net "M_J_CPU1_SA_DQ<18>")
	)
	(gr_poly
		(pts
			(xy 138.194796 -234.15625) (xy 138.09472 -234.056174) (xy 137.994644 -234.15625) (xy 137.994644 -234.2007)
			(xy 138.194796 -234.2007)
		)
		(stroke
			(width 0)
			(type solid)
		)
		(fill yes)
		(layer "In4.Cu")
		(net "M_J_CPU1_SA_DQ<13>")
	)
	(gr_poly
		(pts
			(xy 138.194796 -233.75239) (xy 138.194796 -233.70794) (xy 137.994644 -233.70794) (xy 137.994644 -233.75239)
			(xy 138.09472 -233.852466)
		)
		(stroke
			(width 0)
			(type solid)
		)
		(fill yes)
		(layer "In4.Cu")
		(net "M_J_CPU1_SA_DQ<14>")
	)
	(gr_poly
		(pts
			(xy 138.194796 -232.535984) (xy 138.09472 -232.436162) (xy 137.994644 -232.535984) (xy 137.994644 -232.583736)
			(xy 138.194796 -232.583736)
		)
		(stroke
			(width 0)
			(type solid)
		)
		(fill yes)
		(layer "In4.Cu")
		(net "M_J_CPU1_SA_DQS_DN<6>")
	)
	(gr_poly
		(pts
			(xy 138.194796 -232.132632) (xy 138.194796 -232.08488) (xy 137.994644 -232.08488) (xy 137.994644 -232.132632)
			(xy 138.09472 -232.232454)
		)
		(stroke
			(width 0)
			(type solid)
		)
		(fill yes)
		(layer "In4.Cu")
		(net "M_J_CPU1_SA_DQS_DN<1>")
	)
	(gr_poly
		(pts
			(xy 138.194796 -230.916226) (xy 138.09472 -230.81615) (xy 137.994644 -230.916226) (xy 137.994644 -230.960676)
			(xy 138.194796 -230.960676)
		)
		(stroke
			(width 0)
			(type solid)
		)
		(fill yes)
		(layer "In4.Cu")
		(net "M_J_CPU1_SA_DQ<9>")
	)
	(gr_poly
		(pts
			(xy 138.194796 -230.51262) (xy 138.194796 -230.46817) (xy 137.994644 -230.46817) (xy 137.994644 -230.51262)
			(xy 138.09472 -230.612696)
		)
		(stroke
			(width 0)
			(type solid)
		)
		(fill yes)
		(layer "In4.Cu")
		(net "M_J_CPU1_SA_DQ<10>")
	)
	(gr_poly
		(pts
			(xy 138.194796 -229.296214) (xy 138.09472 -229.196138) (xy 137.994644 -229.296214) (xy 137.994644 -229.340664)
			(xy 138.194796 -229.340664)
		)
		(stroke
			(width 0)
			(type solid)
		)
		(fill yes)
		(layer "In4.Cu")
		(net "M_J_CPU1_SA_DQ<5>")
	)
	(gr_poly
		(pts
			(xy 138.194796 -228.892608) (xy 138.194796 -228.848158) (xy 137.994644 -228.848158) (xy 137.994644 -228.892608)
			(xy 138.09472 -228.992684)
		)
		(stroke
			(width 0)
			(type solid)
		)
		(fill yes)
		(layer "In4.Cu")
		(net "M_J_CPU1_SA_DQ<6>")
	)
	(gr_poly
		(pts
			(xy 138.194796 -227.676202) (xy 138.09472 -227.57638) (xy 137.994644 -227.676202) (xy 137.994644 -227.723954)
			(xy 138.194796 -227.723954)
		)
		(stroke
			(width 0)
			(type solid)
		)
		(fill yes)
		(layer "In4.Cu")
		(net "M_J_CPU1_SA_DQS_DN<5>")
	)
	(gr_poly
		(pts
			(xy 138.194796 -227.27285) (xy 138.194796 -227.225098) (xy 137.994644 -227.225098) (xy 137.994644 -227.27285)
			(xy 138.09472 -227.372672)
		)
		(stroke
			(width 0)
			(type solid)
		)
		(fill yes)
		(layer "In4.Cu")
		(net "M_J_CPU1_SA_DQS_DN<0>")
	)
	(gr_poly
		(pts
			(xy 138.194796 -226.056444) (xy 138.09472 -225.956368) (xy 137.994644 -226.056444) (xy 137.994644 -226.100894)
			(xy 138.194796 -226.100894)
		)
		(stroke
			(width 0)
			(type solid)
		)
		(fill yes)
		(layer "In4.Cu")
		(net "M_J_CPU1_SA_DQ<1>")
	)
	(gr_poly
		(pts
			(xy 138.194796 -225.652584) (xy 138.194796 -225.608134) (xy 137.994644 -225.608134) (xy 137.994644 -225.652584)
			(xy 138.09472 -225.75266)
		)
		(stroke
			(width 0)
			(type solid)
		)
		(fill yes)
		(layer "In4.Cu")
		(net "M_J_CPU1_SA_DQ<2>")
	)
	(gr_poly
		(pts
			(xy 138.49477 -293.32428) (xy 138.49477 -293.27983) (xy 138.294618 -293.27983) (xy 138.294618 -293.32428)
			(xy 138.394694 -293.424356)
		)
		(stroke
			(width 0)
			(type solid)
		)
		(fill yes)
		(layer "In4.Cu")
		(net "M_J_CPU1_SB_DQ<31>")
	)
	(gr_poly
		(pts
			(xy 138.49477 -292.108128) (xy 138.394694 -292.008052) (xy 138.294618 -292.108128) (xy 138.294618 -292.152578)
			(xy 138.49477 -292.152578)
		)
		(stroke
			(width 0)
			(type solid)
		)
		(fill yes)
		(layer "In4.Cu")
		(net "M_J_CPU1_SB_DQ<28>")
	)
	(gr_poly
		(pts
			(xy 138.49477 -291.704522) (xy 138.49477 -291.65677) (xy 138.294618 -291.65677) (xy 138.294618 -291.704522)
			(xy 138.394694 -291.804344)
		)
		(stroke
			(width 0)
			(type solid)
		)
		(fill yes)
		(layer "In4.Cu")
		(net "M_J_CPU1_SB_DQS_DP<8>")
	)
	(gr_poly
		(pts
			(xy 138.49477 -290.487862) (xy 138.394694 -290.38804) (xy 138.294618 -290.487862) (xy 138.294618 -290.535614)
			(xy 138.49477 -290.535614)
		)
		(stroke
			(width 0)
			(type solid)
		)
		(fill yes)
		(layer "In4.Cu")
		(net "M_J_CPU1_SB_DQS_DP<3>")
	)
	(gr_poly
		(pts
			(xy 138.49477 -290.084256) (xy 138.49477 -290.039806) (xy 138.294618 -290.039806) (xy 138.294618 -290.084256)
			(xy 138.394694 -290.184332)
		)
		(stroke
			(width 0)
			(type solid)
		)
		(fill yes)
		(layer "In4.Cu")
		(net "M_J_CPU1_SB_DQ<27>")
	)
	(gr_poly
		(pts
			(xy 138.49477 -288.868104) (xy 138.394694 -288.768028) (xy 138.294618 -288.868104) (xy 138.294618 -288.912554)
			(xy 138.49477 -288.912554)
		)
		(stroke
			(width 0)
			(type solid)
		)
		(fill yes)
		(layer "In4.Cu")
		(net "M_J_CPU1_SB_DQ<24>")
	)
	(gr_poly
		(pts
			(xy 138.49477 -288.464498) (xy 138.49477 -288.420048) (xy 138.294618 -288.420048) (xy 138.294618 -288.464498)
			(xy 138.394694 -288.564574)
		)
		(stroke
			(width 0)
			(type solid)
		)
		(fill yes)
		(layer "In4.Cu")
		(net "M_J_CPU1_SB_DQ<23>")
	)
	(gr_poly
		(pts
			(xy 138.49477 -287.248092) (xy 138.394694 -287.148016) (xy 138.294618 -287.248092) (xy 138.294618 -287.292542)
			(xy 138.49477 -287.292542)
		)
		(stroke
			(width 0)
			(type solid)
		)
		(fill yes)
		(layer "In4.Cu")
		(net "M_J_CPU1_SB_DQ<20>")
	)
	(gr_poly
		(pts
			(xy 138.49477 -286.844486) (xy 138.49477 -286.796734) (xy 138.294618 -286.796734) (xy 138.294618 -286.844486)
			(xy 138.394694 -286.944562)
		)
		(stroke
			(width 0)
			(type solid)
		)
		(fill yes)
		(layer "In4.Cu")
		(net "M_J_CPU1_SB_DQS_DP<7>")
	)
	(gr_poly
		(pts
			(xy 138.49477 -285.62808) (xy 138.394694 -285.528258) (xy 138.294618 -285.62808) (xy 138.294618 -285.675832)
			(xy 138.49477 -285.675832)
		)
		(stroke
			(width 0)
			(type solid)
		)
		(fill yes)
		(layer "In4.Cu")
		(net "M_J_CPU1_SB_DQS_DP<2>")
	)
	(gr_poly
		(pts
			(xy 138.49477 -285.224474) (xy 138.49477 -285.180024) (xy 138.294618 -285.180024) (xy 138.294618 -285.224474)
			(xy 138.394694 -285.32455)
		)
		(stroke
			(width 0)
			(type solid)
		)
		(fill yes)
		(layer "In4.Cu")
		(net "M_J_CPU1_SB_DQ<19>")
	)
	(gr_poly
		(pts
			(xy 138.49477 -284.008322) (xy 138.394694 -283.908246) (xy 138.294618 -284.008322) (xy 138.294618 -284.052772)
			(xy 138.49477 -284.052772)
		)
		(stroke
			(width 0)
			(type solid)
		)
		(fill yes)
		(layer "In4.Cu")
		(net "M_J_CPU1_SB_DQ<16>")
	)
	(gr_poly
		(pts
			(xy 138.49477 -283.604462) (xy 138.49477 -283.560012) (xy 138.294618 -283.560012) (xy 138.294618 -283.604462)
			(xy 138.394694 -283.704538)
		)
		(stroke
			(width 0)
			(type solid)
		)
		(fill yes)
		(layer "In4.Cu")
		(net "M_J_CPU1_SB_DQ<15>")
	)
	(gr_poly
		(pts
			(xy 138.49477 -282.38831) (xy 138.394694 -282.288234) (xy 138.294618 -282.38831) (xy 138.294618 -282.43276)
			(xy 138.49477 -282.43276)
		)
		(stroke
			(width 0)
			(type solid)
		)
		(fill yes)
		(layer "In4.Cu")
		(net "M_J_CPU1_SB_DQ<12>")
	)
	(gr_poly
		(pts
			(xy 138.49477 -281.984704) (xy 138.49477 -281.936952) (xy 138.294618 -281.936952) (xy 138.294618 -281.984704)
			(xy 138.394694 -282.084526)
		)
		(stroke
			(width 0)
			(type solid)
		)
		(fill yes)
		(layer "In4.Cu")
		(net "M_J_CPU1_SB_DQS_DP<6>")
	)
	(gr_poly
		(pts
			(xy 138.49477 -280.768044) (xy 138.394694 -280.668222) (xy 138.294618 -280.768044) (xy 138.294618 -280.815796)
			(xy 138.49477 -280.815796)
		)
		(stroke
			(width 0)
			(type solid)
		)
		(fill yes)
		(layer "In4.Cu")
		(net "M_J_CPU1_SB_DQS_DP<1>")
	)
	(gr_poly
		(pts
			(xy 138.49477 -280.364438) (xy 138.49477 -280.319988) (xy 138.294618 -280.319988) (xy 138.294618 -280.364438)
			(xy 138.394694 -280.464514)
		)
		(stroke
			(width 0)
			(type solid)
		)
		(fill yes)
		(layer "In4.Cu")
		(net "M_J_CPU1_SB_DQ<11>")
	)
	(gr_poly
		(pts
			(xy 138.49477 -279.148286) (xy 138.394694 -279.04821) (xy 138.294618 -279.148286) (xy 138.294618 -279.192736)
			(xy 138.49477 -279.192736)
		)
		(stroke
			(width 0)
			(type solid)
		)
		(fill yes)
		(layer "In4.Cu")
		(net "M_J_CPU1_SB_DQ<8>")
	)
	(gr_poly
		(pts
			(xy 138.49477 -278.744426) (xy 138.49477 -278.699976) (xy 138.294618 -278.699976) (xy 138.294618 -278.744426)
			(xy 138.394694 -278.844502)
		)
		(stroke
			(width 0)
			(type solid)
		)
		(fill yes)
		(layer "In4.Cu")
		(net "M_J_CPU1_SB_DQ<7>")
	)
	(gr_poly
		(pts
			(xy 138.49477 -277.528274) (xy 138.394694 -277.428198) (xy 138.294618 -277.528274) (xy 138.294618 -277.572724)
			(xy 138.49477 -277.572724)
		)
		(stroke
			(width 0)
			(type solid)
		)
		(fill yes)
		(layer "In4.Cu")
		(net "M_J_CPU1_SB_DQ<4>")
	)
	(gr_poly
		(pts
			(xy 138.49477 -277.124668) (xy 138.49477 -277.076916) (xy 138.294618 -277.076916) (xy 138.294618 -277.124668)
			(xy 138.394694 -277.22449)
		)
		(stroke
			(width 0)
			(type solid)
		)
		(fill yes)
		(layer "In4.Cu")
		(net "M_J_CPU1_SB_DQS_DP<5>")
	)
	(gr_poly
		(pts
			(xy 138.49477 -275.908008) (xy 138.394694 -275.808186) (xy 138.294618 -275.908008) (xy 138.294618 -275.95576)
			(xy 138.49477 -275.95576)
		)
		(stroke
			(width 0)
			(type solid)
		)
		(fill yes)
		(layer "In4.Cu")
		(net "M_J_CPU1_SB_DQS_DP<0>")
	)
	(gr_poly
		(pts
			(xy 138.49477 -275.504402) (xy 138.49477 -275.459952) (xy 138.294618 -275.459952) (xy 138.294618 -275.504402)
			(xy 138.394694 -275.604478)
		)
		(stroke
			(width 0)
			(type solid)
		)
		(fill yes)
		(layer "In4.Cu")
		(net "M_J_CPU1_SB_DQ<3>")
	)
	(gr_poly
		(pts
			(xy 138.49477 -274.28825) (xy 138.394694 -274.188174) (xy 138.294618 -274.28825) (xy 138.294618 -274.3327)
			(xy 138.49477 -274.3327)
		)
		(stroke
			(width 0)
			(type solid)
		)
		(fill yes)
		(layer "In4.Cu")
		(net "M_J_CPU1_SB_DQ<0>")
	)
	(gr_poly
		(pts
			(xy 138.49477 -273.88439) (xy 138.49477 -273.83994) (xy 138.294618 -273.83994) (xy 138.294618 -273.88439)
			(xy 138.394694 -273.984466)
		)
		(stroke
			(width 0)
			(type solid)
		)
		(fill yes)
		(layer "In4.Cu")
		(net "M_J_CPU1_SB_CB<3>")
	)
	(gr_poly
		(pts
			(xy 138.49477 -272.668238) (xy 138.394694 -272.568162) (xy 138.294618 -272.668238) (xy 138.294618 -272.712688)
			(xy 138.49477 -272.712688)
		)
		(stroke
			(width 0)
			(type solid)
		)
		(fill yes)
		(layer "In4.Cu")
		(net "M_J_CPU1_SB_CB<0>")
	)
	(gr_poly
		(pts
			(xy 138.49477 -272.264632) (xy 138.49477 -272.21688) (xy 138.294618 -272.21688) (xy 138.294618 -272.264632)
			(xy 138.394694 -272.364454)
		)
		(stroke
			(width 0)
			(type solid)
		)
		(fill yes)
		(layer "In4.Cu")
		(net "M_J_CPU1_SB_DQS_DP<4>")
	)
	(gr_poly
		(pts
			(xy 138.49477 -271.047972) (xy 138.394694 -270.94815) (xy 138.294618 -271.047972) (xy 138.294618 -271.095724)
			(xy 138.49477 -271.095724)
		)
		(stroke
			(width 0)
			(type solid)
		)
		(fill yes)
		(layer "In4.Cu")
		(net "M_J_CPU1_SB_DQS_DP<9>")
	)
	(gr_poly
		(pts
			(xy 138.49477 -270.644366) (xy 138.49477 -270.599916) (xy 138.294618 -270.599916) (xy 138.294618 -270.644366)
			(xy 138.394694 -270.744442)
		)
		(stroke
			(width 0)
			(type solid)
		)
		(fill yes)
		(layer "In4.Cu")
		(net "M_J_CPU1_SB_CB<7>")
	)
	(gr_poly
		(pts
			(xy 138.49477 -269.428214) (xy 138.394694 -269.328138) (xy 138.294618 -269.428214) (xy 138.294618 -269.472664)
			(xy 138.49477 -269.472664)
		)
		(stroke
			(width 0)
			(type solid)
		)
		(fill yes)
		(layer "In4.Cu")
		(net "M_J_CPU1_SB_CB<4>")
	)
	(gr_poly
		(pts
			(xy 138.49477 -267.808202) (xy 138.394694 -267.708126) (xy 138.294618 -267.808202) (xy 138.294618 -267.852652)
			(xy 138.49477 -267.852652)
		)
		(stroke
			(width 0)
			(type solid)
		)
		(fill yes)
		(layer "In4.Cu")
		(net "M_J_CPU1_SB_RSP<0>")
	)
	(gr_poly
		(pts
			(xy 138.49477 -265.78433) (xy 138.49477 -265.73988) (xy 138.294618 -265.73988) (xy 138.294618 -265.78433)
			(xy 138.394694 -265.884406)
		)
		(stroke
			(width 0)
			(type solid)
		)
		(fill yes)
		(layer "In4.Cu")
		(net "M_J_CPU1_SB_CS_N<0>")
	)
	(gr_poly
		(pts
			(xy 138.49477 -264.568178) (xy 138.394694 -264.468102) (xy 138.294618 -264.568178) (xy 138.294618 -264.612628)
			(xy 138.49477 -264.612628)
		)
		(stroke
			(width 0)
			(type solid)
		)
		(fill yes)
		(layer "In4.Cu")
		(net "M_J_CPU1_SB_CA<6>")
	)
	(gr_poly
		(pts
			(xy 138.49477 -264.164318) (xy 138.49477 -264.119868) (xy 138.294618 -264.119868) (xy 138.294618 -264.164318)
			(xy 138.394694 -264.264394)
		)
		(stroke
			(width 0)
			(type solid)
		)
		(fill yes)
		(layer "In4.Cu")
		(net "M_J_CPU1_SB_CA<5>")
	)
	(gr_poly
		(pts
			(xy 138.49477 -262.948166) (xy 138.394694 -262.84809) (xy 138.294618 -262.948166) (xy 138.294618 -262.992616)
			(xy 138.49477 -262.992616)
		)
		(stroke
			(width 0)
			(type solid)
		)
		(fill yes)
		(layer "In4.Cu")
		(net "M_J_CPU1_SB_CA<2>")
	)
	(gr_poly
		(pts
			(xy 138.49477 -262.544306) (xy 138.49477 -262.499856) (xy 138.294618 -262.499856) (xy 138.294618 -262.544306)
			(xy 138.394694 -262.644382)
		)
		(stroke
			(width 0)
			(type solid)
		)
		(fill yes)
		(layer "In4.Cu")
		(net "M_J_CPU1_SB_CA<1>")
	)
	(gr_poly
		(pts
			(xy 138.66495 -256.026158) (xy 138.564874 -255.926336) (xy 138.464798 -256.026158) (xy 138.464798 -256.07391)
			(xy 138.66495 -256.07391)
		)
		(stroke
			(width 0)
			(type solid)
		)
		(fill yes)
		(layer "In4.Cu")
		(net "M_J_CPU1_CLK_DP<0>")
	)
	(gr_poly
		(pts
			(xy 138.66495 -255.622552) (xy 138.66495 -255.578102) (xy 138.464798 -255.578102) (xy 138.464798 -255.622552)
			(xy 138.564874 -255.722628)
		)
		(stroke
			(width 0)
			(type solid)
		)
		(fill yes)
		(layer "In4.Cu")
		(net "M_J_CPU1_SA_PAR")
	)
	(gr_poly
		(pts
			(xy 138.66495 -254.4064) (xy 138.564874 -254.306324) (xy 138.464798 -254.4064) (xy 138.464798 -254.45085)
			(xy 138.66495 -254.45085)
		)
		(stroke
			(width 0)
			(type solid)
		)
		(fill yes)
		(layer "In4.Cu")
		(net "M_J_CPU1_SA_CA<4>")
	)
	(gr_poly
		(pts
			(xy 138.66495 -254.00254) (xy 138.66495 -253.95809) (xy 138.464798 -253.95809) (xy 138.464798 -254.00254)
			(xy 138.564874 -254.102616)
		)
		(stroke
			(width 0)
			(type solid)
		)
		(fill yes)
		(layer "In4.Cu")
		(net "M_J_CPU1_SA_CA<3>")
	)
	(gr_poly
		(pts
			(xy 138.66495 -252.786388) (xy 138.564874 -252.686312) (xy 138.464798 -252.786388) (xy 138.464798 -252.830838)
			(xy 138.66495 -252.830838)
		)
		(stroke
			(width 0)
			(type solid)
		)
		(fill yes)
		(layer "In4.Cu")
		(net "M_J_CPU1_SA_CA<0>")
	)
	(gr_poly
		(pts
			(xy 138.66495 -251.166376) (xy 138.564874 -251.0663) (xy 138.464798 -251.166376) (xy 138.464798 -251.210826)
			(xy 138.66495 -251.210826)
		)
		(stroke
			(width 0)
			(type solid)
		)
		(fill yes)
		(layer "In4.Cu")
		(net "M_J_CPU1_SA_CS_N<0>")
	)
	(gr_poly
		(pts
			(xy 138.66495 -250.762516) (xy 138.66495 -250.718066) (xy 138.464798 -250.718066) (xy 138.464798 -250.762516)
			(xy 138.564874 -250.862592)
		)
		(stroke
			(width 0)
			(type solid)
		)
		(fill yes)
		(layer "In4.Cu")
		(net "M_J_CPU1_RESET_N")
	)
	(gr_poly
		(pts
			(xy 138.66495 -249.142504) (xy 138.66495 -249.098054) (xy 138.464798 -249.098054) (xy 138.464798 -249.142504)
			(xy 138.564874 -249.24258)
		)
		(stroke
			(width 0)
			(type solid)
		)
		(fill yes)
		(layer "In4.Cu")
		(net "M_J_CPU1_SA_CB<7>")
	)
	(gr_poly
		(pts
			(xy 138.66495 -247.926352) (xy 138.564874 -247.826276) (xy 138.464798 -247.926352) (xy 138.464798 -247.970802)
			(xy 138.66495 -247.970802)
		)
		(stroke
			(width 0)
			(type solid)
		)
		(fill yes)
		(layer "In4.Cu")
		(net "M_J_CPU1_SA_CB<4>")
	)
	(gr_poly
		(pts
			(xy 138.66495 -247.522746) (xy 138.66495 -247.474994) (xy 138.464798 -247.474994) (xy 138.464798 -247.522746)
			(xy 138.564874 -247.622568)
		)
		(stroke
			(width 0)
			(type solid)
		)
		(fill yes)
		(layer "In4.Cu")
		(net "M_J_CPU1_SA_DQS_DP<9>")
	)
	(gr_poly
		(pts
			(xy 138.66495 -246.306086) (xy 138.564874 -246.206264) (xy 138.464798 -246.306086) (xy 138.464798 -246.353838)
			(xy 138.66495 -246.353838)
		)
		(stroke
			(width 0)
			(type solid)
		)
		(fill yes)
		(layer "In4.Cu")
		(net "M_J_CPU1_SA_DQS_DP<4>")
	)
	(gr_poly
		(pts
			(xy 138.66495 -245.90248) (xy 138.66495 -245.85803) (xy 138.464798 -245.85803) (xy 138.464798 -245.90248)
			(xy 138.564874 -246.002556)
		)
		(stroke
			(width 0)
			(type solid)
		)
		(fill yes)
		(layer "In4.Cu")
		(net "M_J_CPU1_SA_CB<3>")
	)
	(gr_poly
		(pts
			(xy 138.66495 -244.686328) (xy 138.564874 -244.586252) (xy 138.464798 -244.686328) (xy 138.464798 -244.730778)
			(xy 138.66495 -244.730778)
		)
		(stroke
			(width 0)
			(type solid)
		)
		(fill yes)
		(layer "In4.Cu")
		(net "M_J_CPU1_SA_CB<0>")
	)
	(gr_poly
		(pts
			(xy 138.66495 -244.282468) (xy 138.66495 -244.238018) (xy 138.464798 -244.238018) (xy 138.464798 -244.282468)
			(xy 138.564874 -244.382544)
		)
		(stroke
			(width 0)
			(type solid)
		)
		(fill yes)
		(layer "In4.Cu")
		(net "M_J_CPU1_SA_DQ<31>")
	)
	(gr_poly
		(pts
			(xy 138.66495 -243.066316) (xy 138.564874 -242.96624) (xy 138.464798 -243.066316) (xy 138.464798 -243.110766)
			(xy 138.66495 -243.110766)
		)
		(stroke
			(width 0)
			(type solid)
		)
		(fill yes)
		(layer "In4.Cu")
		(net "M_J_CPU1_SA_DQ<28>")
	)
	(gr_poly
		(pts
			(xy 138.66495 -242.66271) (xy 138.66495 -242.614958) (xy 138.464798 -242.614958) (xy 138.464798 -242.66271)
			(xy 138.564874 -242.762532)
		)
		(stroke
			(width 0)
			(type solid)
		)
		(fill yes)
		(layer "In4.Cu")
		(net "M_J_CPU1_SA_DQS_DP<8>")
	)
	(gr_poly
		(pts
			(xy 138.66495 -241.44605) (xy 138.564874 -241.346228) (xy 138.464798 -241.44605) (xy 138.464798 -241.493802)
			(xy 138.66495 -241.493802)
		)
		(stroke
			(width 0)
			(type solid)
		)
		(fill yes)
		(layer "In4.Cu")
		(net "M_J_CPU1_SA_DQS_DP<3>")
	)
	(gr_poly
		(pts
			(xy 138.66495 -241.042444) (xy 138.66495 -240.997994) (xy 138.464798 -240.997994) (xy 138.464798 -241.042444)
			(xy 138.564874 -241.14252)
		)
		(stroke
			(width 0)
			(type solid)
		)
		(fill yes)
		(layer "In4.Cu")
		(net "M_J_CPU1_SA_DQ<27>")
	)
	(gr_poly
		(pts
			(xy 138.66495 -239.826292) (xy 138.564874 -239.726216) (xy 138.464798 -239.826292) (xy 138.464798 -239.870742)
			(xy 138.66495 -239.870742)
		)
		(stroke
			(width 0)
			(type solid)
		)
		(fill yes)
		(layer "In4.Cu")
		(net "M_J_CPU1_SA_DQ<24>")
	)
	(gr_poly
		(pts
			(xy 138.66495 -239.422432) (xy 138.66495 -239.377982) (xy 138.464798 -239.377982) (xy 138.464798 -239.422432)
			(xy 138.564874 -239.522508)
		)
		(stroke
			(width 0)
			(type solid)
		)
		(fill yes)
		(layer "In4.Cu")
		(net "M_J_CPU1_SA_DQ<23>")
	)
	(gr_poly
		(pts
			(xy 138.66495 -238.20628) (xy 138.564874 -238.106204) (xy 138.464798 -238.20628) (xy 138.464798 -238.25073)
			(xy 138.66495 -238.25073)
		)
		(stroke
			(width 0)
			(type solid)
		)
		(fill yes)
		(layer "In4.Cu")
		(net "M_J_CPU1_SA_DQ<20>")
	)
	(gr_poly
		(pts
			(xy 138.66495 -237.802674) (xy 138.66495 -237.754922) (xy 138.464798 -237.754922) (xy 138.464798 -237.802674)
			(xy 138.564874 -237.902496)
		)
		(stroke
			(width 0)
			(type solid)
		)
		(fill yes)
		(layer "In4.Cu")
		(net "M_J_CPU1_SA_DQS_DP<7>")
	)
	(gr_poly
		(pts
			(xy 138.66495 -236.586014) (xy 138.564874 -236.486192) (xy 138.464798 -236.586014) (xy 138.464798 -236.633766)
			(xy 138.66495 -236.633766)
		)
		(stroke
			(width 0)
			(type solid)
		)
		(fill yes)
		(layer "In4.Cu")
		(net "M_J_CPU1_SA_DQS_DP<2>")
	)
	(gr_poly
		(pts
			(xy 138.66495 -236.182408) (xy 138.66495 -236.137958) (xy 138.464798 -236.137958) (xy 138.464798 -236.182408)
			(xy 138.564874 -236.282484)
		)
		(stroke
			(width 0)
			(type solid)
		)
		(fill yes)
		(layer "In4.Cu")
		(net "M_J_CPU1_SA_DQ<19>")
	)
	(gr_poly
		(pts
			(xy 138.66495 -234.966256) (xy 138.564874 -234.86618) (xy 138.464798 -234.966256) (xy 138.464798 -235.010706)
			(xy 138.66495 -235.010706)
		)
		(stroke
			(width 0)
			(type solid)
		)
		(fill yes)
		(layer "In4.Cu")
		(net "M_J_CPU1_SA_DQ<16>")
	)
	(gr_poly
		(pts
			(xy 138.66495 -234.562396) (xy 138.66495 -234.517946) (xy 138.464798 -234.517946) (xy 138.464798 -234.562396)
			(xy 138.564874 -234.662472)
		)
		(stroke
			(width 0)
			(type solid)
		)
		(fill yes)
		(layer "In4.Cu")
		(net "M_J_CPU1_SA_DQ<15>")
	)
	(gr_poly
		(pts
			(xy 138.66495 -233.346244) (xy 138.564874 -233.246168) (xy 138.464798 -233.346244) (xy 138.464798 -233.390694)
			(xy 138.66495 -233.390694)
		)
		(stroke
			(width 0)
			(type solid)
		)
		(fill yes)
		(layer "In4.Cu")
		(net "M_J_CPU1_SA_DQ<12>")
	)
	(gr_poly
		(pts
			(xy 138.66495 -232.942638) (xy 138.66495 -232.894886) (xy 138.464798 -232.894886) (xy 138.464798 -232.942638)
			(xy 138.564874 -233.04246)
		)
		(stroke
			(width 0)
			(type solid)
		)
		(fill yes)
		(layer "In4.Cu")
		(net "M_J_CPU1_SA_DQS_DP<6>")
	)
	(gr_poly
		(pts
			(xy 138.66495 -231.725978) (xy 138.564874 -231.626156) (xy 138.464798 -231.725978) (xy 138.464798 -231.77373)
			(xy 138.66495 -231.77373)
		)
		(stroke
			(width 0)
			(type solid)
		)
		(fill yes)
		(layer "In4.Cu")
		(net "M_J_CPU1_SA_DQS_DP<1>")
	)
	(gr_poly
		(pts
			(xy 138.66495 -231.322626) (xy 138.66495 -231.278176) (xy 138.464798 -231.278176) (xy 138.464798 -231.322626)
			(xy 138.564874 -231.422702)
		)
		(stroke
			(width 0)
			(type solid)
		)
		(fill yes)
		(layer "In4.Cu")
		(net "M_J_CPU1_SA_DQ<11>")
	)
	(gr_poly
		(pts
			(xy 138.66495 -230.10622) (xy 138.564874 -230.006144) (xy 138.464798 -230.10622) (xy 138.464798 -230.15067)
			(xy 138.66495 -230.15067)
		)
		(stroke
			(width 0)
			(type solid)
		)
		(fill yes)
		(layer "In4.Cu")
		(net "M_J_CPU1_SA_DQ<8>")
	)
	(gr_poly
		(pts
			(xy 138.66495 -229.702614) (xy 138.66495 -229.658164) (xy 138.464798 -229.658164) (xy 138.464798 -229.702614)
			(xy 138.564874 -229.80269)
		)
		(stroke
			(width 0)
			(type solid)
		)
		(fill yes)
		(layer "In4.Cu")
		(net "M_J_CPU1_SA_DQ<7>")
	)
	(gr_poly
		(pts
			(xy 138.66495 -228.486462) (xy 138.564874 -228.386386) (xy 138.464798 -228.486462) (xy 138.464798 -228.530912)
			(xy 138.66495 -228.530912)
		)
		(stroke
			(width 0)
			(type solid)
		)
		(fill yes)
		(layer "In4.Cu")
		(net "M_J_CPU1_SA_DQ<4>")
	)
	(gr_poly
		(pts
			(xy 138.66495 -228.082856) (xy 138.66495 -228.035104) (xy 138.464798 -228.035104) (xy 138.464798 -228.082856)
			(xy 138.564874 -228.182678)
		)
		(stroke
			(width 0)
			(type solid)
		)
		(fill yes)
		(layer "In4.Cu")
		(net "M_J_CPU1_SA_DQS_DP<5>")
	)
	(gr_poly
		(pts
			(xy 138.66495 -226.866196) (xy 138.564874 -226.766374) (xy 138.464798 -226.866196) (xy 138.464798 -226.913948)
			(xy 138.66495 -226.913948)
		)
		(stroke
			(width 0)
			(type solid)
		)
		(fill yes)
		(layer "In4.Cu")
		(net "M_J_CPU1_SA_DQS_DP<0>")
	)
	(gr_poly
		(pts
			(xy 138.66495 -226.46259) (xy 138.66495 -226.41814) (xy 138.464798 -226.41814) (xy 138.464798 -226.46259)
			(xy 138.564874 -226.562666)
		)
		(stroke
			(width 0)
			(type solid)
		)
		(fill yes)
		(layer "In4.Cu")
		(net "M_J_CPU1_SA_DQ<3>")
	)
	(gr_poly
		(pts
			(xy 138.66495 -225.246438) (xy 138.564874 -225.146362) (xy 138.464798 -225.246438) (xy 138.464798 -225.290888)
			(xy 138.66495 -225.290888)
		)
		(stroke
			(width 0)
			(type solid)
		)
		(fill yes)
		(layer "In4.Cu")
		(net "M_J_CPU1_SA_DQ<0>")
	)
	(gr_poly
		(pts
			(xy 138.964924 -292.918134) (xy 138.864848 -292.818058) (xy 138.764772 -292.918134) (xy 138.764772 -292.962584)
			(xy 138.964924 -292.962584)
		)
		(stroke
			(width 0)
			(type solid)
		)
		(fill yes)
		(layer "In4.Cu")
		(net "M_J_CPU1_SB_DQ<29>")
	)
	(gr_poly
		(pts
			(xy 138.964924 -292.514274) (xy 138.964924 -292.469824) (xy 138.764772 -292.469824) (xy 138.764772 -292.514274)
			(xy 138.864848 -292.61435)
		)
		(stroke
			(width 0)
			(type solid)
		)
		(fill yes)
		(layer "In4.Cu")
		(net "M_J_CPU1_SB_DQ<30>")
	)
	(gr_poly
		(pts
			(xy 138.964924 -291.297868) (xy 138.864848 -291.198046) (xy 138.764772 -291.297868) (xy 138.764772 -291.34562)
			(xy 138.964924 -291.34562)
		)
		(stroke
			(width 0)
			(type solid)
		)
		(fill yes)
		(layer "In4.Cu")
		(net "M_J_CPU1_SB_DQS_DN<8>")
	)
	(gr_poly
		(pts
			(xy 138.964924 -290.894516) (xy 138.964924 -290.846764) (xy 138.764772 -290.846764) (xy 138.764772 -290.894516)
			(xy 138.864848 -290.994338)
		)
		(stroke
			(width 0)
			(type solid)
		)
		(fill yes)
		(layer "In4.Cu")
		(net "M_J_CPU1_SB_DQS_DN<3>")
	)
	(gr_poly
		(pts
			(xy 138.964924 -289.67811) (xy 138.864848 -289.578034) (xy 138.764772 -289.67811) (xy 138.764772 -289.72256)
			(xy 138.964924 -289.72256)
		)
		(stroke
			(width 0)
			(type solid)
		)
		(fill yes)
		(layer "In4.Cu")
		(net "M_J_CPU1_SB_DQ<25>")
	)
	(gr_poly
		(pts
			(xy 138.964924 -289.27425) (xy 138.964924 -289.2298) (xy 138.764772 -289.2298) (xy 138.764772 -289.27425)
			(xy 138.864848 -289.374326)
		)
		(stroke
			(width 0)
			(type solid)
		)
		(fill yes)
		(layer "In4.Cu")
		(net "M_J_CPU1_SB_DQ<26>")
	)
	(gr_poly
		(pts
			(xy 138.964924 -288.058098) (xy 138.864848 -287.958022) (xy 138.764772 -288.058098) (xy 138.764772 -288.102548)
			(xy 138.964924 -288.102548)
		)
		(stroke
			(width 0)
			(type solid)
		)
		(fill yes)
		(layer "In4.Cu")
		(net "M_J_CPU1_SB_DQ<21>")
	)
	(gr_poly
		(pts
			(xy 138.964924 -287.654492) (xy 138.964924 -287.610042) (xy 138.764772 -287.610042) (xy 138.764772 -287.654492)
			(xy 138.864848 -287.754568)
		)
		(stroke
			(width 0)
			(type solid)
		)
		(fill yes)
		(layer "In4.Cu")
		(net "M_J_CPU1_SB_DQ<22>")
	)
	(gr_poly
		(pts
			(xy 138.964924 -286.438086) (xy 138.864848 -286.33801) (xy 138.764772 -286.438086) (xy 138.764772 -286.485838)
			(xy 138.964924 -286.485838)
		)
		(stroke
			(width 0)
			(type solid)
		)
		(fill yes)
		(layer "In4.Cu")
		(net "M_J_CPU1_SB_DQS_DN<7>")
	)
	(gr_poly
		(pts
			(xy 138.964924 -286.034734) (xy 138.964924 -285.986982) (xy 138.764772 -285.986982) (xy 138.764772 -286.034734)
			(xy 138.864848 -286.134556)
		)
		(stroke
			(width 0)
			(type solid)
		)
		(fill yes)
		(layer "In4.Cu")
		(net "M_J_CPU1_SB_DQS_DN<2>")
	)
	(gr_poly
		(pts
			(xy 138.964924 -284.818328) (xy 138.864848 -284.718252) (xy 138.764772 -284.818328) (xy 138.764772 -284.862778)
			(xy 138.964924 -284.862778)
		)
		(stroke
			(width 0)
			(type solid)
		)
		(fill yes)
		(layer "In4.Cu")
		(net "M_J_CPU1_SB_DQ<17>")
	)
	(gr_poly
		(pts
			(xy 138.964924 -284.414468) (xy 138.964924 -284.370018) (xy 138.764772 -284.370018) (xy 138.764772 -284.414468)
			(xy 138.864848 -284.514544)
		)
		(stroke
			(width 0)
			(type solid)
		)
		(fill yes)
		(layer "In4.Cu")
		(net "M_J_CPU1_SB_DQ<18>")
	)
	(gr_poly
		(pts
			(xy 138.964924 -283.198316) (xy 138.864848 -283.09824) (xy 138.764772 -283.198316) (xy 138.764772 -283.242766)
			(xy 138.964924 -283.242766)
		)
		(stroke
			(width 0)
			(type solid)
		)
		(fill yes)
		(layer "In4.Cu")
		(net "M_J_CPU1_SB_DQ<13>")
	)
	(gr_poly
		(pts
			(xy 138.964924 -282.794456) (xy 138.964924 -282.750006) (xy 138.764772 -282.750006) (xy 138.764772 -282.794456)
			(xy 138.864848 -282.894532)
		)
		(stroke
			(width 0)
			(type solid)
		)
		(fill yes)
		(layer "In4.Cu")
		(net "M_J_CPU1_SB_DQ<14>")
	)
	(gr_poly
		(pts
			(xy 138.964924 -281.57805) (xy 138.864848 -281.478228) (xy 138.764772 -281.57805) (xy 138.764772 -281.625802)
			(xy 138.964924 -281.625802)
		)
		(stroke
			(width 0)
			(type solid)
		)
		(fill yes)
		(layer "In4.Cu")
		(net "M_J_CPU1_SB_DQS_DN<6>")
	)
	(gr_poly
		(pts
			(xy 138.964924 -281.174698) (xy 138.964924 -281.126946) (xy 138.764772 -281.126946) (xy 138.764772 -281.174698)
			(xy 138.864848 -281.27452)
		)
		(stroke
			(width 0)
			(type solid)
		)
		(fill yes)
		(layer "In4.Cu")
		(net "M_J_CPU1_SB_DQS_DN<1>")
	)
	(gr_poly
		(pts
			(xy 138.964924 -279.958292) (xy 138.864848 -279.858216) (xy 138.764772 -279.958292) (xy 138.764772 -280.002742)
			(xy 138.964924 -280.002742)
		)
		(stroke
			(width 0)
			(type solid)
		)
		(fill yes)
		(layer "In4.Cu")
		(net "M_J_CPU1_SB_DQ<9>")
	)
	(gr_poly
		(pts
			(xy 138.964924 -279.554432) (xy 138.964924 -279.509982) (xy 138.764772 -279.509982) (xy 138.764772 -279.554432)
			(xy 138.864848 -279.654508)
		)
		(stroke
			(width 0)
			(type solid)
		)
		(fill yes)
		(layer "In4.Cu")
		(net "M_J_CPU1_SB_DQ<10>")
	)
	(gr_poly
		(pts
			(xy 138.964924 -278.33828) (xy 138.864848 -278.238204) (xy 138.764772 -278.33828) (xy 138.764772 -278.38273)
			(xy 138.964924 -278.38273)
		)
		(stroke
			(width 0)
			(type solid)
		)
		(fill yes)
		(layer "In4.Cu")
		(net "M_J_CPU1_SB_DQ<5>")
	)
	(gr_poly
		(pts
			(xy 138.964924 -277.93442) (xy 138.964924 -277.88997) (xy 138.764772 -277.88997) (xy 138.764772 -277.93442)
			(xy 138.864848 -278.034496)
		)
		(stroke
			(width 0)
			(type solid)
		)
		(fill yes)
		(layer "In4.Cu")
		(net "M_J_CPU1_SB_DQ<6>")
	)
	(gr_poly
		(pts
			(xy 138.964924 -276.718014) (xy 138.864848 -276.618192) (xy 138.764772 -276.718014) (xy 138.764772 -276.765766)
			(xy 138.964924 -276.765766)
		)
		(stroke
			(width 0)
			(type solid)
		)
		(fill yes)
		(layer "In4.Cu")
		(net "M_J_CPU1_SB_DQS_DN<5>")
	)
	(gr_poly
		(pts
			(xy 138.964924 -276.314662) (xy 138.964924 -276.26691) (xy 138.764772 -276.26691) (xy 138.764772 -276.314662)
			(xy 138.864848 -276.414484)
		)
		(stroke
			(width 0)
			(type solid)
		)
		(fill yes)
		(layer "In4.Cu")
		(net "M_J_CPU1_SB_DQS_DN<0>")
	)
	(gr_poly
		(pts
			(xy 138.964924 -275.098256) (xy 138.864848 -274.99818) (xy 138.764772 -275.098256) (xy 138.764772 -275.142706)
			(xy 138.964924 -275.142706)
		)
		(stroke
			(width 0)
			(type solid)
		)
		(fill yes)
		(layer "In4.Cu")
		(net "M_J_CPU1_SB_DQ<1>")
	)
	(gr_poly
		(pts
			(xy 138.964924 -274.694396) (xy 138.964924 -274.649946) (xy 138.764772 -274.649946) (xy 138.764772 -274.694396)
			(xy 138.864848 -274.794472)
		)
		(stroke
			(width 0)
			(type solid)
		)
		(fill yes)
		(layer "In4.Cu")
		(net "M_J_CPU1_SB_DQ<2>")
	)
	(gr_poly
		(pts
			(xy 138.964924 -273.478244) (xy 138.864848 -273.378168) (xy 138.764772 -273.478244) (xy 138.764772 -273.522694)
			(xy 138.964924 -273.522694)
		)
		(stroke
			(width 0)
			(type solid)
		)
		(fill yes)
		(layer "In4.Cu")
		(net "M_J_CPU1_SB_CB<1>")
	)
	(gr_poly
		(pts
			(xy 138.964924 -273.074384) (xy 138.964924 -273.029934) (xy 138.764772 -273.029934) (xy 138.764772 -273.074384)
			(xy 138.864848 -273.17446)
		)
		(stroke
			(width 0)
			(type solid)
		)
		(fill yes)
		(layer "In4.Cu")
		(net "M_J_CPU1_SB_CB<2>")
	)
	(gr_poly
		(pts
			(xy 138.964924 -271.857978) (xy 138.864848 -271.758156) (xy 138.764772 -271.857978) (xy 138.764772 -271.90573)
			(xy 138.964924 -271.90573)
		)
		(stroke
			(width 0)
			(type solid)
		)
		(fill yes)
		(layer "In4.Cu")
		(net "M_J_CPU1_SB_DQS_DN<4>")
	)
	(gr_poly
		(pts
			(xy 138.964924 -271.454626) (xy 138.964924 -271.406874) (xy 138.764772 -271.406874) (xy 138.764772 -271.454626)
			(xy 138.864848 -271.554448)
		)
		(stroke
			(width 0)
			(type solid)
		)
		(fill yes)
		(layer "In4.Cu")
		(net "M_J_CPU1_SB_DQS_DN<9>")
	)
	(gr_poly
		(pts
			(xy 138.964924 -270.23822) (xy 138.864848 -270.138144) (xy 138.764772 -270.23822) (xy 138.764772 -270.28267)
			(xy 138.964924 -270.28267)
		)
		(stroke
			(width 0)
			(type solid)
		)
		(fill yes)
		(layer "In4.Cu")
		(net "M_J_CPU1_SB_CB<5>")
	)
	(gr_poly
		(pts
			(xy 138.964924 -269.83436) (xy 138.964924 -269.78991) (xy 138.764772 -269.78991) (xy 138.764772 -269.83436)
			(xy 138.864848 -269.934436)
		)
		(stroke
			(width 0)
			(type solid)
		)
		(fill yes)
		(layer "In4.Cu")
		(net "M_J_CPU1_SB_CB<6>")
	)
	(gr_poly
		(pts
			(xy 138.964924 -266.998196) (xy 138.864848 -266.89812) (xy 138.764772 -266.998196) (xy 138.764772 -267.042646)
			(xy 138.964924 -267.042646)
		)
		(stroke
			(width 0)
			(type solid)
		)
		(fill yes)
		(layer "In4.Cu")
		(net "M_J_CPU1_SA_RSP<0>")
	)
	(gr_poly
		(pts
			(xy 138.964924 -266.594336) (xy 138.964924 -266.549886) (xy 138.764772 -266.549886) (xy 138.764772 -266.594336)
			(xy 138.864848 -266.694412)
		)
		(stroke
			(width 0)
			(type solid)
		)
		(fill yes)
		(layer "In4.Cu")
		(net "M_J_CPU1_SB_CS_N<1>")
	)
	(gr_poly
		(pts
			(xy 138.964924 -265.378184) (xy 138.864848 -265.278108) (xy 138.764772 -265.378184) (xy 138.764772 -265.422634)
			(xy 138.964924 -265.422634)
		)
		(stroke
			(width 0)
			(type solid)
		)
		(fill yes)
		(layer "In4.Cu")
		(net "M_J_CPU1_SB_PAR")
	)
	(gr_poly
		(pts
			(xy 138.964924 -263.758172) (xy 138.864848 -263.658096) (xy 138.764772 -263.758172) (xy 138.764772 -263.802622)
			(xy 138.964924 -263.802622)
		)
		(stroke
			(width 0)
			(type solid)
		)
		(fill yes)
		(layer "In4.Cu")
		(net "M_J_CPU1_SB_CA<4>")
	)
	(gr_poly
		(pts
			(xy 138.964924 -263.354312) (xy 138.964924 -263.309862) (xy 138.764772 -263.309862) (xy 138.764772 -263.354312)
			(xy 138.864848 -263.454388)
		)
		(stroke
			(width 0)
			(type solid)
		)
		(fill yes)
		(layer "In4.Cu")
		(net "M_J_CPU1_SB_CA<3>")
	)
	(gr_poly
		(pts
			(xy 138.964924 -262.13816) (xy 138.864848 -262.038084) (xy 138.764772 -262.13816) (xy 138.764772 -262.18261)
			(xy 138.964924 -262.18261)
		)
		(stroke
			(width 0)
			(type solid)
		)
		(fill yes)
		(layer "In4.Cu")
		(net "M_J_CPU1_SB_CA<0>")
	)
	(gr_poly
		(pts
			(xy 139.13485 -256.432812) (xy 139.13485 -256.38506) (xy 138.934698 -256.38506) (xy 138.934698 -256.432812)
			(xy 139.034774 -256.532634)
		)
		(stroke
			(width 0)
			(type solid)
		)
		(fill yes)
		(layer "In4.Cu")
		(net "M_J_CPU1_CLK_DN<0>")
	)
	(gr_poly
		(pts
			(xy 139.13485 -255.216406) (xy 139.034774 -255.11633) (xy 138.934698 -255.216406) (xy 138.934698 -255.260856)
			(xy 139.13485 -255.260856)
		)
		(stroke
			(width 0)
			(type solid)
		)
		(fill yes)
		(layer "In4.Cu")
		(net "M_J_CPU1_SA_CA<6>")
	)
	(gr_poly
		(pts
			(xy 139.13485 -254.812546) (xy 139.13485 -254.768096) (xy 138.934698 -254.768096) (xy 138.934698 -254.812546)
			(xy 139.034774 -254.912622)
		)
		(stroke
			(width 0)
			(type solid)
		)
		(fill yes)
		(layer "In4.Cu")
		(net "M_J_CPU1_SA_CA<5>")
	)
	(gr_poly
		(pts
			(xy 139.13485 -253.596394) (xy 139.034774 -253.496318) (xy 138.934698 -253.596394) (xy 138.934698 -253.640844)
			(xy 139.13485 -253.640844)
		)
		(stroke
			(width 0)
			(type solid)
		)
		(fill yes)
		(layer "In4.Cu")
		(net "M_J_CPU1_SA_CA<2>")
	)
	(gr_poly
		(pts
			(xy 139.13485 -253.192534) (xy 139.13485 -253.148084) (xy 138.934698 -253.148084) (xy 138.934698 -253.192534)
			(xy 139.034774 -253.29261)
		)
		(stroke
			(width 0)
			(type solid)
		)
		(fill yes)
		(layer "In4.Cu")
		(net "M_J_CPU1_SA_CA<1>")
	)
	(gr_poly
		(pts
			(xy 139.13485 -251.976382) (xy 139.034774 -251.876306) (xy 138.934698 -251.976382) (xy 138.934698 -252.020832)
			(xy 139.13485 -252.020832)
		)
		(stroke
			(width 0)
			(type solid)
		)
		(fill yes)
		(layer "In4.Cu")
		(net "M_J_CPU1_SA_CS_N<1>")
	)
	(gr_poly
		(pts
			(xy 139.13485 -250.35637) (xy 139.034774 -250.256294) (xy 138.934698 -250.35637) (xy 138.934698 -250.40082)
			(xy 139.13485 -250.40082)
		)
		(stroke
			(width 0)
			(type solid)
		)
		(fill yes)
		(layer "In4.Cu")
		(net "M_J_CPU1_ALERT_R_N")
	)
	(gr_poly
		(pts
			(xy 139.13485 -248.736358) (xy 139.034774 -248.636282) (xy 138.934698 -248.736358) (xy 138.934698 -248.780808)
			(xy 139.13485 -248.780808)
		)
		(stroke
			(width 0)
			(type solid)
		)
		(fill yes)
		(layer "In4.Cu")
		(net "M_J_CPU1_SA_CB<5>")
	)
	(gr_poly
		(pts
			(xy 139.13485 -248.332498) (xy 139.13485 -248.288048) (xy 138.934698 -248.288048) (xy 138.934698 -248.332498)
			(xy 139.034774 -248.432574)
		)
		(stroke
			(width 0)
			(type solid)
		)
		(fill yes)
		(layer "In4.Cu")
		(net "M_J_CPU1_SA_CB<6>")
	)
	(gr_poly
		(pts
			(xy 139.13485 -247.116092) (xy 139.034774 -247.01627) (xy 138.934698 -247.116092) (xy 138.934698 -247.163844)
			(xy 139.13485 -247.163844)
		)
		(stroke
			(width 0)
			(type solid)
		)
		(fill yes)
		(layer "In4.Cu")
		(net "M_J_CPU1_SA_DQS_DN<9>")
	)
	(gr_poly
		(pts
			(xy 139.13485 -246.71274) (xy 139.13485 -246.664988) (xy 138.934698 -246.664988) (xy 138.934698 -246.71274)
			(xy 139.034774 -246.812562)
		)
		(stroke
			(width 0)
			(type solid)
		)
		(fill yes)
		(layer "In4.Cu")
		(net "M_J_CPU1_SA_DQS_DN<4>")
	)
	(gr_poly
		(pts
			(xy 139.13485 -245.496334) (xy 139.034774 -245.396258) (xy 138.934698 -245.496334) (xy 138.934698 -245.540784)
			(xy 139.13485 -245.540784)
		)
		(stroke
			(width 0)
			(type solid)
		)
		(fill yes)
		(layer "In4.Cu")
		(net "M_J_CPU1_SA_CB<1>")
	)
	(gr_poly
		(pts
			(xy 139.13485 -245.092474) (xy 139.13485 -245.048024) (xy 138.934698 -245.048024) (xy 138.934698 -245.092474)
			(xy 139.034774 -245.19255)
		)
		(stroke
			(width 0)
			(type solid)
		)
		(fill yes)
		(layer "In4.Cu")
		(net "M_J_CPU1_SA_CB<2>")
	)
	(gr_poly
		(pts
			(xy 139.13485 -243.876322) (xy 139.034774 -243.776246) (xy 138.934698 -243.876322) (xy 138.934698 -243.920772)
			(xy 139.13485 -243.920772)
		)
		(stroke
			(width 0)
			(type solid)
		)
		(fill yes)
		(layer "In4.Cu")
		(net "M_J_CPU1_SA_DQ<29>")
	)
	(gr_poly
		(pts
			(xy 139.13485 -243.472462) (xy 139.13485 -243.428012) (xy 138.934698 -243.428012) (xy 138.934698 -243.472462)
			(xy 139.034774 -243.572538)
		)
		(stroke
			(width 0)
			(type solid)
		)
		(fill yes)
		(layer "In4.Cu")
		(net "M_J_CPU1_SA_DQ<30>")
	)
	(gr_poly
		(pts
			(xy 139.13485 -242.256056) (xy 139.034774 -242.156234) (xy 138.934698 -242.256056) (xy 138.934698 -242.303808)
			(xy 139.13485 -242.303808)
		)
		(stroke
			(width 0)
			(type solid)
		)
		(fill yes)
		(layer "In4.Cu")
		(net "M_J_CPU1_SA_DQS_DN<8>")
	)
	(gr_poly
		(pts
			(xy 139.13485 -241.852704) (xy 139.13485 -241.804952) (xy 138.934698 -241.804952) (xy 138.934698 -241.852704)
			(xy 139.034774 -241.952526)
		)
		(stroke
			(width 0)
			(type solid)
		)
		(fill yes)
		(layer "In4.Cu")
		(net "M_J_CPU1_SA_DQS_DN<3>")
	)
	(gr_poly
		(pts
			(xy 139.13485 -240.636298) (xy 139.034774 -240.536222) (xy 138.934698 -240.636298) (xy 138.934698 -240.680748)
			(xy 139.13485 -240.680748)
		)
		(stroke
			(width 0)
			(type solid)
		)
		(fill yes)
		(layer "In4.Cu")
		(net "M_J_CPU1_SA_DQ<25>")
	)
	(gr_poly
		(pts
			(xy 139.13485 -240.232438) (xy 139.13485 -240.187988) (xy 138.934698 -240.187988) (xy 138.934698 -240.232438)
			(xy 139.034774 -240.332514)
		)
		(stroke
			(width 0)
			(type solid)
		)
		(fill yes)
		(layer "In4.Cu")
		(net "M_J_CPU1_SA_DQ<26>")
	)
	(gr_poly
		(pts
			(xy 139.13485 -239.016286) (xy 139.034774 -238.91621) (xy 138.934698 -239.016286) (xy 138.934698 -239.060736)
			(xy 139.13485 -239.060736)
		)
		(stroke
			(width 0)
			(type solid)
		)
		(fill yes)
		(layer "In4.Cu")
		(net "M_J_CPU1_SA_DQ<21>")
	)
	(gr_poly
		(pts
			(xy 139.13485 -238.612426) (xy 139.13485 -238.567976) (xy 138.934698 -238.567976) (xy 138.934698 -238.612426)
			(xy 139.034774 -238.712502)
		)
		(stroke
			(width 0)
			(type solid)
		)
		(fill yes)
		(layer "In4.Cu")
		(net "M_J_CPU1_SA_DQ<22>")
	)
	(gr_poly
		(pts
			(xy 139.13485 -237.39602) (xy 139.034774 -237.296198) (xy 138.934698 -237.39602) (xy 138.934698 -237.443772)
			(xy 139.13485 -237.443772)
		)
		(stroke
			(width 0)
			(type solid)
		)
		(fill yes)
		(layer "In4.Cu")
		(net "M_J_CPU1_SA_DQS_DN<7>")
	)
	(gr_poly
		(pts
			(xy 139.13485 -236.992668) (xy 139.13485 -236.944916) (xy 138.934698 -236.944916) (xy 138.934698 -236.992668)
			(xy 139.034774 -237.09249)
		)
		(stroke
			(width 0)
			(type solid)
		)
		(fill yes)
		(layer "In4.Cu")
		(net "M_J_CPU1_SA_DQS_DN<2>")
	)
	(gr_poly
		(pts
			(xy 139.13485 -235.776262) (xy 139.034774 -235.676186) (xy 138.934698 -235.776262) (xy 138.934698 -235.820712)
			(xy 139.13485 -235.820712)
		)
		(stroke
			(width 0)
			(type solid)
		)
		(fill yes)
		(layer "In4.Cu")
		(net "M_J_CPU1_SA_DQ<17>")
	)
	(gr_poly
		(pts
			(xy 139.13485 -235.372402) (xy 139.13485 -235.327952) (xy 138.934698 -235.327952) (xy 138.934698 -235.372402)
			(xy 139.034774 -235.472478)
		)
		(stroke
			(width 0)
			(type solid)
		)
		(fill yes)
		(layer "In4.Cu")
		(net "M_J_CPU1_SA_DQ<18>")
	)
	(gr_poly
		(pts
			(xy 139.13485 -234.15625) (xy 139.034774 -234.056174) (xy 138.934698 -234.15625) (xy 138.934698 -234.2007)
			(xy 139.13485 -234.2007)
		)
		(stroke
			(width 0)
			(type solid)
		)
		(fill yes)
		(layer "In4.Cu")
		(net "M_J_CPU1_SA_DQ<13>")
	)
	(gr_poly
		(pts
			(xy 139.13485 -233.75239) (xy 139.13485 -233.70794) (xy 138.934698 -233.70794) (xy 138.934698 -233.75239)
			(xy 139.034774 -233.852466)
		)
		(stroke
			(width 0)
			(type solid)
		)
		(fill yes)
		(layer "In4.Cu")
		(net "M_J_CPU1_SA_DQ<14>")
	)
	(gr_poly
		(pts
			(xy 139.13485 -232.535984) (xy 139.034774 -232.436162) (xy 138.934698 -232.535984) (xy 138.934698 -232.583736)
			(xy 139.13485 -232.583736)
		)
		(stroke
			(width 0)
			(type solid)
		)
		(fill yes)
		(layer "In4.Cu")
		(net "M_J_CPU1_SA_DQS_DN<6>")
	)
	(gr_poly
		(pts
			(xy 139.13485 -232.132632) (xy 139.13485 -232.08488) (xy 138.934698 -232.08488) (xy 138.934698 -232.132632)
			(xy 139.034774 -232.232454)
		)
		(stroke
			(width 0)
			(type solid)
		)
		(fill yes)
		(layer "In4.Cu")
		(net "M_J_CPU1_SA_DQS_DN<1>")
	)
	(gr_poly
		(pts
			(xy 139.13485 -230.916226) (xy 139.034774 -230.81615) (xy 138.934698 -230.916226) (xy 138.934698 -230.960676)
			(xy 139.13485 -230.960676)
		)
		(stroke
			(width 0)
			(type solid)
		)
		(fill yes)
		(layer "In4.Cu")
		(net "M_J_CPU1_SA_DQ<9>")
	)
	(gr_poly
		(pts
			(xy 139.13485 -230.51262) (xy 139.13485 -230.46817) (xy 138.934698 -230.46817) (xy 138.934698 -230.51262)
			(xy 139.034774 -230.612696)
		)
		(stroke
			(width 0)
			(type solid)
		)
		(fill yes)
		(layer "In4.Cu")
		(net "M_J_CPU1_SA_DQ<10>")
	)
	(gr_poly
		(pts
			(xy 139.13485 -229.296214) (xy 139.034774 -229.196138) (xy 138.934698 -229.296214) (xy 138.934698 -229.340664)
			(xy 139.13485 -229.340664)
		)
		(stroke
			(width 0)
			(type solid)
		)
		(fill yes)
		(layer "In4.Cu")
		(net "M_J_CPU1_SA_DQ<5>")
	)
	(gr_poly
		(pts
			(xy 139.13485 -228.892608) (xy 139.13485 -228.848158) (xy 138.934698 -228.848158) (xy 138.934698 -228.892608)
			(xy 139.034774 -228.992684)
		)
		(stroke
			(width 0)
			(type solid)
		)
		(fill yes)
		(layer "In4.Cu")
		(net "M_J_CPU1_SA_DQ<6>")
	)
	(gr_poly
		(pts
			(xy 139.13485 -227.676202) (xy 139.034774 -227.57638) (xy 138.934698 -227.676202) (xy 138.934698 -227.723954)
			(xy 139.13485 -227.723954)
		)
		(stroke
			(width 0)
			(type solid)
		)
		(fill yes)
		(layer "In4.Cu")
		(net "M_J_CPU1_SA_DQS_DN<5>")
	)
	(gr_poly
		(pts
			(xy 139.13485 -227.27285) (xy 139.13485 -227.225098) (xy 138.934698 -227.225098) (xy 138.934698 -227.27285)
			(xy 139.034774 -227.372672)
		)
		(stroke
			(width 0)
			(type solid)
		)
		(fill yes)
		(layer "In4.Cu")
		(net "M_J_CPU1_SA_DQS_DN<0>")
	)
	(gr_poly
		(pts
			(xy 139.13485 -226.056444) (xy 139.034774 -225.956368) (xy 138.934698 -226.056444) (xy 138.934698 -226.100894)
			(xy 139.13485 -226.100894)
		)
		(stroke
			(width 0)
			(type solid)
		)
		(fill yes)
		(layer "In4.Cu")
		(net "M_J_CPU1_SA_DQ<1>")
	)
	(gr_poly
		(pts
			(xy 139.13485 -225.652584) (xy 139.13485 -225.608134) (xy 138.934698 -225.608134) (xy 138.934698 -225.652584)
			(xy 139.034774 -225.75266)
		)
		(stroke
			(width 0)
			(type solid)
		)
		(fill yes)
		(layer "In4.Cu")
		(net "M_J_CPU1_SA_DQ<2>")
	)
	(gr_poly
		(pts
			(xy 139.434824 -293.32428) (xy 139.434824 -293.27983) (xy 139.234672 -293.27983) (xy 139.234672 -293.32428)
			(xy 139.334748 -293.424356)
		)
		(stroke
			(width 0)
			(type solid)
		)
		(fill yes)
		(layer "In4.Cu")
		(net "M_J_CPU1_SB_DQ<31>")
	)
	(gr_poly
		(pts
			(xy 139.434824 -292.108128) (xy 139.334748 -292.008052) (xy 139.234672 -292.108128) (xy 139.234672 -292.152578)
			(xy 139.434824 -292.152578)
		)
		(stroke
			(width 0)
			(type solid)
		)
		(fill yes)
		(layer "In4.Cu")
		(net "M_J_CPU1_SB_DQ<28>")
	)
	(gr_poly
		(pts
			(xy 139.434824 -291.704522) (xy 139.434824 -291.65677) (xy 139.234672 -291.65677) (xy 139.234672 -291.704522)
			(xy 139.334748 -291.804344)
		)
		(stroke
			(width 0)
			(type solid)
		)
		(fill yes)
		(layer "In4.Cu")
		(net "M_J_CPU1_SB_DQS_DP<8>")
	)
	(gr_poly
		(pts
			(xy 139.434824 -290.487862) (xy 139.334748 -290.38804) (xy 139.234672 -290.487862) (xy 139.234672 -290.535614)
			(xy 139.434824 -290.535614)
		)
		(stroke
			(width 0)
			(type solid)
		)
		(fill yes)
		(layer "In4.Cu")
		(net "M_J_CPU1_SB_DQS_DP<3>")
	)
	(gr_poly
		(pts
			(xy 139.434824 -290.084256) (xy 139.434824 -290.039806) (xy 139.234672 -290.039806) (xy 139.234672 -290.084256)
			(xy 139.334748 -290.184332)
		)
		(stroke
			(width 0)
			(type solid)
		)
		(fill yes)
		(layer "In4.Cu")
		(net "M_J_CPU1_SB_DQ<27>")
	)
	(gr_poly
		(pts
			(xy 139.434824 -288.868104) (xy 139.334748 -288.768028) (xy 139.234672 -288.868104) (xy 139.234672 -288.912554)
			(xy 139.434824 -288.912554)
		)
		(stroke
			(width 0)
			(type solid)
		)
		(fill yes)
		(layer "In4.Cu")
		(net "M_J_CPU1_SB_DQ<24>")
	)
	(gr_poly
		(pts
			(xy 139.434824 -288.464498) (xy 139.434824 -288.420048) (xy 139.234672 -288.420048) (xy 139.234672 -288.464498)
			(xy 139.334748 -288.564574)
		)
		(stroke
			(width 0)
			(type solid)
		)
		(fill yes)
		(layer "In4.Cu")
		(net "M_J_CPU1_SB_DQ<23>")
	)
	(gr_poly
		(pts
			(xy 139.434824 -287.248092) (xy 139.334748 -287.148016) (xy 139.234672 -287.248092) (xy 139.234672 -287.292542)
			(xy 139.434824 -287.292542)
		)
		(stroke
			(width 0)
			(type solid)
		)
		(fill yes)
		(layer "In4.Cu")
		(net "M_J_CPU1_SB_DQ<20>")
	)
	(gr_poly
		(pts
			(xy 139.434824 -286.844486) (xy 139.434824 -286.796734) (xy 139.234672 -286.796734) (xy 139.234672 -286.844486)
			(xy 139.334748 -286.944562)
		)
		(stroke
			(width 0)
			(type solid)
		)
		(fill yes)
		(layer "In4.Cu")
		(net "M_J_CPU1_SB_DQS_DP<7>")
	)
	(gr_poly
		(pts
			(xy 139.434824 -285.62808) (xy 139.334748 -285.528258) (xy 139.234672 -285.62808) (xy 139.234672 -285.675832)
			(xy 139.434824 -285.675832)
		)
		(stroke
			(width 0)
			(type solid)
		)
		(fill yes)
		(layer "In4.Cu")
		(net "M_J_CPU1_SB_DQS_DP<2>")
	)
	(gr_poly
		(pts
			(xy 139.434824 -285.224474) (xy 139.434824 -285.180024) (xy 139.234672 -285.180024) (xy 139.234672 -285.224474)
			(xy 139.334748 -285.32455)
		)
		(stroke
			(width 0)
			(type solid)
		)
		(fill yes)
		(layer "In4.Cu")
		(net "M_J_CPU1_SB_DQ<19>")
	)
	(gr_poly
		(pts
			(xy 139.434824 -284.008322) (xy 139.334748 -283.908246) (xy 139.234672 -284.008322) (xy 139.234672 -284.052772)
			(xy 139.434824 -284.052772)
		)
		(stroke
			(width 0)
			(type solid)
		)
		(fill yes)
		(layer "In4.Cu")
		(net "M_J_CPU1_SB_DQ<16>")
	)
	(gr_poly
		(pts
			(xy 139.434824 -283.604462) (xy 139.434824 -283.560012) (xy 139.234672 -283.560012) (xy 139.234672 -283.604462)
			(xy 139.334748 -283.704538)
		)
		(stroke
			(width 0)
			(type solid)
		)
		(fill yes)
		(layer "In4.Cu")
		(net "M_J_CPU1_SB_DQ<15>")
	)
	(gr_poly
		(pts
			(xy 139.434824 -282.38831) (xy 139.334748 -282.288234) (xy 139.234672 -282.38831) (xy 139.234672 -282.43276)
			(xy 139.434824 -282.43276)
		)
		(stroke
			(width 0)
			(type solid)
		)
		(fill yes)
		(layer "In4.Cu")
		(net "M_J_CPU1_SB_DQ<12>")
	)
	(gr_poly
		(pts
			(xy 139.434824 -281.984704) (xy 139.434824 -281.936952) (xy 139.234672 -281.936952) (xy 139.234672 -281.984704)
			(xy 139.334748 -282.084526)
		)
		(stroke
			(width 0)
			(type solid)
		)
		(fill yes)
		(layer "In4.Cu")
		(net "M_J_CPU1_SB_DQS_DP<6>")
	)
	(gr_poly
		(pts
			(xy 139.434824 -280.768044) (xy 139.334748 -280.668222) (xy 139.234672 -280.768044) (xy 139.234672 -280.815796)
			(xy 139.434824 -280.815796)
		)
		(stroke
			(width 0)
			(type solid)
		)
		(fill yes)
		(layer "In4.Cu")
		(net "M_J_CPU1_SB_DQS_DP<1>")
	)
	(gr_poly
		(pts
			(xy 139.434824 -280.364438) (xy 139.434824 -280.319988) (xy 139.234672 -280.319988) (xy 139.234672 -280.364438)
			(xy 139.334748 -280.464514)
		)
		(stroke
			(width 0)
			(type solid)
		)
		(fill yes)
		(layer "In4.Cu")
		(net "M_J_CPU1_SB_DQ<11>")
	)
	(gr_poly
		(pts
			(xy 139.434824 -279.148286) (xy 139.334748 -279.04821) (xy 139.234672 -279.148286) (xy 139.234672 -279.192736)
			(xy 139.434824 -279.192736)
		)
		(stroke
			(width 0)
			(type solid)
		)
		(fill yes)
		(layer "In4.Cu")
		(net "M_J_CPU1_SB_DQ<8>")
	)
	(gr_poly
		(pts
			(xy 139.434824 -278.744426) (xy 139.434824 -278.699976) (xy 139.234672 -278.699976) (xy 139.234672 -278.744426)
			(xy 139.334748 -278.844502)
		)
		(stroke
			(width 0)
			(type solid)
		)
		(fill yes)
		(layer "In4.Cu")
		(net "M_J_CPU1_SB_DQ<7>")
	)
	(gr_poly
		(pts
			(xy 139.434824 -277.528274) (xy 139.334748 -277.428198) (xy 139.234672 -277.528274) (xy 139.234672 -277.572724)
			(xy 139.434824 -277.572724)
		)
		(stroke
			(width 0)
			(type solid)
		)
		(fill yes)
		(layer "In4.Cu")
		(net "M_J_CPU1_SB_DQ<4>")
	)
	(gr_poly
		(pts
			(xy 139.434824 -277.124668) (xy 139.434824 -277.076916) (xy 139.234672 -277.076916) (xy 139.234672 -277.124668)
			(xy 139.334748 -277.22449)
		)
		(stroke
			(width 0)
			(type solid)
		)
		(fill yes)
		(layer "In4.Cu")
		(net "M_J_CPU1_SB_DQS_DP<5>")
	)
	(gr_poly
		(pts
			(xy 139.434824 -275.908008) (xy 139.334748 -275.808186) (xy 139.234672 -275.908008) (xy 139.234672 -275.95576)
			(xy 139.434824 -275.95576)
		)
		(stroke
			(width 0)
			(type solid)
		)
		(fill yes)
		(layer "In4.Cu")
		(net "M_J_CPU1_SB_DQS_DP<0>")
	)
	(gr_poly
		(pts
			(xy 139.434824 -275.504402) (xy 139.434824 -275.459952) (xy 139.234672 -275.459952) (xy 139.234672 -275.504402)
			(xy 139.334748 -275.604478)
		)
		(stroke
			(width 0)
			(type solid)
		)
		(fill yes)
		(layer "In4.Cu")
		(net "M_J_CPU1_SB_DQ<3>")
	)
	(gr_poly
		(pts
			(xy 139.434824 -274.28825) (xy 139.334748 -274.188174) (xy 139.234672 -274.28825) (xy 139.234672 -274.3327)
			(xy 139.434824 -274.3327)
		)
		(stroke
			(width 0)
			(type solid)
		)
		(fill yes)
		(layer "In4.Cu")
		(net "M_J_CPU1_SB_DQ<0>")
	)
	(gr_poly
		(pts
			(xy 139.434824 -273.88439) (xy 139.434824 -273.83994) (xy 139.234672 -273.83994) (xy 139.234672 -273.88439)
			(xy 139.334748 -273.984466)
		)
		(stroke
			(width 0)
			(type solid)
		)
		(fill yes)
		(layer "In4.Cu")
		(net "M_J_CPU1_SB_CB<3>")
	)
	(gr_poly
		(pts
			(xy 139.434824 -272.668238) (xy 139.334748 -272.568162) (xy 139.234672 -272.668238) (xy 139.234672 -272.712688)
			(xy 139.434824 -272.712688)
		)
		(stroke
			(width 0)
			(type solid)
		)
		(fill yes)
		(layer "In4.Cu")
		(net "M_J_CPU1_SB_CB<0>")
	)
	(gr_poly
		(pts
			(xy 139.434824 -272.264632) (xy 139.434824 -272.21688) (xy 139.234672 -272.21688) (xy 139.234672 -272.264632)
			(xy 139.334748 -272.364454)
		)
		(stroke
			(width 0)
			(type solid)
		)
		(fill yes)
		(layer "In4.Cu")
		(net "M_J_CPU1_SB_DQS_DP<4>")
	)
	(gr_poly
		(pts
			(xy 139.434824 -271.047972) (xy 139.334748 -270.94815) (xy 139.234672 -271.047972) (xy 139.234672 -271.095724)
			(xy 139.434824 -271.095724)
		)
		(stroke
			(width 0)
			(type solid)
		)
		(fill yes)
		(layer "In4.Cu")
		(net "M_J_CPU1_SB_DQS_DP<9>")
	)
	(gr_poly
		(pts
			(xy 139.434824 -270.644366) (xy 139.434824 -270.599916) (xy 139.234672 -270.599916) (xy 139.234672 -270.644366)
			(xy 139.334748 -270.744442)
		)
		(stroke
			(width 0)
			(type solid)
		)
		(fill yes)
		(layer "In4.Cu")
		(net "M_J_CPU1_SB_CB<7>")
	)
	(gr_poly
		(pts
			(xy 139.434824 -269.428214) (xy 139.334748 -269.328138) (xy 139.234672 -269.428214) (xy 139.234672 -269.472664)
			(xy 139.434824 -269.472664)
		)
		(stroke
			(width 0)
			(type solid)
		)
		(fill yes)
		(layer "In4.Cu")
		(net "M_J_CPU1_SB_CB<4>")
	)
	(gr_poly
		(pts
			(xy 139.434824 -267.808202) (xy 139.334748 -267.708126) (xy 139.234672 -267.808202) (xy 139.234672 -267.852652)
			(xy 139.434824 -267.852652)
		)
		(stroke
			(width 0)
			(type solid)
		)
		(fill yes)
		(layer "In4.Cu")
		(net "M_J_CPU1_SB_RSP<0>")
	)
	(gr_poly
		(pts
			(xy 139.434824 -265.78433) (xy 139.434824 -265.73988) (xy 139.234672 -265.73988) (xy 139.234672 -265.78433)
			(xy 139.334748 -265.884406)
		)
		(stroke
			(width 0)
			(type solid)
		)
		(fill yes)
		(layer "In4.Cu")
		(net "M_J_CPU1_SB_CS_N<0>")
	)
	(gr_poly
		(pts
			(xy 139.434824 -264.568178) (xy 139.334748 -264.468102) (xy 139.234672 -264.568178) (xy 139.234672 -264.612628)
			(xy 139.434824 -264.612628)
		)
		(stroke
			(width 0)
			(type solid)
		)
		(fill yes)
		(layer "In4.Cu")
		(net "M_J_CPU1_SB_CA<6>")
	)
	(gr_poly
		(pts
			(xy 139.434824 -264.164318) (xy 139.434824 -264.119868) (xy 139.234672 -264.119868) (xy 139.234672 -264.164318)
			(xy 139.334748 -264.264394)
		)
		(stroke
			(width 0)
			(type solid)
		)
		(fill yes)
		(layer "In4.Cu")
		(net "M_J_CPU1_SB_CA<5>")
	)
	(gr_poly
		(pts
			(xy 139.434824 -262.948166) (xy 139.334748 -262.84809) (xy 139.234672 -262.948166) (xy 139.234672 -262.992616)
			(xy 139.434824 -262.992616)
		)
		(stroke
			(width 0)
			(type solid)
		)
		(fill yes)
		(layer "In4.Cu")
		(net "M_J_CPU1_SB_CA<2>")
	)
	(gr_poly
		(pts
			(xy 139.434824 -262.544306) (xy 139.434824 -262.499856) (xy 139.234672 -262.499856) (xy 139.234672 -262.544306)
			(xy 139.334748 -262.644382)
		)
		(stroke
			(width 0)
			(type solid)
		)
		(fill yes)
		(layer "In4.Cu")
		(net "M_J_CPU1_SB_CA<1>")
	)
	(gr_poly
		(pts
			(xy 139.60475 -256.026158) (xy 139.504674 -255.926336) (xy 139.404598 -256.026158) (xy 139.404598 -256.07391)
			(xy 139.60475 -256.07391)
		)
		(stroke
			(width 0)
			(type solid)
		)
		(fill yes)
		(layer "In4.Cu")
		(net "M_J_CPU1_CLK_DP<0>")
	)
	(gr_poly
		(pts
			(xy 139.60475 -255.622552) (xy 139.60475 -255.578102) (xy 139.404598 -255.578102) (xy 139.404598 -255.622552)
			(xy 139.504674 -255.722628)
		)
		(stroke
			(width 0)
			(type solid)
		)
		(fill yes)
		(layer "In4.Cu")
		(net "M_J_CPU1_SA_PAR")
	)
	(gr_poly
		(pts
			(xy 139.60475 -254.4064) (xy 139.504674 -254.306324) (xy 139.404598 -254.4064) (xy 139.404598 -254.45085)
			(xy 139.60475 -254.45085)
		)
		(stroke
			(width 0)
			(type solid)
		)
		(fill yes)
		(layer "In4.Cu")
		(net "M_J_CPU1_SA_CA<4>")
	)
	(gr_poly
		(pts
			(xy 139.60475 -254.00254) (xy 139.60475 -253.95809) (xy 139.404598 -253.95809) (xy 139.404598 -254.00254)
			(xy 139.504674 -254.102616)
		)
		(stroke
			(width 0)
			(type solid)
		)
		(fill yes)
		(layer "In4.Cu")
		(net "M_J_CPU1_SA_CA<3>")
	)
	(gr_poly
		(pts
			(xy 139.60475 -252.786388) (xy 139.504674 -252.686312) (xy 139.404598 -252.786388) (xy 139.404598 -252.830838)
			(xy 139.60475 -252.830838)
		)
		(stroke
			(width 0)
			(type solid)
		)
		(fill yes)
		(layer "In4.Cu")
		(net "M_J_CPU1_SA_CA<0>")
	)
	(gr_poly
		(pts
			(xy 139.60475 -251.166376) (xy 139.504674 -251.0663) (xy 139.404598 -251.166376) (xy 139.404598 -251.210826)
			(xy 139.60475 -251.210826)
		)
		(stroke
			(width 0)
			(type solid)
		)
		(fill yes)
		(layer "In4.Cu")
		(net "M_J_CPU1_SA_CS_N<0>")
	)
	(gr_poly
		(pts
			(xy 139.60475 -250.762516) (xy 139.60475 -250.718066) (xy 139.404598 -250.718066) (xy 139.404598 -250.762516)
			(xy 139.504674 -250.862592)
		)
		(stroke
			(width 0)
			(type solid)
		)
		(fill yes)
		(layer "In4.Cu")
		(net "M_J_CPU1_RESET_N")
	)
	(gr_poly
		(pts
			(xy 139.60475 -249.142504) (xy 139.60475 -249.098054) (xy 139.404598 -249.098054) (xy 139.404598 -249.142504)
			(xy 139.504674 -249.24258)
		)
		(stroke
			(width 0)
			(type solid)
		)
		(fill yes)
		(layer "In4.Cu")
		(net "M_J_CPU1_SA_CB<7>")
	)
	(gr_poly
		(pts
			(xy 139.60475 -247.926352) (xy 139.504674 -247.826276) (xy 139.404598 -247.926352) (xy 139.404598 -247.970802)
			(xy 139.60475 -247.970802)
		)
		(stroke
			(width 0)
			(type solid)
		)
		(fill yes)
		(layer "In4.Cu")
		(net "M_J_CPU1_SA_CB<4>")
	)
	(gr_poly
		(pts
			(xy 139.60475 -247.522746) (xy 139.60475 -247.474994) (xy 139.404598 -247.474994) (xy 139.404598 -247.522746)
			(xy 139.504674 -247.622568)
		)
		(stroke
			(width 0)
			(type solid)
		)
		(fill yes)
		(layer "In4.Cu")
		(net "M_J_CPU1_SA_DQS_DP<9>")
	)
	(gr_poly
		(pts
			(xy 139.60475 -246.306086) (xy 139.504674 -246.206264) (xy 139.404598 -246.306086) (xy 139.404598 -246.353838)
			(xy 139.60475 -246.353838)
		)
		(stroke
			(width 0)
			(type solid)
		)
		(fill yes)
		(layer "In4.Cu")
		(net "M_J_CPU1_SA_DQS_DP<4>")
	)
	(gr_poly
		(pts
			(xy 139.60475 -245.90248) (xy 139.60475 -245.85803) (xy 139.404598 -245.85803) (xy 139.404598 -245.90248)
			(xy 139.504674 -246.002556)
		)
		(stroke
			(width 0)
			(type solid)
		)
		(fill yes)
		(layer "In4.Cu")
		(net "M_J_CPU1_SA_CB<3>")
	)
	(gr_poly
		(pts
			(xy 139.60475 -244.686328) (xy 139.504674 -244.586252) (xy 139.404598 -244.686328) (xy 139.404598 -244.730778)
			(xy 139.60475 -244.730778)
		)
		(stroke
			(width 0)
			(type solid)
		)
		(fill yes)
		(layer "In4.Cu")
		(net "M_J_CPU1_SA_CB<0>")
	)
	(gr_poly
		(pts
			(xy 139.60475 -244.282468) (xy 139.60475 -244.238018) (xy 139.404598 -244.238018) (xy 139.404598 -244.282468)
			(xy 139.504674 -244.382544)
		)
		(stroke
			(width 0)
			(type solid)
		)
		(fill yes)
		(layer "In4.Cu")
		(net "M_J_CPU1_SA_DQ<31>")
	)
	(gr_poly
		(pts
			(xy 139.60475 -243.066316) (xy 139.504674 -242.96624) (xy 139.404598 -243.066316) (xy 139.404598 -243.110766)
			(xy 139.60475 -243.110766)
		)
		(stroke
			(width 0)
			(type solid)
		)
		(fill yes)
		(layer "In4.Cu")
		(net "M_J_CPU1_SA_DQ<28>")
	)
	(gr_poly
		(pts
			(xy 139.60475 -242.66271) (xy 139.60475 -242.614958) (xy 139.404598 -242.614958) (xy 139.404598 -242.66271)
			(xy 139.504674 -242.762532)
		)
		(stroke
			(width 0)
			(type solid)
		)
		(fill yes)
		(layer "In4.Cu")
		(net "M_J_CPU1_SA_DQS_DP<8>")
	)
	(gr_poly
		(pts
			(xy 139.60475 -241.44605) (xy 139.504674 -241.346228) (xy 139.404598 -241.44605) (xy 139.404598 -241.493802)
			(xy 139.60475 -241.493802)
		)
		(stroke
			(width 0)
			(type solid)
		)
		(fill yes)
		(layer "In4.Cu")
		(net "M_J_CPU1_SA_DQS_DP<3>")
	)
	(gr_poly
		(pts
			(xy 139.60475 -241.042444) (xy 139.60475 -240.997994) (xy 139.404598 -240.997994) (xy 139.404598 -241.042444)
			(xy 139.504674 -241.14252)
		)
		(stroke
			(width 0)
			(type solid)
		)
		(fill yes)
		(layer "In4.Cu")
		(net "M_J_CPU1_SA_DQ<27>")
	)
	(gr_poly
		(pts
			(xy 139.60475 -239.826292) (xy 139.504674 -239.726216) (xy 139.404598 -239.826292) (xy 139.404598 -239.870742)
			(xy 139.60475 -239.870742)
		)
		(stroke
			(width 0)
			(type solid)
		)
		(fill yes)
		(layer "In4.Cu")
		(net "M_J_CPU1_SA_DQ<24>")
	)
	(gr_poly
		(pts
			(xy 139.60475 -239.422432) (xy 139.60475 -239.377982) (xy 139.404598 -239.377982) (xy 139.404598 -239.422432)
			(xy 139.504674 -239.522508)
		)
		(stroke
			(width 0)
			(type solid)
		)
		(fill yes)
		(layer "In4.Cu")
		(net "M_J_CPU1_SA_DQ<23>")
	)
	(gr_poly
		(pts
			(xy 139.60475 -238.20628) (xy 139.504674 -238.106204) (xy 139.404598 -238.20628) (xy 139.404598 -238.25073)
			(xy 139.60475 -238.25073)
		)
		(stroke
			(width 0)
			(type solid)
		)
		(fill yes)
		(layer "In4.Cu")
		(net "M_J_CPU1_SA_DQ<20>")
	)
	(gr_poly
		(pts
			(xy 139.60475 -237.802674) (xy 139.60475 -237.754922) (xy 139.404598 -237.754922) (xy 139.404598 -237.802674)
			(xy 139.504674 -237.902496)
		)
		(stroke
			(width 0)
			(type solid)
		)
		(fill yes)
		(layer "In4.Cu")
		(net "M_J_CPU1_SA_DQS_DP<7>")
	)
	(gr_poly
		(pts
			(xy 139.60475 -236.586014) (xy 139.504674 -236.486192) (xy 139.404598 -236.586014) (xy 139.404598 -236.633766)
			(xy 139.60475 -236.633766)
		)
		(stroke
			(width 0)
			(type solid)
		)
		(fill yes)
		(layer "In4.Cu")
		(net "M_J_CPU1_SA_DQS_DP<2>")
	)
	(gr_poly
		(pts
			(xy 139.60475 -236.182408) (xy 139.60475 -236.137958) (xy 139.404598 -236.137958) (xy 139.404598 -236.182408)
			(xy 139.504674 -236.282484)
		)
		(stroke
			(width 0)
			(type solid)
		)
		(fill yes)
		(layer "In4.Cu")
		(net "M_J_CPU1_SA_DQ<19>")
	)
	(gr_poly
		(pts
			(xy 139.60475 -234.966256) (xy 139.504674 -234.86618) (xy 139.404598 -234.966256) (xy 139.404598 -235.010706)
			(xy 139.60475 -235.010706)
		)
		(stroke
			(width 0)
			(type solid)
		)
		(fill yes)
		(layer "In4.Cu")
		(net "M_J_CPU1_SA_DQ<16>")
	)
	(gr_poly
		(pts
			(xy 139.60475 -234.562396) (xy 139.60475 -234.517946) (xy 139.404598 -234.517946) (xy 139.404598 -234.562396)
			(xy 139.504674 -234.662472)
		)
		(stroke
			(width 0)
			(type solid)
		)
		(fill yes)
		(layer "In4.Cu")
		(net "M_J_CPU1_SA_DQ<15>")
	)
	(gr_poly
		(pts
			(xy 139.60475 -233.346244) (xy 139.504674 -233.246168) (xy 139.404598 -233.346244) (xy 139.404598 -233.390694)
			(xy 139.60475 -233.390694)
		)
		(stroke
			(width 0)
			(type solid)
		)
		(fill yes)
		(layer "In4.Cu")
		(net "M_J_CPU1_SA_DQ<12>")
	)
	(gr_poly
		(pts
			(xy 139.60475 -232.942638) (xy 139.60475 -232.894886) (xy 139.404598 -232.894886) (xy 139.404598 -232.942638)
			(xy 139.504674 -233.04246)
		)
		(stroke
			(width 0)
			(type solid)
		)
		(fill yes)
		(layer "In4.Cu")
		(net "M_J_CPU1_SA_DQS_DP<6>")
	)
	(gr_poly
		(pts
			(xy 139.60475 -231.725978) (xy 139.504674 -231.626156) (xy 139.404598 -231.725978) (xy 139.404598 -231.77373)
			(xy 139.60475 -231.77373)
		)
		(stroke
			(width 0)
			(type solid)
		)
		(fill yes)
		(layer "In4.Cu")
		(net "M_J_CPU1_SA_DQS_DP<1>")
	)
	(gr_poly
		(pts
			(xy 139.60475 -231.322626) (xy 139.60475 -231.278176) (xy 139.404598 -231.278176) (xy 139.404598 -231.322626)
			(xy 139.504674 -231.422702)
		)
		(stroke
			(width 0)
			(type solid)
		)
		(fill yes)
		(layer "In4.Cu")
		(net "M_J_CPU1_SA_DQ<11>")
	)
	(gr_poly
		(pts
			(xy 139.60475 -230.10622) (xy 139.504674 -230.006144) (xy 139.404598 -230.10622) (xy 139.404598 -230.15067)
			(xy 139.60475 -230.15067)
		)
		(stroke
			(width 0)
			(type solid)
		)
		(fill yes)
		(layer "In4.Cu")
		(net "M_J_CPU1_SA_DQ<8>")
	)
	(gr_poly
		(pts
			(xy 139.60475 -229.702614) (xy 139.60475 -229.658164) (xy 139.404598 -229.658164) (xy 139.404598 -229.702614)
			(xy 139.504674 -229.80269)
		)
		(stroke
			(width 0)
			(type solid)
		)
		(fill yes)
		(layer "In4.Cu")
		(net "M_J_CPU1_SA_DQ<7>")
	)
	(gr_poly
		(pts
			(xy 139.60475 -228.486462) (xy 139.504674 -228.386386) (xy 139.404598 -228.486462) (xy 139.404598 -228.530912)
			(xy 139.60475 -228.530912)
		)
		(stroke
			(width 0)
			(type solid)
		)
		(fill yes)
		(layer "In4.Cu")
		(net "M_J_CPU1_SA_DQ<4>")
	)
	(gr_poly
		(pts
			(xy 139.60475 -228.082856) (xy 139.60475 -228.035104) (xy 139.404598 -228.035104) (xy 139.404598 -228.082856)
			(xy 139.504674 -228.182678)
		)
		(stroke
			(width 0)
			(type solid)
		)
		(fill yes)
		(layer "In4.Cu")
		(net "M_J_CPU1_SA_DQS_DP<5>")
	)
	(gr_poly
		(pts
			(xy 139.60475 -226.866196) (xy 139.504674 -226.766374) (xy 139.404598 -226.866196) (xy 139.404598 -226.913948)
			(xy 139.60475 -226.913948)
		)
		(stroke
			(width 0)
			(type solid)
		)
		(fill yes)
		(layer "In4.Cu")
		(net "M_J_CPU1_SA_DQS_DP<0>")
	)
	(gr_poly
		(pts
			(xy 139.60475 -226.46259) (xy 139.60475 -226.41814) (xy 139.404598 -226.41814) (xy 139.404598 -226.46259)
			(xy 139.504674 -226.562666)
		)
		(stroke
			(width 0)
			(type solid)
		)
		(fill yes)
		(layer "In4.Cu")
		(net "M_J_CPU1_SA_DQ<3>")
	)
	(gr_poly
		(pts
			(xy 139.60475 -225.246438) (xy 139.504674 -225.146362) (xy 139.404598 -225.246438) (xy 139.404598 -225.290888)
			(xy 139.60475 -225.290888)
		)
		(stroke
			(width 0)
			(type solid)
		)
		(fill yes)
		(layer "In4.Cu")
		(net "M_J_CPU1_SA_DQ<0>")
	)
	(gr_poly
		(pts
			(xy 139.904724 -292.918134) (xy 139.804648 -292.818058) (xy 139.704572 -292.918134) (xy 139.704572 -292.962584)
			(xy 139.904724 -292.962584)
		)
		(stroke
			(width 0)
			(type solid)
		)
		(fill yes)
		(layer "In4.Cu")
		(net "M_J_CPU1_SB_DQ<29>")
	)
	(gr_poly
		(pts
			(xy 139.904724 -292.514274) (xy 139.904724 -292.469824) (xy 139.704572 -292.469824) (xy 139.704572 -292.514274)
			(xy 139.804648 -292.61435)
		)
		(stroke
			(width 0)
			(type solid)
		)
		(fill yes)
		(layer "In4.Cu")
		(net "M_J_CPU1_SB_DQ<30>")
	)
	(gr_poly
		(pts
			(xy 139.904724 -291.297868) (xy 139.804648 -291.198046) (xy 139.704572 -291.297868) (xy 139.704572 -291.34562)
			(xy 139.904724 -291.34562)
		)
		(stroke
			(width 0)
			(type solid)
		)
		(fill yes)
		(layer "In4.Cu")
		(net "M_J_CPU1_SB_DQS_DN<8>")
	)
	(gr_poly
		(pts
			(xy 139.904724 -290.894516) (xy 139.904724 -290.846764) (xy 139.704572 -290.846764) (xy 139.704572 -290.894516)
			(xy 139.804648 -290.994338)
		)
		(stroke
			(width 0)
			(type solid)
		)
		(fill yes)
		(layer "In4.Cu")
		(net "M_J_CPU1_SB_DQS_DN<3>")
	)
	(gr_poly
		(pts
			(xy 139.904724 -289.67811) (xy 139.804648 -289.578034) (xy 139.704572 -289.67811) (xy 139.704572 -289.72256)
			(xy 139.904724 -289.72256)
		)
		(stroke
			(width 0)
			(type solid)
		)
		(fill yes)
		(layer "In4.Cu")
		(net "M_J_CPU1_SB_DQ<25>")
	)
	(gr_poly
		(pts
			(xy 139.904724 -289.27425) (xy 139.904724 -289.2298) (xy 139.704572 -289.2298) (xy 139.704572 -289.27425)
			(xy 139.804648 -289.374326)
		)
		(stroke
			(width 0)
			(type solid)
		)
		(fill yes)
		(layer "In4.Cu")
		(net "M_J_CPU1_SB_DQ<26>")
	)
	(gr_poly
		(pts
			(xy 139.904724 -288.058098) (xy 139.804648 -287.958022) (xy 139.704572 -288.058098) (xy 139.704572 -288.102548)
			(xy 139.904724 -288.102548)
		)
		(stroke
			(width 0)
			(type solid)
		)
		(fill yes)
		(layer "In4.Cu")
		(net "M_J_CPU1_SB_DQ<21>")
	)
	(gr_poly
		(pts
			(xy 139.904724 -287.654492) (xy 139.904724 -287.610042) (xy 139.704572 -287.610042) (xy 139.704572 -287.654492)
			(xy 139.804648 -287.754568)
		)
		(stroke
			(width 0)
			(type solid)
		)
		(fill yes)
		(layer "In4.Cu")
		(net "M_J_CPU1_SB_DQ<22>")
	)
	(gr_poly
		(pts
			(xy 139.904724 -286.438086) (xy 139.804648 -286.33801) (xy 139.704572 -286.438086) (xy 139.704572 -286.485838)
			(xy 139.904724 -286.485838)
		)
		(stroke
			(width 0)
			(type solid)
		)
		(fill yes)
		(layer "In4.Cu")
		(net "M_J_CPU1_SB_DQS_DN<7>")
	)
	(gr_poly
		(pts
			(xy 139.904724 -286.034734) (xy 139.904724 -285.986982) (xy 139.704572 -285.986982) (xy 139.704572 -286.034734)
			(xy 139.804648 -286.134556)
		)
		(stroke
			(width 0)
			(type solid)
		)
		(fill yes)
		(layer "In4.Cu")
		(net "M_J_CPU1_SB_DQS_DN<2>")
	)
	(gr_poly
		(pts
			(xy 139.904724 -284.818328) (xy 139.804648 -284.718252) (xy 139.704572 -284.818328) (xy 139.704572 -284.862778)
			(xy 139.904724 -284.862778)
		)
		(stroke
			(width 0)
			(type solid)
		)
		(fill yes)
		(layer "In4.Cu")
		(net "M_J_CPU1_SB_DQ<17>")
	)
	(gr_poly
		(pts
			(xy 139.904724 -284.414468) (xy 139.904724 -284.370018) (xy 139.704572 -284.370018) (xy 139.704572 -284.414468)
			(xy 139.804648 -284.514544)
		)
		(stroke
			(width 0)
			(type solid)
		)
		(fill yes)
		(layer "In4.Cu")
		(net "M_J_CPU1_SB_DQ<18>")
	)
	(gr_poly
		(pts
			(xy 139.904724 -283.198316) (xy 139.804648 -283.09824) (xy 139.704572 -283.198316) (xy 139.704572 -283.242766)
			(xy 139.904724 -283.242766)
		)
		(stroke
			(width 0)
			(type solid)
		)
		(fill yes)
		(layer "In4.Cu")
		(net "M_J_CPU1_SB_DQ<13>")
	)
	(gr_poly
		(pts
			(xy 139.904724 -282.794456) (xy 139.904724 -282.750006) (xy 139.704572 -282.750006) (xy 139.704572 -282.794456)
			(xy 139.804648 -282.894532)
		)
		(stroke
			(width 0)
			(type solid)
		)
		(fill yes)
		(layer "In4.Cu")
		(net "M_J_CPU1_SB_DQ<14>")
	)
	(gr_poly
		(pts
			(xy 139.904724 -281.57805) (xy 139.804648 -281.478228) (xy 139.704572 -281.57805) (xy 139.704572 -281.625802)
			(xy 139.904724 -281.625802)
		)
		(stroke
			(width 0)
			(type solid)
		)
		(fill yes)
		(layer "In4.Cu")
		(net "M_J_CPU1_SB_DQS_DN<6>")
	)
	(gr_poly
		(pts
			(xy 139.904724 -281.174698) (xy 139.904724 -281.126946) (xy 139.704572 -281.126946) (xy 139.704572 -281.174698)
			(xy 139.804648 -281.27452)
		)
		(stroke
			(width 0)
			(type solid)
		)
		(fill yes)
		(layer "In4.Cu")
		(net "M_J_CPU1_SB_DQS_DN<1>")
	)
	(gr_poly
		(pts
			(xy 139.904724 -279.958292) (xy 139.804648 -279.858216) (xy 139.704572 -279.958292) (xy 139.704572 -280.002742)
			(xy 139.904724 -280.002742)
		)
		(stroke
			(width 0)
			(type solid)
		)
		(fill yes)
		(layer "In4.Cu")
		(net "M_J_CPU1_SB_DQ<9>")
	)
	(gr_poly
		(pts
			(xy 139.904724 -279.554432) (xy 139.904724 -279.509982) (xy 139.704572 -279.509982) (xy 139.704572 -279.554432)
			(xy 139.804648 -279.654508)
		)
		(stroke
			(width 0)
			(type solid)
		)
		(fill yes)
		(layer "In4.Cu")
		(net "M_J_CPU1_SB_DQ<10>")
	)
	(gr_poly
		(pts
			(xy 139.904724 -278.33828) (xy 139.804648 -278.238204) (xy 139.704572 -278.33828) (xy 139.704572 -278.38273)
			(xy 139.904724 -278.38273)
		)
		(stroke
			(width 0)
			(type solid)
		)
		(fill yes)
		(layer "In4.Cu")
		(net "M_J_CPU1_SB_DQ<5>")
	)
	(gr_poly
		(pts
			(xy 139.904724 -277.93442) (xy 139.904724 -277.88997) (xy 139.704572 -277.88997) (xy 139.704572 -277.93442)
			(xy 139.804648 -278.034496)
		)
		(stroke
			(width 0)
			(type solid)
		)
		(fill yes)
		(layer "In4.Cu")
		(net "M_J_CPU1_SB_DQ<6>")
	)
	(gr_poly
		(pts
			(xy 139.904724 -276.718014) (xy 139.804648 -276.618192) (xy 139.704572 -276.718014) (xy 139.704572 -276.765766)
			(xy 139.904724 -276.765766)
		)
		(stroke
			(width 0)
			(type solid)
		)
		(fill yes)
		(layer "In4.Cu")
		(net "M_J_CPU1_SB_DQS_DN<5>")
	)
	(gr_poly
		(pts
			(xy 139.904724 -276.314662) (xy 139.904724 -276.26691) (xy 139.704572 -276.26691) (xy 139.704572 -276.314662)
			(xy 139.804648 -276.414484)
		)
		(stroke
			(width 0)
			(type solid)
		)
		(fill yes)
		(layer "In4.Cu")
		(net "M_J_CPU1_SB_DQS_DN<0>")
	)
	(gr_poly
		(pts
			(xy 139.904724 -275.098256) (xy 139.804648 -274.99818) (xy 139.704572 -275.098256) (xy 139.704572 -275.142706)
			(xy 139.904724 -275.142706)
		)
		(stroke
			(width 0)
			(type solid)
		)
		(fill yes)
		(layer "In4.Cu")
		(net "M_J_CPU1_SB_DQ<1>")
	)
	(gr_poly
		(pts
			(xy 139.904724 -274.694396) (xy 139.904724 -274.649946) (xy 139.704572 -274.649946) (xy 139.704572 -274.694396)
			(xy 139.804648 -274.794472)
		)
		(stroke
			(width 0)
			(type solid)
		)
		(fill yes)
		(layer "In4.Cu")
		(net "M_J_CPU1_SB_DQ<2>")
	)
	(gr_poly
		(pts
			(xy 139.904724 -273.478244) (xy 139.804648 -273.378168) (xy 139.704572 -273.478244) (xy 139.704572 -273.522694)
			(xy 139.904724 -273.522694)
		)
		(stroke
			(width 0)
			(type solid)
		)
		(fill yes)
		(layer "In4.Cu")
		(net "M_J_CPU1_SB_CB<1>")
	)
	(gr_poly
		(pts
			(xy 139.904724 -273.074384) (xy 139.904724 -273.029934) (xy 139.704572 -273.029934) (xy 139.704572 -273.074384)
			(xy 139.804648 -273.17446)
		)
		(stroke
			(width 0)
			(type solid)
		)
		(fill yes)
		(layer "In4.Cu")
		(net "M_J_CPU1_SB_CB<2>")
	)
	(gr_poly
		(pts
			(xy 139.904724 -271.857978) (xy 139.804648 -271.758156) (xy 139.704572 -271.857978) (xy 139.704572 -271.90573)
			(xy 139.904724 -271.90573)
		)
		(stroke
			(width 0)
			(type solid)
		)
		(fill yes)
		(layer "In4.Cu")
		(net "M_J_CPU1_SB_DQS_DN<4>")
	)
	(gr_poly
		(pts
			(xy 139.904724 -271.454626) (xy 139.904724 -271.406874) (xy 139.704572 -271.406874) (xy 139.704572 -271.454626)
			(xy 139.804648 -271.554448)
		)
		(stroke
			(width 0)
			(type solid)
		)
		(fill yes)
		(layer "In4.Cu")
		(net "M_J_CPU1_SB_DQS_DN<9>")
	)
	(gr_poly
		(pts
			(xy 139.904724 -270.23822) (xy 139.804648 -270.138144) (xy 139.704572 -270.23822) (xy 139.704572 -270.28267)
			(xy 139.904724 -270.28267)
		)
		(stroke
			(width 0)
			(type solid)
		)
		(fill yes)
		(layer "In4.Cu")
		(net "M_J_CPU1_SB_CB<5>")
	)
	(gr_poly
		(pts
			(xy 139.904724 -269.83436) (xy 139.904724 -269.78991) (xy 139.704572 -269.78991) (xy 139.704572 -269.83436)
			(xy 139.804648 -269.934436)
		)
		(stroke
			(width 0)
			(type solid)
		)
		(fill yes)
		(layer "In4.Cu")
		(net "M_J_CPU1_SB_CB<6>")
	)
	(gr_poly
		(pts
			(xy 139.904724 -266.998196) (xy 139.804648 -266.89812) (xy 139.704572 -266.998196) (xy 139.704572 -267.042646)
			(xy 139.904724 -267.042646)
		)
		(stroke
			(width 0)
			(type solid)
		)
		(fill yes)
		(layer "In4.Cu")
		(net "M_J_CPU1_SA_RSP<0>")
	)
	(gr_poly
		(pts
			(xy 139.904724 -266.594336) (xy 139.904724 -266.549886) (xy 139.704572 -266.549886) (xy 139.704572 -266.594336)
			(xy 139.804648 -266.694412)
		)
		(stroke
			(width 0)
			(type solid)
		)
		(fill yes)
		(layer "In4.Cu")
		(net "M_J_CPU1_SB_CS_N<1>")
	)
	(gr_poly
		(pts
			(xy 139.904724 -265.378184) (xy 139.804648 -265.278108) (xy 139.704572 -265.378184) (xy 139.704572 -265.422634)
			(xy 139.904724 -265.422634)
		)
		(stroke
			(width 0)
			(type solid)
		)
		(fill yes)
		(layer "In4.Cu")
		(net "M_J_CPU1_SB_PAR")
	)
	(gr_poly
		(pts
			(xy 139.904724 -263.758172) (xy 139.804648 -263.658096) (xy 139.704572 -263.758172) (xy 139.704572 -263.802622)
			(xy 139.904724 -263.802622)
		)
		(stroke
			(width 0)
			(type solid)
		)
		(fill yes)
		(layer "In4.Cu")
		(net "M_J_CPU1_SB_CA<4>")
	)
	(gr_poly
		(pts
			(xy 139.904724 -263.354312) (xy 139.904724 -263.309862) (xy 139.704572 -263.309862) (xy 139.704572 -263.354312)
			(xy 139.804648 -263.454388)
		)
		(stroke
			(width 0)
			(type solid)
		)
		(fill yes)
		(layer "In4.Cu")
		(net "M_J_CPU1_SB_CA<3>")
	)
	(gr_poly
		(pts
			(xy 139.904724 -262.13816) (xy 139.804648 -262.038084) (xy 139.704572 -262.13816) (xy 139.704572 -262.18261)
			(xy 139.904724 -262.18261)
		)
		(stroke
			(width 0)
			(type solid)
		)
		(fill yes)
		(layer "In4.Cu")
		(net "M_J_CPU1_SB_CA<0>")
	)
	(gr_poly
		(pts
			(xy 140.074904 -256.432812) (xy 140.074904 -256.38506) (xy 139.874752 -256.38506) (xy 139.874752 -256.432812)
			(xy 139.974828 -256.532634)
		)
		(stroke
			(width 0)
			(type solid)
		)
		(fill yes)
		(layer "In4.Cu")
		(net "M_J_CPU1_CLK_DN<0>")
	)
	(gr_poly
		(pts
			(xy 140.074904 -255.216406) (xy 139.974828 -255.11633) (xy 139.874752 -255.216406) (xy 139.874752 -255.260856)
			(xy 140.074904 -255.260856)
		)
		(stroke
			(width 0)
			(type solid)
		)
		(fill yes)
		(layer "In4.Cu")
		(net "M_J_CPU1_SA_CA<6>")
	)
	(gr_poly
		(pts
			(xy 140.074904 -254.812546) (xy 140.074904 -254.768096) (xy 139.874752 -254.768096) (xy 139.874752 -254.812546)
			(xy 139.974828 -254.912622)
		)
		(stroke
			(width 0)
			(type solid)
		)
		(fill yes)
		(layer "In4.Cu")
		(net "M_J_CPU1_SA_CA<5>")
	)
	(gr_poly
		(pts
			(xy 140.074904 -253.596394) (xy 139.974828 -253.496318) (xy 139.874752 -253.596394) (xy 139.874752 -253.640844)
			(xy 140.074904 -253.640844)
		)
		(stroke
			(width 0)
			(type solid)
		)
		(fill yes)
		(layer "In4.Cu")
		(net "M_J_CPU1_SA_CA<2>")
	)
	(gr_poly
		(pts
			(xy 140.074904 -253.192534) (xy 140.074904 -253.148084) (xy 139.874752 -253.148084) (xy 139.874752 -253.192534)
			(xy 139.974828 -253.29261)
		)
		(stroke
			(width 0)
			(type solid)
		)
		(fill yes)
		(layer "In4.Cu")
		(net "M_J_CPU1_SA_CA<1>")
	)
	(gr_poly
		(pts
			(xy 140.074904 -251.976382) (xy 139.974828 -251.876306) (xy 139.874752 -251.976382) (xy 139.874752 -252.020832)
			(xy 140.074904 -252.020832)
		)
		(stroke
			(width 0)
			(type solid)
		)
		(fill yes)
		(layer "In4.Cu")
		(net "M_J_CPU1_SA_CS_N<1>")
	)
	(gr_poly
		(pts
			(xy 140.074904 -250.35637) (xy 139.974828 -250.256294) (xy 139.874752 -250.35637) (xy 139.874752 -250.40082)
			(xy 140.074904 -250.40082)
		)
		(stroke
			(width 0)
			(type solid)
		)
		(fill yes)
		(layer "In4.Cu")
		(net "M_J_CPU1_ALERT_R_N")
	)
	(gr_poly
		(pts
			(xy 140.074904 -248.736358) (xy 139.974828 -248.636282) (xy 139.874752 -248.736358) (xy 139.874752 -248.780808)
			(xy 140.074904 -248.780808)
		)
		(stroke
			(width 0)
			(type solid)
		)
		(fill yes)
		(layer "In4.Cu")
		(net "M_J_CPU1_SA_CB<5>")
	)
	(gr_poly
		(pts
			(xy 140.074904 -248.332498) (xy 140.074904 -248.288048) (xy 139.874752 -248.288048) (xy 139.874752 -248.332498)
			(xy 139.974828 -248.432574)
		)
		(stroke
			(width 0)
			(type solid)
		)
		(fill yes)
		(layer "In4.Cu")
		(net "M_J_CPU1_SA_CB<6>")
	)
	(gr_poly
		(pts
			(xy 140.074904 -247.116092) (xy 139.974828 -247.01627) (xy 139.874752 -247.116092) (xy 139.874752 -247.163844)
			(xy 140.074904 -247.163844)
		)
		(stroke
			(width 0)
			(type solid)
		)
		(fill yes)
		(layer "In4.Cu")
		(net "M_J_CPU1_SA_DQS_DN<9>")
	)
	(gr_poly
		(pts
			(xy 140.074904 -246.71274) (xy 140.074904 -246.664988) (xy 139.874752 -246.664988) (xy 139.874752 -246.71274)
			(xy 139.974828 -246.812562)
		)
		(stroke
			(width 0)
			(type solid)
		)
		(fill yes)
		(layer "In4.Cu")
		(net "M_J_CPU1_SA_DQS_DN<4>")
	)
	(gr_poly
		(pts
			(xy 140.074904 -245.496334) (xy 139.974828 -245.396258) (xy 139.874752 -245.496334) (xy 139.874752 -245.540784)
			(xy 140.074904 -245.540784)
		)
		(stroke
			(width 0)
			(type solid)
		)
		(fill yes)
		(layer "In4.Cu")
		(net "M_J_CPU1_SA_CB<1>")
	)
	(gr_poly
		(pts
			(xy 140.074904 -245.092474) (xy 140.074904 -245.048024) (xy 139.874752 -245.048024) (xy 139.874752 -245.092474)
			(xy 139.974828 -245.19255)
		)
		(stroke
			(width 0)
			(type solid)
		)
		(fill yes)
		(layer "In4.Cu")
		(net "M_J_CPU1_SA_CB<2>")
	)
	(gr_poly
		(pts
			(xy 140.074904 -243.876322) (xy 139.974828 -243.776246) (xy 139.874752 -243.876322) (xy 139.874752 -243.920772)
			(xy 140.074904 -243.920772)
		)
		(stroke
			(width 0)
			(type solid)
		)
		(fill yes)
		(layer "In4.Cu")
		(net "M_J_CPU1_SA_DQ<29>")
	)
	(gr_poly
		(pts
			(xy 140.074904 -243.472462) (xy 140.074904 -243.428012) (xy 139.874752 -243.428012) (xy 139.874752 -243.472462)
			(xy 139.974828 -243.572538)
		)
		(stroke
			(width 0)
			(type solid)
		)
		(fill yes)
		(layer "In4.Cu")
		(net "M_J_CPU1_SA_DQ<30>")
	)
	(gr_poly
		(pts
			(xy 140.074904 -242.256056) (xy 139.974828 -242.156234) (xy 139.874752 -242.256056) (xy 139.874752 -242.303808)
			(xy 140.074904 -242.303808)
		)
		(stroke
			(width 0)
			(type solid)
		)
		(fill yes)
		(layer "In4.Cu")
		(net "M_J_CPU1_SA_DQS_DN<8>")
	)
	(gr_poly
		(pts
			(xy 140.074904 -241.852704) (xy 140.074904 -241.804952) (xy 139.874752 -241.804952) (xy 139.874752 -241.852704)
			(xy 139.974828 -241.952526)
		)
		(stroke
			(width 0)
			(type solid)
		)
		(fill yes)
		(layer "In4.Cu")
		(net "M_J_CPU1_SA_DQS_DN<3>")
	)
	(gr_poly
		(pts
			(xy 140.074904 -240.636298) (xy 139.974828 -240.536222) (xy 139.874752 -240.636298) (xy 139.874752 -240.680748)
			(xy 140.074904 -240.680748)
		)
		(stroke
			(width 0)
			(type solid)
		)
		(fill yes)
		(layer "In4.Cu")
		(net "M_J_CPU1_SA_DQ<25>")
	)
	(gr_poly
		(pts
			(xy 140.074904 -240.232438) (xy 140.074904 -240.187988) (xy 139.874752 -240.187988) (xy 139.874752 -240.232438)
			(xy 139.974828 -240.332514)
		)
		(stroke
			(width 0)
			(type solid)
		)
		(fill yes)
		(layer "In4.Cu")
		(net "M_J_CPU1_SA_DQ<26>")
	)
	(gr_poly
		(pts
			(xy 140.074904 -239.016286) (xy 139.974828 -238.91621) (xy 139.874752 -239.016286) (xy 139.874752 -239.060736)
			(xy 140.074904 -239.060736)
		)
		(stroke
			(width 0)
			(type solid)
		)
		(fill yes)
		(layer "In4.Cu")
		(net "M_J_CPU1_SA_DQ<21>")
	)
	(gr_poly
		(pts
			(xy 140.074904 -238.612426) (xy 140.074904 -238.567976) (xy 139.874752 -238.567976) (xy 139.874752 -238.612426)
			(xy 139.974828 -238.712502)
		)
		(stroke
			(width 0)
			(type solid)
		)
		(fill yes)
		(layer "In4.Cu")
		(net "M_J_CPU1_SA_DQ<22>")
	)
	(gr_poly
		(pts
			(xy 140.074904 -237.39602) (xy 139.974828 -237.296198) (xy 139.874752 -237.39602) (xy 139.874752 -237.443772)
			(xy 140.074904 -237.443772)
		)
		(stroke
			(width 0)
			(type solid)
		)
		(fill yes)
		(layer "In4.Cu")
		(net "M_J_CPU1_SA_DQS_DN<7>")
	)
	(gr_poly
		(pts
			(xy 140.074904 -236.992668) (xy 140.074904 -236.944916) (xy 139.874752 -236.944916) (xy 139.874752 -236.992668)
			(xy 139.974828 -237.09249)
		)
		(stroke
			(width 0)
			(type solid)
		)
		(fill yes)
		(layer "In4.Cu")
		(net "M_J_CPU1_SA_DQS_DN<2>")
	)
	(gr_poly
		(pts
			(xy 140.074904 -235.776262) (xy 139.974828 -235.676186) (xy 139.874752 -235.776262) (xy 139.874752 -235.820712)
			(xy 140.074904 -235.820712)
		)
		(stroke
			(width 0)
			(type solid)
		)
		(fill yes)
		(layer "In4.Cu")
		(net "M_J_CPU1_SA_DQ<17>")
	)
	(gr_poly
		(pts
			(xy 140.074904 -235.372402) (xy 140.074904 -235.327952) (xy 139.874752 -235.327952) (xy 139.874752 -235.372402)
			(xy 139.974828 -235.472478)
		)
		(stroke
			(width 0)
			(type solid)
		)
		(fill yes)
		(layer "In4.Cu")
		(net "M_J_CPU1_SA_DQ<18>")
	)
	(gr_poly
		(pts
			(xy 140.074904 -234.15625) (xy 139.974828 -234.056174) (xy 139.874752 -234.15625) (xy 139.874752 -234.2007)
			(xy 140.074904 -234.2007)
		)
		(stroke
			(width 0)
			(type solid)
		)
		(fill yes)
		(layer "In4.Cu")
		(net "M_J_CPU1_SA_DQ<13>")
	)
	(gr_poly
		(pts
			(xy 140.074904 -233.75239) (xy 140.074904 -233.70794) (xy 139.874752 -233.70794) (xy 139.874752 -233.75239)
			(xy 139.974828 -233.852466)
		)
		(stroke
			(width 0)
			(type solid)
		)
		(fill yes)
		(layer "In4.Cu")
		(net "M_J_CPU1_SA_DQ<14>")
	)
	(gr_poly
		(pts
			(xy 140.074904 -232.535984) (xy 139.974828 -232.436162) (xy 139.874752 -232.535984) (xy 139.874752 -232.583736)
			(xy 140.074904 -232.583736)
		)
		(stroke
			(width 0)
			(type solid)
		)
		(fill yes)
		(layer "In4.Cu")
		(net "M_J_CPU1_SA_DQS_DN<6>")
	)
	(gr_poly
		(pts
			(xy 140.074904 -232.132632) (xy 140.074904 -232.08488) (xy 139.874752 -232.08488) (xy 139.874752 -232.132632)
			(xy 139.974828 -232.232454)
		)
		(stroke
			(width 0)
			(type solid)
		)
		(fill yes)
		(layer "In4.Cu")
		(net "M_J_CPU1_SA_DQS_DN<1>")
	)
	(gr_poly
		(pts
			(xy 140.074904 -230.916226) (xy 139.974828 -230.81615) (xy 139.874752 -230.916226) (xy 139.874752 -230.960676)
			(xy 140.074904 -230.960676)
		)
		(stroke
			(width 0)
			(type solid)
		)
		(fill yes)
		(layer "In4.Cu")
		(net "M_J_CPU1_SA_DQ<9>")
	)
	(gr_poly
		(pts
			(xy 140.074904 -230.51262) (xy 140.074904 -230.46817) (xy 139.874752 -230.46817) (xy 139.874752 -230.51262)
			(xy 139.974828 -230.612696)
		)
		(stroke
			(width 0)
			(type solid)
		)
		(fill yes)
		(layer "In4.Cu")
		(net "M_J_CPU1_SA_DQ<10>")
	)
	(gr_poly
		(pts
			(xy 140.074904 -229.296214) (xy 139.974828 -229.196138) (xy 139.874752 -229.296214) (xy 139.874752 -229.340664)
			(xy 140.074904 -229.340664)
		)
		(stroke
			(width 0)
			(type solid)
		)
		(fill yes)
		(layer "In4.Cu")
		(net "M_J_CPU1_SA_DQ<5>")
	)
	(gr_poly
		(pts
			(xy 140.074904 -228.892608) (xy 140.074904 -228.848158) (xy 139.874752 -228.848158) (xy 139.874752 -228.892608)
			(xy 139.974828 -228.992684)
		)
		(stroke
			(width 0)
			(type solid)
		)
		(fill yes)
		(layer "In4.Cu")
		(net "M_J_CPU1_SA_DQ<6>")
	)
	(gr_poly
		(pts
			(xy 140.074904 -227.676202) (xy 139.974828 -227.57638) (xy 139.874752 -227.676202) (xy 139.874752 -227.723954)
			(xy 140.074904 -227.723954)
		)
		(stroke
			(width 0)
			(type solid)
		)
		(fill yes)
		(layer "In4.Cu")
		(net "M_J_CPU1_SA_DQS_DN<5>")
	)
	(gr_poly
		(pts
			(xy 140.074904 -227.27285) (xy 140.074904 -227.225098) (xy 139.874752 -227.225098) (xy 139.874752 -227.27285)
			(xy 139.974828 -227.372672)
		)
		(stroke
			(width 0)
			(type solid)
		)
		(fill yes)
		(layer "In4.Cu")
		(net "M_J_CPU1_SA_DQS_DN<0>")
	)
	(gr_poly
		(pts
			(xy 140.074904 -226.056444) (xy 139.974828 -225.956368) (xy 139.874752 -226.056444) (xy 139.874752 -226.100894)
			(xy 140.074904 -226.100894)
		)
		(stroke
			(width 0)
			(type solid)
		)
		(fill yes)
		(layer "In4.Cu")
		(net "M_J_CPU1_SA_DQ<1>")
	)
	(gr_poly
		(pts
			(xy 140.074904 -225.652584) (xy 140.074904 -225.608134) (xy 139.874752 -225.608134) (xy 139.874752 -225.652584)
			(xy 139.974828 -225.75266)
		)
		(stroke
			(width 0)
			(type solid)
		)
		(fill yes)
		(layer "In4.Cu")
		(net "M_J_CPU1_SA_DQ<2>")
	)
	(gr_poly
		(pts
			(xy 140.374878 -293.32428) (xy 140.374878 -293.27983) (xy 140.174726 -293.27983) (xy 140.174726 -293.32428)
			(xy 140.274802 -293.424356)
		)
		(stroke
			(width 0)
			(type solid)
		)
		(fill yes)
		(layer "In4.Cu")
		(net "M_J_CPU1_SB_DQ<31>")
	)
	(gr_poly
		(pts
			(xy 140.374878 -292.108128) (xy 140.274802 -292.008052) (xy 140.174726 -292.108128) (xy 140.174726 -292.152578)
			(xy 140.374878 -292.152578)
		)
		(stroke
			(width 0)
			(type solid)
		)
		(fill yes)
		(layer "In4.Cu")
		(net "M_J_CPU1_SB_DQ<28>")
	)
	(gr_poly
		(pts
			(xy 140.374878 -291.704522) (xy 140.374878 -291.65677) (xy 140.174726 -291.65677) (xy 140.174726 -291.704522)
			(xy 140.274802 -291.804344)
		)
		(stroke
			(width 0)
			(type solid)
		)
		(fill yes)
		(layer "In4.Cu")
		(net "M_J_CPU1_SB_DQS_DP<8>")
	)
	(gr_poly
		(pts
			(xy 140.374878 -290.487862) (xy 140.274802 -290.38804) (xy 140.174726 -290.487862) (xy 140.174726 -290.535614)
			(xy 140.374878 -290.535614)
		)
		(stroke
			(width 0)
			(type solid)
		)
		(fill yes)
		(layer "In4.Cu")
		(net "M_J_CPU1_SB_DQS_DP<3>")
	)
	(gr_poly
		(pts
			(xy 140.374878 -290.084256) (xy 140.374878 -290.039806) (xy 140.174726 -290.039806) (xy 140.174726 -290.084256)
			(xy 140.274802 -290.184332)
		)
		(stroke
			(width 0)
			(type solid)
		)
		(fill yes)
		(layer "In4.Cu")
		(net "M_J_CPU1_SB_DQ<27>")
	)
	(gr_poly
		(pts
			(xy 140.374878 -288.868104) (xy 140.274802 -288.768028) (xy 140.174726 -288.868104) (xy 140.174726 -288.912554)
			(xy 140.374878 -288.912554)
		)
		(stroke
			(width 0)
			(type solid)
		)
		(fill yes)
		(layer "In4.Cu")
		(net "M_J_CPU1_SB_DQ<24>")
	)
	(gr_poly
		(pts
			(xy 140.374878 -288.464498) (xy 140.374878 -288.420048) (xy 140.174726 -288.420048) (xy 140.174726 -288.464498)
			(xy 140.274802 -288.564574)
		)
		(stroke
			(width 0)
			(type solid)
		)
		(fill yes)
		(layer "In4.Cu")
		(net "M_J_CPU1_SB_DQ<23>")
	)
	(gr_poly
		(pts
			(xy 140.374878 -287.248092) (xy 140.274802 -287.148016) (xy 140.174726 -287.248092) (xy 140.174726 -287.292542)
			(xy 140.374878 -287.292542)
		)
		(stroke
			(width 0)
			(type solid)
		)
		(fill yes)
		(layer "In4.Cu")
		(net "M_J_CPU1_SB_DQ<20>")
	)
	(gr_poly
		(pts
			(xy 140.374878 -286.844486) (xy 140.374878 -286.796734) (xy 140.174726 -286.796734) (xy 140.174726 -286.844486)
			(xy 140.274802 -286.944562)
		)
		(stroke
			(width 0)
			(type solid)
		)
		(fill yes)
		(layer "In4.Cu")
		(net "M_J_CPU1_SB_DQS_DP<7>")
	)
	(gr_poly
		(pts
			(xy 140.374878 -285.62808) (xy 140.274802 -285.528258) (xy 140.174726 -285.62808) (xy 140.174726 -285.675832)
			(xy 140.374878 -285.675832)
		)
		(stroke
			(width 0)
			(type solid)
		)
		(fill yes)
		(layer "In4.Cu")
		(net "M_J_CPU1_SB_DQS_DP<2>")
	)
	(gr_poly
		(pts
			(xy 140.374878 -285.224474) (xy 140.374878 -285.180024) (xy 140.174726 -285.180024) (xy 140.174726 -285.224474)
			(xy 140.274802 -285.32455)
		)
		(stroke
			(width 0)
			(type solid)
		)
		(fill yes)
		(layer "In4.Cu")
		(net "M_J_CPU1_SB_DQ<19>")
	)
	(gr_poly
		(pts
			(xy 140.374878 -284.008322) (xy 140.274802 -283.908246) (xy 140.174726 -284.008322) (xy 140.174726 -284.052772)
			(xy 140.374878 -284.052772)
		)
		(stroke
			(width 0)
			(type solid)
		)
		(fill yes)
		(layer "In4.Cu")
		(net "M_J_CPU1_SB_DQ<16>")
	)
	(gr_poly
		(pts
			(xy 140.374878 -283.604462) (xy 140.374878 -283.560012) (xy 140.174726 -283.560012) (xy 140.174726 -283.604462)
			(xy 140.274802 -283.704538)
		)
		(stroke
			(width 0)
			(type solid)
		)
		(fill yes)
		(layer "In4.Cu")
		(net "M_J_CPU1_SB_DQ<15>")
	)
	(gr_poly
		(pts
			(xy 140.374878 -282.38831) (xy 140.274802 -282.288234) (xy 140.174726 -282.38831) (xy 140.174726 -282.43276)
			(xy 140.374878 -282.43276)
		)
		(stroke
			(width 0)
			(type solid)
		)
		(fill yes)
		(layer "In4.Cu")
		(net "M_J_CPU1_SB_DQ<12>")
	)
	(gr_poly
		(pts
			(xy 140.374878 -281.984704) (xy 140.374878 -281.936952) (xy 140.174726 -281.936952) (xy 140.174726 -281.984704)
			(xy 140.274802 -282.084526)
		)
		(stroke
			(width 0)
			(type solid)
		)
		(fill yes)
		(layer "In4.Cu")
		(net "M_J_CPU1_SB_DQS_DP<6>")
	)
	(gr_poly
		(pts
			(xy 140.374878 -280.768044) (xy 140.274802 -280.668222) (xy 140.174726 -280.768044) (xy 140.174726 -280.815796)
			(xy 140.374878 -280.815796)
		)
		(stroke
			(width 0)
			(type solid)
		)
		(fill yes)
		(layer "In4.Cu")
		(net "M_J_CPU1_SB_DQS_DP<1>")
	)
	(gr_poly
		(pts
			(xy 140.374878 -280.364438) (xy 140.374878 -280.319988) (xy 140.174726 -280.319988) (xy 140.174726 -280.364438)
			(xy 140.274802 -280.464514)
		)
		(stroke
			(width 0)
			(type solid)
		)
		(fill yes)
		(layer "In4.Cu")
		(net "M_J_CPU1_SB_DQ<11>")
	)
	(gr_poly
		(pts
			(xy 140.374878 -279.148286) (xy 140.274802 -279.04821) (xy 140.174726 -279.148286) (xy 140.174726 -279.192736)
			(xy 140.374878 -279.192736)
		)
		(stroke
			(width 0)
			(type solid)
		)
		(fill yes)
		(layer "In4.Cu")
		(net "M_J_CPU1_SB_DQ<8>")
	)
	(gr_poly
		(pts
			(xy 140.374878 -278.744426) (xy 140.374878 -278.699976) (xy 140.174726 -278.699976) (xy 140.174726 -278.744426)
			(xy 140.274802 -278.844502)
		)
		(stroke
			(width 0)
			(type solid)
		)
		(fill yes)
		(layer "In4.Cu")
		(net "M_J_CPU1_SB_DQ<7>")
	)
	(gr_poly
		(pts
			(xy 140.374878 -277.528274) (xy 140.274802 -277.428198) (xy 140.174726 -277.528274) (xy 140.174726 -277.572724)
			(xy 140.374878 -277.572724)
		)
		(stroke
			(width 0)
			(type solid)
		)
		(fill yes)
		(layer "In4.Cu")
		(net "M_J_CPU1_SB_DQ<4>")
	)
	(gr_poly
		(pts
			(xy 140.374878 -277.124668) (xy 140.374878 -277.076916) (xy 140.174726 -277.076916) (xy 140.174726 -277.124668)
			(xy 140.274802 -277.22449)
		)
		(stroke
			(width 0)
			(type solid)
		)
		(fill yes)
		(layer "In4.Cu")
		(net "M_J_CPU1_SB_DQS_DP<5>")
	)
	(gr_poly
		(pts
			(xy 140.374878 -275.908008) (xy 140.274802 -275.808186) (xy 140.174726 -275.908008) (xy 140.174726 -275.95576)
			(xy 140.374878 -275.95576)
		)
		(stroke
			(width 0)
			(type solid)
		)
		(fill yes)
		(layer "In4.Cu")
		(net "M_J_CPU1_SB_DQS_DP<0>")
	)
	(gr_poly
		(pts
			(xy 140.374878 -275.504402) (xy 140.374878 -275.459952) (xy 140.174726 -275.459952) (xy 140.174726 -275.504402)
			(xy 140.274802 -275.604478)
		)
		(stroke
			(width 0)
			(type solid)
		)
		(fill yes)
		(layer "In4.Cu")
		(net "M_J_CPU1_SB_DQ<3>")
	)
	(gr_poly
		(pts
			(xy 140.374878 -274.28825) (xy 140.274802 -274.188174) (xy 140.174726 -274.28825) (xy 140.174726 -274.3327)
			(xy 140.374878 -274.3327)
		)
		(stroke
			(width 0)
			(type solid)
		)
		(fill yes)
		(layer "In4.Cu")
		(net "M_J_CPU1_SB_DQ<0>")
	)
	(gr_poly
		(pts
			(xy 140.374878 -273.88439) (xy 140.374878 -273.83994) (xy 140.174726 -273.83994) (xy 140.174726 -273.88439)
			(xy 140.274802 -273.984466)
		)
		(stroke
			(width 0)
			(type solid)
		)
		(fill yes)
		(layer "In4.Cu")
		(net "M_J_CPU1_SB_CB<3>")
	)
	(gr_poly
		(pts
			(xy 140.374878 -272.668238) (xy 140.274802 -272.568162) (xy 140.174726 -272.668238) (xy 140.174726 -272.712688)
			(xy 140.374878 -272.712688)
		)
		(stroke
			(width 0)
			(type solid)
		)
		(fill yes)
		(layer "In4.Cu")
		(net "M_J_CPU1_SB_CB<0>")
	)
	(gr_poly
		(pts
			(xy 140.374878 -272.264632) (xy 140.374878 -272.21688) (xy 140.174726 -272.21688) (xy 140.174726 -272.264632)
			(xy 140.274802 -272.364454)
		)
		(stroke
			(width 0)
			(type solid)
		)
		(fill yes)
		(layer "In4.Cu")
		(net "M_J_CPU1_SB_DQS_DP<4>")
	)
	(gr_poly
		(pts
			(xy 140.374878 -271.047972) (xy 140.274802 -270.94815) (xy 140.174726 -271.047972) (xy 140.174726 -271.095724)
			(xy 140.374878 -271.095724)
		)
		(stroke
			(width 0)
			(type solid)
		)
		(fill yes)
		(layer "In4.Cu")
		(net "M_J_CPU1_SB_DQS_DP<9>")
	)
	(gr_poly
		(pts
			(xy 140.374878 -270.644366) (xy 140.374878 -270.599916) (xy 140.174726 -270.599916) (xy 140.174726 -270.644366)
			(xy 140.274802 -270.744442)
		)
		(stroke
			(width 0)
			(type solid)
		)
		(fill yes)
		(layer "In4.Cu")
		(net "M_J_CPU1_SB_CB<7>")
	)
	(gr_poly
		(pts
			(xy 140.374878 -269.428214) (xy 140.274802 -269.328138) (xy 140.174726 -269.428214) (xy 140.174726 -269.472664)
			(xy 140.374878 -269.472664)
		)
		(stroke
			(width 0)
			(type solid)
		)
		(fill yes)
		(layer "In4.Cu")
		(net "M_J_CPU1_SB_CB<4>")
	)
	(gr_poly
		(pts
			(xy 140.374878 -267.808202) (xy 140.274802 -267.708126) (xy 140.174726 -267.808202) (xy 140.174726 -267.852652)
			(xy 140.374878 -267.852652)
		)
		(stroke
			(width 0)
			(type solid)
		)
		(fill yes)
		(layer "In4.Cu")
		(net "M_J_CPU1_SB_RSP<0>")
	)
	(gr_poly
		(pts
			(xy 140.374878 -265.78433) (xy 140.374878 -265.73988) (xy 140.174726 -265.73988) (xy 140.174726 -265.78433)
			(xy 140.274802 -265.884406)
		)
		(stroke
			(width 0)
			(type solid)
		)
		(fill yes)
		(layer "In4.Cu")
		(net "M_J_CPU1_SB_CS_N<0>")
	)
	(gr_poly
		(pts
			(xy 140.374878 -264.568178) (xy 140.274802 -264.468102) (xy 140.174726 -264.568178) (xy 140.174726 -264.612628)
			(xy 140.374878 -264.612628)
		)
		(stroke
			(width 0)
			(type solid)
		)
		(fill yes)
		(layer "In4.Cu")
		(net "M_J_CPU1_SB_CA<6>")
	)
	(gr_poly
		(pts
			(xy 140.374878 -264.164318) (xy 140.374878 -264.119868) (xy 140.174726 -264.119868) (xy 140.174726 -264.164318)
			(xy 140.274802 -264.264394)
		)
		(stroke
			(width 0)
			(type solid)
		)
		(fill yes)
		(layer "In4.Cu")
		(net "M_J_CPU1_SB_CA<5>")
	)
	(gr_poly
		(pts
			(xy 140.374878 -262.948166) (xy 140.274802 -262.84809) (xy 140.174726 -262.948166) (xy 140.174726 -262.992616)
			(xy 140.374878 -262.992616)
		)
		(stroke
			(width 0)
			(type solid)
		)
		(fill yes)
		(layer "In4.Cu")
		(net "M_J_CPU1_SB_CA<2>")
	)
	(gr_poly
		(pts
			(xy 140.374878 -262.544306) (xy 140.374878 -262.499856) (xy 140.174726 -262.499856) (xy 140.174726 -262.544306)
			(xy 140.274802 -262.644382)
		)
		(stroke
			(width 0)
			(type solid)
		)
		(fill yes)
		(layer "In4.Cu")
		(net "M_J_CPU1_SB_CA<1>")
	)
	(gr_poly
		(pts
			(xy 140.464032 -224.695766) (xy 140.425424 -224.673414) (xy 140.289026 -224.70999) (xy 140.325602 -224.846642)
			(xy 140.363956 -224.868994)
		)
		(stroke
			(width 0)
			(type solid)
		)
		(fill yes)
		(layer "In4.Cu")
		(net "M_J_CPU1_SA_DQ<0>")
	)
	(gr_poly
		(pts
			(xy 140.544804 -256.026158) (xy 140.444728 -255.926336) (xy 140.344652 -256.026158) (xy 140.344652 -256.07391)
			(xy 140.544804 -256.07391)
		)
		(stroke
			(width 0)
			(type solid)
		)
		(fill yes)
		(layer "In4.Cu")
		(net "M_J_CPU1_CLK_DP<0>")
	)
	(gr_poly
		(pts
			(xy 140.544804 -255.622552) (xy 140.544804 -255.578102) (xy 140.344652 -255.578102) (xy 140.344652 -255.622552)
			(xy 140.444728 -255.722628)
		)
		(stroke
			(width 0)
			(type solid)
		)
		(fill yes)
		(layer "In4.Cu")
		(net "M_J_CPU1_SA_PAR")
	)
	(gr_poly
		(pts
			(xy 140.544804 -254.4064) (xy 140.444728 -254.306324) (xy 140.344652 -254.4064) (xy 140.344652 -254.45085)
			(xy 140.544804 -254.45085)
		)
		(stroke
			(width 0)
			(type solid)
		)
		(fill yes)
		(layer "In4.Cu")
		(net "M_J_CPU1_SA_CA<4>")
	)
	(gr_poly
		(pts
			(xy 140.544804 -254.00254) (xy 140.544804 -253.95809) (xy 140.344652 -253.95809) (xy 140.344652 -254.00254)
			(xy 140.444728 -254.102616)
		)
		(stroke
			(width 0)
			(type solid)
		)
		(fill yes)
		(layer "In4.Cu")
		(net "M_J_CPU1_SA_CA<3>")
	)
	(gr_poly
		(pts
			(xy 140.544804 -252.786388) (xy 140.444728 -252.686312) (xy 140.344652 -252.786388) (xy 140.344652 -252.830838)
			(xy 140.544804 -252.830838)
		)
		(stroke
			(width 0)
			(type solid)
		)
		(fill yes)
		(layer "In4.Cu")
		(net "M_J_CPU1_SA_CA<0>")
	)
	(gr_poly
		(pts
			(xy 140.544804 -251.166376) (xy 140.444728 -251.0663) (xy 140.344652 -251.166376) (xy 140.344652 -251.210826)
			(xy 140.544804 -251.210826)
		)
		(stroke
			(width 0)
			(type solid)
		)
		(fill yes)
		(layer "In4.Cu")
		(net "M_J_CPU1_SA_CS_N<0>")
	)
	(gr_poly
		(pts
			(xy 140.544804 -250.762516) (xy 140.544804 -250.718066) (xy 140.344652 -250.718066) (xy 140.344652 -250.762516)
			(xy 140.444728 -250.862592)
		)
		(stroke
			(width 0)
			(type solid)
		)
		(fill yes)
		(layer "In4.Cu")
		(net "M_J_CPU1_RESET_N")
	)
	(gr_poly
		(pts
			(xy 140.544804 -249.142504) (xy 140.544804 -249.098054) (xy 140.344652 -249.098054) (xy 140.344652 -249.142504)
			(xy 140.444728 -249.24258)
		)
		(stroke
			(width 0)
			(type solid)
		)
		(fill yes)
		(layer "In4.Cu")
		(net "M_J_CPU1_SA_CB<7>")
	)
	(gr_poly
		(pts
			(xy 140.544804 -247.926352) (xy 140.444728 -247.826276) (xy 140.344652 -247.926352) (xy 140.344652 -247.970802)
			(xy 140.544804 -247.970802)
		)
		(stroke
			(width 0)
			(type solid)
		)
		(fill yes)
		(layer "In4.Cu")
		(net "M_J_CPU1_SA_CB<4>")
	)
	(gr_poly
		(pts
			(xy 140.544804 -247.522746) (xy 140.544804 -247.474994) (xy 140.344652 -247.474994) (xy 140.344652 -247.522746)
			(xy 140.444728 -247.622568)
		)
		(stroke
			(width 0)
			(type solid)
		)
		(fill yes)
		(layer "In4.Cu")
		(net "M_J_CPU1_SA_DQS_DP<9>")
	)
	(gr_poly
		(pts
			(xy 140.544804 -246.306086) (xy 140.444728 -246.206264) (xy 140.344652 -246.306086) (xy 140.344652 -246.353838)
			(xy 140.544804 -246.353838)
		)
		(stroke
			(width 0)
			(type solid)
		)
		(fill yes)
		(layer "In4.Cu")
		(net "M_J_CPU1_SA_DQS_DP<4>")
	)
	(gr_poly
		(pts
			(xy 140.544804 -245.90248) (xy 140.544804 -245.85803) (xy 140.344652 -245.85803) (xy 140.344652 -245.90248)
			(xy 140.444728 -246.002556)
		)
		(stroke
			(width 0)
			(type solid)
		)
		(fill yes)
		(layer "In4.Cu")
		(net "M_J_CPU1_SA_CB<3>")
	)
	(gr_poly
		(pts
			(xy 140.544804 -244.686328) (xy 140.444728 -244.586252) (xy 140.344652 -244.686328) (xy 140.344652 -244.730778)
			(xy 140.544804 -244.730778)
		)
		(stroke
			(width 0)
			(type solid)
		)
		(fill yes)
		(layer "In4.Cu")
		(net "M_J_CPU1_SA_CB<0>")
	)
	(gr_poly
		(pts
			(xy 140.544804 -244.282468) (xy 140.544804 -244.238018) (xy 140.344652 -244.238018) (xy 140.344652 -244.282468)
			(xy 140.444728 -244.382544)
		)
		(stroke
			(width 0)
			(type solid)
		)
		(fill yes)
		(layer "In4.Cu")
		(net "M_J_CPU1_SA_DQ<31>")
	)
	(gr_poly
		(pts
			(xy 140.544804 -243.066316) (xy 140.444728 -242.96624) (xy 140.344652 -243.066316) (xy 140.344652 -243.110766)
			(xy 140.544804 -243.110766)
		)
		(stroke
			(width 0)
			(type solid)
		)
		(fill yes)
		(layer "In4.Cu")
		(net "M_J_CPU1_SA_DQ<28>")
	)
	(gr_poly
		(pts
			(xy 140.544804 -242.66271) (xy 140.544804 -242.614958) (xy 140.344652 -242.614958) (xy 140.344652 -242.66271)
			(xy 140.444728 -242.762532)
		)
		(stroke
			(width 0)
			(type solid)
		)
		(fill yes)
		(layer "In4.Cu")
		(net "M_J_CPU1_SA_DQS_DP<8>")
	)
	(gr_poly
		(pts
			(xy 140.544804 -241.44605) (xy 140.444728 -241.346228) (xy 140.344652 -241.44605) (xy 140.344652 -241.493802)
			(xy 140.544804 -241.493802)
		)
		(stroke
			(width 0)
			(type solid)
		)
		(fill yes)
		(layer "In4.Cu")
		(net "M_J_CPU1_SA_DQS_DP<3>")
	)
	(gr_poly
		(pts
			(xy 140.544804 -241.042444) (xy 140.544804 -240.997994) (xy 140.344652 -240.997994) (xy 140.344652 -241.042444)
			(xy 140.444728 -241.14252)
		)
		(stroke
			(width 0)
			(type solid)
		)
		(fill yes)
		(layer "In4.Cu")
		(net "M_J_CPU1_SA_DQ<27>")
	)
	(gr_poly
		(pts
			(xy 140.544804 -239.826292) (xy 140.444728 -239.726216) (xy 140.344652 -239.826292) (xy 140.344652 -239.870742)
			(xy 140.544804 -239.870742)
		)
		(stroke
			(width 0)
			(type solid)
		)
		(fill yes)
		(layer "In4.Cu")
		(net "M_J_CPU1_SA_DQ<24>")
	)
	(gr_poly
		(pts
			(xy 140.544804 -239.422432) (xy 140.544804 -239.377982) (xy 140.344652 -239.377982) (xy 140.344652 -239.422432)
			(xy 140.444728 -239.522508)
		)
		(stroke
			(width 0)
			(type solid)
		)
		(fill yes)
		(layer "In4.Cu")
		(net "M_J_CPU1_SA_DQ<23>")
	)
	(gr_poly
		(pts
			(xy 140.544804 -238.20628) (xy 140.444728 -238.106204) (xy 140.344652 -238.20628) (xy 140.344652 -238.25073)
			(xy 140.544804 -238.25073)
		)
		(stroke
			(width 0)
			(type solid)
		)
		(fill yes)
		(layer "In4.Cu")
		(net "M_J_CPU1_SA_DQ<20>")
	)
	(gr_poly
		(pts
			(xy 140.544804 -237.802674) (xy 140.544804 -237.754922) (xy 140.344652 -237.754922) (xy 140.344652 -237.802674)
			(xy 140.444728 -237.902496)
		)
		(stroke
			(width 0)
			(type solid)
		)
		(fill yes)
		(layer "In4.Cu")
		(net "M_J_CPU1_SA_DQS_DP<7>")
	)
	(gr_poly
		(pts
			(xy 140.544804 -236.586014) (xy 140.444728 -236.486192) (xy 140.344652 -236.586014) (xy 140.344652 -236.633766)
			(xy 140.544804 -236.633766)
		)
		(stroke
			(width 0)
			(type solid)
		)
		(fill yes)
		(layer "In4.Cu")
		(net "M_J_CPU1_SA_DQS_DP<2>")
	)
	(gr_poly
		(pts
			(xy 140.544804 -236.182408) (xy 140.544804 -236.137958) (xy 140.344652 -236.137958) (xy 140.344652 -236.182408)
			(xy 140.444728 -236.282484)
		)
		(stroke
			(width 0)
			(type solid)
		)
		(fill yes)
		(layer "In4.Cu")
		(net "M_J_CPU1_SA_DQ<19>")
	)
	(gr_poly
		(pts
			(xy 140.544804 -234.966256) (xy 140.444728 -234.86618) (xy 140.344652 -234.966256) (xy 140.344652 -235.010706)
			(xy 140.544804 -235.010706)
		)
		(stroke
			(width 0)
			(type solid)
		)
		(fill yes)
		(layer "In4.Cu")
		(net "M_J_CPU1_SA_DQ<16>")
	)
	(gr_poly
		(pts
			(xy 140.544804 -234.562396) (xy 140.544804 -234.517946) (xy 140.344652 -234.517946) (xy 140.344652 -234.562396)
			(xy 140.444728 -234.662472)
		)
		(stroke
			(width 0)
			(type solid)
		)
		(fill yes)
		(layer "In4.Cu")
		(net "M_J_CPU1_SA_DQ<15>")
	)
	(gr_poly
		(pts
			(xy 140.544804 -233.346244) (xy 140.444728 -233.246168) (xy 140.344652 -233.346244) (xy 140.344652 -233.390694)
			(xy 140.544804 -233.390694)
		)
		(stroke
			(width 0)
			(type solid)
		)
		(fill yes)
		(layer "In4.Cu")
		(net "M_J_CPU1_SA_DQ<12>")
	)
	(gr_poly
		(pts
			(xy 140.544804 -232.942638) (xy 140.544804 -232.894886) (xy 140.344652 -232.894886) (xy 140.344652 -232.942638)
			(xy 140.444728 -233.04246)
		)
		(stroke
			(width 0)
			(type solid)
		)
		(fill yes)
		(layer "In4.Cu")
		(net "M_J_CPU1_SA_DQS_DP<6>")
	)
	(gr_poly
		(pts
			(xy 140.544804 -231.725978) (xy 140.444728 -231.626156) (xy 140.344652 -231.725978) (xy 140.344652 -231.77373)
			(xy 140.544804 -231.77373)
		)
		(stroke
			(width 0)
			(type solid)
		)
		(fill yes)
		(layer "In4.Cu")
		(net "M_J_CPU1_SA_DQS_DP<1>")
	)
	(gr_poly
		(pts
			(xy 140.544804 -231.322626) (xy 140.544804 -231.278176) (xy 140.344652 -231.278176) (xy 140.344652 -231.322626)
			(xy 140.444728 -231.422702)
		)
		(stroke
			(width 0)
			(type solid)
		)
		(fill yes)
		(layer "In4.Cu")
		(net "M_J_CPU1_SA_DQ<11>")
	)
	(gr_poly
		(pts
			(xy 140.544804 -230.10622) (xy 140.444728 -230.006144) (xy 140.344652 -230.10622) (xy 140.344652 -230.15067)
			(xy 140.544804 -230.15067)
		)
		(stroke
			(width 0)
			(type solid)
		)
		(fill yes)
		(layer "In4.Cu")
		(net "M_J_CPU1_SA_DQ<8>")
	)
	(gr_poly
		(pts
			(xy 140.544804 -229.702614) (xy 140.544804 -229.658164) (xy 140.344652 -229.658164) (xy 140.344652 -229.702614)
			(xy 140.444728 -229.80269)
		)
		(stroke
			(width 0)
			(type solid)
		)
		(fill yes)
		(layer "In4.Cu")
		(net "M_J_CPU1_SA_DQ<7>")
	)
	(gr_poly
		(pts
			(xy 140.544804 -228.486462) (xy 140.444728 -228.386386) (xy 140.344652 -228.486462) (xy 140.344652 -228.530912)
			(xy 140.544804 -228.530912)
		)
		(stroke
			(width 0)
			(type solid)
		)
		(fill yes)
		(layer "In4.Cu")
		(net "M_J_CPU1_SA_DQ<4>")
	)
	(gr_poly
		(pts
			(xy 140.544804 -228.082856) (xy 140.544804 -228.035104) (xy 140.344652 -228.035104) (xy 140.344652 -228.082856)
			(xy 140.444728 -228.182678)
		)
		(stroke
			(width 0)
			(type solid)
		)
		(fill yes)
		(layer "In4.Cu")
		(net "M_J_CPU1_SA_DQS_DP<5>")
	)
	(gr_poly
		(pts
			(xy 140.544804 -226.866196) (xy 140.444728 -226.766374) (xy 140.344652 -226.866196) (xy 140.344652 -226.913948)
			(xy 140.544804 -226.913948)
		)
		(stroke
			(width 0)
			(type solid)
		)
		(fill yes)
		(layer "In4.Cu")
		(net "M_J_CPU1_SA_DQS_DP<0>")
	)
	(gr_poly
		(pts
			(xy 140.544804 -226.46259) (xy 140.544804 -226.41814) (xy 140.344652 -226.41814) (xy 140.344652 -226.46259)
			(xy 140.444728 -226.562666)
		)
		(stroke
			(width 0)
			(type solid)
		)
		(fill yes)
		(layer "In4.Cu")
		(net "M_J_CPU1_SA_DQ<3>")
	)
	(gr_poly
		(pts
			(xy 140.600938 -225.379026) (xy 140.564108 -225.242374) (xy 140.525754 -225.220022) (xy 140.425678 -225.39325)
			(xy 140.464286 -225.415602)
		)
		(stroke
			(width 0)
			(type solid)
		)
		(fill yes)
		(layer "In4.Cu")
		(net "M_J_CPU1_SA_DQ<2>")
	)
	(gr_poly
		(pts
			(xy 140.844778 -292.918134) (xy 140.744702 -292.818058) (xy 140.644626 -292.918134) (xy 140.644626 -292.962584)
			(xy 140.844778 -292.962584)
		)
		(stroke
			(width 0)
			(type solid)
		)
		(fill yes)
		(layer "In4.Cu")
		(net "M_J_CPU1_SB_DQ<29>")
	)
	(gr_poly
		(pts
			(xy 140.844778 -292.514274) (xy 140.844778 -292.469824) (xy 140.644626 -292.469824) (xy 140.644626 -292.514274)
			(xy 140.744702 -292.61435)
		)
		(stroke
			(width 0)
			(type solid)
		)
		(fill yes)
		(layer "In4.Cu")
		(net "M_J_CPU1_SB_DQ<30>")
	)
	(gr_poly
		(pts
			(xy 140.844778 -291.297868) (xy 140.744702 -291.198046) (xy 140.644626 -291.297868) (xy 140.644626 -291.34562)
			(xy 140.844778 -291.34562)
		)
		(stroke
			(width 0)
			(type solid)
		)
		(fill yes)
		(layer "In4.Cu")
		(net "M_J_CPU1_SB_DQS_DN<8>")
	)
	(gr_poly
		(pts
			(xy 140.844778 -290.894516) (xy 140.844778 -290.846764) (xy 140.644626 -290.846764) (xy 140.644626 -290.894516)
			(xy 140.744702 -290.994338)
		)
		(stroke
			(width 0)
			(type solid)
		)
		(fill yes)
		(layer "In4.Cu")
		(net "M_J_CPU1_SB_DQS_DN<3>")
	)
	(gr_poly
		(pts
			(xy 140.844778 -289.67811) (xy 140.744702 -289.578034) (xy 140.644626 -289.67811) (xy 140.644626 -289.72256)
			(xy 140.844778 -289.72256)
		)
		(stroke
			(width 0)
			(type solid)
		)
		(fill yes)
		(layer "In4.Cu")
		(net "M_J_CPU1_SB_DQ<25>")
	)
	(gr_poly
		(pts
			(xy 140.844778 -289.27425) (xy 140.844778 -289.2298) (xy 140.644626 -289.2298) (xy 140.644626 -289.27425)
			(xy 140.744702 -289.374326)
		)
		(stroke
			(width 0)
			(type solid)
		)
		(fill yes)
		(layer "In4.Cu")
		(net "M_J_CPU1_SB_DQ<26>")
	)
	(gr_poly
		(pts
			(xy 140.844778 -288.058098) (xy 140.744702 -287.958022) (xy 140.644626 -288.058098) (xy 140.644626 -288.102548)
			(xy 140.844778 -288.102548)
		)
		(stroke
			(width 0)
			(type solid)
		)
		(fill yes)
		(layer "In4.Cu")
		(net "M_J_CPU1_SB_DQ<21>")
	)
	(gr_poly
		(pts
			(xy 140.844778 -287.654492) (xy 140.844778 -287.610042) (xy 140.644626 -287.610042) (xy 140.644626 -287.654492)
			(xy 140.744702 -287.754568)
		)
		(stroke
			(width 0)
			(type solid)
		)
		(fill yes)
		(layer "In4.Cu")
		(net "M_J_CPU1_SB_DQ<22>")
	)
	(gr_poly
		(pts
			(xy 140.844778 -286.438086) (xy 140.744702 -286.33801) (xy 140.644626 -286.438086) (xy 140.644626 -286.485838)
			(xy 140.844778 -286.485838)
		)
		(stroke
			(width 0)
			(type solid)
		)
		(fill yes)
		(layer "In4.Cu")
		(net "M_J_CPU1_SB_DQS_DN<7>")
	)
	(gr_poly
		(pts
			(xy 140.844778 -286.034734) (xy 140.844778 -285.986982) (xy 140.644626 -285.986982) (xy 140.644626 -286.034734)
			(xy 140.744702 -286.134556)
		)
		(stroke
			(width 0)
			(type solid)
		)
		(fill yes)
		(layer "In4.Cu")
		(net "M_J_CPU1_SB_DQS_DN<2>")
	)
	(gr_poly
		(pts
			(xy 140.844778 -284.818328) (xy 140.744702 -284.718252) (xy 140.644626 -284.818328) (xy 140.644626 -284.862778)
			(xy 140.844778 -284.862778)
		)
		(stroke
			(width 0)
			(type solid)
		)
		(fill yes)
		(layer "In4.Cu")
		(net "M_J_CPU1_SB_DQ<17>")
	)
	(gr_poly
		(pts
			(xy 140.844778 -284.414468) (xy 140.844778 -284.370018) (xy 140.644626 -284.370018) (xy 140.644626 -284.414468)
			(xy 140.744702 -284.514544)
		)
		(stroke
			(width 0)
			(type solid)
		)
		(fill yes)
		(layer "In4.Cu")
		(net "M_J_CPU1_SB_DQ<18>")
	)
	(gr_poly
		(pts
			(xy 140.844778 -283.198316) (xy 140.744702 -283.09824) (xy 140.644626 -283.198316) (xy 140.644626 -283.242766)
			(xy 140.844778 -283.242766)
		)
		(stroke
			(width 0)
			(type solid)
		)
		(fill yes)
		(layer "In4.Cu")
		(net "M_J_CPU1_SB_DQ<13>")
	)
	(gr_poly
		(pts
			(xy 140.844778 -282.794456) (xy 140.844778 -282.750006) (xy 140.644626 -282.750006) (xy 140.644626 -282.794456)
			(xy 140.744702 -282.894532)
		)
		(stroke
			(width 0)
			(type solid)
		)
		(fill yes)
		(layer "In4.Cu")
		(net "M_J_CPU1_SB_DQ<14>")
	)
	(gr_poly
		(pts
			(xy 140.844778 -281.57805) (xy 140.744702 -281.478228) (xy 140.644626 -281.57805) (xy 140.644626 -281.625802)
			(xy 140.844778 -281.625802)
		)
		(stroke
			(width 0)
			(type solid)
		)
		(fill yes)
		(layer "In4.Cu")
		(net "M_J_CPU1_SB_DQS_DN<6>")
	)
	(gr_poly
		(pts
			(xy 140.844778 -281.174698) (xy 140.844778 -281.126946) (xy 140.644626 -281.126946) (xy 140.644626 -281.174698)
			(xy 140.744702 -281.27452)
		)
		(stroke
			(width 0)
			(type solid)
		)
		(fill yes)
		(layer "In4.Cu")
		(net "M_J_CPU1_SB_DQS_DN<1>")
	)
	(gr_poly
		(pts
			(xy 140.844778 -279.958292) (xy 140.744702 -279.858216) (xy 140.644626 -279.958292) (xy 140.644626 -280.002742)
			(xy 140.844778 -280.002742)
		)
		(stroke
			(width 0)
			(type solid)
		)
		(fill yes)
		(layer "In4.Cu")
		(net "M_J_CPU1_SB_DQ<9>")
	)
	(gr_poly
		(pts
			(xy 140.844778 -279.554432) (xy 140.844778 -279.509982) (xy 140.644626 -279.509982) (xy 140.644626 -279.554432)
			(xy 140.744702 -279.654508)
		)
		(stroke
			(width 0)
			(type solid)
		)
		(fill yes)
		(layer "In4.Cu")
		(net "M_J_CPU1_SB_DQ<10>")
	)
	(gr_poly
		(pts
			(xy 140.844778 -278.33828) (xy 140.744702 -278.238204) (xy 140.644626 -278.33828) (xy 140.644626 -278.38273)
			(xy 140.844778 -278.38273)
		)
		(stroke
			(width 0)
			(type solid)
		)
		(fill yes)
		(layer "In4.Cu")
		(net "M_J_CPU1_SB_DQ<5>")
	)
	(gr_poly
		(pts
			(xy 140.844778 -277.93442) (xy 140.844778 -277.88997) (xy 140.644626 -277.88997) (xy 140.644626 -277.93442)
			(xy 140.744702 -278.034496)
		)
		(stroke
			(width 0)
			(type solid)
		)
		(fill yes)
		(layer "In4.Cu")
		(net "M_J_CPU1_SB_DQ<6>")
	)
	(gr_poly
		(pts
			(xy 140.844778 -276.718014) (xy 140.744702 -276.618192) (xy 140.644626 -276.718014) (xy 140.644626 -276.765766)
			(xy 140.844778 -276.765766)
		)
		(stroke
			(width 0)
			(type solid)
		)
		(fill yes)
		(layer "In4.Cu")
		(net "M_J_CPU1_SB_DQS_DN<5>")
	)
	(gr_poly
		(pts
			(xy 140.844778 -276.314662) (xy 140.844778 -276.26691) (xy 140.644626 -276.26691) (xy 140.644626 -276.314662)
			(xy 140.744702 -276.414484)
		)
		(stroke
			(width 0)
			(type solid)
		)
		(fill yes)
		(layer "In4.Cu")
		(net "M_J_CPU1_SB_DQS_DN<0>")
	)
	(gr_poly
		(pts
			(xy 140.844778 -275.098256) (xy 140.744702 -274.99818) (xy 140.644626 -275.098256) (xy 140.644626 -275.142706)
			(xy 140.844778 -275.142706)
		)
		(stroke
			(width 0)
			(type solid)
		)
		(fill yes)
		(layer "In4.Cu")
		(net "M_J_CPU1_SB_DQ<1>")
	)
	(gr_poly
		(pts
			(xy 140.844778 -274.694396) (xy 140.844778 -274.649946) (xy 140.644626 -274.649946) (xy 140.644626 -274.694396)
			(xy 140.744702 -274.794472)
		)
		(stroke
			(width 0)
			(type solid)
		)
		(fill yes)
		(layer "In4.Cu")
		(net "M_J_CPU1_SB_DQ<2>")
	)
	(gr_poly
		(pts
			(xy 140.844778 -273.478244) (xy 140.744702 -273.378168) (xy 140.644626 -273.478244) (xy 140.644626 -273.522694)
			(xy 140.844778 -273.522694)
		)
		(stroke
			(width 0)
			(type solid)
		)
		(fill yes)
		(layer "In4.Cu")
		(net "M_J_CPU1_SB_CB<1>")
	)
	(gr_poly
		(pts
			(xy 140.844778 -273.074384) (xy 140.844778 -273.029934) (xy 140.644626 -273.029934) (xy 140.644626 -273.074384)
			(xy 140.744702 -273.17446)
		)
		(stroke
			(width 0)
			(type solid)
		)
		(fill yes)
		(layer "In4.Cu")
		(net "M_J_CPU1_SB_CB<2>")
	)
	(gr_poly
		(pts
			(xy 140.844778 -271.857978) (xy 140.744702 -271.758156) (xy 140.644626 -271.857978) (xy 140.644626 -271.90573)
			(xy 140.844778 -271.90573)
		)
		(stroke
			(width 0)
			(type solid)
		)
		(fill yes)
		(layer "In4.Cu")
		(net "M_J_CPU1_SB_DQS_DN<4>")
	)
	(gr_poly
		(pts
			(xy 140.844778 -271.454626) (xy 140.844778 -271.406874) (xy 140.644626 -271.406874) (xy 140.644626 -271.454626)
			(xy 140.744702 -271.554448)
		)
		(stroke
			(width 0)
			(type solid)
		)
		(fill yes)
		(layer "In4.Cu")
		(net "M_J_CPU1_SB_DQS_DN<9>")
	)
	(gr_poly
		(pts
			(xy 140.844778 -270.23822) (xy 140.744702 -270.138144) (xy 140.644626 -270.23822) (xy 140.644626 -270.28267)
			(xy 140.844778 -270.28267)
		)
		(stroke
			(width 0)
			(type solid)
		)
		(fill yes)
		(layer "In4.Cu")
		(net "M_J_CPU1_SB_CB<5>")
	)
	(gr_poly
		(pts
			(xy 140.844778 -269.83436) (xy 140.844778 -269.78991) (xy 140.644626 -269.78991) (xy 140.644626 -269.83436)
			(xy 140.744702 -269.934436)
		)
		(stroke
			(width 0)
			(type solid)
		)
		(fill yes)
		(layer "In4.Cu")
		(net "M_J_CPU1_SB_CB<6>")
	)
	(gr_poly
		(pts
			(xy 140.844778 -266.998196) (xy 140.744702 -266.89812) (xy 140.644626 -266.998196) (xy 140.644626 -267.042646)
			(xy 140.844778 -267.042646)
		)
		(stroke
			(width 0)
			(type solid)
		)
		(fill yes)
		(layer "In4.Cu")
		(net "M_J_CPU1_SA_RSP<0>")
	)
	(gr_poly
		(pts
			(xy 140.844778 -266.594336) (xy 140.844778 -266.549886) (xy 140.644626 -266.549886) (xy 140.644626 -266.594336)
			(xy 140.744702 -266.694412)
		)
		(stroke
			(width 0)
			(type solid)
		)
		(fill yes)
		(layer "In4.Cu")
		(net "M_J_CPU1_SB_CS_N<1>")
	)
	(gr_poly
		(pts
			(xy 140.844778 -265.378184) (xy 140.744702 -265.278108) (xy 140.644626 -265.378184) (xy 140.644626 -265.422634)
			(xy 140.844778 -265.422634)
		)
		(stroke
			(width 0)
			(type solid)
		)
		(fill yes)
		(layer "In4.Cu")
		(net "M_J_CPU1_SB_PAR")
	)
	(gr_poly
		(pts
			(xy 140.844778 -263.758172) (xy 140.744702 -263.658096) (xy 140.644626 -263.758172) (xy 140.644626 -263.802622)
			(xy 140.844778 -263.802622)
		)
		(stroke
			(width 0)
			(type solid)
		)
		(fill yes)
		(layer "In4.Cu")
		(net "M_J_CPU1_SB_CA<4>")
	)
	(gr_poly
		(pts
			(xy 140.844778 -263.354312) (xy 140.844778 -263.309862) (xy 140.644626 -263.309862) (xy 140.644626 -263.354312)
			(xy 140.744702 -263.454388)
		)
		(stroke
			(width 0)
			(type solid)
		)
		(fill yes)
		(layer "In4.Cu")
		(net "M_J_CPU1_SB_CA<3>")
	)
	(gr_poly
		(pts
			(xy 140.844778 -262.13816) (xy 140.744702 -262.038084) (xy 140.644626 -262.13816) (xy 140.644626 -262.18261)
			(xy 140.844778 -262.18261)
		)
		(stroke
			(width 0)
			(type solid)
		)
		(fill yes)
		(layer "In4.Cu")
		(net "M_J_CPU1_SB_CA<0>")
	)
	(gr_poly
		(pts
			(xy 140.933932 -225.505772) (xy 140.895324 -225.48342) (xy 140.758926 -225.519996) (xy 140.795502 -225.656648)
			(xy 140.833856 -225.679)
		)
		(stroke
			(width 0)
			(type solid)
		)
		(fill yes)
		(layer "In4.Cu")
		(net "M_J_CPU1_SA_DQ<1>")
	)
	(gr_poly
		(pts
			(xy 140.93444 -223.884998) (xy 140.896086 -223.862646) (xy 140.759434 -223.899222) (xy 140.79601 -224.035874)
			(xy 140.834618 -224.058226)
		)
		(stroke
			(width 0)
			(type solid)
		)
		(fill yes)
		(layer "In4.Cu")
		(net "M_J_CPU1_SA_DQ<0>")
	)
	(gr_poly
		(pts
			(xy 141.014958 -256.432812) (xy 141.014958 -256.38506) (xy 140.814806 -256.38506) (xy 140.814806 -256.432812)
			(xy 140.914882 -256.532634)
		)
		(stroke
			(width 0)
			(type solid)
		)
		(fill yes)
		(layer "In4.Cu")
		(net "M_J_CPU1_CLK_DN<0>")
	)
	(gr_poly
		(pts
			(xy 141.014958 -255.216406) (xy 140.914882 -255.11633) (xy 140.814806 -255.216406) (xy 140.814806 -255.260856)
			(xy 141.014958 -255.260856)
		)
		(stroke
			(width 0)
			(type solid)
		)
		(fill yes)
		(layer "In4.Cu")
		(net "M_J_CPU1_SA_CA<6>")
	)
	(gr_poly
		(pts
			(xy 141.014958 -254.812546) (xy 141.014958 -254.768096) (xy 140.814806 -254.768096) (xy 140.814806 -254.812546)
			(xy 140.914882 -254.912622)
		)
		(stroke
			(width 0)
			(type solid)
		)
		(fill yes)
		(layer "In4.Cu")
		(net "M_J_CPU1_SA_CA<5>")
	)
	(gr_poly
		(pts
			(xy 141.014958 -253.596394) (xy 140.914882 -253.496318) (xy 140.814806 -253.596394) (xy 140.814806 -253.640844)
			(xy 141.014958 -253.640844)
		)
		(stroke
			(width 0)
			(type solid)
		)
		(fill yes)
		(layer "In4.Cu")
		(net "M_J_CPU1_SA_CA<2>")
	)
	(gr_poly
		(pts
			(xy 141.014958 -253.192534) (xy 141.014958 -253.148084) (xy 140.814806 -253.148084) (xy 140.814806 -253.192534)
			(xy 140.914882 -253.29261)
		)
		(stroke
			(width 0)
			(type solid)
		)
		(fill yes)
		(layer "In4.Cu")
		(net "M_J_CPU1_SA_CA<1>")
	)
	(gr_poly
		(pts
			(xy 141.014958 -251.976382) (xy 140.914882 -251.876306) (xy 140.814806 -251.976382) (xy 140.814806 -252.020832)
			(xy 141.014958 -252.020832)
		)
		(stroke
			(width 0)
			(type solid)
		)
		(fill yes)
		(layer "In4.Cu")
		(net "M_J_CPU1_SA_CS_N<1>")
	)
	(gr_poly
		(pts
			(xy 141.014958 -250.35637) (xy 140.914882 -250.256294) (xy 140.814806 -250.35637) (xy 140.814806 -250.40082)
			(xy 141.014958 -250.40082)
		)
		(stroke
			(width 0)
			(type solid)
		)
		(fill yes)
		(layer "In4.Cu")
		(net "M_J_CPU1_ALERT_R_N")
	)
	(gr_poly
		(pts
			(xy 141.014958 -248.736358) (xy 140.914882 -248.636282) (xy 140.814806 -248.736358) (xy 140.814806 -248.780808)
			(xy 141.014958 -248.780808)
		)
		(stroke
			(width 0)
			(type solid)
		)
		(fill yes)
		(layer "In4.Cu")
		(net "M_J_CPU1_SA_CB<5>")
	)
	(gr_poly
		(pts
			(xy 141.014958 -248.332498) (xy 141.014958 -248.288048) (xy 140.814806 -248.288048) (xy 140.814806 -248.332498)
			(xy 140.914882 -248.432574)
		)
		(stroke
			(width 0)
			(type solid)
		)
		(fill yes)
		(layer "In4.Cu")
		(net "M_J_CPU1_SA_CB<6>")
	)
	(gr_poly
		(pts
			(xy 141.014958 -247.116092) (xy 140.914882 -247.01627) (xy 140.814806 -247.116092) (xy 140.814806 -247.163844)
			(xy 141.014958 -247.163844)
		)
		(stroke
			(width 0)
			(type solid)
		)
		(fill yes)
		(layer "In4.Cu")
		(net "M_J_CPU1_SA_DQS_DN<9>")
	)
	(gr_poly
		(pts
			(xy 141.014958 -246.71274) (xy 141.014958 -246.664988) (xy 140.814806 -246.664988) (xy 140.814806 -246.71274)
			(xy 140.914882 -246.812562)
		)
		(stroke
			(width 0)
			(type solid)
		)
		(fill yes)
		(layer "In4.Cu")
		(net "M_J_CPU1_SA_DQS_DN<4>")
	)
	(gr_poly
		(pts
			(xy 141.014958 -245.496334) (xy 140.914882 -245.396258) (xy 140.814806 -245.496334) (xy 140.814806 -245.540784)
			(xy 141.014958 -245.540784)
		)
		(stroke
			(width 0)
			(type solid)
		)
		(fill yes)
		(layer "In4.Cu")
		(net "M_J_CPU1_SA_CB<1>")
	)
	(gr_poly
		(pts
			(xy 141.014958 -245.092474) (xy 141.014958 -245.048024) (xy 140.814806 -245.048024) (xy 140.814806 -245.092474)
			(xy 140.914882 -245.19255)
		)
		(stroke
			(width 0)
			(type solid)
		)
		(fill yes)
		(layer "In4.Cu")
		(net "M_J_CPU1_SA_CB<2>")
	)
	(gr_poly
		(pts
			(xy 141.014958 -243.876322) (xy 140.914882 -243.776246) (xy 140.814806 -243.876322) (xy 140.814806 -243.920772)
			(xy 141.014958 -243.920772)
		)
		(stroke
			(width 0)
			(type solid)
		)
		(fill yes)
		(layer "In4.Cu")
		(net "M_J_CPU1_SA_DQ<29>")
	)
	(gr_poly
		(pts
			(xy 141.014958 -243.472462) (xy 141.014958 -243.428012) (xy 140.814806 -243.428012) (xy 140.814806 -243.472462)
			(xy 140.914882 -243.572538)
		)
		(stroke
			(width 0)
			(type solid)
		)
		(fill yes)
		(layer "In4.Cu")
		(net "M_J_CPU1_SA_DQ<30>")
	)
	(gr_poly
		(pts
			(xy 141.014958 -242.256056) (xy 140.914882 -242.156234) (xy 140.814806 -242.256056) (xy 140.814806 -242.303808)
			(xy 141.014958 -242.303808)
		)
		(stroke
			(width 0)
			(type solid)
		)
		(fill yes)
		(layer "In4.Cu")
		(net "M_J_CPU1_SA_DQS_DN<8>")
	)
	(gr_poly
		(pts
			(xy 141.014958 -241.852704) (xy 141.014958 -241.804952) (xy 140.814806 -241.804952) (xy 140.814806 -241.852704)
			(xy 140.914882 -241.952526)
		)
		(stroke
			(width 0)
			(type solid)
		)
		(fill yes)
		(layer "In4.Cu")
		(net "M_J_CPU1_SA_DQS_DN<3>")
	)
	(gr_poly
		(pts
			(xy 141.014958 -240.636298) (xy 140.914882 -240.536222) (xy 140.814806 -240.636298) (xy 140.814806 -240.680748)
			(xy 141.014958 -240.680748)
		)
		(stroke
			(width 0)
			(type solid)
		)
		(fill yes)
		(layer "In4.Cu")
		(net "M_J_CPU1_SA_DQ<25>")
	)
	(gr_poly
		(pts
			(xy 141.014958 -240.232438) (xy 141.014958 -240.187988) (xy 140.814806 -240.187988) (xy 140.814806 -240.232438)
			(xy 140.914882 -240.332514)
		)
		(stroke
			(width 0)
			(type solid)
		)
		(fill yes)
		(layer "In4.Cu")
		(net "M_J_CPU1_SA_DQ<26>")
	)
	(gr_poly
		(pts
			(xy 141.014958 -239.016286) (xy 140.914882 -238.91621) (xy 140.814806 -239.016286) (xy 140.814806 -239.060736)
			(xy 141.014958 -239.060736)
		)
		(stroke
			(width 0)
			(type solid)
		)
		(fill yes)
		(layer "In4.Cu")
		(net "M_J_CPU1_SA_DQ<21>")
	)
	(gr_poly
		(pts
			(xy 141.014958 -238.612426) (xy 141.014958 -238.567976) (xy 140.814806 -238.567976) (xy 140.814806 -238.612426)
			(xy 140.914882 -238.712502)
		)
		(stroke
			(width 0)
			(type solid)
		)
		(fill yes)
		(layer "In4.Cu")
		(net "M_J_CPU1_SA_DQ<22>")
	)
	(gr_poly
		(pts
			(xy 141.014958 -237.39602) (xy 140.914882 -237.296198) (xy 140.814806 -237.39602) (xy 140.814806 -237.443772)
			(xy 141.014958 -237.443772)
		)
		(stroke
			(width 0)
			(type solid)
		)
		(fill yes)
		(layer "In4.Cu")
		(net "M_J_CPU1_SA_DQS_DN<7>")
	)
	(gr_poly
		(pts
			(xy 141.014958 -236.992668) (xy 141.014958 -236.944916) (xy 140.814806 -236.944916) (xy 140.814806 -236.992668)
			(xy 140.914882 -237.09249)
		)
		(stroke
			(width 0)
			(type solid)
		)
		(fill yes)
		(layer "In4.Cu")
		(net "M_J_CPU1_SA_DQS_DN<2>")
	)
	(gr_poly
		(pts
			(xy 141.014958 -235.776262) (xy 140.914882 -235.676186) (xy 140.814806 -235.776262) (xy 140.814806 -235.820712)
			(xy 141.014958 -235.820712)
		)
		(stroke
			(width 0)
			(type solid)
		)
		(fill yes)
		(layer "In4.Cu")
		(net "M_J_CPU1_SA_DQ<17>")
	)
	(gr_poly
		(pts
			(xy 141.014958 -235.372402) (xy 141.014958 -235.327952) (xy 140.814806 -235.327952) (xy 140.814806 -235.372402)
			(xy 140.914882 -235.472478)
		)
		(stroke
			(width 0)
			(type solid)
		)
		(fill yes)
		(layer "In4.Cu")
		(net "M_J_CPU1_SA_DQ<18>")
	)
	(gr_poly
		(pts
			(xy 141.014958 -234.15625) (xy 140.914882 -234.056174) (xy 140.814806 -234.15625) (xy 140.814806 -234.2007)
			(xy 141.014958 -234.2007)
		)
		(stroke
			(width 0)
			(type solid)
		)
		(fill yes)
		(layer "In4.Cu")
		(net "M_J_CPU1_SA_DQ<13>")
	)
	(gr_poly
		(pts
			(xy 141.014958 -233.75239) (xy 141.014958 -233.70794) (xy 140.814806 -233.70794) (xy 140.814806 -233.75239)
			(xy 140.914882 -233.852466)
		)
		(stroke
			(width 0)
			(type solid)
		)
		(fill yes)
		(layer "In4.Cu")
		(net "M_J_CPU1_SA_DQ<14>")
	)
	(gr_poly
		(pts
			(xy 141.014958 -232.535984) (xy 140.914882 -232.436162) (xy 140.814806 -232.535984) (xy 140.814806 -232.583736)
			(xy 141.014958 -232.583736)
		)
		(stroke
			(width 0)
			(type solid)
		)
		(fill yes)
		(layer "In4.Cu")
		(net "M_J_CPU1_SA_DQS_DN<6>")
	)
	(gr_poly
		(pts
			(xy 141.014958 -232.132632) (xy 141.014958 -232.08488) (xy 140.814806 -232.08488) (xy 140.814806 -232.132632)
			(xy 140.914882 -232.232454)
		)
		(stroke
			(width 0)
			(type solid)
		)
		(fill yes)
		(layer "In4.Cu")
		(net "M_J_CPU1_SA_DQS_DN<1>")
	)
	(gr_poly
		(pts
			(xy 141.014958 -230.916226) (xy 140.914882 -230.81615) (xy 140.814806 -230.916226) (xy 140.814806 -230.960676)
			(xy 141.014958 -230.960676)
		)
		(stroke
			(width 0)
			(type solid)
		)
		(fill yes)
		(layer "In4.Cu")
		(net "M_J_CPU1_SA_DQ<9>")
	)
	(gr_poly
		(pts
			(xy 141.014958 -230.51262) (xy 141.014958 -230.46817) (xy 140.814806 -230.46817) (xy 140.814806 -230.51262)
			(xy 140.914882 -230.612696)
		)
		(stroke
			(width 0)
			(type solid)
		)
		(fill yes)
		(layer "In4.Cu")
		(net "M_J_CPU1_SA_DQ<10>")
	)
	(gr_poly
		(pts
			(xy 141.014958 -229.296214) (xy 140.914882 -229.196138) (xy 140.814806 -229.296214) (xy 140.814806 -229.340664)
			(xy 141.014958 -229.340664)
		)
		(stroke
			(width 0)
			(type solid)
		)
		(fill yes)
		(layer "In4.Cu")
		(net "M_J_CPU1_SA_DQ<5>")
	)
	(gr_poly
		(pts
			(xy 141.014958 -228.892608) (xy 141.014958 -228.848158) (xy 140.814806 -228.848158) (xy 140.814806 -228.892608)
			(xy 140.914882 -228.992684)
		)
		(stroke
			(width 0)
			(type solid)
		)
		(fill yes)
		(layer "In4.Cu")
		(net "M_J_CPU1_SA_DQ<6>")
	)
	(gr_poly
		(pts
			(xy 141.014958 -227.676202) (xy 140.914882 -227.57638) (xy 140.814806 -227.676202) (xy 140.814806 -227.723954)
			(xy 141.014958 -227.723954)
		)
		(stroke
			(width 0)
			(type solid)
		)
		(fill yes)
		(layer "In4.Cu")
		(net "M_J_CPU1_SA_DQS_DN<5>")
	)
	(gr_poly
		(pts
			(xy 141.014958 -227.27285) (xy 141.014958 -227.225098) (xy 140.814806 -227.225098) (xy 140.814806 -227.27285)
			(xy 140.914882 -227.372672)
		)
		(stroke
			(width 0)
			(type solid)
		)
		(fill yes)
		(layer "In4.Cu")
		(net "M_J_CPU1_SA_DQS_DN<0>")
	)
	(gr_poly
		(pts
			(xy 141.070076 -224.57029) (xy 141.0335 -224.433638) (xy 140.994892 -224.41154) (xy 140.894816 -224.584768)
			(xy 140.933424 -224.606866)
		)
		(stroke
			(width 0)
			(type solid)
		)
		(fill yes)
		(layer "In4.Cu")
		(net "M_J_CPU1_SA_DQ<2>")
	)
	(gr_poly
		(pts
			(xy 141.070838 -226.189032) (xy 141.034008 -226.05238) (xy 140.995654 -226.030028) (xy 140.895578 -226.203256)
			(xy 140.934186 -226.225608)
		)
		(stroke
			(width 0)
			(type solid)
		)
		(fill yes)
		(layer "In4.Cu")
		(net "M_J_CPU1_SA_DQ<3>")
	)
	(gr_poly
		(pts
			(xy 141.314932 -293.32428) (xy 141.314932 -293.27983) (xy 141.11478 -293.27983) (xy 141.11478 -293.32428)
			(xy 141.214856 -293.424356)
		)
		(stroke
			(width 0)
			(type solid)
		)
		(fill yes)
		(layer "In4.Cu")
		(net "M_J_CPU1_SB_DQ<31>")
	)
	(gr_poly
		(pts
			(xy 141.314932 -292.108128) (xy 141.214856 -292.008052) (xy 141.11478 -292.108128) (xy 141.11478 -292.152578)
			(xy 141.314932 -292.152578)
		)
		(stroke
			(width 0)
			(type solid)
		)
		(fill yes)
		(layer "In4.Cu")
		(net "M_J_CPU1_SB_DQ<28>")
	)
	(gr_poly
		(pts
			(xy 141.314932 -291.704522) (xy 141.314932 -291.65677) (xy 141.11478 -291.65677) (xy 141.11478 -291.704522)
			(xy 141.214856 -291.804344)
		)
		(stroke
			(width 0)
			(type solid)
		)
		(fill yes)
		(layer "In4.Cu")
		(net "M_J_CPU1_SB_DQS_DP<8>")
	)
	(gr_poly
		(pts
			(xy 141.314932 -290.487862) (xy 141.214856 -290.38804) (xy 141.11478 -290.487862) (xy 141.11478 -290.535614)
			(xy 141.314932 -290.535614)
		)
		(stroke
			(width 0)
			(type solid)
		)
		(fill yes)
		(layer "In4.Cu")
		(net "M_J_CPU1_SB_DQS_DP<3>")
	)
	(gr_poly
		(pts
			(xy 141.314932 -290.084256) (xy 141.314932 -290.039806) (xy 141.11478 -290.039806) (xy 141.11478 -290.084256)
			(xy 141.214856 -290.184332)
		)
		(stroke
			(width 0)
			(type solid)
		)
		(fill yes)
		(layer "In4.Cu")
		(net "M_J_CPU1_SB_DQ<27>")
	)
	(gr_poly
		(pts
			(xy 141.314932 -288.868104) (xy 141.214856 -288.768028) (xy 141.11478 -288.868104) (xy 141.11478 -288.912554)
			(xy 141.314932 -288.912554)
		)
		(stroke
			(width 0)
			(type solid)
		)
		(fill yes)
		(layer "In4.Cu")
		(net "M_J_CPU1_SB_DQ<24>")
	)
	(gr_poly
		(pts
			(xy 141.314932 -288.464498) (xy 141.314932 -288.420048) (xy 141.11478 -288.420048) (xy 141.11478 -288.464498)
			(xy 141.214856 -288.564574)
		)
		(stroke
			(width 0)
			(type solid)
		)
		(fill yes)
		(layer "In4.Cu")
		(net "M_J_CPU1_SB_DQ<23>")
	)
	(gr_poly
		(pts
			(xy 141.314932 -287.248092) (xy 141.214856 -287.148016) (xy 141.11478 -287.248092) (xy 141.11478 -287.292542)
			(xy 141.314932 -287.292542)
		)
		(stroke
			(width 0)
			(type solid)
		)
		(fill yes)
		(layer "In4.Cu")
		(net "M_J_CPU1_SB_DQ<20>")
	)
	(gr_poly
		(pts
			(xy 141.314932 -286.844486) (xy 141.314932 -286.796734) (xy 141.11478 -286.796734) (xy 141.11478 -286.844486)
			(xy 141.214856 -286.944562)
		)
		(stroke
			(width 0)
			(type solid)
		)
		(fill yes)
		(layer "In4.Cu")
		(net "M_J_CPU1_SB_DQS_DP<7>")
	)
	(gr_poly
		(pts
			(xy 141.314932 -285.62808) (xy 141.214856 -285.528258) (xy 141.11478 -285.62808) (xy 141.11478 -285.675832)
			(xy 141.314932 -285.675832)
		)
		(stroke
			(width 0)
			(type solid)
		)
		(fill yes)
		(layer "In4.Cu")
		(net "M_J_CPU1_SB_DQS_DP<2>")
	)
	(gr_poly
		(pts
			(xy 141.314932 -285.224474) (xy 141.314932 -285.180024) (xy 141.11478 -285.180024) (xy 141.11478 -285.224474)
			(xy 141.214856 -285.32455)
		)
		(stroke
			(width 0)
			(type solid)
		)
		(fill yes)
		(layer "In4.Cu")
		(net "M_J_CPU1_SB_DQ<19>")
	)
	(gr_poly
		(pts
			(xy 141.314932 -284.008322) (xy 141.214856 -283.908246) (xy 141.11478 -284.008322) (xy 141.11478 -284.052772)
			(xy 141.314932 -284.052772)
		)
		(stroke
			(width 0)
			(type solid)
		)
		(fill yes)
		(layer "In4.Cu")
		(net "M_J_CPU1_SB_DQ<16>")
	)
	(gr_poly
		(pts
			(xy 141.314932 -283.604462) (xy 141.314932 -283.560012) (xy 141.11478 -283.560012) (xy 141.11478 -283.604462)
			(xy 141.214856 -283.704538)
		)
		(stroke
			(width 0)
			(type solid)
		)
		(fill yes)
		(layer "In4.Cu")
		(net "M_J_CPU1_SB_DQ<15>")
	)
	(gr_poly
		(pts
			(xy 141.314932 -282.38831) (xy 141.214856 -282.288234) (xy 141.11478 -282.38831) (xy 141.11478 -282.43276)
			(xy 141.314932 -282.43276)
		)
		(stroke
			(width 0)
			(type solid)
		)
		(fill yes)
		(layer "In4.Cu")
		(net "M_J_CPU1_SB_DQ<12>")
	)
	(gr_poly
		(pts
			(xy 141.314932 -281.984704) (xy 141.314932 -281.936952) (xy 141.11478 -281.936952) (xy 141.11478 -281.984704)
			(xy 141.214856 -282.084526)
		)
		(stroke
			(width 0)
			(type solid)
		)
		(fill yes)
		(layer "In4.Cu")
		(net "M_J_CPU1_SB_DQS_DP<6>")
	)
	(gr_poly
		(pts
			(xy 141.314932 -280.768044) (xy 141.214856 -280.668222) (xy 141.11478 -280.768044) (xy 141.11478 -280.815796)
			(xy 141.314932 -280.815796)
		)
		(stroke
			(width 0)
			(type solid)
		)
		(fill yes)
		(layer "In4.Cu")
		(net "M_J_CPU1_SB_DQS_DP<1>")
	)
	(gr_poly
		(pts
			(xy 141.314932 -280.364438) (xy 141.314932 -280.319988) (xy 141.11478 -280.319988) (xy 141.11478 -280.364438)
			(xy 141.214856 -280.464514)
		)
		(stroke
			(width 0)
			(type solid)
		)
		(fill yes)
		(layer "In4.Cu")
		(net "M_J_CPU1_SB_DQ<11>")
	)
	(gr_poly
		(pts
			(xy 141.314932 -279.148286) (xy 141.214856 -279.04821) (xy 141.11478 -279.148286) (xy 141.11478 -279.192736)
			(xy 141.314932 -279.192736)
		)
		(stroke
			(width 0)
			(type solid)
		)
		(fill yes)
		(layer "In4.Cu")
		(net "M_J_CPU1_SB_DQ<8>")
	)
	(gr_poly
		(pts
			(xy 141.314932 -278.744426) (xy 141.314932 -278.699976) (xy 141.11478 -278.699976) (xy 141.11478 -278.744426)
			(xy 141.214856 -278.844502)
		)
		(stroke
			(width 0)
			(type solid)
		)
		(fill yes)
		(layer "In4.Cu")
		(net "M_J_CPU1_SB_DQ<7>")
	)
	(gr_poly
		(pts
			(xy 141.314932 -277.528274) (xy 141.214856 -277.428198) (xy 141.11478 -277.528274) (xy 141.11478 -277.572724)
			(xy 141.314932 -277.572724)
		)
		(stroke
			(width 0)
			(type solid)
		)
		(fill yes)
		(layer "In4.Cu")
		(net "M_J_CPU1_SB_DQ<4>")
	)
	(gr_poly
		(pts
			(xy 141.314932 -277.124668) (xy 141.314932 -277.076916) (xy 141.11478 -277.076916) (xy 141.11478 -277.124668)
			(xy 141.214856 -277.22449)
		)
		(stroke
			(width 0)
			(type solid)
		)
		(fill yes)
		(layer "In4.Cu")
		(net "M_J_CPU1_SB_DQS_DP<5>")
	)
	(gr_poly
		(pts
			(xy 141.314932 -275.908008) (xy 141.214856 -275.808186) (xy 141.11478 -275.908008) (xy 141.11478 -275.95576)
			(xy 141.314932 -275.95576)
		)
		(stroke
			(width 0)
			(type solid)
		)
		(fill yes)
		(layer "In4.Cu")
		(net "M_J_CPU1_SB_DQS_DP<0>")
	)
	(gr_poly
		(pts
			(xy 141.314932 -275.504402) (xy 141.314932 -275.459952) (xy 141.11478 -275.459952) (xy 141.11478 -275.504402)
			(xy 141.214856 -275.604478)
		)
		(stroke
			(width 0)
			(type solid)
		)
		(fill yes)
		(layer "In4.Cu")
		(net "M_J_CPU1_SB_DQ<3>")
	)
	(gr_poly
		(pts
			(xy 141.314932 -274.28825) (xy 141.214856 -274.188174) (xy 141.11478 -274.28825) (xy 141.11478 -274.3327)
			(xy 141.314932 -274.3327)
		)
		(stroke
			(width 0)
			(type solid)
		)
		(fill yes)
		(layer "In4.Cu")
		(net "M_J_CPU1_SB_DQ<0>")
	)
	(gr_poly
		(pts
			(xy 141.314932 -273.88439) (xy 141.314932 -273.83994) (xy 141.11478 -273.83994) (xy 141.11478 -273.88439)
			(xy 141.214856 -273.984466)
		)
		(stroke
			(width 0)
			(type solid)
		)
		(fill yes)
		(layer "In4.Cu")
		(net "M_J_CPU1_SB_CB<3>")
	)
	(gr_poly
		(pts
			(xy 141.314932 -272.668238) (xy 141.214856 -272.568162) (xy 141.11478 -272.668238) (xy 141.11478 -272.712688)
			(xy 141.314932 -272.712688)
		)
		(stroke
			(width 0)
			(type solid)
		)
		(fill yes)
		(layer "In4.Cu")
		(net "M_J_CPU1_SB_CB<0>")
	)
	(gr_poly
		(pts
			(xy 141.314932 -272.264632) (xy 141.314932 -272.21688) (xy 141.11478 -272.21688) (xy 141.11478 -272.264632)
			(xy 141.214856 -272.364454)
		)
		(stroke
			(width 0)
			(type solid)
		)
		(fill yes)
		(layer "In4.Cu")
		(net "M_J_CPU1_SB_DQS_DP<4>")
	)
	(gr_poly
		(pts
			(xy 141.314932 -271.047972) (xy 141.214856 -270.94815) (xy 141.11478 -271.047972) (xy 141.11478 -271.095724)
			(xy 141.314932 -271.095724)
		)
		(stroke
			(width 0)
			(type solid)
		)
		(fill yes)
		(layer "In4.Cu")
		(net "M_J_CPU1_SB_DQS_DP<9>")
	)
	(gr_poly
		(pts
			(xy 141.314932 -270.644366) (xy 141.314932 -270.599916) (xy 141.11478 -270.599916) (xy 141.11478 -270.644366)
			(xy 141.214856 -270.744442)
		)
		(stroke
			(width 0)
			(type solid)
		)
		(fill yes)
		(layer "In4.Cu")
		(net "M_J_CPU1_SB_CB<7>")
	)
	(gr_poly
		(pts
			(xy 141.314932 -269.428214) (xy 141.214856 -269.328138) (xy 141.11478 -269.428214) (xy 141.11478 -269.472664)
			(xy 141.314932 -269.472664)
		)
		(stroke
			(width 0)
			(type solid)
		)
		(fill yes)
		(layer "In4.Cu")
		(net "M_J_CPU1_SB_CB<4>")
	)
	(gr_poly
		(pts
			(xy 141.314932 -267.808202) (xy 141.214856 -267.708126) (xy 141.11478 -267.808202) (xy 141.11478 -267.852652)
			(xy 141.314932 -267.852652)
		)
		(stroke
			(width 0)
			(type solid)
		)
		(fill yes)
		(layer "In4.Cu")
		(net "M_J_CPU1_SB_RSP<0>")
	)
	(gr_poly
		(pts
			(xy 141.314932 -265.78433) (xy 141.314932 -265.73988) (xy 141.11478 -265.73988) (xy 141.11478 -265.78433)
			(xy 141.214856 -265.884406)
		)
		(stroke
			(width 0)
			(type solid)
		)
		(fill yes)
		(layer "In4.Cu")
		(net "M_J_CPU1_SB_CS_N<0>")
	)
	(gr_poly
		(pts
			(xy 141.314932 -264.568178) (xy 141.214856 -264.468102) (xy 141.11478 -264.568178) (xy 141.11478 -264.612628)
			(xy 141.314932 -264.612628)
		)
		(stroke
			(width 0)
			(type solid)
		)
		(fill yes)
		(layer "In4.Cu")
		(net "M_J_CPU1_SB_CA<6>")
	)
	(gr_poly
		(pts
			(xy 141.314932 -264.164318) (xy 141.314932 -264.119868) (xy 141.11478 -264.119868) (xy 141.11478 -264.164318)
			(xy 141.214856 -264.264394)
		)
		(stroke
			(width 0)
			(type solid)
		)
		(fill yes)
		(layer "In4.Cu")
		(net "M_J_CPU1_SB_CA<5>")
	)
	(gr_poly
		(pts
			(xy 141.314932 -262.948166) (xy 141.214856 -262.84809) (xy 141.11478 -262.948166) (xy 141.11478 -262.992616)
			(xy 141.314932 -262.992616)
		)
		(stroke
			(width 0)
			(type solid)
		)
		(fill yes)
		(layer "In4.Cu")
		(net "M_J_CPU1_SB_CA<2>")
	)
	(gr_poly
		(pts
			(xy 141.314932 -262.544306) (xy 141.314932 -262.499856) (xy 141.11478 -262.499856) (xy 141.11478 -262.544306)
			(xy 141.214856 -262.644382)
		)
		(stroke
			(width 0)
			(type solid)
		)
		(fill yes)
		(layer "In4.Cu")
		(net "M_J_CPU1_SB_CA<1>")
	)
	(gr_poly
		(pts
			(xy 141.404594 -223.074992) (xy 141.36624 -223.05264) (xy 141.229588 -223.089216) (xy 141.266164 -223.225868)
			(xy 141.304518 -223.24822)
		)
		(stroke
			(width 0)
			(type solid)
		)
		(fill yes)
		(layer "In4.Cu")
		(net "M_J_CPU1_SA_DQ<0>")
	)
	(gr_poly
		(pts
			(xy 141.404848 -224.694242) (xy 141.36624 -224.672144) (xy 141.229588 -224.70872) (xy 141.266164 -224.845372)
			(xy 141.304772 -224.86747)
		)
		(stroke
			(width 0)
			(type solid)
		)
		(fill yes)
		(layer "In4.Cu")
		(net "M_J_CPU1_SA_DQ<1>")
	)
	(gr_poly
		(pts
			(xy 141.407896 -226.31527) (xy 141.366494 -226.291394) (xy 141.229842 -226.32797) (xy 141.266672 -226.464622)
			(xy 141.30782 -226.488498)
		)
		(stroke
			(width 0)
			(type solid)
		)
		(fill yes)
		(layer "In4.Cu")
		(net "M_J_CPU1_SA_DQS_DP<0>")
	)
	(gr_poly
		(pts
			(xy 141.484858 -256.026158) (xy 141.384782 -255.926336) (xy 141.284706 -256.026158) (xy 141.284706 -256.07391)
			(xy 141.484858 -256.07391)
		)
		(stroke
			(width 0)
			(type solid)
		)
		(fill yes)
		(layer "In4.Cu")
		(net "M_J_CPU1_CLK_DP<0>")
	)
	(gr_poly
		(pts
			(xy 141.484858 -255.622552) (xy 141.484858 -255.578102) (xy 141.284706 -255.578102) (xy 141.284706 -255.622552)
			(xy 141.384782 -255.722628)
		)
		(stroke
			(width 0)
			(type solid)
		)
		(fill yes)
		(layer "In4.Cu")
		(net "M_J_CPU1_SA_PAR")
	)
	(gr_poly
		(pts
			(xy 141.484858 -254.4064) (xy 141.384782 -254.306324) (xy 141.284706 -254.4064) (xy 141.284706 -254.45085)
			(xy 141.484858 -254.45085)
		)
		(stroke
			(width 0)
			(type solid)
		)
		(fill yes)
		(layer "In4.Cu")
		(net "M_J_CPU1_SA_CA<4>")
	)
	(gr_poly
		(pts
			(xy 141.484858 -254.00254) (xy 141.484858 -253.95809) (xy 141.284706 -253.95809) (xy 141.284706 -254.00254)
			(xy 141.384782 -254.102616)
		)
		(stroke
			(width 0)
			(type solid)
		)
		(fill yes)
		(layer "In4.Cu")
		(net "M_J_CPU1_SA_CA<3>")
	)
	(gr_poly
		(pts
			(xy 141.484858 -252.786388) (xy 141.384782 -252.686312) (xy 141.284706 -252.786388) (xy 141.284706 -252.830838)
			(xy 141.484858 -252.830838)
		)
		(stroke
			(width 0)
			(type solid)
		)
		(fill yes)
		(layer "In4.Cu")
		(net "M_J_CPU1_SA_CA<0>")
	)
	(gr_poly
		(pts
			(xy 141.484858 -251.166376) (xy 141.384782 -251.0663) (xy 141.284706 -251.166376) (xy 141.284706 -251.210826)
			(xy 141.484858 -251.210826)
		)
		(stroke
			(width 0)
			(type solid)
		)
		(fill yes)
		(layer "In4.Cu")
		(net "M_J_CPU1_SA_CS_N<0>")
	)
	(gr_poly
		(pts
			(xy 141.484858 -250.762516) (xy 141.484858 -250.718066) (xy 141.284706 -250.718066) (xy 141.284706 -250.762516)
			(xy 141.384782 -250.862592)
		)
		(stroke
			(width 0)
			(type solid)
		)
		(fill yes)
		(layer "In4.Cu")
		(net "M_J_CPU1_RESET_N")
	)
	(gr_poly
		(pts
			(xy 141.484858 -249.142504) (xy 141.484858 -249.098054) (xy 141.284706 -249.098054) (xy 141.284706 -249.142504)
			(xy 141.384782 -249.24258)
		)
		(stroke
			(width 0)
			(type solid)
		)
		(fill yes)
		(layer "In4.Cu")
		(net "M_J_CPU1_SA_CB<7>")
	)
	(gr_poly
		(pts
			(xy 141.484858 -247.926352) (xy 141.384782 -247.826276) (xy 141.284706 -247.926352) (xy 141.284706 -247.970802)
			(xy 141.484858 -247.970802)
		)
		(stroke
			(width 0)
			(type solid)
		)
		(fill yes)
		(layer "In4.Cu")
		(net "M_J_CPU1_SA_CB<4>")
	)
	(gr_poly
		(pts
			(xy 141.484858 -247.522746) (xy 141.484858 -247.474994) (xy 141.284706 -247.474994) (xy 141.284706 -247.522746)
			(xy 141.384782 -247.622568)
		)
		(stroke
			(width 0)
			(type solid)
		)
		(fill yes)
		(layer "In4.Cu")
		(net "M_J_CPU1_SA_DQS_DP<9>")
	)
	(gr_poly
		(pts
			(xy 141.484858 -246.306086) (xy 141.384782 -246.206264) (xy 141.284706 -246.306086) (xy 141.284706 -246.353838)
			(xy 141.484858 -246.353838)
		)
		(stroke
			(width 0)
			(type solid)
		)
		(fill yes)
		(layer "In4.Cu")
		(net "M_J_CPU1_SA_DQS_DP<4>")
	)
	(gr_poly
		(pts
			(xy 141.484858 -245.90248) (xy 141.484858 -245.85803) (xy 141.284706 -245.85803) (xy 141.284706 -245.90248)
			(xy 141.384782 -246.002556)
		)
		(stroke
			(width 0)
			(type solid)
		)
		(fill yes)
		(layer "In4.Cu")
		(net "M_J_CPU1_SA_CB<3>")
	)
	(gr_poly
		(pts
			(xy 141.484858 -244.686328) (xy 141.384782 -244.586252) (xy 141.284706 -244.686328) (xy 141.284706 -244.730778)
			(xy 141.484858 -244.730778)
		)
		(stroke
			(width 0)
			(type solid)
		)
		(fill yes)
		(layer "In4.Cu")
		(net "M_J_CPU1_SA_CB<0>")
	)
	(gr_poly
		(pts
			(xy 141.484858 -244.282468) (xy 141.484858 -244.238018) (xy 141.284706 -244.238018) (xy 141.284706 -244.282468)
			(xy 141.384782 -244.382544)
		)
		(stroke
			(width 0)
			(type solid)
		)
		(fill yes)
		(layer "In4.Cu")
		(net "M_J_CPU1_SA_DQ<31>")
	)
	(gr_poly
		(pts
			(xy 141.484858 -243.066316) (xy 141.384782 -242.96624) (xy 141.284706 -243.066316) (xy 141.284706 -243.110766)
			(xy 141.484858 -243.110766)
		)
		(stroke
			(width 0)
			(type solid)
		)
		(fill yes)
		(layer "In4.Cu")
		(net "M_J_CPU1_SA_DQ<28>")
	)
	(gr_poly
		(pts
			(xy 141.484858 -242.66271) (xy 141.484858 -242.614958) (xy 141.284706 -242.614958) (xy 141.284706 -242.66271)
			(xy 141.384782 -242.762532)
		)
		(stroke
			(width 0)
			(type solid)
		)
		(fill yes)
		(layer "In4.Cu")
		(net "M_J_CPU1_SA_DQS_DP<8>")
	)
	(gr_poly
		(pts
			(xy 141.484858 -241.44605) (xy 141.384782 -241.346228) (xy 141.284706 -241.44605) (xy 141.284706 -241.493802)
			(xy 141.484858 -241.493802)
		)
		(stroke
			(width 0)
			(type solid)
		)
		(fill yes)
		(layer "In4.Cu")
		(net "M_J_CPU1_SA_DQS_DP<3>")
	)
	(gr_poly
		(pts
			(xy 141.484858 -241.042444) (xy 141.484858 -240.997994) (xy 141.284706 -240.997994) (xy 141.284706 -241.042444)
			(xy 141.384782 -241.14252)
		)
		(stroke
			(width 0)
			(type solid)
		)
		(fill yes)
		(layer "In4.Cu")
		(net "M_J_CPU1_SA_DQ<27>")
	)
	(gr_poly
		(pts
			(xy 141.484858 -239.826292) (xy 141.384782 -239.726216) (xy 141.284706 -239.826292) (xy 141.284706 -239.870742)
			(xy 141.484858 -239.870742)
		)
		(stroke
			(width 0)
			(type solid)
		)
		(fill yes)
		(layer "In4.Cu")
		(net "M_J_CPU1_SA_DQ<24>")
	)
	(gr_poly
		(pts
			(xy 141.484858 -239.422432) (xy 141.484858 -239.377982) (xy 141.284706 -239.377982) (xy 141.284706 -239.422432)
			(xy 141.384782 -239.522508)
		)
		(stroke
			(width 0)
			(type solid)
		)
		(fill yes)
		(layer "In4.Cu")
		(net "M_J_CPU1_SA_DQ<23>")
	)
	(gr_poly
		(pts
			(xy 141.484858 -238.20628) (xy 141.384782 -238.106204) (xy 141.284706 -238.20628) (xy 141.284706 -238.25073)
			(xy 141.484858 -238.25073)
		)
		(stroke
			(width 0)
			(type solid)
		)
		(fill yes)
		(layer "In4.Cu")
		(net "M_J_CPU1_SA_DQ<20>")
	)
	(gr_poly
		(pts
			(xy 141.484858 -237.802674) (xy 141.484858 -237.754922) (xy 141.284706 -237.754922) (xy 141.284706 -237.802674)
			(xy 141.384782 -237.902496)
		)
		(stroke
			(width 0)
			(type solid)
		)
		(fill yes)
		(layer "In4.Cu")
		(net "M_J_CPU1_SA_DQS_DP<7>")
	)
	(gr_poly
		(pts
			(xy 141.484858 -236.586014) (xy 141.384782 -236.486192) (xy 141.284706 -236.586014) (xy 141.284706 -236.633766)
			(xy 141.484858 -236.633766)
		)
		(stroke
			(width 0)
			(type solid)
		)
		(fill yes)
		(layer "In4.Cu")
		(net "M_J_CPU1_SA_DQS_DP<2>")
	)
	(gr_poly
		(pts
			(xy 141.484858 -236.182408) (xy 141.484858 -236.137958) (xy 141.284706 -236.137958) (xy 141.284706 -236.182408)
			(xy 141.384782 -236.282484)
		)
		(stroke
			(width 0)
			(type solid)
		)
		(fill yes)
		(layer "In4.Cu")
		(net "M_J_CPU1_SA_DQ<19>")
	)
	(gr_poly
		(pts
			(xy 141.484858 -234.966256) (xy 141.384782 -234.86618) (xy 141.284706 -234.966256) (xy 141.284706 -235.010706)
			(xy 141.484858 -235.010706)
		)
		(stroke
			(width 0)
			(type solid)
		)
		(fill yes)
		(layer "In4.Cu")
		(net "M_J_CPU1_SA_DQ<16>")
	)
	(gr_poly
		(pts
			(xy 141.484858 -234.562396) (xy 141.484858 -234.517946) (xy 141.284706 -234.517946) (xy 141.284706 -234.562396)
			(xy 141.384782 -234.662472)
		)
		(stroke
			(width 0)
			(type solid)
		)
		(fill yes)
		(layer "In4.Cu")
		(net "M_J_CPU1_SA_DQ<15>")
	)
	(gr_poly
		(pts
			(xy 141.484858 -233.346244) (xy 141.384782 -233.246168) (xy 141.284706 -233.346244) (xy 141.284706 -233.390694)
			(xy 141.484858 -233.390694)
		)
		(stroke
			(width 0)
			(type solid)
		)
		(fill yes)
		(layer "In4.Cu")
		(net "M_J_CPU1_SA_DQ<12>")
	)
	(gr_poly
		(pts
			(xy 141.484858 -232.942638) (xy 141.484858 -232.894886) (xy 141.284706 -232.894886) (xy 141.284706 -232.942638)
			(xy 141.384782 -233.04246)
		)
		(stroke
			(width 0)
			(type solid)
		)
		(fill yes)
		(layer "In4.Cu")
		(net "M_J_CPU1_SA_DQS_DP<6>")
	)
	(gr_poly
		(pts
			(xy 141.484858 -231.725978) (xy 141.384782 -231.626156) (xy 141.284706 -231.725978) (xy 141.284706 -231.77373)
			(xy 141.484858 -231.77373)
		)
		(stroke
			(width 0)
			(type solid)
		)
		(fill yes)
		(layer "In4.Cu")
		(net "M_J_CPU1_SA_DQS_DP<1>")
	)
	(gr_poly
		(pts
			(xy 141.484858 -231.322626) (xy 141.484858 -231.278176) (xy 141.284706 -231.278176) (xy 141.284706 -231.322626)
			(xy 141.384782 -231.422702)
		)
		(stroke
			(width 0)
			(type solid)
		)
		(fill yes)
		(layer "In4.Cu")
		(net "M_J_CPU1_SA_DQ<11>")
	)
	(gr_poly
		(pts
			(xy 141.484858 -230.10622) (xy 141.384782 -230.006144) (xy 141.284706 -230.10622) (xy 141.284706 -230.15067)
			(xy 141.484858 -230.15067)
		)
		(stroke
			(width 0)
			(type solid)
		)
		(fill yes)
		(layer "In4.Cu")
		(net "M_J_CPU1_SA_DQ<8>")
	)
	(gr_poly
		(pts
			(xy 141.484858 -229.702614) (xy 141.484858 -229.658164) (xy 141.284706 -229.658164) (xy 141.284706 -229.702614)
			(xy 141.384782 -229.80269)
		)
		(stroke
			(width 0)
			(type solid)
		)
		(fill yes)
		(layer "In4.Cu")
		(net "M_J_CPU1_SA_DQ<7>")
	)
	(gr_poly
		(pts
			(xy 141.484858 -228.486462) (xy 141.384782 -228.386386) (xy 141.284706 -228.486462) (xy 141.284706 -228.530912)
			(xy 141.484858 -228.530912)
		)
		(stroke
			(width 0)
			(type solid)
		)
		(fill yes)
		(layer "In4.Cu")
		(net "M_J_CPU1_SA_DQ<4>")
	)
	(gr_poly
		(pts
			(xy 141.484858 -228.082856) (xy 141.484858 -228.035104) (xy 141.284706 -228.035104) (xy 141.284706 -228.082856)
			(xy 141.384782 -228.182678)
		)
		(stroke
			(width 0)
			(type solid)
		)
		(fill yes)
		(layer "In4.Cu")
		(net "M_J_CPU1_SA_DQS_DP<5>")
	)
	(gr_poly
		(pts
			(xy 141.539722 -227.00107) (xy 141.502892 -226.864418) (xy 141.461744 -226.840542) (xy 141.361668 -227.01377)
			(xy 141.40307 -227.037646)
		)
		(stroke
			(width 0)
			(type solid)
		)
		(fill yes)
		(layer "In4.Cu")
		(net "M_J_CPU1_SA_DQS_DN<0>")
	)
	(gr_poly
		(pts
			(xy 141.539976 -225.380296) (xy 141.5034 -225.243644) (xy 141.464792 -225.221546) (xy 141.364716 -225.394774)
			(xy 141.403324 -225.416872)
		)
		(stroke
			(width 0)
			(type solid)
		)
		(fill yes)
		(layer "In4.Cu")
		(net "M_J_CPU1_SA_DQ<3>")
	)
	(gr_poly
		(pts
			(xy 141.541246 -223.758252) (xy 141.50467 -223.6216) (xy 141.466316 -223.599502) (xy 141.36624 -223.77273)
			(xy 141.404848 -223.794828)
		)
		(stroke
			(width 0)
			(type solid)
		)
		(fill yes)
		(layer "In4.Cu")
		(net "M_J_CPU1_SA_DQ<2>")
	)
	(gr_poly
		(pts
			(xy 141.784832 -292.918134) (xy 141.684756 -292.818058) (xy 141.58468 -292.918134) (xy 141.58468 -292.962584)
			(xy 141.784832 -292.962584)
		)
		(stroke
			(width 0)
			(type solid)
		)
		(fill yes)
		(layer "In4.Cu")
		(net "M_J_CPU1_SB_DQ<29>")
	)
	(gr_poly
		(pts
			(xy 141.784832 -292.514274) (xy 141.784832 -292.469824) (xy 141.58468 -292.469824) (xy 141.58468 -292.514274)
			(xy 141.684756 -292.61435)
		)
		(stroke
			(width 0)
			(type solid)
		)
		(fill yes)
		(layer "In4.Cu")
		(net "M_J_CPU1_SB_DQ<30>")
	)
	(gr_poly
		(pts
			(xy 141.784832 -291.297868) (xy 141.684756 -291.198046) (xy 141.58468 -291.297868) (xy 141.58468 -291.34562)
			(xy 141.784832 -291.34562)
		)
		(stroke
			(width 0)
			(type solid)
		)
		(fill yes)
		(layer "In4.Cu")
		(net "M_J_CPU1_SB_DQS_DN<8>")
	)
	(gr_poly
		(pts
			(xy 141.784832 -290.894516) (xy 141.784832 -290.846764) (xy 141.58468 -290.846764) (xy 141.58468 -290.894516)
			(xy 141.684756 -290.994338)
		)
		(stroke
			(width 0)
			(type solid)
		)
		(fill yes)
		(layer "In4.Cu")
		(net "M_J_CPU1_SB_DQS_DN<3>")
	)
	(gr_poly
		(pts
			(xy 141.784832 -289.67811) (xy 141.684756 -289.578034) (xy 141.58468 -289.67811) (xy 141.58468 -289.72256)
			(xy 141.784832 -289.72256)
		)
		(stroke
			(width 0)
			(type solid)
		)
		(fill yes)
		(layer "In4.Cu")
		(net "M_J_CPU1_SB_DQ<25>")
	)
	(gr_poly
		(pts
			(xy 141.784832 -289.27425) (xy 141.784832 -289.2298) (xy 141.58468 -289.2298) (xy 141.58468 -289.27425)
			(xy 141.684756 -289.374326)
		)
		(stroke
			(width 0)
			(type solid)
		)
		(fill yes)
		(layer "In4.Cu")
		(net "M_J_CPU1_SB_DQ<26>")
	)
	(gr_poly
		(pts
			(xy 141.784832 -288.058098) (xy 141.684756 -287.958022) (xy 141.58468 -288.058098) (xy 141.58468 -288.102548)
			(xy 141.784832 -288.102548)
		)
		(stroke
			(width 0)
			(type solid)
		)
		(fill yes)
		(layer "In4.Cu")
		(net "M_J_CPU1_SB_DQ<21>")
	)
	(gr_poly
		(pts
			(xy 141.784832 -287.654492) (xy 141.784832 -287.610042) (xy 141.58468 -287.610042) (xy 141.58468 -287.654492)
			(xy 141.684756 -287.754568)
		)
		(stroke
			(width 0)
			(type solid)
		)
		(fill yes)
		(layer "In4.Cu")
		(net "M_J_CPU1_SB_DQ<22>")
	)
	(gr_poly
		(pts
			(xy 141.784832 -286.438086) (xy 141.684756 -286.33801) (xy 141.58468 -286.438086) (xy 141.58468 -286.485838)
			(xy 141.784832 -286.485838)
		)
		(stroke
			(width 0)
			(type solid)
		)
		(fill yes)
		(layer "In4.Cu")
		(net "M_J_CPU1_SB_DQS_DN<7>")
	)
	(gr_poly
		(pts
			(xy 141.784832 -286.034734) (xy 141.784832 -285.986982) (xy 141.58468 -285.986982) (xy 141.58468 -286.034734)
			(xy 141.684756 -286.134556)
		)
		(stroke
			(width 0)
			(type solid)
		)
		(fill yes)
		(layer "In4.Cu")
		(net "M_J_CPU1_SB_DQS_DN<2>")
	)
	(gr_poly
		(pts
			(xy 141.784832 -284.818328) (xy 141.684756 -284.718252) (xy 141.58468 -284.818328) (xy 141.58468 -284.862778)
			(xy 141.784832 -284.862778)
		)
		(stroke
			(width 0)
			(type solid)
		)
		(fill yes)
		(layer "In4.Cu")
		(net "M_J_CPU1_SB_DQ<17>")
	)
	(gr_poly
		(pts
			(xy 141.784832 -284.414468) (xy 141.784832 -284.370018) (xy 141.58468 -284.370018) (xy 141.58468 -284.414468)
			(xy 141.684756 -284.514544)
		)
		(stroke
			(width 0)
			(type solid)
		)
		(fill yes)
		(layer "In4.Cu")
		(net "M_J_CPU1_SB_DQ<18>")
	)
	(gr_poly
		(pts
			(xy 141.784832 -283.198316) (xy 141.684756 -283.09824) (xy 141.58468 -283.198316) (xy 141.58468 -283.242766)
			(xy 141.784832 -283.242766)
		)
		(stroke
			(width 0)
			(type solid)
		)
		(fill yes)
		(layer "In4.Cu")
		(net "M_J_CPU1_SB_DQ<13>")
	)
	(gr_poly
		(pts
			(xy 141.784832 -282.794456) (xy 141.784832 -282.750006) (xy 141.58468 -282.750006) (xy 141.58468 -282.794456)
			(xy 141.684756 -282.894532)
		)
		(stroke
			(width 0)
			(type solid)
		)
		(fill yes)
		(layer "In4.Cu")
		(net "M_J_CPU1_SB_DQ<14>")
	)
	(gr_poly
		(pts
			(xy 141.784832 -281.57805) (xy 141.684756 -281.478228) (xy 141.58468 -281.57805) (xy 141.58468 -281.625802)
			(xy 141.784832 -281.625802)
		)
		(stroke
			(width 0)
			(type solid)
		)
		(fill yes)
		(layer "In4.Cu")
		(net "M_J_CPU1_SB_DQS_DN<6>")
	)
	(gr_poly
		(pts
			(xy 141.784832 -281.174698) (xy 141.784832 -281.126946) (xy 141.58468 -281.126946) (xy 141.58468 -281.174698)
			(xy 141.684756 -281.27452)
		)
		(stroke
			(width 0)
			(type solid)
		)
		(fill yes)
		(layer "In4.Cu")
		(net "M_J_CPU1_SB_DQS_DN<1>")
	)
	(gr_poly
		(pts
			(xy 141.784832 -279.958292) (xy 141.684756 -279.858216) (xy 141.58468 -279.958292) (xy 141.58468 -280.002742)
			(xy 141.784832 -280.002742)
		)
		(stroke
			(width 0)
			(type solid)
		)
		(fill yes)
		(layer "In4.Cu")
		(net "M_J_CPU1_SB_DQ<9>")
	)
	(gr_poly
		(pts
			(xy 141.784832 -279.554432) (xy 141.784832 -279.509982) (xy 141.58468 -279.509982) (xy 141.58468 -279.554432)
			(xy 141.684756 -279.654508)
		)
		(stroke
			(width 0)
			(type solid)
		)
		(fill yes)
		(layer "In4.Cu")
		(net "M_J_CPU1_SB_DQ<10>")
	)
	(gr_poly
		(pts
			(xy 141.784832 -278.33828) (xy 141.684756 -278.238204) (xy 141.58468 -278.33828) (xy 141.58468 -278.38273)
			(xy 141.784832 -278.38273)
		)
		(stroke
			(width 0)
			(type solid)
		)
		(fill yes)
		(layer "In4.Cu")
		(net "M_J_CPU1_SB_DQ<5>")
	)
	(gr_poly
		(pts
			(xy 141.784832 -277.93442) (xy 141.784832 -277.88997) (xy 141.58468 -277.88997) (xy 141.58468 -277.93442)
			(xy 141.684756 -278.034496)
		)
		(stroke
			(width 0)
			(type solid)
		)
		(fill yes)
		(layer "In4.Cu")
		(net "M_J_CPU1_SB_DQ<6>")
	)
	(gr_poly
		(pts
			(xy 141.784832 -276.718014) (xy 141.684756 -276.618192) (xy 141.58468 -276.718014) (xy 141.58468 -276.765766)
			(xy 141.784832 -276.765766)
		)
		(stroke
			(width 0)
			(type solid)
		)
		(fill yes)
		(layer "In4.Cu")
		(net "M_J_CPU1_SB_DQS_DN<5>")
	)
	(gr_poly
		(pts
			(xy 141.784832 -276.314662) (xy 141.784832 -276.26691) (xy 141.58468 -276.26691) (xy 141.58468 -276.314662)
			(xy 141.684756 -276.414484)
		)
		(stroke
			(width 0)
			(type solid)
		)
		(fill yes)
		(layer "In4.Cu")
		(net "M_J_CPU1_SB_DQS_DN<0>")
	)
	(gr_poly
		(pts
			(xy 141.784832 -275.098256) (xy 141.684756 -274.99818) (xy 141.58468 -275.098256) (xy 141.58468 -275.142706)
			(xy 141.784832 -275.142706)
		)
		(stroke
			(width 0)
			(type solid)
		)
		(fill yes)
		(layer "In4.Cu")
		(net "M_J_CPU1_SB_DQ<1>")
	)
	(gr_poly
		(pts
			(xy 141.784832 -274.694396) (xy 141.784832 -274.649946) (xy 141.58468 -274.649946) (xy 141.58468 -274.694396)
			(xy 141.684756 -274.794472)
		)
		(stroke
			(width 0)
			(type solid)
		)
		(fill yes)
		(layer "In4.Cu")
		(net "M_J_CPU1_SB_DQ<2>")
	)
	(gr_poly
		(pts
			(xy 141.784832 -273.478244) (xy 141.684756 -273.378168) (xy 141.58468 -273.478244) (xy 141.58468 -273.522694)
			(xy 141.784832 -273.522694)
		)
		(stroke
			(width 0)
			(type solid)
		)
		(fill yes)
		(layer "In4.Cu")
		(net "M_J_CPU1_SB_CB<1>")
	)
	(gr_poly
		(pts
			(xy 141.784832 -273.074384) (xy 141.784832 -273.029934) (xy 141.58468 -273.029934) (xy 141.58468 -273.074384)
			(xy 141.684756 -273.17446)
		)
		(stroke
			(width 0)
			(type solid)
		)
		(fill yes)
		(layer "In4.Cu")
		(net "M_J_CPU1_SB_CB<2>")
	)
	(gr_poly
		(pts
			(xy 141.784832 -271.857978) (xy 141.684756 -271.758156) (xy 141.58468 -271.857978) (xy 141.58468 -271.90573)
			(xy 141.784832 -271.90573)
		)
		(stroke
			(width 0)
			(type solid)
		)
		(fill yes)
		(layer "In4.Cu")
		(net "M_J_CPU1_SB_DQS_DN<4>")
	)
	(gr_poly
		(pts
			(xy 141.784832 -271.454626) (xy 141.784832 -271.406874) (xy 141.58468 -271.406874) (xy 141.58468 -271.454626)
			(xy 141.684756 -271.554448)
		)
		(stroke
			(width 0)
			(type solid)
		)
		(fill yes)
		(layer "In4.Cu")
		(net "M_J_CPU1_SB_DQS_DN<9>")
	)
	(gr_poly
		(pts
			(xy 141.784832 -270.23822) (xy 141.684756 -270.138144) (xy 141.58468 -270.23822) (xy 141.58468 -270.28267)
			(xy 141.784832 -270.28267)
		)
		(stroke
			(width 0)
			(type solid)
		)
		(fill yes)
		(layer "In4.Cu")
		(net "M_J_CPU1_SB_CB<5>")
	)
	(gr_poly
		(pts
			(xy 141.784832 -269.83436) (xy 141.784832 -269.78991) (xy 141.58468 -269.78991) (xy 141.58468 -269.83436)
			(xy 141.684756 -269.934436)
		)
		(stroke
			(width 0)
			(type solid)
		)
		(fill yes)
		(layer "In4.Cu")
		(net "M_J_CPU1_SB_CB<6>")
	)
	(gr_poly
		(pts
			(xy 141.784832 -266.998196) (xy 141.684756 -266.89812) (xy 141.58468 -266.998196) (xy 141.58468 -267.042646)
			(xy 141.784832 -267.042646)
		)
		(stroke
			(width 0)
			(type solid)
		)
		(fill yes)
		(layer "In4.Cu")
		(net "M_J_CPU1_SA_RSP<0>")
	)
	(gr_poly
		(pts
			(xy 141.784832 -266.594336) (xy 141.784832 -266.549886) (xy 141.58468 -266.549886) (xy 141.58468 -266.594336)
			(xy 141.684756 -266.694412)
		)
		(stroke
			(width 0)
			(type solid)
		)
		(fill yes)
		(layer "In4.Cu")
		(net "M_J_CPU1_SB_CS_N<1>")
	)
	(gr_poly
		(pts
			(xy 141.784832 -265.378184) (xy 141.684756 -265.278108) (xy 141.58468 -265.378184) (xy 141.58468 -265.422634)
			(xy 141.784832 -265.422634)
		)
		(stroke
			(width 0)
			(type solid)
		)
		(fill yes)
		(layer "In4.Cu")
		(net "M_J_CPU1_SB_PAR")
	)
	(gr_poly
		(pts
			(xy 141.784832 -263.758172) (xy 141.684756 -263.658096) (xy 141.58468 -263.758172) (xy 141.58468 -263.802622)
			(xy 141.784832 -263.802622)
		)
		(stroke
			(width 0)
			(type solid)
		)
		(fill yes)
		(layer "In4.Cu")
		(net "M_J_CPU1_SB_CA<4>")
	)
	(gr_poly
		(pts
			(xy 141.784832 -263.354312) (xy 141.784832 -263.309862) (xy 141.58468 -263.309862) (xy 141.58468 -263.354312)
			(xy 141.684756 -263.454388)
		)
		(stroke
			(width 0)
			(type solid)
		)
		(fill yes)
		(layer "In4.Cu")
		(net "M_J_CPU1_SB_CA<3>")
	)
	(gr_poly
		(pts
			(xy 141.784832 -262.13816) (xy 141.684756 -262.038084) (xy 141.58468 -262.13816) (xy 141.58468 -262.18261)
			(xy 141.784832 -262.18261)
		)
		(stroke
			(width 0)
			(type solid)
		)
		(fill yes)
		(layer "In4.Cu")
		(net "M_J_CPU1_SB_CA<0>")
	)
	(gr_poly
		(pts
			(xy 141.873732 -223.886268) (xy 141.835124 -223.86417) (xy 141.698726 -223.900746) (xy 141.735302 -224.037144)
			(xy 141.773656 -224.059496)
		)
		(stroke
			(width 0)
			(type solid)
		)
		(fill yes)
		(layer "In4.Cu")
		(net "M_J_CPU1_SA_DQ<1>")
	)
	(gr_poly
		(pts
			(xy 141.87678 -227.126546) (xy 141.835632 -227.10267) (xy 141.69898 -227.1395) (xy 141.735556 -227.275898)
			(xy 141.776958 -227.299774)
		)
		(stroke
			(width 0)
			(type solid)
		)
		(fill yes)
		(layer "In4.Cu")
		(net "M_J_CPU1_SA_DQS_DN<5>")
	)
	(gr_poly
		(pts
			(xy 141.87678 -225.506534) (xy 141.835632 -225.482912) (xy 141.69898 -225.519488) (xy 141.735556 -225.655886)
			(xy 141.776958 -225.679762)
		)
		(stroke
			(width 0)
			(type solid)
		)
		(fill yes)
		(layer "In4.Cu")
		(net "M_J_CPU1_SA_DQS_DP<0>")
	)
	(gr_poly
		(pts
			(xy 141.954758 -256.432812) (xy 141.954758 -256.38506) (xy 141.754606 -256.38506) (xy 141.754606 -256.432812)
			(xy 141.854682 -256.532634)
		)
		(stroke
			(width 0)
			(type solid)
		)
		(fill yes)
		(layer "In4.Cu")
		(net "M_J_CPU1_CLK_DN<0>")
	)
	(gr_poly
		(pts
			(xy 141.954758 -255.216406) (xy 141.854682 -255.11633) (xy 141.754606 -255.216406) (xy 141.754606 -255.260856)
			(xy 141.954758 -255.260856)
		)
		(stroke
			(width 0)
			(type solid)
		)
		(fill yes)
		(layer "In4.Cu")
		(net "M_J_CPU1_SA_CA<6>")
	)
	(gr_poly
		(pts
			(xy 141.954758 -254.812546) (xy 141.954758 -254.768096) (xy 141.754606 -254.768096) (xy 141.754606 -254.812546)
			(xy 141.854682 -254.912622)
		)
		(stroke
			(width 0)
			(type solid)
		)
		(fill yes)
		(layer "In4.Cu")
		(net "M_J_CPU1_SA_CA<5>")
	)
	(gr_poly
		(pts
			(xy 141.954758 -253.596394) (xy 141.854682 -253.496318) (xy 141.754606 -253.596394) (xy 141.754606 -253.640844)
			(xy 141.954758 -253.640844)
		)
		(stroke
			(width 0)
			(type solid)
		)
		(fill yes)
		(layer "In4.Cu")
		(net "M_J_CPU1_SA_CA<2>")
	)
	(gr_poly
		(pts
			(xy 141.954758 -253.192534) (xy 141.954758 -253.148084) (xy 141.754606 -253.148084) (xy 141.754606 -253.192534)
			(xy 141.854682 -253.29261)
		)
		(stroke
			(width 0)
			(type solid)
		)
		(fill yes)
		(layer "In4.Cu")
		(net "M_J_CPU1_SA_CA<1>")
	)
	(gr_poly
		(pts
			(xy 141.954758 -251.976382) (xy 141.854682 -251.876306) (xy 141.754606 -251.976382) (xy 141.754606 -252.020832)
			(xy 141.954758 -252.020832)
		)
		(stroke
			(width 0)
			(type solid)
		)
		(fill yes)
		(layer "In4.Cu")
		(net "M_J_CPU1_SA_CS_N<1>")
	)
	(gr_poly
		(pts
			(xy 141.954758 -250.35637) (xy 141.854682 -250.256294) (xy 141.754606 -250.35637) (xy 141.754606 -250.40082)
			(xy 141.954758 -250.40082)
		)
		(stroke
			(width 0)
			(type solid)
		)
		(fill yes)
		(layer "In4.Cu")
		(net "M_J_CPU1_ALERT_R_N")
	)
	(gr_poly
		(pts
			(xy 141.954758 -248.736358) (xy 141.854682 -248.636282) (xy 141.754606 -248.736358) (xy 141.754606 -248.780808)
			(xy 141.954758 -248.780808)
		)
		(stroke
			(width 0)
			(type solid)
		)
		(fill yes)
		(layer "In4.Cu")
		(net "M_J_CPU1_SA_CB<5>")
	)
	(gr_poly
		(pts
			(xy 141.954758 -248.332498) (xy 141.954758 -248.288048) (xy 141.754606 -248.288048) (xy 141.754606 -248.332498)
			(xy 141.854682 -248.432574)
		)
		(stroke
			(width 0)
			(type solid)
		)
		(fill yes)
		(layer "In4.Cu")
		(net "M_J_CPU1_SA_CB<6>")
	)
	(gr_poly
		(pts
			(xy 141.954758 -247.116092) (xy 141.854682 -247.01627) (xy 141.754606 -247.116092) (xy 141.754606 -247.163844)
			(xy 141.954758 -247.163844)
		)
		(stroke
			(width 0)
			(type solid)
		)
		(fill yes)
		(layer "In4.Cu")
		(net "M_J_CPU1_SA_DQS_DN<9>")
	)
	(gr_poly
		(pts
			(xy 141.954758 -246.71274) (xy 141.954758 -246.664988) (xy 141.754606 -246.664988) (xy 141.754606 -246.71274)
			(xy 141.854682 -246.812562)
		)
		(stroke
			(width 0)
			(type solid)
		)
		(fill yes)
		(layer "In4.Cu")
		(net "M_J_CPU1_SA_DQS_DN<4>")
	)
	(gr_poly
		(pts
			(xy 141.954758 -245.496334) (xy 141.854682 -245.396258) (xy 141.754606 -245.496334) (xy 141.754606 -245.540784)
			(xy 141.954758 -245.540784)
		)
		(stroke
			(width 0)
			(type solid)
		)
		(fill yes)
		(layer "In4.Cu")
		(net "M_J_CPU1_SA_CB<1>")
	)
	(gr_poly
		(pts
			(xy 141.954758 -245.092474) (xy 141.954758 -245.048024) (xy 141.754606 -245.048024) (xy 141.754606 -245.092474)
			(xy 141.854682 -245.19255)
		)
		(stroke
			(width 0)
			(type solid)
		)
		(fill yes)
		(layer "In4.Cu")
		(net "M_J_CPU1_SA_CB<2>")
	)
	(gr_poly
		(pts
			(xy 141.954758 -243.876322) (xy 141.854682 -243.776246) (xy 141.754606 -243.876322) (xy 141.754606 -243.920772)
			(xy 141.954758 -243.920772)
		)
		(stroke
			(width 0)
			(type solid)
		)
		(fill yes)
		(layer "In4.Cu")
		(net "M_J_CPU1_SA_DQ<29>")
	)
	(gr_poly
		(pts
			(xy 141.954758 -243.472462) (xy 141.954758 -243.428012) (xy 141.754606 -243.428012) (xy 141.754606 -243.472462)
			(xy 141.854682 -243.572538)
		)
		(stroke
			(width 0)
			(type solid)
		)
		(fill yes)
		(layer "In4.Cu")
		(net "M_J_CPU1_SA_DQ<30>")
	)
	(gr_poly
		(pts
			(xy 141.954758 -242.256056) (xy 141.854682 -242.156234) (xy 141.754606 -242.256056) (xy 141.754606 -242.303808)
			(xy 141.954758 -242.303808)
		)
		(stroke
			(width 0)
			(type solid)
		)
		(fill yes)
		(layer "In4.Cu")
		(net "M_J_CPU1_SA_DQS_DN<8>")
	)
	(gr_poly
		(pts
			(xy 141.954758 -241.852704) (xy 141.954758 -241.804952) (xy 141.754606 -241.804952) (xy 141.754606 -241.852704)
			(xy 141.854682 -241.952526)
		)
		(stroke
			(width 0)
			(type solid)
		)
		(fill yes)
		(layer "In4.Cu")
		(net "M_J_CPU1_SA_DQS_DN<3>")
	)
	(gr_poly
		(pts
			(xy 141.954758 -240.636298) (xy 141.854682 -240.536222) (xy 141.754606 -240.636298) (xy 141.754606 -240.680748)
			(xy 141.954758 -240.680748)
		)
		(stroke
			(width 0)
			(type solid)
		)
		(fill yes)
		(layer "In4.Cu")
		(net "M_J_CPU1_SA_DQ<25>")
	)
	(gr_poly
		(pts
			(xy 141.954758 -240.232438) (xy 141.954758 -240.187988) (xy 141.754606 -240.187988) (xy 141.754606 -240.232438)
			(xy 141.854682 -240.332514)
		)
		(stroke
			(width 0)
			(type solid)
		)
		(fill yes)
		(layer "In4.Cu")
		(net "M_J_CPU1_SA_DQ<26>")
	)
	(gr_poly
		(pts
			(xy 141.954758 -239.016286) (xy 141.854682 -238.91621) (xy 141.754606 -239.016286) (xy 141.754606 -239.060736)
			(xy 141.954758 -239.060736)
		)
		(stroke
			(width 0)
			(type solid)
		)
		(fill yes)
		(layer "In4.Cu")
		(net "M_J_CPU1_SA_DQ<21>")
	)
	(gr_poly
		(pts
			(xy 141.954758 -238.612426) (xy 141.954758 -238.567976) (xy 141.754606 -238.567976) (xy 141.754606 -238.612426)
			(xy 141.854682 -238.712502)
		)
		(stroke
			(width 0)
			(type solid)
		)
		(fill yes)
		(layer "In4.Cu")
		(net "M_J_CPU1_SA_DQ<22>")
	)
	(gr_poly
		(pts
			(xy 141.954758 -237.39602) (xy 141.854682 -237.296198) (xy 141.754606 -237.39602) (xy 141.754606 -237.443772)
			(xy 141.954758 -237.443772)
		)
		(stroke
			(width 0)
			(type solid)
		)
		(fill yes)
		(layer "In4.Cu")
		(net "M_J_CPU1_SA_DQS_DN<7>")
	)
	(gr_poly
		(pts
			(xy 141.954758 -236.992668) (xy 141.954758 -236.944916) (xy 141.754606 -236.944916) (xy 141.754606 -236.992668)
			(xy 141.854682 -237.09249)
		)
		(stroke
			(width 0)
			(type solid)
		)
		(fill yes)
		(layer "In4.Cu")
		(net "M_J_CPU1_SA_DQS_DN<2>")
	)
	(gr_poly
		(pts
			(xy 141.954758 -235.776262) (xy 141.854682 -235.676186) (xy 141.754606 -235.776262) (xy 141.754606 -235.820712)
			(xy 141.954758 -235.820712)
		)
		(stroke
			(width 0)
			(type solid)
		)
		(fill yes)
		(layer "In4.Cu")
		(net "M_J_CPU1_SA_DQ<17>")
	)
	(gr_poly
		(pts
			(xy 141.954758 -235.372402) (xy 141.954758 -235.327952) (xy 141.754606 -235.327952) (xy 141.754606 -235.372402)
			(xy 141.854682 -235.472478)
		)
		(stroke
			(width 0)
			(type solid)
		)
		(fill yes)
		(layer "In4.Cu")
		(net "M_J_CPU1_SA_DQ<18>")
	)
	(gr_poly
		(pts
			(xy 141.954758 -234.15625) (xy 141.854682 -234.056174) (xy 141.754606 -234.15625) (xy 141.754606 -234.2007)
			(xy 141.954758 -234.2007)
		)
		(stroke
			(width 0)
			(type solid)
		)
		(fill yes)
		(layer "In4.Cu")
		(net "M_J_CPU1_SA_DQ<13>")
	)
	(gr_poly
		(pts
			(xy 141.954758 -233.75239) (xy 141.954758 -233.70794) (xy 141.754606 -233.70794) (xy 141.754606 -233.75239)
			(xy 141.854682 -233.852466)
		)
		(stroke
			(width 0)
			(type solid)
		)
		(fill yes)
		(layer "In4.Cu")
		(net "M_J_CPU1_SA_DQ<14>")
	)
	(gr_poly
		(pts
			(xy 141.954758 -232.535984) (xy 141.854682 -232.436162) (xy 141.754606 -232.535984) (xy 141.754606 -232.583736)
			(xy 141.954758 -232.583736)
		)
		(stroke
			(width 0)
			(type solid)
		)
		(fill yes)
		(layer "In4.Cu")
		(net "M_J_CPU1_SA_DQS_DN<6>")
	)
	(gr_poly
		(pts
			(xy 141.954758 -232.132632) (xy 141.954758 -232.08488) (xy 141.754606 -232.08488) (xy 141.754606 -232.132632)
			(xy 141.854682 -232.232454)
		)
		(stroke
			(width 0)
			(type solid)
		)
		(fill yes)
		(layer "In4.Cu")
		(net "M_J_CPU1_SA_DQS_DN<1>")
	)
	(gr_poly
		(pts
			(xy 141.954758 -230.916226) (xy 141.854682 -230.81615) (xy 141.754606 -230.916226) (xy 141.754606 -230.960676)
			(xy 141.954758 -230.960676)
		)
		(stroke
			(width 0)
			(type solid)
		)
		(fill yes)
		(layer "In4.Cu")
		(net "M_J_CPU1_SA_DQ<9>")
	)
	(gr_poly
		(pts
			(xy 141.954758 -230.51262) (xy 141.954758 -230.46817) (xy 141.754606 -230.46817) (xy 141.754606 -230.51262)
			(xy 141.854682 -230.612696)
		)
		(stroke
			(width 0)
			(type solid)
		)
		(fill yes)
		(layer "In4.Cu")
		(net "M_J_CPU1_SA_DQ<10>")
	)
	(gr_poly
		(pts
			(xy 141.954758 -229.296214) (xy 141.854682 -229.196138) (xy 141.754606 -229.296214) (xy 141.754606 -229.340664)
			(xy 141.954758 -229.340664)
		)
		(stroke
			(width 0)
			(type solid)
		)
		(fill yes)
		(layer "In4.Cu")
		(net "M_J_CPU1_SA_DQ<5>")
	)
	(gr_poly
		(pts
			(xy 141.954758 -228.892608) (xy 141.954758 -228.848158) (xy 141.754606 -228.848158) (xy 141.754606 -228.892608)
			(xy 141.854682 -228.992684)
		)
		(stroke
			(width 0)
			(type solid)
		)
		(fill yes)
		(layer "In4.Cu")
		(net "M_J_CPU1_SA_DQ<6>")
	)
	(gr_poly
		(pts
			(xy 142.010638 -227.809552) (xy 141.974062 -227.673154) (xy 141.93266 -227.649278) (xy 141.832838 -227.822506)
			(xy 141.873986 -227.846128)
		)
		(stroke
			(width 0)
			(type solid)
		)
		(fill yes)
		(layer "In4.Cu")
		(net "M_J_CPU1_SA_DQS_DP<5>")
	)
	(gr_poly
		(pts
			(xy 142.010638 -226.18954) (xy 141.974062 -226.053142) (xy 141.93266 -226.029266) (xy 141.832838 -226.202494)
			(xy 141.873986 -226.22637)
		)
		(stroke
			(width 0)
			(type solid)
		)
		(fill yes)
		(layer "In4.Cu")
		(net "M_J_CPU1_SA_DQS_DN<0>")
	)
	(gr_poly
		(pts
			(xy 142.010638 -224.56902) (xy 141.974062 -224.432368) (xy 141.935708 -224.410016) (xy 141.835632 -224.583244)
			(xy 141.87424 -224.605596)
		)
		(stroke
			(width 0)
			(type solid)
		)
		(fill yes)
		(layer "In4.Cu")
		(net "M_J_CPU1_SA_DQ<3>")
	)
	(gr_poly
		(pts
			(xy 142.0114 -222.948246) (xy 141.974824 -222.811594) (xy 141.936216 -222.789496) (xy 141.836394 -222.962724)
			(xy 141.874748 -222.984822)
		)
		(stroke
			(width 0)
			(type solid)
		)
		(fill yes)
		(layer "In4.Cu")
		(net "M_J_CPU1_SA_DQ<2>")
	)
	(gr_poly
		(pts
			(xy 142.254732 -293.32428) (xy 142.254732 -293.27983) (xy 142.05458 -293.27983) (xy 142.05458 -293.32428)
			(xy 142.154656 -293.424356)
		)
		(stroke
			(width 0)
			(type solid)
		)
		(fill yes)
		(layer "In4.Cu")
		(net "M_J_CPU1_SB_DQ<31>")
	)
	(gr_poly
		(pts
			(xy 142.254732 -292.108128) (xy 142.154656 -292.008052) (xy 142.05458 -292.108128) (xy 142.05458 -292.152578)
			(xy 142.254732 -292.152578)
		)
		(stroke
			(width 0)
			(type solid)
		)
		(fill yes)
		(layer "In4.Cu")
		(net "M_J_CPU1_SB_DQ<28>")
	)
	(gr_poly
		(pts
			(xy 142.254732 -291.704522) (xy 142.254732 -291.65677) (xy 142.05458 -291.65677) (xy 142.05458 -291.704522)
			(xy 142.154656 -291.804344)
		)
		(stroke
			(width 0)
			(type solid)
		)
		(fill yes)
		(layer "In4.Cu")
		(net "M_J_CPU1_SB_DQS_DP<8>")
	)
	(gr_poly
		(pts
			(xy 142.254732 -290.487862) (xy 142.154656 -290.38804) (xy 142.05458 -290.487862) (xy 142.05458 -290.535614)
			(xy 142.254732 -290.535614)
		)
		(stroke
			(width 0)
			(type solid)
		)
		(fill yes)
		(layer "In4.Cu")
		(net "M_J_CPU1_SB_DQS_DP<3>")
	)
	(gr_poly
		(pts
			(xy 142.254732 -290.084256) (xy 142.254732 -290.039806) (xy 142.05458 -290.039806) (xy 142.05458 -290.084256)
			(xy 142.154656 -290.184332)
		)
		(stroke
			(width 0)
			(type solid)
		)
		(fill yes)
		(layer "In4.Cu")
		(net "M_J_CPU1_SB_DQ<27>")
	)
	(gr_poly
		(pts
			(xy 142.254732 -288.868104) (xy 142.154656 -288.768028) (xy 142.05458 -288.868104) (xy 142.05458 -288.912554)
			(xy 142.254732 -288.912554)
		)
		(stroke
			(width 0)
			(type solid)
		)
		(fill yes)
		(layer "In4.Cu")
		(net "M_J_CPU1_SB_DQ<24>")
	)
	(gr_poly
		(pts
			(xy 142.254732 -288.464498) (xy 142.254732 -288.420048) (xy 142.05458 -288.420048) (xy 142.05458 -288.464498)
			(xy 142.154656 -288.564574)
		)
		(stroke
			(width 0)
			(type solid)
		)
		(fill yes)
		(layer "In4.Cu")
		(net "M_J_CPU1_SB_DQ<23>")
	)
	(gr_poly
		(pts
			(xy 142.254732 -287.248092) (xy 142.154656 -287.148016) (xy 142.05458 -287.248092) (xy 142.05458 -287.292542)
			(xy 142.254732 -287.292542)
		)
		(stroke
			(width 0)
			(type solid)
		)
		(fill yes)
		(layer "In4.Cu")
		(net "M_J_CPU1_SB_DQ<20>")
	)
	(gr_poly
		(pts
			(xy 142.254732 -286.844486) (xy 142.254732 -286.796734) (xy 142.05458 -286.796734) (xy 142.05458 -286.844486)
			(xy 142.154656 -286.944562)
		)
		(stroke
			(width 0)
			(type solid)
		)
		(fill yes)
		(layer "In4.Cu")
		(net "M_J_CPU1_SB_DQS_DP<7>")
	)
	(gr_poly
		(pts
			(xy 142.254732 -285.62808) (xy 142.154656 -285.528258) (xy 142.05458 -285.62808) (xy 142.05458 -285.675832)
			(xy 142.254732 -285.675832)
		)
		(stroke
			(width 0)
			(type solid)
		)
		(fill yes)
		(layer "In4.Cu")
		(net "M_J_CPU1_SB_DQS_DP<2>")
	)
	(gr_poly
		(pts
			(xy 142.254732 -285.224474) (xy 142.254732 -285.180024) (xy 142.05458 -285.180024) (xy 142.05458 -285.224474)
			(xy 142.154656 -285.32455)
		)
		(stroke
			(width 0)
			(type solid)
		)
		(fill yes)
		(layer "In4.Cu")
		(net "M_J_CPU1_SB_DQ<19>")
	)
	(gr_poly
		(pts
			(xy 142.254732 -284.008322) (xy 142.154656 -283.908246) (xy 142.05458 -284.008322) (xy 142.05458 -284.052772)
			(xy 142.254732 -284.052772)
		)
		(stroke
			(width 0)
			(type solid)
		)
		(fill yes)
		(layer "In4.Cu")
		(net "M_J_CPU1_SB_DQ<16>")
	)
	(gr_poly
		(pts
			(xy 142.254732 -283.604462) (xy 142.254732 -283.560012) (xy 142.05458 -283.560012) (xy 142.05458 -283.604462)
			(xy 142.154656 -283.704538)
		)
		(stroke
			(width 0)
			(type solid)
		)
		(fill yes)
		(layer "In4.Cu")
		(net "M_J_CPU1_SB_DQ<15>")
	)
	(gr_poly
		(pts
			(xy 142.254732 -282.38831) (xy 142.154656 -282.288234) (xy 142.05458 -282.38831) (xy 142.05458 -282.43276)
			(xy 142.254732 -282.43276)
		)
		(stroke
			(width 0)
			(type solid)
		)
		(fill yes)
		(layer "In4.Cu")
		(net "M_J_CPU1_SB_DQ<12>")
	)
	(gr_poly
		(pts
			(xy 142.254732 -281.984704) (xy 142.254732 -281.936952) (xy 142.05458 -281.936952) (xy 142.05458 -281.984704)
			(xy 142.154656 -282.084526)
		)
		(stroke
			(width 0)
			(type solid)
		)
		(fill yes)
		(layer "In4.Cu")
		(net "M_J_CPU1_SB_DQS_DP<6>")
	)
	(gr_poly
		(pts
			(xy 142.254732 -280.768044) (xy 142.154656 -280.668222) (xy 142.05458 -280.768044) (xy 142.05458 -280.815796)
			(xy 142.254732 -280.815796)
		)
		(stroke
			(width 0)
			(type solid)
		)
		(fill yes)
		(layer "In4.Cu")
		(net "M_J_CPU1_SB_DQS_DP<1>")
	)
	(gr_poly
		(pts
			(xy 142.254732 -280.364438) (xy 142.254732 -280.319988) (xy 142.05458 -280.319988) (xy 142.05458 -280.364438)
			(xy 142.154656 -280.464514)
		)
		(stroke
			(width 0)
			(type solid)
		)
		(fill yes)
		(layer "In4.Cu")
		(net "M_J_CPU1_SB_DQ<11>")
	)
	(gr_poly
		(pts
			(xy 142.254732 -279.148286) (xy 142.154656 -279.04821) (xy 142.05458 -279.148286) (xy 142.05458 -279.192736)
			(xy 142.254732 -279.192736)
		)
		(stroke
			(width 0)
			(type solid)
		)
		(fill yes)
		(layer "In4.Cu")
		(net "M_J_CPU1_SB_DQ<8>")
	)
	(gr_poly
		(pts
			(xy 142.254732 -278.744426) (xy 142.254732 -278.699976) (xy 142.05458 -278.699976) (xy 142.05458 -278.744426)
			(xy 142.154656 -278.844502)
		)
		(stroke
			(width 0)
			(type solid)
		)
		(fill yes)
		(layer "In4.Cu")
		(net "M_J_CPU1_SB_DQ<7>")
	)
	(gr_poly
		(pts
			(xy 142.254732 -277.528274) (xy 142.154656 -277.428198) (xy 142.05458 -277.528274) (xy 142.05458 -277.572724)
			(xy 142.254732 -277.572724)
		)
		(stroke
			(width 0)
			(type solid)
		)
		(fill yes)
		(layer "In4.Cu")
		(net "M_J_CPU1_SB_DQ<4>")
	)
	(gr_poly
		(pts
			(xy 142.254732 -277.124668) (xy 142.254732 -277.076916) (xy 142.05458 -277.076916) (xy 142.05458 -277.124668)
			(xy 142.154656 -277.22449)
		)
		(stroke
			(width 0)
			(type solid)
		)
		(fill yes)
		(layer "In4.Cu")
		(net "M_J_CPU1_SB_DQS_DP<5>")
	)
	(gr_poly
		(pts
			(xy 142.254732 -275.908008) (xy 142.154656 -275.808186) (xy 142.05458 -275.908008) (xy 142.05458 -275.95576)
			(xy 142.254732 -275.95576)
		)
		(stroke
			(width 0)
			(type solid)
		)
		(fill yes)
		(layer "In4.Cu")
		(net "M_J_CPU1_SB_DQS_DP<0>")
	)
	(gr_poly
		(pts
			(xy 142.254732 -275.504402) (xy 142.254732 -275.459952) (xy 142.05458 -275.459952) (xy 142.05458 -275.504402)
			(xy 142.154656 -275.604478)
		)
		(stroke
			(width 0)
			(type solid)
		)
		(fill yes)
		(layer "In4.Cu")
		(net "M_J_CPU1_SB_DQ<3>")
	)
	(gr_poly
		(pts
			(xy 142.254732 -274.28825) (xy 142.154656 -274.188174) (xy 142.05458 -274.28825) (xy 142.05458 -274.3327)
			(xy 142.254732 -274.3327)
		)
		(stroke
			(width 0)
			(type solid)
		)
		(fill yes)
		(layer "In4.Cu")
		(net "M_J_CPU1_SB_DQ<0>")
	)
	(gr_poly
		(pts
			(xy 142.254732 -273.88439) (xy 142.254732 -273.83994) (xy 142.05458 -273.83994) (xy 142.05458 -273.88439)
			(xy 142.154656 -273.984466)
		)
		(stroke
			(width 0)
			(type solid)
		)
		(fill yes)
		(layer "In4.Cu")
		(net "M_J_CPU1_SB_CB<3>")
	)
	(gr_poly
		(pts
			(xy 142.254732 -272.668238) (xy 142.154656 -272.568162) (xy 142.05458 -272.668238) (xy 142.05458 -272.712688)
			(xy 142.254732 -272.712688)
		)
		(stroke
			(width 0)
			(type solid)
		)
		(fill yes)
		(layer "In4.Cu")
		(net "M_J_CPU1_SB_CB<0>")
	)
	(gr_poly
		(pts
			(xy 142.254732 -272.264632) (xy 142.254732 -272.21688) (xy 142.05458 -272.21688) (xy 142.05458 -272.264632)
			(xy 142.154656 -272.364454)
		)
		(stroke
			(width 0)
			(type solid)
		)
		(fill yes)
		(layer "In4.Cu")
		(net "M_J_CPU1_SB_DQS_DP<4>")
	)
	(gr_poly
		(pts
			(xy 142.254732 -271.047972) (xy 142.154656 -270.94815) (xy 142.05458 -271.047972) (xy 142.05458 -271.095724)
			(xy 142.254732 -271.095724)
		)
		(stroke
			(width 0)
			(type solid)
		)
		(fill yes)
		(layer "In4.Cu")
		(net "M_J_CPU1_SB_DQS_DP<9>")
	)
	(gr_poly
		(pts
			(xy 142.254732 -270.644366) (xy 142.254732 -270.599916) (xy 142.05458 -270.599916) (xy 142.05458 -270.644366)
			(xy 142.154656 -270.744442)
		)
		(stroke
			(width 0)
			(type solid)
		)
		(fill yes)
		(layer "In4.Cu")
		(net "M_J_CPU1_SB_CB<7>")
	)
	(gr_poly
		(pts
			(xy 142.254732 -269.428214) (xy 142.154656 -269.328138) (xy 142.05458 -269.428214) (xy 142.05458 -269.472664)
			(xy 142.254732 -269.472664)
		)
		(stroke
			(width 0)
			(type solid)
		)
		(fill yes)
		(layer "In4.Cu")
		(net "M_J_CPU1_SB_CB<4>")
	)
	(gr_poly
		(pts
			(xy 142.254732 -267.808202) (xy 142.154656 -267.708126) (xy 142.05458 -267.808202) (xy 142.05458 -267.852652)
			(xy 142.254732 -267.852652)
		)
		(stroke
			(width 0)
			(type solid)
		)
		(fill yes)
		(layer "In4.Cu")
		(net "M_J_CPU1_SB_RSP<0>")
	)
	(gr_poly
		(pts
			(xy 142.254732 -265.78433) (xy 142.254732 -265.73988) (xy 142.05458 -265.73988) (xy 142.05458 -265.78433)
			(xy 142.154656 -265.884406)
		)
		(stroke
			(width 0)
			(type solid)
		)
		(fill yes)
		(layer "In4.Cu")
		(net "M_J_CPU1_SB_CS_N<0>")
	)
	(gr_poly
		(pts
			(xy 142.254732 -264.568178) (xy 142.154656 -264.468102) (xy 142.05458 -264.568178) (xy 142.05458 -264.612628)
			(xy 142.254732 -264.612628)
		)
		(stroke
			(width 0)
			(type solid)
		)
		(fill yes)
		(layer "In4.Cu")
		(net "M_J_CPU1_SB_CA<6>")
	)
	(gr_poly
		(pts
			(xy 142.254732 -264.164318) (xy 142.254732 -264.119868) (xy 142.05458 -264.119868) (xy 142.05458 -264.164318)
			(xy 142.154656 -264.264394)
		)
		(stroke
			(width 0)
			(type solid)
		)
		(fill yes)
		(layer "In4.Cu")
		(net "M_J_CPU1_SB_CA<5>")
	)
	(gr_poly
		(pts
			(xy 142.254732 -262.948166) (xy 142.154656 -262.84809) (xy 142.05458 -262.948166) (xy 142.05458 -262.992616)
			(xy 142.254732 -262.992616)
		)
		(stroke
			(width 0)
			(type solid)
		)
		(fill yes)
		(layer "In4.Cu")
		(net "M_J_CPU1_SB_CA<2>")
	)
	(gr_poly
		(pts
			(xy 142.254732 -262.544306) (xy 142.254732 -262.499856) (xy 142.05458 -262.499856) (xy 142.05458 -262.544306)
			(xy 142.154656 -262.644382)
		)
		(stroke
			(width 0)
			(type solid)
		)
		(fill yes)
		(layer "In4.Cu")
		(net "M_J_CPU1_SB_CA<1>")
	)
	(gr_poly
		(pts
			(xy 142.343886 -227.93579) (xy 142.305278 -227.913438) (xy 142.168626 -227.950014) (xy 142.205456 -228.086666)
			(xy 142.24381 -228.109018)
		)
		(stroke
			(width 0)
			(type solid)
		)
		(fill yes)
		(layer "In4.Cu")
		(net "M_J_CPU1_SA_DQ<4>")
	)
	(gr_poly
		(pts
			(xy 142.345918 -223.072706) (xy 142.30731 -223.050608) (xy 142.170912 -223.087184) (xy 142.207488 -223.223836)
			(xy 142.245842 -223.245934)
		)
		(stroke
			(width 0)
			(type solid)
		)
		(fill yes)
		(layer "In4.Cu")
		(net "M_J_CPU1_SA_DQ<1>")
	)
	(gr_poly
		(pts
			(xy 142.34668 -226.31654) (xy 142.305532 -226.292664) (xy 142.16888 -226.329494) (xy 142.205456 -226.465892)
			(xy 142.246858 -226.489768)
		)
		(stroke
			(width 0)
			(type solid)
		)
		(fill yes)
		(layer "In4.Cu")
		(net "M_J_CPU1_SA_DQS_DN<5>")
	)
	(gr_poly
		(pts
			(xy 142.34668 -224.696528) (xy 142.305532 -224.672652) (xy 142.16888 -224.709482) (xy 142.205456 -224.84588)
			(xy 142.246858 -224.869756)
		)
		(stroke
			(width 0)
			(type solid)
		)
		(fill yes)
		(layer "In4.Cu")
		(net "M_J_CPU1_SA_DQS_DP<0>")
	)
	(gr_poly
		(pts
			(xy 142.424912 -256.026158) (xy 142.324836 -255.926336) (xy 142.22476 -256.026158) (xy 142.22476 -256.07391)
			(xy 142.424912 -256.07391)
		)
		(stroke
			(width 0)
			(type solid)
		)
		(fill yes)
		(layer "In4.Cu")
		(net "M_J_CPU1_CLK_DP<0>")
	)
	(gr_poly
		(pts
			(xy 142.424912 -255.622552) (xy 142.424912 -255.578102) (xy 142.22476 -255.578102) (xy 142.22476 -255.622552)
			(xy 142.324836 -255.722628)
		)
		(stroke
			(width 0)
			(type solid)
		)
		(fill yes)
		(layer "In4.Cu")
		(net "M_J_CPU1_SA_PAR")
	)
	(gr_poly
		(pts
			(xy 142.424912 -254.4064) (xy 142.324836 -254.306324) (xy 142.22476 -254.4064) (xy 142.22476 -254.45085)
			(xy 142.424912 -254.45085)
		)
		(stroke
			(width 0)
			(type solid)
		)
		(fill yes)
		(layer "In4.Cu")
		(net "M_J_CPU1_SA_CA<4>")
	)
	(gr_poly
		(pts
			(xy 142.424912 -254.00254) (xy 142.424912 -253.95809) (xy 142.22476 -253.95809) (xy 142.22476 -254.00254)
			(xy 142.324836 -254.102616)
		)
		(stroke
			(width 0)
			(type solid)
		)
		(fill yes)
		(layer "In4.Cu")
		(net "M_J_CPU1_SA_CA<3>")
	)
	(gr_poly
		(pts
			(xy 142.424912 -252.786388) (xy 142.324836 -252.686312) (xy 142.22476 -252.786388) (xy 142.22476 -252.830838)
			(xy 142.424912 -252.830838)
		)
		(stroke
			(width 0)
			(type solid)
		)
		(fill yes)
		(layer "In4.Cu")
		(net "M_J_CPU1_SA_CA<0>")
	)
	(gr_poly
		(pts
			(xy 142.424912 -251.166376) (xy 142.324836 -251.0663) (xy 142.22476 -251.166376) (xy 142.22476 -251.210826)
			(xy 142.424912 -251.210826)
		)
		(stroke
			(width 0)
			(type solid)
		)
		(fill yes)
		(layer "In4.Cu")
		(net "M_J_CPU1_SA_CS_N<0>")
	)
	(gr_poly
		(pts
			(xy 142.424912 -250.762516) (xy 142.424912 -250.718066) (xy 142.22476 -250.718066) (xy 142.22476 -250.762516)
			(xy 142.324836 -250.862592)
		)
		(stroke
			(width 0)
			(type solid)
		)
		(fill yes)
		(layer "In4.Cu")
		(net "M_J_CPU1_RESET_N")
	)
	(gr_poly
		(pts
			(xy 142.424912 -249.142504) (xy 142.424912 -249.098054) (xy 142.22476 -249.098054) (xy 142.22476 -249.142504)
			(xy 142.324836 -249.24258)
		)
		(stroke
			(width 0)
			(type solid)
		)
		(fill yes)
		(layer "In4.Cu")
		(net "M_J_CPU1_SA_CB<7>")
	)
	(gr_poly
		(pts
			(xy 142.424912 -247.926352) (xy 142.324836 -247.826276) (xy 142.22476 -247.926352) (xy 142.22476 -247.970802)
			(xy 142.424912 -247.970802)
		)
		(stroke
			(width 0)
			(type solid)
		)
		(fill yes)
		(layer "In4.Cu")
		(net "M_J_CPU1_SA_CB<4>")
	)
	(gr_poly
		(pts
			(xy 142.424912 -247.522746) (xy 142.424912 -247.474994) (xy 142.22476 -247.474994) (xy 142.22476 -247.522746)
			(xy 142.324836 -247.622568)
		)
		(stroke
			(width 0)
			(type solid)
		)
		(fill yes)
		(layer "In4.Cu")
		(net "M_J_CPU1_SA_DQS_DP<9>")
	)
	(gr_poly
		(pts
			(xy 142.424912 -246.306086) (xy 142.324836 -246.206264) (xy 142.22476 -246.306086) (xy 142.22476 -246.353838)
			(xy 142.424912 -246.353838)
		)
		(stroke
			(width 0)
			(type solid)
		)
		(fill yes)
		(layer "In4.Cu")
		(net "M_J_CPU1_SA_DQS_DP<4>")
	)
	(gr_poly
		(pts
			(xy 142.424912 -245.90248) (xy 142.424912 -245.85803) (xy 142.22476 -245.85803) (xy 142.22476 -245.90248)
			(xy 142.324836 -246.002556)
		)
		(stroke
			(width 0)
			(type solid)
		)
		(fill yes)
		(layer "In4.Cu")
		(net "M_J_CPU1_SA_CB<3>")
	)
	(gr_poly
		(pts
			(xy 142.424912 -244.686328) (xy 142.324836 -244.586252) (xy 142.22476 -244.686328) (xy 142.22476 -244.730778)
			(xy 142.424912 -244.730778)
		)
		(stroke
			(width 0)
			(type solid)
		)
		(fill yes)
		(layer "In4.Cu")
		(net "M_J_CPU1_SA_CB<0>")
	)
	(gr_poly
		(pts
			(xy 142.424912 -244.282468) (xy 142.424912 -244.238018) (xy 142.22476 -244.238018) (xy 142.22476 -244.282468)
			(xy 142.324836 -244.382544)
		)
		(stroke
			(width 0)
			(type solid)
		)
		(fill yes)
		(layer "In4.Cu")
		(net "M_J_CPU1_SA_DQ<31>")
	)
	(gr_poly
		(pts
			(xy 142.424912 -243.066316) (xy 142.324836 -242.96624) (xy 142.22476 -243.066316) (xy 142.22476 -243.110766)
			(xy 142.424912 -243.110766)
		)
		(stroke
			(width 0)
			(type solid)
		)
		(fill yes)
		(layer "In4.Cu")
		(net "M_J_CPU1_SA_DQ<28>")
	)
	(gr_poly
		(pts
			(xy 142.424912 -242.66271) (xy 142.424912 -242.614958) (xy 142.22476 -242.614958) (xy 142.22476 -242.66271)
			(xy 142.324836 -242.762532)
		)
		(stroke
			(width 0)
			(type solid)
		)
		(fill yes)
		(layer "In4.Cu")
		(net "M_J_CPU1_SA_DQS_DP<8>")
	)
	(gr_poly
		(pts
			(xy 142.424912 -241.44605) (xy 142.324836 -241.346228) (xy 142.22476 -241.44605) (xy 142.22476 -241.493802)
			(xy 142.424912 -241.493802)
		)
		(stroke
			(width 0)
			(type solid)
		)
		(fill yes)
		(layer "In4.Cu")
		(net "M_J_CPU1_SA_DQS_DP<3>")
	)
	(gr_poly
		(pts
			(xy 142.424912 -241.042444) (xy 142.424912 -240.997994) (xy 142.22476 -240.997994) (xy 142.22476 -241.042444)
			(xy 142.324836 -241.14252)
		)
		(stroke
			(width 0)
			(type solid)
		)
		(fill yes)
		(layer "In4.Cu")
		(net "M_J_CPU1_SA_DQ<27>")
	)
	(gr_poly
		(pts
			(xy 142.424912 -239.826292) (xy 142.324836 -239.726216) (xy 142.22476 -239.826292) (xy 142.22476 -239.870742)
			(xy 142.424912 -239.870742)
		)
		(stroke
			(width 0)
			(type solid)
		)
		(fill yes)
		(layer "In4.Cu")
		(net "M_J_CPU1_SA_DQ<24>")
	)
	(gr_poly
		(pts
			(xy 142.424912 -239.422432) (xy 142.424912 -239.377982) (xy 142.22476 -239.377982) (xy 142.22476 -239.422432)
			(xy 142.324836 -239.522508)
		)
		(stroke
			(width 0)
			(type solid)
		)
		(fill yes)
		(layer "In4.Cu")
		(net "M_J_CPU1_SA_DQ<23>")
	)
	(gr_poly
		(pts
			(xy 142.424912 -238.20628) (xy 142.324836 -238.106204) (xy 142.22476 -238.20628) (xy 142.22476 -238.25073)
			(xy 142.424912 -238.25073)
		)
		(stroke
			(width 0)
			(type solid)
		)
		(fill yes)
		(layer "In4.Cu")
		(net "M_J_CPU1_SA_DQ<20>")
	)
	(gr_poly
		(pts
			(xy 142.424912 -237.802674) (xy 142.424912 -237.754922) (xy 142.22476 -237.754922) (xy 142.22476 -237.802674)
			(xy 142.324836 -237.902496)
		)
		(stroke
			(width 0)
			(type solid)
		)
		(fill yes)
		(layer "In4.Cu")
		(net "M_J_CPU1_SA_DQS_DP<7>")
	)
	(gr_poly
		(pts
			(xy 142.424912 -236.586014) (xy 142.324836 -236.486192) (xy 142.22476 -236.586014) (xy 142.22476 -236.633766)
			(xy 142.424912 -236.633766)
		)
		(stroke
			(width 0)
			(type solid)
		)
		(fill yes)
		(layer "In4.Cu")
		(net "M_J_CPU1_SA_DQS_DP<2>")
	)
	(gr_poly
		(pts
			(xy 142.424912 -236.182408) (xy 142.424912 -236.137958) (xy 142.22476 -236.137958) (xy 142.22476 -236.182408)
			(xy 142.324836 -236.282484)
		)
		(stroke
			(width 0)
			(type solid)
		)
		(fill yes)
		(layer "In4.Cu")
		(net "M_J_CPU1_SA_DQ<19>")
	)
	(gr_poly
		(pts
			(xy 142.424912 -234.966256) (xy 142.324836 -234.86618) (xy 142.22476 -234.966256) (xy 142.22476 -235.010706)
			(xy 142.424912 -235.010706)
		)
		(stroke
			(width 0)
			(type solid)
		)
		(fill yes)
		(layer "In4.Cu")
		(net "M_J_CPU1_SA_DQ<16>")
	)
	(gr_poly
		(pts
			(xy 142.424912 -234.562396) (xy 142.424912 -234.517946) (xy 142.22476 -234.517946) (xy 142.22476 -234.562396)
			(xy 142.324836 -234.662472)
		)
		(stroke
			(width 0)
			(type solid)
		)
		(fill yes)
		(layer "In4.Cu")
		(net "M_J_CPU1_SA_DQ<15>")
	)
	(gr_poly
		(pts
			(xy 142.424912 -233.346244) (xy 142.324836 -233.246168) (xy 142.22476 -233.346244) (xy 142.22476 -233.390694)
			(xy 142.424912 -233.390694)
		)
		(stroke
			(width 0)
			(type solid)
		)
		(fill yes)
		(layer "In4.Cu")
		(net "M_J_CPU1_SA_DQ<12>")
	)
	(gr_poly
		(pts
			(xy 142.424912 -232.942638) (xy 142.424912 -232.894886) (xy 142.22476 -232.894886) (xy 142.22476 -232.942638)
			(xy 142.324836 -233.04246)
		)
		(stroke
			(width 0)
			(type solid)
		)
		(fill yes)
		(layer "In4.Cu")
		(net "M_J_CPU1_SA_DQS_DP<6>")
	)
	(gr_poly
		(pts
			(xy 142.424912 -231.725978) (xy 142.324836 -231.626156) (xy 142.22476 -231.725978) (xy 142.22476 -231.77373)
			(xy 142.424912 -231.77373)
		)
		(stroke
			(width 0)
			(type solid)
		)
		(fill yes)
		(layer "In4.Cu")
		(net "M_J_CPU1_SA_DQS_DP<1>")
	)
	(gr_poly
		(pts
			(xy 142.424912 -231.322626) (xy 142.424912 -231.278176) (xy 142.22476 -231.278176) (xy 142.22476 -231.322626)
			(xy 142.324836 -231.422702)
		)
		(stroke
			(width 0)
			(type solid)
		)
		(fill yes)
		(layer "In4.Cu")
		(net "M_J_CPU1_SA_DQ<11>")
	)
	(gr_poly
		(pts
			(xy 142.424912 -230.10622) (xy 142.324836 -230.006144) (xy 142.22476 -230.10622) (xy 142.22476 -230.15067)
			(xy 142.424912 -230.15067)
		)
		(stroke
			(width 0)
			(type solid)
		)
		(fill yes)
		(layer "In4.Cu")
		(net "M_J_CPU1_SA_DQ<8>")
	)
	(gr_poly
		(pts
			(xy 142.424912 -229.702614) (xy 142.424912 -229.658164) (xy 142.22476 -229.658164) (xy 142.22476 -229.702614)
			(xy 142.324836 -229.80269)
		)
		(stroke
			(width 0)
			(type solid)
		)
		(fill yes)
		(layer "In4.Cu")
		(net "M_J_CPU1_SA_DQ<7>")
	)
	(gr_poly
		(pts
			(xy 142.479776 -223.761046) (xy 142.4432 -223.624394) (xy 142.404592 -223.602296) (xy 142.30477 -223.77527)
			(xy 142.343124 -223.797622)
		)
		(stroke
			(width 0)
			(type solid)
		)
		(fill yes)
		(layer "In4.Cu")
		(net "M_J_CPU1_SA_DQ<3>")
	)
	(gr_poly
		(pts
			(xy 142.480538 -228.61905) (xy 142.443962 -228.482398) (xy 142.405608 -228.460046) (xy 142.305532 -228.633274)
			(xy 142.34414 -228.655626)
		)
		(stroke
			(width 0)
			(type solid)
		)
		(fill yes)
		(layer "In4.Cu")
		(net "M_J_CPU1_SA_DQ<6>")
	)
	(gr_poly
		(pts
			(xy 142.480538 -226.999546) (xy 142.443962 -226.863148) (xy 142.40256 -226.839272) (xy 142.302738 -227.0125)
			(xy 142.343886 -227.036376)
		)
		(stroke
			(width 0)
			(type solid)
		)
		(fill yes)
		(layer "In4.Cu")
		(net "M_J_CPU1_SA_DQS_DP<5>")
	)
	(gr_poly
		(pts
			(xy 142.480538 -225.379534) (xy 142.443962 -225.243136) (xy 142.40256 -225.21926) (xy 142.302738 -225.392488)
			(xy 142.343886 -225.416364)
		)
		(stroke
			(width 0)
			(type solid)
		)
		(fill yes)
		(layer "In4.Cu")
		(net "M_J_CPU1_SA_DQS_DN<0>")
	)
	(gr_poly
		(pts
			(xy 142.724886 -292.918134) (xy 142.62481 -292.818058) (xy 142.524734 -292.918134) (xy 142.524734 -292.962584)
			(xy 142.724886 -292.962584)
		)
		(stroke
			(width 0)
			(type solid)
		)
		(fill yes)
		(layer "In4.Cu")
		(net "M_J_CPU1_SB_DQ<29>")
	)
	(gr_poly
		(pts
			(xy 142.724886 -292.514274) (xy 142.724886 -292.469824) (xy 142.524734 -292.469824) (xy 142.524734 -292.514274)
			(xy 142.62481 -292.61435)
		)
		(stroke
			(width 0)
			(type solid)
		)
		(fill yes)
		(layer "In4.Cu")
		(net "M_J_CPU1_SB_DQ<30>")
	)
	(gr_poly
		(pts
			(xy 142.724886 -291.297868) (xy 142.62481 -291.198046) (xy 142.524734 -291.297868) (xy 142.524734 -291.34562)
			(xy 142.724886 -291.34562)
		)
		(stroke
			(width 0)
			(type solid)
		)
		(fill yes)
		(layer "In4.Cu")
		(net "M_J_CPU1_SB_DQS_DN<8>")
	)
	(gr_poly
		(pts
			(xy 142.724886 -290.894516) (xy 142.724886 -290.846764) (xy 142.524734 -290.846764) (xy 142.524734 -290.894516)
			(xy 142.62481 -290.994338)
		)
		(stroke
			(width 0)
			(type solid)
		)
		(fill yes)
		(layer "In4.Cu")
		(net "M_J_CPU1_SB_DQS_DN<3>")
	)
	(gr_poly
		(pts
			(xy 142.724886 -289.67811) (xy 142.62481 -289.578034) (xy 142.524734 -289.67811) (xy 142.524734 -289.72256)
			(xy 142.724886 -289.72256)
		)
		(stroke
			(width 0)
			(type solid)
		)
		(fill yes)
		(layer "In4.Cu")
		(net "M_J_CPU1_SB_DQ<25>")
	)
	(gr_poly
		(pts
			(xy 142.724886 -289.27425) (xy 142.724886 -289.2298) (xy 142.524734 -289.2298) (xy 142.524734 -289.27425)
			(xy 142.62481 -289.374326)
		)
		(stroke
			(width 0)
			(type solid)
		)
		(fill yes)
		(layer "In4.Cu")
		(net "M_J_CPU1_SB_DQ<26>")
	)
	(gr_poly
		(pts
			(xy 142.724886 -288.058098) (xy 142.62481 -287.958022) (xy 142.524734 -288.058098) (xy 142.524734 -288.102548)
			(xy 142.724886 -288.102548)
		)
		(stroke
			(width 0)
			(type solid)
		)
		(fill yes)
		(layer "In4.Cu")
		(net "M_J_CPU1_SB_DQ<21>")
	)
	(gr_poly
		(pts
			(xy 142.724886 -287.654492) (xy 142.724886 -287.610042) (xy 142.524734 -287.610042) (xy 142.524734 -287.654492)
			(xy 142.62481 -287.754568)
		)
		(stroke
			(width 0)
			(type solid)
		)
		(fill yes)
		(layer "In4.Cu")
		(net "M_J_CPU1_SB_DQ<22>")
	)
	(gr_poly
		(pts
			(xy 142.724886 -286.438086) (xy 142.62481 -286.33801) (xy 142.524734 -286.438086) (xy 142.524734 -286.485838)
			(xy 142.724886 -286.485838)
		)
		(stroke
			(width 0)
			(type solid)
		)
		(fill yes)
		(layer "In4.Cu")
		(net "M_J_CPU1_SB_DQS_DN<7>")
	)
	(gr_poly
		(pts
			(xy 142.724886 -286.034734) (xy 142.724886 -285.986982) (xy 142.524734 -285.986982) (xy 142.524734 -286.034734)
			(xy 142.62481 -286.134556)
		)
		(stroke
			(width 0)
			(type solid)
		)
		(fill yes)
		(layer "In4.Cu")
		(net "M_J_CPU1_SB_DQS_DN<2>")
	)
	(gr_poly
		(pts
			(xy 142.724886 -284.818328) (xy 142.62481 -284.718252) (xy 142.524734 -284.818328) (xy 142.524734 -284.862778)
			(xy 142.724886 -284.862778)
		)
		(stroke
			(width 0)
			(type solid)
		)
		(fill yes)
		(layer "In4.Cu")
		(net "M_J_CPU1_SB_DQ<17>")
	)
	(gr_poly
		(pts
			(xy 142.724886 -284.414468) (xy 142.724886 -284.370018) (xy 142.524734 -284.370018) (xy 142.524734 -284.414468)
			(xy 142.62481 -284.514544)
		)
		(stroke
			(width 0)
			(type solid)
		)
		(fill yes)
		(layer "In4.Cu")
		(net "M_J_CPU1_SB_DQ<18>")
	)
	(gr_poly
		(pts
			(xy 142.724886 -283.198316) (xy 142.62481 -283.09824) (xy 142.524734 -283.198316) (xy 142.524734 -283.242766)
			(xy 142.724886 -283.242766)
		)
		(stroke
			(width 0)
			(type solid)
		)
		(fill yes)
		(layer "In4.Cu")
		(net "M_J_CPU1_SB_DQ<13>")
	)
	(gr_poly
		(pts
			(xy 142.724886 -282.794456) (xy 142.724886 -282.750006) (xy 142.524734 -282.750006) (xy 142.524734 -282.794456)
			(xy 142.62481 -282.894532)
		)
		(stroke
			(width 0)
			(type solid)
		)
		(fill yes)
		(layer "In4.Cu")
		(net "M_J_CPU1_SB_DQ<14>")
	)
	(gr_poly
		(pts
			(xy 142.724886 -281.57805) (xy 142.62481 -281.478228) (xy 142.524734 -281.57805) (xy 142.524734 -281.625802)
			(xy 142.724886 -281.625802)
		)
		(stroke
			(width 0)
			(type solid)
		)
		(fill yes)
		(layer "In4.Cu")
		(net "M_J_CPU1_SB_DQS_DN<6>")
	)
	(gr_poly
		(pts
			(xy 142.724886 -281.174698) (xy 142.724886 -281.126946) (xy 142.524734 -281.126946) (xy 142.524734 -281.174698)
			(xy 142.62481 -281.27452)
		)
		(stroke
			(width 0)
			(type solid)
		)
		(fill yes)
		(layer "In4.Cu")
		(net "M_J_CPU1_SB_DQS_DN<1>")
	)
	(gr_poly
		(pts
			(xy 142.724886 -279.958292) (xy 142.62481 -279.858216) (xy 142.524734 -279.958292) (xy 142.524734 -280.002742)
			(xy 142.724886 -280.002742)
		)
		(stroke
			(width 0)
			(type solid)
		)
		(fill yes)
		(layer "In4.Cu")
		(net "M_J_CPU1_SB_DQ<9>")
	)
	(gr_poly
		(pts
			(xy 142.724886 -279.554432) (xy 142.724886 -279.509982) (xy 142.524734 -279.509982) (xy 142.524734 -279.554432)
			(xy 142.62481 -279.654508)
		)
		(stroke
			(width 0)
			(type solid)
		)
		(fill yes)
		(layer "In4.Cu")
		(net "M_J_CPU1_SB_DQ<10>")
	)
	(gr_poly
		(pts
			(xy 142.724886 -278.33828) (xy 142.62481 -278.238204) (xy 142.524734 -278.33828) (xy 142.524734 -278.38273)
			(xy 142.724886 -278.38273)
		)
		(stroke
			(width 0)
			(type solid)
		)
		(fill yes)
		(layer "In4.Cu")
		(net "M_J_CPU1_SB_DQ<5>")
	)
	(gr_poly
		(pts
			(xy 142.724886 -277.93442) (xy 142.724886 -277.88997) (xy 142.524734 -277.88997) (xy 142.524734 -277.93442)
			(xy 142.62481 -278.034496)
		)
		(stroke
			(width 0)
			(type solid)
		)
		(fill yes)
		(layer "In4.Cu")
		(net "M_J_CPU1_SB_DQ<6>")
	)
	(gr_poly
		(pts
			(xy 142.724886 -276.718014) (xy 142.62481 -276.618192) (xy 142.524734 -276.718014) (xy 142.524734 -276.765766)
			(xy 142.724886 -276.765766)
		)
		(stroke
			(width 0)
			(type solid)
		)
		(fill yes)
		(layer "In4.Cu")
		(net "M_J_CPU1_SB_DQS_DN<5>")
	)
	(gr_poly
		(pts
			(xy 142.724886 -276.314662) (xy 142.724886 -276.26691) (xy 142.524734 -276.26691) (xy 142.524734 -276.314662)
			(xy 142.62481 -276.414484)
		)
		(stroke
			(width 0)
			(type solid)
		)
		(fill yes)
		(layer "In4.Cu")
		(net "M_J_CPU1_SB_DQS_DN<0>")
	)
	(gr_poly
		(pts
			(xy 142.724886 -275.098256) (xy 142.62481 -274.99818) (xy 142.524734 -275.098256) (xy 142.524734 -275.142706)
			(xy 142.724886 -275.142706)
		)
		(stroke
			(width 0)
			(type solid)
		)
		(fill yes)
		(layer "In4.Cu")
		(net "M_J_CPU1_SB_DQ<1>")
	)
	(gr_poly
		(pts
			(xy 142.724886 -274.694396) (xy 142.724886 -274.649946) (xy 142.524734 -274.649946) (xy 142.524734 -274.694396)
			(xy 142.62481 -274.794472)
		)
		(stroke
			(width 0)
			(type solid)
		)
		(fill yes)
		(layer "In4.Cu")
		(net "M_J_CPU1_SB_DQ<2>")
	)
	(gr_poly
		(pts
			(xy 142.724886 -273.478244) (xy 142.62481 -273.378168) (xy 142.524734 -273.478244) (xy 142.524734 -273.522694)
			(xy 142.724886 -273.522694)
		)
		(stroke
			(width 0)
			(type solid)
		)
		(fill yes)
		(layer "In4.Cu")
		(net "M_J_CPU1_SB_CB<1>")
	)
	(gr_poly
		(pts
			(xy 142.724886 -273.074384) (xy 142.724886 -273.029934) (xy 142.524734 -273.029934) (xy 142.524734 -273.074384)
			(xy 142.62481 -273.17446)
		)
		(stroke
			(width 0)
			(type solid)
		)
		(fill yes)
		(layer "In4.Cu")
		(net "M_J_CPU1_SB_CB<2>")
	)
	(gr_poly
		(pts
			(xy 142.724886 -271.857978) (xy 142.62481 -271.758156) (xy 142.524734 -271.857978) (xy 142.524734 -271.90573)
			(xy 142.724886 -271.90573)
		)
		(stroke
			(width 0)
			(type solid)
		)
		(fill yes)
		(layer "In4.Cu")
		(net "M_J_CPU1_SB_DQS_DN<4>")
	)
	(gr_poly
		(pts
			(xy 142.724886 -271.454626) (xy 142.724886 -271.406874) (xy 142.524734 -271.406874) (xy 142.524734 -271.454626)
			(xy 142.62481 -271.554448)
		)
		(stroke
			(width 0)
			(type solid)
		)
		(fill yes)
		(layer "In4.Cu")
		(net "M_J_CPU1_SB_DQS_DN<9>")
	)
	(gr_poly
		(pts
			(xy 142.724886 -270.23822) (xy 142.62481 -270.138144) (xy 142.524734 -270.23822) (xy 142.524734 -270.28267)
			(xy 142.724886 -270.28267)
		)
		(stroke
			(width 0)
			(type solid)
		)
		(fill yes)
		(layer "In4.Cu")
		(net "M_J_CPU1_SB_CB<5>")
	)
	(gr_poly
		(pts
			(xy 142.724886 -269.83436) (xy 142.724886 -269.78991) (xy 142.524734 -269.78991) (xy 142.524734 -269.83436)
			(xy 142.62481 -269.934436)
		)
		(stroke
			(width 0)
			(type solid)
		)
		(fill yes)
		(layer "In4.Cu")
		(net "M_J_CPU1_SB_CB<6>")
	)
	(gr_poly
		(pts
			(xy 142.724886 -266.998196) (xy 142.62481 -266.89812) (xy 142.524734 -266.998196) (xy 142.524734 -267.042646)
			(xy 142.724886 -267.042646)
		)
		(stroke
			(width 0)
			(type solid)
		)
		(fill yes)
		(layer "In4.Cu")
		(net "M_J_CPU1_SA_RSP<0>")
	)
	(gr_poly
		(pts
			(xy 142.724886 -266.594336) (xy 142.724886 -266.549886) (xy 142.524734 -266.549886) (xy 142.524734 -266.594336)
			(xy 142.62481 -266.694412)
		)
		(stroke
			(width 0)
			(type solid)
		)
		(fill yes)
		(layer "In4.Cu")
		(net "M_J_CPU1_SB_CS_N<1>")
	)
	(gr_poly
		(pts
			(xy 142.724886 -265.378184) (xy 142.62481 -265.278108) (xy 142.524734 -265.378184) (xy 142.524734 -265.422634)
			(xy 142.724886 -265.422634)
		)
		(stroke
			(width 0)
			(type solid)
		)
		(fill yes)
		(layer "In4.Cu")
		(net "M_J_CPU1_SB_PAR")
	)
	(gr_poly
		(pts
			(xy 142.724886 -263.758172) (xy 142.62481 -263.658096) (xy 142.524734 -263.758172) (xy 142.524734 -263.802622)
			(xy 142.724886 -263.802622)
		)
		(stroke
			(width 0)
			(type solid)
		)
		(fill yes)
		(layer "In4.Cu")
		(net "M_J_CPU1_SB_CA<4>")
	)
	(gr_poly
		(pts
			(xy 142.724886 -263.354312) (xy 142.724886 -263.309862) (xy 142.524734 -263.309862) (xy 142.524734 -263.354312)
			(xy 142.62481 -263.454388)
		)
		(stroke
			(width 0)
			(type solid)
		)
		(fill yes)
		(layer "In4.Cu")
		(net "M_J_CPU1_SB_CA<3>")
	)
	(gr_poly
		(pts
			(xy 142.724886 -262.13816) (xy 142.62481 -262.038084) (xy 142.524734 -262.13816) (xy 142.524734 -262.18261)
			(xy 142.724886 -262.18261)
		)
		(stroke
			(width 0)
			(type solid)
		)
		(fill yes)
		(layer "In4.Cu")
		(net "M_J_CPU1_SB_CA<0>")
	)
	(gr_poly
		(pts
			(xy 142.814802 -228.744272) (xy 142.776194 -228.722174) (xy 142.639542 -228.75875) (xy 142.676118 -228.895402)
			(xy 142.714726 -228.9175)
		)
		(stroke
			(width 0)
			(type solid)
		)
		(fill yes)
		(layer "In4.Cu")
		(net "M_J_CPU1_SA_DQ<5>")
	)
	(gr_poly
		(pts
			(xy 142.814802 -227.12426) (xy 142.776194 -227.102162) (xy 142.639542 -227.138738) (xy 142.676118 -227.27539)
			(xy 142.714726 -227.297488)
		)
		(stroke
			(width 0)
			(type solid)
		)
		(fill yes)
		(layer "In4.Cu")
		(net "M_J_CPU1_SA_DQ<4>")
	)
	(gr_poly
		(pts
			(xy 142.81531 -222.263462) (xy 142.776956 -222.241364) (xy 142.640304 -222.27794) (xy 142.67688 -222.414592)
			(xy 142.715488 -222.43669)
		)
		(stroke
			(width 0)
			(type solid)
		)
		(fill yes)
		(layer "In4.Cu")
		(net "M_J_CPU1_SA_DQ<1>")
	)
	(gr_poly
		(pts
			(xy 142.87119 -236.99216) (xy 142.87119 -236.944408) (xy 142.671038 -236.944408) (xy 142.671038 -236.99216)
			(xy 142.771114 -237.092236)
		)
		(stroke
			(width 0)
			(type solid)
		)
		(fill yes)
		(layer "In4.Cu")
		(net "M_J_CPU1_SA_DQS_DN<2>")
	)
	(gr_poly
		(pts
			(xy 142.894812 -256.432812) (xy 142.894812 -256.38506) (xy 142.69466 -256.38506) (xy 142.69466 -256.432812)
			(xy 142.794736 -256.532634)
		)
		(stroke
			(width 0)
			(type solid)
		)
		(fill yes)
		(layer "In4.Cu")
		(net "M_J_CPU1_CLK_DN<0>")
	)
	(gr_poly
		(pts
			(xy 142.894812 -255.216406) (xy 142.794736 -255.11633) (xy 142.69466 -255.216406) (xy 142.69466 -255.260856)
			(xy 142.894812 -255.260856)
		)
		(stroke
			(width 0)
			(type solid)
		)
		(fill yes)
		(layer "In4.Cu")
		(net "M_J_CPU1_SA_CA<6>")
	)
	(gr_poly
		(pts
			(xy 142.894812 -254.812546) (xy 142.894812 -254.768096) (xy 142.69466 -254.768096) (xy 142.69466 -254.812546)
			(xy 142.794736 -254.912622)
		)
		(stroke
			(width 0)
			(type solid)
		)
		(fill yes)
		(layer "In4.Cu")
		(net "M_J_CPU1_SA_CA<5>")
	)
	(gr_poly
		(pts
			(xy 142.894812 -253.596394) (xy 142.794736 -253.496318) (xy 142.69466 -253.596394) (xy 142.69466 -253.640844)
			(xy 142.894812 -253.640844)
		)
		(stroke
			(width 0)
			(type solid)
		)
		(fill yes)
		(layer "In4.Cu")
		(net "M_J_CPU1_SA_CA<2>")
	)
	(gr_poly
		(pts
			(xy 142.894812 -253.192534) (xy 142.894812 -253.148084) (xy 142.69466 -253.148084) (xy 142.69466 -253.192534)
			(xy 142.794736 -253.29261)
		)
		(stroke
			(width 0)
			(type solid)
		)
		(fill yes)
		(layer "In4.Cu")
		(net "M_J_CPU1_SA_CA<1>")
	)
	(gr_poly
		(pts
			(xy 142.894812 -251.976382) (xy 142.794736 -251.876306) (xy 142.69466 -251.976382) (xy 142.69466 -252.020832)
			(xy 142.894812 -252.020832)
		)
		(stroke
			(width 0)
			(type solid)
		)
		(fill yes)
		(layer "In4.Cu")
		(net "M_J_CPU1_SA_CS_N<1>")
	)
	(gr_poly
		(pts
			(xy 142.894812 -250.35637) (xy 142.794736 -250.256294) (xy 142.69466 -250.35637) (xy 142.69466 -250.40082)
			(xy 142.894812 -250.40082)
		)
		(stroke
			(width 0)
			(type solid)
		)
		(fill yes)
		(layer "In4.Cu")
		(net "M_J_CPU1_ALERT_R_N")
	)
	(gr_poly
		(pts
			(xy 142.894812 -248.736358) (xy 142.794736 -248.636282) (xy 142.69466 -248.736358) (xy 142.69466 -248.780808)
			(xy 142.894812 -248.780808)
		)
		(stroke
			(width 0)
			(type solid)
		)
		(fill yes)
		(layer "In4.Cu")
		(net "M_J_CPU1_SA_CB<5>")
	)
	(gr_poly
		(pts
			(xy 142.894812 -248.332498) (xy 142.894812 -248.288048) (xy 142.69466 -248.288048) (xy 142.69466 -248.332498)
			(xy 142.794736 -248.432574)
		)
		(stroke
			(width 0)
			(type solid)
		)
		(fill yes)
		(layer "In4.Cu")
		(net "M_J_CPU1_SA_CB<6>")
	)
	(gr_poly
		(pts
			(xy 142.894812 -247.116092) (xy 142.794736 -247.01627) (xy 142.69466 -247.116092) (xy 142.69466 -247.163844)
			(xy 142.894812 -247.163844)
		)
		(stroke
			(width 0)
			(type solid)
		)
		(fill yes)
		(layer "In4.Cu")
		(net "M_J_CPU1_SA_DQS_DN<9>")
	)
	(gr_poly
		(pts
			(xy 142.894812 -246.71274) (xy 142.894812 -246.664988) (xy 142.69466 -246.664988) (xy 142.69466 -246.71274)
			(xy 142.794736 -246.812562)
		)
		(stroke
			(width 0)
			(type solid)
		)
		(fill yes)
		(layer "In4.Cu")
		(net "M_J_CPU1_SA_DQS_DN<4>")
	)
	(gr_poly
		(pts
			(xy 142.894812 -245.496334) (xy 142.794736 -245.396258) (xy 142.69466 -245.496334) (xy 142.69466 -245.540784)
			(xy 142.894812 -245.540784)
		)
		(stroke
			(width 0)
			(type solid)
		)
		(fill yes)
		(layer "In4.Cu")
		(net "M_J_CPU1_SA_CB<1>")
	)
	(gr_poly
		(pts
			(xy 142.894812 -245.092474) (xy 142.894812 -245.048024) (xy 142.69466 -245.048024) (xy 142.69466 -245.092474)
			(xy 142.794736 -245.19255)
		)
		(stroke
			(width 0)
			(type solid)
		)
		(fill yes)
		(layer "In4.Cu")
		(net "M_J_CPU1_SA_CB<2>")
	)
	(gr_poly
		(pts
			(xy 142.894812 -243.876322) (xy 142.794736 -243.776246) (xy 142.69466 -243.876322) (xy 142.69466 -243.920772)
			(xy 142.894812 -243.920772)
		)
		(stroke
			(width 0)
			(type solid)
		)
		(fill yes)
		(layer "In4.Cu")
		(net "M_J_CPU1_SA_DQ<29>")
	)
	(gr_poly
		(pts
			(xy 142.894812 -243.472462) (xy 142.894812 -243.428012) (xy 142.69466 -243.428012) (xy 142.69466 -243.472462)
			(xy 142.794736 -243.572538)
		)
		(stroke
			(width 0)
			(type solid)
		)
		(fill yes)
		(layer "In4.Cu")
		(net "M_J_CPU1_SA_DQ<30>")
	)
	(gr_poly
		(pts
			(xy 142.894812 -242.256056) (xy 142.794736 -242.156234) (xy 142.69466 -242.256056) (xy 142.69466 -242.303808)
			(xy 142.894812 -242.303808)
		)
		(stroke
			(width 0)
			(type solid)
		)
		(fill yes)
		(layer "In4.Cu")
		(net "M_J_CPU1_SA_DQS_DN<8>")
	)
	(gr_poly
		(pts
			(xy 142.894812 -241.852704) (xy 142.894812 -241.804952) (xy 142.69466 -241.804952) (xy 142.69466 -241.852704)
			(xy 142.794736 -241.952526)
		)
		(stroke
			(width 0)
			(type solid)
		)
		(fill yes)
		(layer "In4.Cu")
		(net "M_J_CPU1_SA_DQS_DN<3>")
	)
	(gr_poly
		(pts
			(xy 142.894812 -240.636298) (xy 142.794736 -240.536222) (xy 142.69466 -240.636298) (xy 142.69466 -240.680748)
			(xy 142.894812 -240.680748)
		)
		(stroke
			(width 0)
			(type solid)
		)
		(fill yes)
		(layer "In4.Cu")
		(net "M_J_CPU1_SA_DQ<25>")
	)
	(gr_poly
		(pts
			(xy 142.894812 -240.232438) (xy 142.894812 -240.187988) (xy 142.69466 -240.187988) (xy 142.69466 -240.232438)
			(xy 142.794736 -240.332514)
		)
		(stroke
			(width 0)
			(type solid)
		)
		(fill yes)
		(layer "In4.Cu")
		(net "M_J_CPU1_SA_DQ<26>")
	)
	(gr_poly
		(pts
			(xy 142.894812 -239.016286) (xy 142.794736 -238.91621) (xy 142.69466 -239.016286) (xy 142.69466 -239.060736)
			(xy 142.894812 -239.060736)
		)
		(stroke
			(width 0)
			(type solid)
		)
		(fill yes)
		(layer "In4.Cu")
		(net "M_J_CPU1_SA_DQ<21>")
	)
	(gr_poly
		(pts
			(xy 142.894812 -238.612426) (xy 142.894812 -238.567976) (xy 142.69466 -238.567976) (xy 142.69466 -238.612426)
			(xy 142.794736 -238.712502)
		)
		(stroke
			(width 0)
			(type solid)
		)
		(fill yes)
		(layer "In4.Cu")
		(net "M_J_CPU1_SA_DQ<22>")
	)
	(gr_poly
		(pts
			(xy 142.894812 -237.39602) (xy 142.794736 -237.296198) (xy 142.69466 -237.39602) (xy 142.69466 -237.443772)
			(xy 142.894812 -237.443772)
		)
		(stroke
			(width 0)
			(type solid)
		)
		(fill yes)
		(layer "In4.Cu")
		(net "M_J_CPU1_SA_DQS_DN<7>")
	)
	(gr_poly
		(pts
			(xy 142.894812 -235.776262) (xy 142.794736 -235.676186) (xy 142.69466 -235.776262) (xy 142.69466 -235.820712)
			(xy 142.894812 -235.820712)
		)
		(stroke
			(width 0)
			(type solid)
		)
		(fill yes)
		(layer "In4.Cu")
		(net "M_J_CPU1_SA_DQ<17>")
	)
	(gr_poly
		(pts
			(xy 142.894812 -235.372402) (xy 142.894812 -235.327952) (xy 142.69466 -235.327952) (xy 142.69466 -235.372402)
			(xy 142.794736 -235.472478)
		)
		(stroke
			(width 0)
			(type solid)
		)
		(fill yes)
		(layer "In4.Cu")
		(net "M_J_CPU1_SA_DQ<18>")
	)
	(gr_poly
		(pts
			(xy 142.894812 -234.15625) (xy 142.794736 -234.056174) (xy 142.69466 -234.15625) (xy 142.69466 -234.2007)
			(xy 142.894812 -234.2007)
		)
		(stroke
			(width 0)
			(type solid)
		)
		(fill yes)
		(layer "In4.Cu")
		(net "M_J_CPU1_SA_DQ<13>")
	)
	(gr_poly
		(pts
			(xy 142.894812 -233.75239) (xy 142.894812 -233.70794) (xy 142.69466 -233.70794) (xy 142.69466 -233.75239)
			(xy 142.794736 -233.852466)
		)
		(stroke
			(width 0)
			(type solid)
		)
		(fill yes)
		(layer "In4.Cu")
		(net "M_J_CPU1_SA_DQ<14>")
	)
	(gr_poly
		(pts
			(xy 142.894812 -232.535984) (xy 142.794736 -232.436162) (xy 142.69466 -232.535984) (xy 142.69466 -232.583736)
			(xy 142.894812 -232.583736)
		)
		(stroke
			(width 0)
			(type solid)
		)
		(fill yes)
		(layer "In4.Cu")
		(net "M_J_CPU1_SA_DQS_DN<6>")
	)
	(gr_poly
		(pts
			(xy 142.894812 -232.132632) (xy 142.894812 -232.08488) (xy 142.69466 -232.08488) (xy 142.69466 -232.132632)
			(xy 142.794736 -232.232454)
		)
		(stroke
			(width 0)
			(type solid)
		)
		(fill yes)
		(layer "In4.Cu")
		(net "M_J_CPU1_SA_DQS_DN<1>")
	)
	(gr_poly
		(pts
			(xy 142.894812 -230.916226) (xy 142.794736 -230.81615) (xy 142.69466 -230.916226) (xy 142.69466 -230.960676)
			(xy 142.894812 -230.960676)
		)
		(stroke
			(width 0)
			(type solid)
		)
		(fill yes)
		(layer "In4.Cu")
		(net "M_J_CPU1_SA_DQ<9>")
	)
	(gr_poly
		(pts
			(xy 142.894812 -230.51262) (xy 142.894812 -230.46817) (xy 142.69466 -230.46817) (xy 142.69466 -230.51262)
			(xy 142.794736 -230.612696)
		)
		(stroke
			(width 0)
			(type solid)
		)
		(fill yes)
		(layer "In4.Cu")
		(net "M_J_CPU1_SA_DQ<10>")
	)
	(gr_poly
		(pts
			(xy 142.949422 -222.951802) (xy 142.912846 -222.81515) (xy 142.874492 -222.793052) (xy 142.774416 -222.96628)
			(xy 142.81277 -222.988378)
		)
		(stroke
			(width 0)
			(type solid)
		)
		(fill yes)
		(layer "In4.Cu")
		(net "M_J_CPU1_SA_DQ<3>")
	)
	(gr_poly
		(pts
			(xy 142.94993 -229.430326) (xy 142.913354 -229.293674) (xy 142.874746 -229.271576) (xy 142.77467 -229.444804)
			(xy 142.813278 -229.466902)
		)
		(stroke
			(width 0)
			(type solid)
		)
		(fill yes)
		(layer "In4.Cu")
		(net "M_J_CPU1_SA_DQ<7>")
	)
	(gr_poly
		(pts
			(xy 142.94993 -227.810314) (xy 142.913354 -227.673662) (xy 142.874746 -227.651564) (xy 142.77467 -227.824792)
			(xy 142.813278 -227.84689)
		)
		(stroke
			(width 0)
			(type solid)
		)
		(fill yes)
		(layer "In4.Cu")
		(net "M_J_CPU1_SA_DQ<6>")
	)
	(gr_poly
		(pts
			(xy 143.194786 -293.32428) (xy 143.194786 -293.27983) (xy 142.994634 -293.27983) (xy 142.994634 -293.32428)
			(xy 143.09471 -293.424356)
		)
		(stroke
			(width 0)
			(type solid)
		)
		(fill yes)
		(layer "In4.Cu")
		(net "M_J_CPU1_SB_DQ<31>")
	)
	(gr_poly
		(pts
			(xy 143.194786 -292.108128) (xy 143.09471 -292.008052) (xy 142.994634 -292.108128) (xy 142.994634 -292.152578)
			(xy 143.194786 -292.152578)
		)
		(stroke
			(width 0)
			(type solid)
		)
		(fill yes)
		(layer "In4.Cu")
		(net "M_J_CPU1_SB_DQ<28>")
	)
	(gr_poly
		(pts
			(xy 143.194786 -291.704522) (xy 143.194786 -291.65677) (xy 142.994634 -291.65677) (xy 142.994634 -291.704522)
			(xy 143.09471 -291.804344)
		)
		(stroke
			(width 0)
			(type solid)
		)
		(fill yes)
		(layer "In4.Cu")
		(net "M_J_CPU1_SB_DQS_DP<8>")
	)
	(gr_poly
		(pts
			(xy 143.194786 -290.487862) (xy 143.09471 -290.38804) (xy 142.994634 -290.487862) (xy 142.994634 -290.535614)
			(xy 143.194786 -290.535614)
		)
		(stroke
			(width 0)
			(type solid)
		)
		(fill yes)
		(layer "In4.Cu")
		(net "M_J_CPU1_SB_DQS_DP<3>")
	)
	(gr_poly
		(pts
			(xy 143.194786 -290.084256) (xy 143.194786 -290.039806) (xy 142.994634 -290.039806) (xy 142.994634 -290.084256)
			(xy 143.09471 -290.184332)
		)
		(stroke
			(width 0)
			(type solid)
		)
		(fill yes)
		(layer "In4.Cu")
		(net "M_J_CPU1_SB_DQ<27>")
	)
	(gr_poly
		(pts
			(xy 143.194786 -288.868104) (xy 143.09471 -288.768028) (xy 142.994634 -288.868104) (xy 142.994634 -288.912554)
			(xy 143.194786 -288.912554)
		)
		(stroke
			(width 0)
			(type solid)
		)
		(fill yes)
		(layer "In4.Cu")
		(net "M_J_CPU1_SB_DQ<24>")
	)
	(gr_poly
		(pts
			(xy 143.194786 -288.464498) (xy 143.194786 -288.420048) (xy 142.994634 -288.420048) (xy 142.994634 -288.464498)
			(xy 143.09471 -288.564574)
		)
		(stroke
			(width 0)
			(type solid)
		)
		(fill yes)
		(layer "In4.Cu")
		(net "M_J_CPU1_SB_DQ<23>")
	)
	(gr_poly
		(pts
			(xy 143.194786 -287.248092) (xy 143.09471 -287.148016) (xy 142.994634 -287.248092) (xy 142.994634 -287.292542)
			(xy 143.194786 -287.292542)
		)
		(stroke
			(width 0)
			(type solid)
		)
		(fill yes)
		(layer "In4.Cu")
		(net "M_J_CPU1_SB_DQ<20>")
	)
	(gr_poly
		(pts
			(xy 143.194786 -286.844486) (xy 143.194786 -286.796734) (xy 142.994634 -286.796734) (xy 142.994634 -286.844486)
			(xy 143.09471 -286.944562)
		)
		(stroke
			(width 0)
			(type solid)
		)
		(fill yes)
		(layer "In4.Cu")
		(net "M_J_CPU1_SB_DQS_DP<7>")
	)
	(gr_poly
		(pts
			(xy 143.194786 -285.62808) (xy 143.09471 -285.528258) (xy 142.994634 -285.62808) (xy 142.994634 -285.675832)
			(xy 143.194786 -285.675832)
		)
		(stroke
			(width 0)
			(type solid)
		)
		(fill yes)
		(layer "In4.Cu")
		(net "M_J_CPU1_SB_DQS_DP<2>")
	)
	(gr_poly
		(pts
			(xy 143.194786 -285.224474) (xy 143.194786 -285.180024) (xy 142.994634 -285.180024) (xy 142.994634 -285.224474)
			(xy 143.09471 -285.32455)
		)
		(stroke
			(width 0)
			(type solid)
		)
		(fill yes)
		(layer "In4.Cu")
		(net "M_J_CPU1_SB_DQ<19>")
	)
	(gr_poly
		(pts
			(xy 143.194786 -284.008322) (xy 143.09471 -283.908246) (xy 142.994634 -284.008322) (xy 142.994634 -284.052772)
			(xy 143.194786 -284.052772)
		)
		(stroke
			(width 0)
			(type solid)
		)
		(fill yes)
		(layer "In4.Cu")
		(net "M_J_CPU1_SB_DQ<16>")
	)
	(gr_poly
		(pts
			(xy 143.194786 -283.604462) (xy 143.194786 -283.560012) (xy 142.994634 -283.560012) (xy 142.994634 -283.604462)
			(xy 143.09471 -283.704538)
		)
		(stroke
			(width 0)
			(type solid)
		)
		(fill yes)
		(layer "In4.Cu")
		(net "M_J_CPU1_SB_DQ<15>")
	)
	(gr_poly
		(pts
			(xy 143.194786 -282.38831) (xy 143.09471 -282.288234) (xy 142.994634 -282.38831) (xy 142.994634 -282.43276)
			(xy 143.194786 -282.43276)
		)
		(stroke
			(width 0)
			(type solid)
		)
		(fill yes)
		(layer "In4.Cu")
		(net "M_J_CPU1_SB_DQ<12>")
	)
	(gr_poly
		(pts
			(xy 143.194786 -281.984704) (xy 143.194786 -281.936952) (xy 142.994634 -281.936952) (xy 142.994634 -281.984704)
			(xy 143.09471 -282.084526)
		)
		(stroke
			(width 0)
			(type solid)
		)
		(fill yes)
		(layer "In4.Cu")
		(net "M_J_CPU1_SB_DQS_DP<6>")
	)
	(gr_poly
		(pts
			(xy 143.194786 -280.768044) (xy 143.09471 -280.668222) (xy 142.994634 -280.768044) (xy 142.994634 -280.815796)
			(xy 143.194786 -280.815796)
		)
		(stroke
			(width 0)
			(type solid)
		)
		(fill yes)
		(layer "In4.Cu")
		(net "M_J_CPU1_SB_DQS_DP<1>")
	)
	(gr_poly
		(pts
			(xy 143.194786 -280.364438) (xy 143.194786 -280.319988) (xy 142.994634 -280.319988) (xy 142.994634 -280.364438)
			(xy 143.09471 -280.464514)
		)
		(stroke
			(width 0)
			(type solid)
		)
		(fill yes)
		(layer "In4.Cu")
		(net "M_J_CPU1_SB_DQ<11>")
	)
	(gr_poly
		(pts
			(xy 143.194786 -279.148286) (xy 143.09471 -279.04821) (xy 142.994634 -279.148286) (xy 142.994634 -279.192736)
			(xy 143.194786 -279.192736)
		)
		(stroke
			(width 0)
			(type solid)
		)
		(fill yes)
		(layer "In4.Cu")
		(net "M_J_CPU1_SB_DQ<8>")
	)
	(gr_poly
		(pts
			(xy 143.194786 -278.744426) (xy 143.194786 -278.699976) (xy 142.994634 -278.699976) (xy 142.994634 -278.744426)
			(xy 143.09471 -278.844502)
		)
		(stroke
			(width 0)
			(type solid)
		)
		(fill yes)
		(layer "In4.Cu")
		(net "M_J_CPU1_SB_DQ<7>")
	)
	(gr_poly
		(pts
			(xy 143.194786 -277.528274) (xy 143.09471 -277.428198) (xy 142.994634 -277.528274) (xy 142.994634 -277.572724)
			(xy 143.194786 -277.572724)
		)
		(stroke
			(width 0)
			(type solid)
		)
		(fill yes)
		(layer "In4.Cu")
		(net "M_J_CPU1_SB_DQ<4>")
	)
	(gr_poly
		(pts
			(xy 143.194786 -277.124668) (xy 143.194786 -277.076916) (xy 142.994634 -277.076916) (xy 142.994634 -277.124668)
			(xy 143.09471 -277.22449)
		)
		(stroke
			(width 0)
			(type solid)
		)
		(fill yes)
		(layer "In4.Cu")
		(net "M_J_CPU1_SB_DQS_DP<5>")
	)
	(gr_poly
		(pts
			(xy 143.194786 -275.908008) (xy 143.09471 -275.808186) (xy 142.994634 -275.908008) (xy 142.994634 -275.95576)
			(xy 143.194786 -275.95576)
		)
		(stroke
			(width 0)
			(type solid)
		)
		(fill yes)
		(layer "In4.Cu")
		(net "M_J_CPU1_SB_DQS_DP<0>")
	)
	(gr_poly
		(pts
			(xy 143.194786 -275.504402) (xy 143.194786 -275.459952) (xy 142.994634 -275.459952) (xy 142.994634 -275.504402)
			(xy 143.09471 -275.604478)
		)
		(stroke
			(width 0)
			(type solid)
		)
		(fill yes)
		(layer "In4.Cu")
		(net "M_J_CPU1_SB_DQ<3>")
	)
	(gr_poly
		(pts
			(xy 143.194786 -274.28825) (xy 143.09471 -274.188174) (xy 142.994634 -274.28825) (xy 142.994634 -274.3327)
			(xy 143.194786 -274.3327)
		)
		(stroke
			(width 0)
			(type solid)
		)
		(fill yes)
		(layer "In4.Cu")
		(net "M_J_CPU1_SB_DQ<0>")
	)
	(gr_poly
		(pts
			(xy 143.194786 -273.88439) (xy 143.194786 -273.83994) (xy 142.994634 -273.83994) (xy 142.994634 -273.88439)
			(xy 143.09471 -273.984466)
		)
		(stroke
			(width 0)
			(type solid)
		)
		(fill yes)
		(layer "In4.Cu")
		(net "M_J_CPU1_SB_CB<3>")
	)
	(gr_poly
		(pts
			(xy 143.194786 -272.668238) (xy 143.09471 -272.568162) (xy 142.994634 -272.668238) (xy 142.994634 -272.712688)
			(xy 143.194786 -272.712688)
		)
		(stroke
			(width 0)
			(type solid)
		)
		(fill yes)
		(layer "In4.Cu")
		(net "M_J_CPU1_SB_CB<0>")
	)
	(gr_poly
		(pts
			(xy 143.194786 -272.264632) (xy 143.194786 -272.21688) (xy 142.994634 -272.21688) (xy 142.994634 -272.264632)
			(xy 143.09471 -272.364454)
		)
		(stroke
			(width 0)
			(type solid)
		)
		(fill yes)
		(layer "In4.Cu")
		(net "M_J_CPU1_SB_DQS_DP<4>")
	)
	(gr_poly
		(pts
			(xy 143.194786 -271.047972) (xy 143.09471 -270.94815) (xy 142.994634 -271.047972) (xy 142.994634 -271.095724)
			(xy 143.194786 -271.095724)
		)
		(stroke
			(width 0)
			(type solid)
		)
		(fill yes)
		(layer "In4.Cu")
		(net "M_J_CPU1_SB_DQS_DP<9>")
	)
	(gr_poly
		(pts
			(xy 143.194786 -270.644366) (xy 143.194786 -270.599916) (xy 142.994634 -270.599916) (xy 142.994634 -270.644366)
			(xy 143.09471 -270.744442)
		)
		(stroke
			(width 0)
			(type solid)
		)
		(fill yes)
		(layer "In4.Cu")
		(net "M_J_CPU1_SB_CB<7>")
	)
	(gr_poly
		(pts
			(xy 143.194786 -269.428214) (xy 143.09471 -269.328138) (xy 142.994634 -269.428214) (xy 142.994634 -269.472664)
			(xy 143.194786 -269.472664)
		)
		(stroke
			(width 0)
			(type solid)
		)
		(fill yes)
		(layer "In4.Cu")
		(net "M_J_CPU1_SB_CB<4>")
	)
	(gr_poly
		(pts
			(xy 143.194786 -267.808202) (xy 143.09471 -267.708126) (xy 142.994634 -267.808202) (xy 142.994634 -267.852652)
			(xy 143.194786 -267.852652)
		)
		(stroke
			(width 0)
			(type solid)
		)
		(fill yes)
		(layer "In4.Cu")
		(net "M_J_CPU1_SB_RSP<0>")
	)
	(gr_poly
		(pts
			(xy 143.194786 -265.78433) (xy 143.194786 -265.73988) (xy 142.994634 -265.73988) (xy 142.994634 -265.78433)
			(xy 143.09471 -265.884406)
		)
		(stroke
			(width 0)
			(type solid)
		)
		(fill yes)
		(layer "In4.Cu")
		(net "M_J_CPU1_SB_CS_N<0>")
	)
	(gr_poly
		(pts
			(xy 143.194786 -264.568178) (xy 143.09471 -264.468102) (xy 142.994634 -264.568178) (xy 142.994634 -264.612628)
			(xy 143.194786 -264.612628)
		)
		(stroke
			(width 0)
			(type solid)
		)
		(fill yes)
		(layer "In4.Cu")
		(net "M_J_CPU1_SB_CA<6>")
	)
	(gr_poly
		(pts
			(xy 143.194786 -264.164318) (xy 143.194786 -264.119868) (xy 142.994634 -264.119868) (xy 142.994634 -264.164318)
			(xy 143.09471 -264.264394)
		)
		(stroke
			(width 0)
			(type solid)
		)
		(fill yes)
		(layer "In4.Cu")
		(net "M_J_CPU1_SB_CA<5>")
	)
	(gr_poly
		(pts
			(xy 143.194786 -262.948166) (xy 143.09471 -262.84809) (xy 142.994634 -262.948166) (xy 142.994634 -262.992616)
			(xy 143.194786 -262.992616)
		)
		(stroke
			(width 0)
			(type solid)
		)
		(fill yes)
		(layer "In4.Cu")
		(net "M_J_CPU1_SB_CA<2>")
	)
	(gr_poly
		(pts
			(xy 143.194786 -262.544306) (xy 143.194786 -262.499856) (xy 142.994634 -262.499856) (xy 142.994634 -262.544306)
			(xy 143.09471 -262.644382)
		)
		(stroke
			(width 0)
			(type solid)
		)
		(fill yes)
		(layer "In4.Cu")
		(net "M_J_CPU1_SB_CA<1>")
	)
	(gr_poly
		(pts
			(xy 143.28394 -229.555548) (xy 143.245332 -229.533196) (xy 143.108934 -229.569772) (xy 143.14551 -229.706424)
			(xy 143.183864 -229.728776)
		)
		(stroke
			(width 0)
			(type solid)
		)
		(fill yes)
		(layer "In4.Cu")
		(net "M_J_CPU1_SA_DQ<8>")
	)
	(gr_poly
		(pts
			(xy 143.28394 -227.93579) (xy 143.245332 -227.913438) (xy 143.108934 -227.950014) (xy 143.14551 -228.086666)
			(xy 143.183864 -228.109018)
		)
		(stroke
			(width 0)
			(type solid)
		)
		(fill yes)
		(layer "In4.Cu")
		(net "M_J_CPU1_SA_DQ<5>")
	)
	(gr_poly
		(pts
			(xy 143.28394 -226.315778) (xy 143.245332 -226.293426) (xy 143.108934 -226.330002) (xy 143.14551 -226.466654)
			(xy 143.183864 -226.489006)
		)
		(stroke
			(width 0)
			(type solid)
		)
		(fill yes)
		(layer "In4.Cu")
		(net "M_J_CPU1_SA_DQ<4>")
	)
	(gr_poly
		(pts
			(xy 143.286734 -224.696528) (xy 143.245586 -224.672652) (xy 143.108934 -224.709482) (xy 143.14551 -224.84588)
			(xy 143.186912 -224.869756)
		)
		(stroke
			(width 0)
			(type solid)
		)
		(fill yes)
		(layer "In4.Cu")
		(net "M_J_CPU1_SA_DQS_DN<5>")
	)
	(gr_poly
		(pts
			(xy 143.286734 -223.076516) (xy 143.245586 -223.05264) (xy 143.108934 -223.08947) (xy 143.14551 -223.225868)
			(xy 143.186912 -223.249744)
		)
		(stroke
			(width 0)
			(type solid)
		)
		(fill yes)
		(layer "In4.Cu")
		(net "M_J_CPU1_SA_DQS_DP<0>")
	)
	(gr_poly
		(pts
			(xy 143.340836 -236.586522) (xy 143.24076 -236.486446) (xy 143.140938 -236.586522) (xy 143.140938 -236.63402)
			(xy 143.340836 -236.63402)
		)
		(stroke
			(width 0)
			(type solid)
		)
		(fill yes)
		(layer "In4.Cu")
		(net "M_J_CPU1_SA_DQS_DP<2>")
	)
	(gr_poly
		(pts
			(xy 143.364712 -256.026158) (xy 143.264636 -255.926336) (xy 143.16456 -256.026158) (xy 143.16456 -256.07391)
			(xy 143.364712 -256.07391)
		)
		(stroke
			(width 0)
			(type solid)
		)
		(fill yes)
		(layer "In4.Cu")
		(net "M_J_CPU1_CLK_DP<0>")
	)
	(gr_poly
		(pts
			(xy 143.364712 -255.622552) (xy 143.364712 -255.578102) (xy 143.16456 -255.578102) (xy 143.16456 -255.622552)
			(xy 143.264636 -255.722628)
		)
		(stroke
			(width 0)
			(type solid)
		)
		(fill yes)
		(layer "In4.Cu")
		(net "M_J_CPU1_SA_PAR")
	)
	(gr_poly
		(pts
			(xy 143.364712 -254.4064) (xy 143.264636 -254.306324) (xy 143.16456 -254.4064) (xy 143.16456 -254.45085)
			(xy 143.364712 -254.45085)
		)
		(stroke
			(width 0)
			(type solid)
		)
		(fill yes)
		(layer "In4.Cu")
		(net "M_J_CPU1_SA_CA<4>")
	)
	(gr_poly
		(pts
			(xy 143.364712 -254.00254) (xy 143.364712 -253.95809) (xy 143.16456 -253.95809) (xy 143.16456 -254.00254)
			(xy 143.264636 -254.102616)
		)
		(stroke
			(width 0)
			(type solid)
		)
		(fill yes)
		(layer "In4.Cu")
		(net "M_J_CPU1_SA_CA<3>")
	)
	(gr_poly
		(pts
			(xy 143.364712 -252.786388) (xy 143.264636 -252.686312) (xy 143.16456 -252.786388) (xy 143.16456 -252.830838)
			(xy 143.364712 -252.830838)
		)
		(stroke
			(width 0)
			(type solid)
		)
		(fill yes)
		(layer "In4.Cu")
		(net "M_J_CPU1_SA_CA<0>")
	)
	(gr_poly
		(pts
			(xy 143.364712 -251.166376) (xy 143.264636 -251.0663) (xy 143.16456 -251.166376) (xy 143.16456 -251.210826)
			(xy 143.364712 -251.210826)
		)
		(stroke
			(width 0)
			(type solid)
		)
		(fill yes)
		(layer "In4.Cu")
		(net "M_J_CPU1_SA_CS_N<0>")
	)
	(gr_poly
		(pts
			(xy 143.364712 -250.762516) (xy 143.364712 -250.718066) (xy 143.16456 -250.718066) (xy 143.16456 -250.762516)
			(xy 143.264636 -250.862592)
		)
		(stroke
			(width 0)
			(type solid)
		)
		(fill yes)
		(layer "In4.Cu")
		(net "M_J_CPU1_RESET_N")
	)
	(gr_poly
		(pts
			(xy 143.364712 -249.142504) (xy 143.364712 -249.098054) (xy 143.16456 -249.098054) (xy 143.16456 -249.142504)
			(xy 143.264636 -249.24258)
		)
		(stroke
			(width 0)
			(type solid)
		)
		(fill yes)
		(layer "In4.Cu")
		(net "M_J_CPU1_SA_CB<7>")
	)
	(gr_poly
		(pts
			(xy 143.364712 -247.926352) (xy 143.264636 -247.826276) (xy 143.16456 -247.926352) (xy 143.16456 -247.970802)
			(xy 143.364712 -247.970802)
		)
		(stroke
			(width 0)
			(type solid)
		)
		(fill yes)
		(layer "In4.Cu")
		(net "M_J_CPU1_SA_CB<4>")
	)
	(gr_poly
		(pts
			(xy 143.364712 -247.522746) (xy 143.364712 -247.474994) (xy 143.16456 -247.474994) (xy 143.16456 -247.522746)
			(xy 143.264636 -247.622568)
		)
		(stroke
			(width 0)
			(type solid)
		)
		(fill yes)
		(layer "In4.Cu")
		(net "M_J_CPU1_SA_DQS_DP<9>")
	)
	(gr_poly
		(pts
			(xy 143.364712 -246.306086) (xy 143.264636 -246.206264) (xy 143.16456 -246.306086) (xy 143.16456 -246.353838)
			(xy 143.364712 -246.353838)
		)
		(stroke
			(width 0)
			(type solid)
		)
		(fill yes)
		(layer "In4.Cu")
		(net "M_J_CPU1_SA_DQS_DP<4>")
	)
	(gr_poly
		(pts
			(xy 143.364712 -245.90248) (xy 143.364712 -245.85803) (xy 143.16456 -245.85803) (xy 143.16456 -245.90248)
			(xy 143.264636 -246.002556)
		)
		(stroke
			(width 0)
			(type solid)
		)
		(fill yes)
		(layer "In4.Cu")
		(net "M_J_CPU1_SA_CB<3>")
	)
	(gr_poly
		(pts
			(xy 143.364712 -244.686328) (xy 143.264636 -244.586252) (xy 143.16456 -244.686328) (xy 143.16456 -244.730778)
			(xy 143.364712 -244.730778)
		)
		(stroke
			(width 0)
			(type solid)
		)
		(fill yes)
		(layer "In4.Cu")
		(net "M_J_CPU1_SA_CB<0>")
	)
	(gr_poly
		(pts
			(xy 143.364712 -244.282468) (xy 143.364712 -244.238018) (xy 143.16456 -244.238018) (xy 143.16456 -244.282468)
			(xy 143.264636 -244.382544)
		)
		(stroke
			(width 0)
			(type solid)
		)
		(fill yes)
		(layer "In4.Cu")
		(net "M_J_CPU1_SA_DQ<31>")
	)
	(gr_poly
		(pts
			(xy 143.364712 -243.066316) (xy 143.264636 -242.96624) (xy 143.16456 -243.066316) (xy 143.16456 -243.110766)
			(xy 143.364712 -243.110766)
		)
		(stroke
			(width 0)
			(type solid)
		)
		(fill yes)
		(layer "In4.Cu")
		(net "M_J_CPU1_SA_DQ<28>")
	)
	(gr_poly
		(pts
			(xy 143.364712 -242.66271) (xy 143.364712 -242.614958) (xy 143.16456 -242.614958) (xy 143.16456 -242.66271)
			(xy 143.264636 -242.762532)
		)
		(stroke
			(width 0)
			(type solid)
		)
		(fill yes)
		(layer "In4.Cu")
		(net "M_J_CPU1_SA_DQS_DP<8>")
	)
	(gr_poly
		(pts
			(xy 143.364712 -241.44605) (xy 143.264636 -241.346228) (xy 143.16456 -241.44605) (xy 143.16456 -241.493802)
			(xy 143.364712 -241.493802)
		)
		(stroke
			(width 0)
			(type solid)
		)
		(fill yes)
		(layer "In4.Cu")
		(net "M_J_CPU1_SA_DQS_DP<3>")
	)
	(gr_poly
		(pts
			(xy 143.364712 -241.042444) (xy 143.364712 -240.997994) (xy 143.16456 -240.997994) (xy 143.16456 -241.042444)
			(xy 143.264636 -241.14252)
		)
		(stroke
			(width 0)
			(type solid)
		)
		(fill yes)
		(layer "In4.Cu")
		(net "M_J_CPU1_SA_DQ<27>")
	)
	(gr_poly
		(pts
			(xy 143.364712 -239.826292) (xy 143.264636 -239.726216) (xy 143.16456 -239.826292) (xy 143.16456 -239.870742)
			(xy 143.364712 -239.870742)
		)
		(stroke
			(width 0)
			(type solid)
		)
		(fill yes)
		(layer "In4.Cu")
		(net "M_J_CPU1_SA_DQ<24>")
	)
	(gr_poly
		(pts
			(xy 143.364712 -239.422432) (xy 143.364712 -239.377982) (xy 143.16456 -239.377982) (xy 143.16456 -239.422432)
			(xy 143.264636 -239.522508)
		)
		(stroke
			(width 0)
			(type solid)
		)
		(fill yes)
		(layer "In4.Cu")
		(net "M_J_CPU1_SA_DQ<23>")
	)
	(gr_poly
		(pts
			(xy 143.364712 -238.20628) (xy 143.264636 -238.106204) (xy 143.16456 -238.20628) (xy 143.16456 -238.25073)
			(xy 143.364712 -238.25073)
		)
		(stroke
			(width 0)
			(type solid)
		)
		(fill yes)
		(layer "In4.Cu")
		(net "M_J_CPU1_SA_DQ<20>")
	)
	(gr_poly
		(pts
			(xy 143.364712 -237.802674) (xy 143.364712 -237.754922) (xy 143.16456 -237.754922) (xy 143.16456 -237.802674)
			(xy 143.264636 -237.902496)
		)
		(stroke
			(width 0)
			(type solid)
		)
		(fill yes)
		(layer "In4.Cu")
		(net "M_J_CPU1_SA_DQS_DP<7>")
	)
	(gr_poly
		(pts
			(xy 143.364712 -236.182408) (xy 143.364712 -236.137958) (xy 143.16456 -236.137958) (xy 143.16456 -236.182408)
			(xy 143.264636 -236.282484)
		)
		(stroke
			(width 0)
			(type solid)
		)
		(fill yes)
		(layer "In4.Cu")
		(net "M_J_CPU1_SA_DQ<19>")
	)
	(gr_poly
		(pts
			(xy 143.364712 -234.966256) (xy 143.264636 -234.86618) (xy 143.16456 -234.966256) (xy 143.16456 -235.010706)
			(xy 143.364712 -235.010706)
		)
		(stroke
			(width 0)
			(type solid)
		)
		(fill yes)
		(layer "In4.Cu")
		(net "M_J_CPU1_SA_DQ<16>")
	)
	(gr_poly
		(pts
			(xy 143.364712 -234.562396) (xy 143.364712 -234.517946) (xy 143.16456 -234.517946) (xy 143.16456 -234.562396)
			(xy 143.264636 -234.662472)
		)
		(stroke
			(width 0)
			(type solid)
		)
		(fill yes)
		(layer "In4.Cu")
		(net "M_J_CPU1_SA_DQ<15>")
	)
	(gr_poly
		(pts
			(xy 143.364712 -233.346244) (xy 143.264636 -233.246168) (xy 143.16456 -233.346244) (xy 143.16456 -233.390694)
			(xy 143.364712 -233.390694)
		)
		(stroke
			(width 0)
			(type solid)
		)
		(fill yes)
		(layer "In4.Cu")
		(net "M_J_CPU1_SA_DQ<12>")
	)
	(gr_poly
		(pts
			(xy 143.364712 -232.942638) (xy 143.364712 -232.894886) (xy 143.16456 -232.894886) (xy 143.16456 -232.942638)
			(xy 143.264636 -233.04246)
		)
		(stroke
			(width 0)
			(type solid)
		)
		(fill yes)
		(layer "In4.Cu")
		(net "M_J_CPU1_SA_DQS_DP<6>")
	)
	(gr_poly
		(pts
			(xy 143.364712 -231.725978) (xy 143.264636 -231.626156) (xy 143.16456 -231.725978) (xy 143.16456 -231.77373)
			(xy 143.364712 -231.77373)
		)
		(stroke
			(width 0)
			(type solid)
		)
		(fill yes)
		(layer "In4.Cu")
		(net "M_J_CPU1_SA_DQS_DP<1>")
	)
	(gr_poly
		(pts
			(xy 143.364712 -231.322626) (xy 143.364712 -231.278176) (xy 143.16456 -231.278176) (xy 143.16456 -231.322626)
			(xy 143.264636 -231.422702)
		)
		(stroke
			(width 0)
			(type solid)
		)
		(fill yes)
		(layer "In4.Cu")
		(net "M_J_CPU1_SA_DQ<11>")
	)
	(gr_poly
		(pts
			(xy 143.420084 -230.240078) (xy 143.383508 -230.103426) (xy 143.3449 -230.081328) (xy 143.244824 -230.254556)
			(xy 143.283432 -230.276654)
		)
		(stroke
			(width 0)
			(type solid)
		)
		(fill yes)
		(layer "In4.Cu")
		(net "M_J_CPU1_SA_DQ<10>")
	)
	(gr_poly
		(pts
			(xy 143.420592 -225.379534) (xy 143.384016 -225.243136) (xy 143.342614 -225.21926) (xy 143.242792 -225.392488)
			(xy 143.28394 -225.416364)
		)
		(stroke
			(width 0)
			(type solid)
		)
		(fill yes)
		(layer "In4.Cu")
		(net "M_J_CPU1_SA_DQS_DP<5>")
	)
	(gr_poly
		(pts
			(xy 143.420592 -223.759522) (xy 143.384016 -223.623124) (xy 143.342614 -223.599248) (xy 143.242792 -223.772476)
			(xy 143.28394 -223.796352)
		)
		(stroke
			(width 0)
			(type solid)
		)
		(fill yes)
		(layer "In4.Cu")
		(net "M_J_CPU1_SA_DQS_DN<0>")
	)
	(gr_poly
		(pts
			(xy 143.420846 -228.61905) (xy 143.384016 -228.482398) (xy 143.345662 -228.460046) (xy 143.245586 -228.633274)
			(xy 143.284194 -228.655626)
		)
		(stroke
			(width 0)
			(type solid)
		)
		(fill yes)
		(layer "In4.Cu")
		(net "M_J_CPU1_SA_DQ<7>")
	)
	(gr_poly
		(pts
			(xy 143.420846 -226.999038) (xy 143.384016 -226.862386) (xy 143.345662 -226.840034) (xy 143.245586 -227.013262)
			(xy 143.284194 -227.035614)
		)
		(stroke
			(width 0)
			(type solid)
		)
		(fill yes)
		(layer "In4.Cu")
		(net "M_J_CPU1_SA_DQ<6>")
	)
	(gr_poly
		(pts
			(xy 143.422116 -222.138494) (xy 143.385286 -222.001842) (xy 143.346932 -221.979744) (xy 143.246856 -222.152972)
			(xy 143.285464 -222.17507)
		)
		(stroke
			(width 0)
			(type solid)
		)
		(fill yes)
		(layer "In4.Cu")
		(net "M_J_CPU1_SA_DQ<3>")
	)
	(gr_poly
		(pts
			(xy 143.664686 -292.918134) (xy 143.56461 -292.818058) (xy 143.464534 -292.918134) (xy 143.464534 -292.962584)
			(xy 143.664686 -292.962584)
		)
		(stroke
			(width 0)
			(type solid)
		)
		(fill yes)
		(layer "In4.Cu")
		(net "M_J_CPU1_SB_DQ<29>")
	)
	(gr_poly
		(pts
			(xy 143.664686 -292.514274) (xy 143.664686 -292.469824) (xy 143.464534 -292.469824) (xy 143.464534 -292.514274)
			(xy 143.56461 -292.61435)
		)
		(stroke
			(width 0)
			(type solid)
		)
		(fill yes)
		(layer "In4.Cu")
		(net "M_J_CPU1_SB_DQ<30>")
	)
	(gr_poly
		(pts
			(xy 143.664686 -291.297868) (xy 143.56461 -291.198046) (xy 143.464534 -291.297868) (xy 143.464534 -291.34562)
			(xy 143.664686 -291.34562)
		)
		(stroke
			(width 0)
			(type solid)
		)
		(fill yes)
		(layer "In4.Cu")
		(net "M_J_CPU1_SB_DQS_DN<8>")
	)
	(gr_poly
		(pts
			(xy 143.664686 -290.894516) (xy 143.664686 -290.846764) (xy 143.464534 -290.846764) (xy 143.464534 -290.894516)
			(xy 143.56461 -290.994338)
		)
		(stroke
			(width 0)
			(type solid)
		)
		(fill yes)
		(layer "In4.Cu")
		(net "M_J_CPU1_SB_DQS_DN<3>")
	)
	(gr_poly
		(pts
			(xy 143.664686 -289.67811) (xy 143.56461 -289.578034) (xy 143.464534 -289.67811) (xy 143.464534 -289.72256)
			(xy 143.664686 -289.72256)
		)
		(stroke
			(width 0)
			(type solid)
		)
		(fill yes)
		(layer "In4.Cu")
		(net "M_J_CPU1_SB_DQ<25>")
	)
	(gr_poly
		(pts
			(xy 143.664686 -289.27425) (xy 143.664686 -289.2298) (xy 143.464534 -289.2298) (xy 143.464534 -289.27425)
			(xy 143.56461 -289.374326)
		)
		(stroke
			(width 0)
			(type solid)
		)
		(fill yes)
		(layer "In4.Cu")
		(net "M_J_CPU1_SB_DQ<26>")
	)
	(gr_poly
		(pts
			(xy 143.664686 -288.058098) (xy 143.56461 -287.958022) (xy 143.464534 -288.058098) (xy 143.464534 -288.102548)
			(xy 143.664686 -288.102548)
		)
		(stroke
			(width 0)
			(type solid)
		)
		(fill yes)
		(layer "In4.Cu")
		(net "M_J_CPU1_SB_DQ<21>")
	)
	(gr_poly
		(pts
			(xy 143.664686 -287.654492) (xy 143.664686 -287.610042) (xy 143.464534 -287.610042) (xy 143.464534 -287.654492)
			(xy 143.56461 -287.754568)
		)
		(stroke
			(width 0)
			(type solid)
		)
		(fill yes)
		(layer "In4.Cu")
		(net "M_J_CPU1_SB_DQ<22>")
	)
	(gr_poly
		(pts
			(xy 143.664686 -286.438086) (xy 143.56461 -286.33801) (xy 143.464534 -286.438086) (xy 143.464534 -286.485838)
			(xy 143.664686 -286.485838)
		)
		(stroke
			(width 0)
			(type solid)
		)
		(fill yes)
		(layer "In4.Cu")
		(net "M_J_CPU1_SB_DQS_DN<7>")
	)
	(gr_poly
		(pts
			(xy 143.664686 -286.034734) (xy 143.664686 -285.986982) (xy 143.464534 -285.986982) (xy 143.464534 -286.034734)
			(xy 143.56461 -286.134556)
		)
		(stroke
			(width 0)
			(type solid)
		)
		(fill yes)
		(layer "In4.Cu")
		(net "M_J_CPU1_SB_DQS_DN<2>")
	)
	(gr_poly
		(pts
			(xy 143.664686 -284.818328) (xy 143.56461 -284.718252) (xy 143.464534 -284.818328) (xy 143.464534 -284.862778)
			(xy 143.664686 -284.862778)
		)
		(stroke
			(width 0)
			(type solid)
		)
		(fill yes)
		(layer "In4.Cu")
		(net "M_J_CPU1_SB_DQ<17>")
	)
	(gr_poly
		(pts
			(xy 143.664686 -284.414468) (xy 143.664686 -284.370018) (xy 143.464534 -284.370018) (xy 143.464534 -284.414468)
			(xy 143.56461 -284.514544)
		)
		(stroke
			(width 0)
			(type solid)
		)
		(fill yes)
		(layer "In4.Cu")
		(net "M_J_CPU1_SB_DQ<18>")
	)
	(gr_poly
		(pts
			(xy 143.664686 -283.198316) (xy 143.56461 -283.09824) (xy 143.464534 -283.198316) (xy 143.464534 -283.242766)
			(xy 143.664686 -283.242766)
		)
		(stroke
			(width 0)
			(type solid)
		)
		(fill yes)
		(layer "In4.Cu")
		(net "M_J_CPU1_SB_DQ<13>")
	)
	(gr_poly
		(pts
			(xy 143.664686 -282.794456) (xy 143.664686 -282.750006) (xy 143.464534 -282.750006) (xy 143.464534 -282.794456)
			(xy 143.56461 -282.894532)
		)
		(stroke
			(width 0)
			(type solid)
		)
		(fill yes)
		(layer "In4.Cu")
		(net "M_J_CPU1_SB_DQ<14>")
	)
	(gr_poly
		(pts
			(xy 143.664686 -281.57805) (xy 143.56461 -281.478228) (xy 143.464534 -281.57805) (xy 143.464534 -281.625802)
			(xy 143.664686 -281.625802)
		)
		(stroke
			(width 0)
			(type solid)
		)
		(fill yes)
		(layer "In4.Cu")
		(net "M_J_CPU1_SB_DQS_DN<6>")
	)
	(gr_poly
		(pts
			(xy 143.664686 -281.174698) (xy 143.664686 -281.126946) (xy 143.464534 -281.126946) (xy 143.464534 -281.174698)
			(xy 143.56461 -281.27452)
		)
		(stroke
			(width 0)
			(type solid)
		)
		(fill yes)
		(layer "In4.Cu")
		(net "M_J_CPU1_SB_DQS_DN<1>")
	)
	(gr_poly
		(pts
			(xy 143.664686 -279.958292) (xy 143.56461 -279.858216) (xy 143.464534 -279.958292) (xy 143.464534 -280.002742)
			(xy 143.664686 -280.002742)
		)
		(stroke
			(width 0)
			(type solid)
		)
		(fill yes)
		(layer "In4.Cu")
		(net "M_J_CPU1_SB_DQ<9>")
	)
	(gr_poly
		(pts
			(xy 143.664686 -279.554432) (xy 143.664686 -279.509982) (xy 143.464534 -279.509982) (xy 143.464534 -279.554432)
			(xy 143.56461 -279.654508)
		)
		(stroke
			(width 0)
			(type solid)
		)
		(fill yes)
		(layer "In4.Cu")
		(net "M_J_CPU1_SB_DQ<10>")
	)
	(gr_poly
		(pts
			(xy 143.664686 -278.33828) (xy 143.56461 -278.238204) (xy 143.464534 -278.33828) (xy 143.464534 -278.38273)
			(xy 143.664686 -278.38273)
		)
		(stroke
			(width 0)
			(type solid)
		)
		(fill yes)
		(layer "In4.Cu")
		(net "M_J_CPU1_SB_DQ<5>")
	)
	(gr_poly
		(pts
			(xy 143.664686 -277.93442) (xy 143.664686 -277.88997) (xy 143.464534 -277.88997) (xy 143.464534 -277.93442)
			(xy 143.56461 -278.034496)
		)
		(stroke
			(width 0)
			(type solid)
		)
		(fill yes)
		(layer "In4.Cu")
		(net "M_J_CPU1_SB_DQ<6>")
	)
	(gr_poly
		(pts
			(xy 143.664686 -276.718014) (xy 143.56461 -276.618192) (xy 143.464534 -276.718014) (xy 143.464534 -276.765766)
			(xy 143.664686 -276.765766)
		)
		(stroke
			(width 0)
			(type solid)
		)
		(fill yes)
		(layer "In4.Cu")
		(net "M_J_CPU1_SB_DQS_DN<5>")
	)
	(gr_poly
		(pts
			(xy 143.664686 -276.314662) (xy 143.664686 -276.26691) (xy 143.464534 -276.26691) (xy 143.464534 -276.314662)
			(xy 143.56461 -276.414484)
		)
		(stroke
			(width 0)
			(type solid)
		)
		(fill yes)
		(layer "In4.Cu")
		(net "M_J_CPU1_SB_DQS_DN<0>")
	)
	(gr_poly
		(pts
			(xy 143.664686 -275.098256) (xy 143.56461 -274.99818) (xy 143.464534 -275.098256) (xy 143.464534 -275.142706)
			(xy 143.664686 -275.142706)
		)
		(stroke
			(width 0)
			(type solid)
		)
		(fill yes)
		(layer "In4.Cu")
		(net "M_J_CPU1_SB_DQ<1>")
	)
	(gr_poly
		(pts
			(xy 143.664686 -274.694396) (xy 143.664686 -274.649946) (xy 143.464534 -274.649946) (xy 143.464534 -274.694396)
			(xy 143.56461 -274.794472)
		)
		(stroke
			(width 0)
			(type solid)
		)
		(fill yes)
		(layer "In4.Cu")
		(net "M_J_CPU1_SB_DQ<2>")
	)
	(gr_poly
		(pts
			(xy 143.664686 -273.478244) (xy 143.56461 -273.378168) (xy 143.464534 -273.478244) (xy 143.464534 -273.522694)
			(xy 143.664686 -273.522694)
		)
		(stroke
			(width 0)
			(type solid)
		)
		(fill yes)
		(layer "In4.Cu")
		(net "M_J_CPU1_SB_CB<1>")
	)
	(gr_poly
		(pts
			(xy 143.664686 -273.074384) (xy 143.664686 -273.029934) (xy 143.464534 -273.029934) (xy 143.464534 -273.074384)
			(xy 143.56461 -273.17446)
		)
		(stroke
			(width 0)
			(type solid)
		)
		(fill yes)
		(layer "In4.Cu")
		(net "M_J_CPU1_SB_CB<2>")
	)
	(gr_poly
		(pts
			(xy 143.664686 -271.857978) (xy 143.56461 -271.758156) (xy 143.464534 -271.857978) (xy 143.464534 -271.90573)
			(xy 143.664686 -271.90573)
		)
		(stroke
			(width 0)
			(type solid)
		)
		(fill yes)
		(layer "In4.Cu")
		(net "M_J_CPU1_SB_DQS_DN<4>")
	)
	(gr_poly
		(pts
			(xy 143.664686 -271.454626) (xy 143.664686 -271.406874) (xy 143.464534 -271.406874) (xy 143.464534 -271.454626)
			(xy 143.56461 -271.554448)
		)
		(stroke
			(width 0)
			(type solid)
		)
		(fill yes)
		(layer "In4.Cu")
		(net "M_J_CPU1_SB_DQS_DN<9>")
	)
	(gr_poly
		(pts
			(xy 143.664686 -270.23822) (xy 143.56461 -270.138144) (xy 143.464534 -270.23822) (xy 143.464534 -270.28267)
			(xy 143.664686 -270.28267)
		)
		(stroke
			(width 0)
			(type solid)
		)
		(fill yes)
		(layer "In4.Cu")
		(net "M_J_CPU1_SB_CB<5>")
	)
	(gr_poly
		(pts
			(xy 143.664686 -269.83436) (xy 143.664686 -269.78991) (xy 143.464534 -269.78991) (xy 143.464534 -269.83436)
			(xy 143.56461 -269.934436)
		)
		(stroke
			(width 0)
			(type solid)
		)
		(fill yes)
		(layer "In4.Cu")
		(net "M_J_CPU1_SB_CB<6>")
	)
	(gr_poly
		(pts
			(xy 143.664686 -266.998196) (xy 143.56461 -266.89812) (xy 143.464534 -266.998196) (xy 143.464534 -267.042646)
			(xy 143.664686 -267.042646)
		)
		(stroke
			(width 0)
			(type solid)
		)
		(fill yes)
		(layer "In4.Cu")
		(net "M_J_CPU1_SA_RSP<0>")
	)
	(gr_poly
		(pts
			(xy 143.664686 -266.594336) (xy 143.664686 -266.549886) (xy 143.464534 -266.549886) (xy 143.464534 -266.594336)
			(xy 143.56461 -266.694412)
		)
		(stroke
			(width 0)
			(type solid)
		)
		(fill yes)
		(layer "In4.Cu")
		(net "M_J_CPU1_SB_CS_N<1>")
	)
	(gr_poly
		(pts
			(xy 143.664686 -265.378184) (xy 143.56461 -265.278108) (xy 143.464534 -265.378184) (xy 143.464534 -265.422634)
			(xy 143.664686 -265.422634)
		)
		(stroke
			(width 0)
			(type solid)
		)
		(fill yes)
		(layer "In4.Cu")
		(net "M_J_CPU1_SB_PAR")
	)
	(gr_poly
		(pts
			(xy 143.664686 -263.758172) (xy 143.56461 -263.658096) (xy 143.464534 -263.758172) (xy 143.464534 -263.802622)
			(xy 143.664686 -263.802622)
		)
		(stroke
			(width 0)
			(type solid)
		)
		(fill yes)
		(layer "In4.Cu")
		(net "M_J_CPU1_SB_CA<4>")
	)
	(gr_poly
		(pts
			(xy 143.664686 -263.354312) (xy 143.664686 -263.309862) (xy 143.464534 -263.309862) (xy 143.464534 -263.354312)
			(xy 143.56461 -263.454388)
		)
		(stroke
			(width 0)
			(type solid)
		)
		(fill yes)
		(layer "In4.Cu")
		(net "M_J_CPU1_SB_CA<3>")
	)
	(gr_poly
		(pts
			(xy 143.664686 -262.13816) (xy 143.56461 -262.038084) (xy 143.464534 -262.13816) (xy 143.464534 -262.18261)
			(xy 143.664686 -262.18261)
		)
		(stroke
			(width 0)
			(type solid)
		)
		(fill yes)
		(layer "In4.Cu")
		(net "M_J_CPU1_SB_CA<0>")
	)
	(gr_poly
		(pts
			(xy 143.75384 -225.505772) (xy 143.715232 -225.48342) (xy 143.578834 -225.519996) (xy 143.61541 -225.656648)
			(xy 143.653764 -225.679)
		)
		(stroke
			(width 0)
			(type solid)
		)
		(fill yes)
		(layer "In4.Cu")
		(net "M_J_CPU1_SA_DQ<4>")
	)
	(gr_poly
		(pts
			(xy 143.754856 -230.364284) (xy 143.716248 -230.342186) (xy 143.579596 -230.378762) (xy 143.616172 -230.515414)
			(xy 143.65478 -230.537512)
		)
		(stroke
			(width 0)
			(type solid)
		)
		(fill yes)
		(layer "In4.Cu")
		(net "M_J_CPU1_SA_DQ<9>")
	)
	(gr_poly
		(pts
			(xy 143.756634 -223.886522) (xy 143.715486 -223.8629) (xy 143.578834 -223.899476) (xy 143.61541 -224.035874)
			(xy 143.656812 -224.05975)
		)
		(stroke
			(width 0)
			(type solid)
		)
		(fill yes)
		(layer "In4.Cu")
		(net "M_J_CPU1_SA_DQS_DN<5>")
	)
	(gr_poly
		(pts
			(xy 143.757142 -222.266002) (xy 143.71574 -222.242126) (xy 143.579342 -222.278702) (xy 143.615918 -222.415354)
			(xy 143.657066 -222.43923)
		)
		(stroke
			(width 0)
			(type solid)
		)
		(fill yes)
		(layer "In4.Cu")
		(net "M_J_CPU1_SA_DQS_DP<0>")
	)
	(gr_poly
		(pts
			(xy 143.801084 -235.381292) (xy 143.804894 -235.337096) (xy 143.605758 -235.31957) (xy 143.601948 -235.36402)
			(xy 143.69288 -235.472224)
		)
		(stroke
			(width 0)
			(type solid)
		)
		(fill yes)
		(layer "In4.Cu")
		(net "M_J_CPU1_SA_DQ<18>")
	)
	(gr_poly
		(pts
			(xy 143.82877 -237.39602) (xy 143.728694 -237.296198) (xy 143.628618 -237.39602) (xy 143.628618 -237.443772)
			(xy 143.82877 -237.443772)
		)
		(stroke
			(width 0)
			(type solid)
		)
		(fill yes)
		(layer "In4.Cu")
		(net "M_J_CPU1_SA_DQS_DN<7>")
	)
	(gr_poly
		(pts
			(xy 143.82877 -232.132632) (xy 143.82877 -232.08488) (xy 143.628618 -232.08488) (xy 143.628618 -232.132632)
			(xy 143.728694 -232.232454)
		)
		(stroke
			(width 0)
			(type solid)
		)
		(fill yes)
		(layer "In4.Cu")
		(net "M_J_CPU1_SA_DQS_DN<1>")
	)
	(gr_poly
		(pts
			(xy 143.834866 -256.432812) (xy 143.834866 -256.38506) (xy 143.634714 -256.38506) (xy 143.634714 -256.432812)
			(xy 143.73479 -256.532634)
		)
		(stroke
			(width 0)
			(type solid)
		)
		(fill yes)
		(layer "In4.Cu")
		(net "M_J_CPU1_CLK_DN<0>")
	)
	(gr_poly
		(pts
			(xy 143.840962 -254.812546) (xy 143.840962 -254.768096) (xy 143.64081 -254.768096) (xy 143.64081 -254.812546)
			(xy 143.740886 -254.912622)
		)
		(stroke
			(width 0)
			(type solid)
		)
		(fill yes)
		(layer "In4.Cu")
		(net "M_J_CPU1_SA_CA<5>")
	)
	(gr_poly
		(pts
			(xy 143.840962 -253.192534) (xy 143.840962 -253.148084) (xy 143.64081 -253.148084) (xy 143.64081 -253.192534)
			(xy 143.740886 -253.29261)
		)
		(stroke
			(width 0)
			(type solid)
		)
		(fill yes)
		(layer "In4.Cu")
		(net "M_J_CPU1_SA_CA<1>")
	)
	(gr_poly
		(pts
			(xy 143.840962 -248.332498) (xy 143.840962 -248.288048) (xy 143.64081 -248.288048) (xy 143.64081 -248.332498)
			(xy 143.740886 -248.432574)
		)
		(stroke
			(width 0)
			(type solid)
		)
		(fill yes)
		(layer "In4.Cu")
		(net "M_J_CPU1_SA_CB<6>")
	)
	(gr_poly
		(pts
			(xy 143.840962 -246.71274) (xy 143.840962 -246.665242) (xy 143.64081 -246.665242) (xy 143.64081 -246.71274)
			(xy 143.740886 -246.812816)
		)
		(stroke
			(width 0)
			(type solid)
		)
		(fill yes)
		(layer "In4.Cu")
		(net "M_J_CPU1_SA_DQS_DN<4>")
	)
	(gr_poly
		(pts
			(xy 143.840962 -245.092474) (xy 143.840962 -245.048024) (xy 143.64081 -245.048024) (xy 143.64081 -245.092474)
			(xy 143.740886 -245.19255)
		)
		(stroke
			(width 0)
			(type solid)
		)
		(fill yes)
		(layer "In4.Cu")
		(net "M_J_CPU1_SA_CB<2>")
	)
	(gr_poly
		(pts
			(xy 143.840962 -243.472462) (xy 143.840962 -243.428012) (xy 143.64081 -243.428012) (xy 143.64081 -243.472462)
			(xy 143.740886 -243.572538)
		)
		(stroke
			(width 0)
			(type solid)
		)
		(fill yes)
		(layer "In4.Cu")
		(net "M_J_CPU1_SA_DQ<30>")
	)
	(gr_poly
		(pts
			(xy 143.840962 -241.852704) (xy 143.840962 -241.805206) (xy 143.64081 -241.805206) (xy 143.64081 -241.852704)
			(xy 143.740886 -241.95278)
		)
		(stroke
			(width 0)
			(type solid)
		)
		(fill yes)
		(layer "In4.Cu")
		(net "M_J_CPU1_SA_DQS_DN<3>")
	)
	(gr_poly
		(pts
			(xy 143.840962 -240.232438) (xy 143.840962 -240.187988) (xy 143.64081 -240.187988) (xy 143.64081 -240.232438)
			(xy 143.740886 -240.332514)
		)
		(stroke
			(width 0)
			(type solid)
		)
		(fill yes)
		(layer "In4.Cu")
		(net "M_J_CPU1_SA_DQ<26>")
	)
	(gr_poly
		(pts
			(xy 143.840962 -238.612426) (xy 143.840962 -238.567976) (xy 143.64081 -238.567976) (xy 143.64081 -238.612426)
			(xy 143.740886 -238.712502)
		)
		(stroke
			(width 0)
			(type solid)
		)
		(fill yes)
		(layer "In4.Cu")
		(net "M_J_CPU1_SA_DQ<22>")
	)
	(gr_poly
		(pts
			(xy 143.840962 -233.75239) (xy 143.840962 -233.70794) (xy 143.64081 -233.70794) (xy 143.64081 -233.75239)
			(xy 143.740886 -233.852466)
		)
		(stroke
			(width 0)
			(type solid)
		)
		(fill yes)
		(layer "In4.Cu")
		(net "M_J_CPU1_SA_DQ<14>")
	)
	(gr_poly
		(pts
			(xy 143.843502 -255.216152) (xy 143.743426 -255.116076) (xy 143.643604 -255.216152) (xy 143.643604 -255.260602)
			(xy 143.843502 -255.260602)
		)
		(stroke
			(width 0)
			(type solid)
		)
		(fill yes)
		(layer "In4.Cu")
		(net "M_J_CPU1_SA_CA<6>")
	)
	(gr_poly
		(pts
			(xy 143.843502 -253.59614) (xy 143.743426 -253.496064) (xy 143.643604 -253.59614) (xy 143.643604 -253.64059)
			(xy 143.843502 -253.64059)
		)
		(stroke
			(width 0)
			(type solid)
		)
		(fill yes)
		(layer "In4.Cu")
		(net "M_J_CPU1_SA_CA<2>")
	)
	(gr_poly
		(pts
			(xy 143.843502 -251.976128) (xy 143.743426 -251.876052) (xy 143.643604 -251.976128) (xy 143.643604 -252.020578)
			(xy 143.843502 -252.020578)
		)
		(stroke
			(width 0)
			(type solid)
		)
		(fill yes)
		(layer "In4.Cu")
		(net "M_J_CPU1_SA_CS_N<1>")
	)
	(gr_poly
		(pts
			(xy 143.843502 -250.356116) (xy 143.743426 -250.25604) (xy 143.643604 -250.356116) (xy 143.643604 -250.400566)
			(xy 143.843502 -250.400566)
		)
		(stroke
			(width 0)
			(type solid)
		)
		(fill yes)
		(layer "In4.Cu")
		(net "M_J_CPU1_ALERT_R_N")
	)
	(gr_poly
		(pts
			(xy 143.843502 -248.736104) (xy 143.743426 -248.636028) (xy 143.643604 -248.736104) (xy 143.643604 -248.780554)
			(xy 143.843502 -248.780554)
		)
		(stroke
			(width 0)
			(type solid)
		)
		(fill yes)
		(layer "In4.Cu")
		(net "M_J_CPU1_SA_CB<5>")
	)
	(gr_poly
		(pts
			(xy 143.843502 -247.115838) (xy 143.743426 -247.016016) (xy 143.643604 -247.115838) (xy 143.643604 -247.16359)
			(xy 143.843502 -247.16359)
		)
		(stroke
			(width 0)
			(type solid)
		)
		(fill yes)
		(layer "In4.Cu")
		(net "M_J_CPU1_SA_DQS_DN<9>")
	)
	(gr_poly
		(pts
			(xy 143.843502 -245.49608) (xy 143.743426 -245.396004) (xy 143.643604 -245.49608) (xy 143.643604 -245.54053)
			(xy 143.843502 -245.54053)
		)
		(stroke
			(width 0)
			(type solid)
		)
		(fill yes)
		(layer "In4.Cu")
		(net "M_J_CPU1_SA_CB<1>")
	)
	(gr_poly
		(pts
			(xy 143.843502 -243.876068) (xy 143.743426 -243.775992) (xy 143.643604 -243.876068) (xy 143.643604 -243.920518)
			(xy 143.843502 -243.920518)
		)
		(stroke
			(width 0)
			(type solid)
		)
		(fill yes)
		(layer "In4.Cu")
		(net "M_J_CPU1_SA_DQ<29>")
	)
	(gr_poly
		(pts
			(xy 143.843502 -242.255802) (xy 143.743426 -242.15598) (xy 143.643604 -242.255802) (xy 143.643604 -242.303554)
			(xy 143.843502 -242.303554)
		)
		(stroke
			(width 0)
			(type solid)
		)
		(fill yes)
		(layer "In4.Cu")
		(net "M_J_CPU1_SA_DQS_DN<8>")
	)
	(gr_poly
		(pts
			(xy 143.843502 -240.636044) (xy 143.743426 -240.535968) (xy 143.643604 -240.636044) (xy 143.643604 -240.680494)
			(xy 143.843502 -240.680494)
		)
		(stroke
			(width 0)
			(type solid)
		)
		(fill yes)
		(layer "In4.Cu")
		(net "M_J_CPU1_SA_DQ<25>")
	)
	(gr_poly
		(pts
			(xy 143.843502 -239.016032) (xy 143.743426 -238.915956) (xy 143.643604 -239.016032) (xy 143.643604 -239.060482)
			(xy 143.843502 -239.060482)
		)
		(stroke
			(width 0)
			(type solid)
		)
		(fill yes)
		(layer "In4.Cu")
		(net "M_J_CPU1_SA_DQ<21>")
	)
	(gr_poly
		(pts
			(xy 143.843502 -235.776008) (xy 143.743426 -235.675932) (xy 143.643604 -235.776008) (xy 143.643604 -235.820458)
			(xy 143.843502 -235.820458)
		)
		(stroke
			(width 0)
			(type solid)
		)
		(fill yes)
		(layer "In4.Cu")
		(net "M_J_CPU1_SA_DQ<17>")
	)
	(gr_poly
		(pts
			(xy 143.852392 -236.99216) (xy 143.852392 -236.944662) (xy 143.652494 -236.944662) (xy 143.652494 -236.99216)
			(xy 143.75257 -237.092236)
		)
		(stroke
			(width 0)
			(type solid)
		)
		(fill yes)
		(layer "In4.Cu")
		(net "M_J_CPU1_SA_DQS_DN<2>")
	)
	(gr_poly
		(pts
			(xy 143.890492 -224.569528) (xy 143.853916 -224.43313) (xy 143.812514 -224.409254) (xy 143.712692 -224.582482)
			(xy 143.75384 -224.606104)
		)
		(stroke
			(width 0)
			(type solid)
		)
		(fill yes)
		(layer "In4.Cu")
		(net "M_J_CPU1_SA_DQS_DP<5>")
	)
	(gr_poly
		(pts
			(xy 143.890492 -222.949516) (xy 143.853916 -222.813118) (xy 143.812514 -222.789242) (xy 143.712692 -222.96247)
			(xy 143.75384 -222.986092)
		)
		(stroke
			(width 0)
			(type solid)
		)
		(fill yes)
		(layer "In4.Cu")
		(net "M_J_CPU1_SA_DQS_DN<0>")
	)
	(gr_poly
		(pts
			(xy 143.890746 -231.049068) (xy 143.853916 -230.912416) (xy 143.815562 -230.890064) (xy 143.715486 -231.063292)
			(xy 143.754094 -231.085644)
		)
		(stroke
			(width 0)
			(type solid)
		)
		(fill yes)
		(layer "In4.Cu")
		(net "M_J_CPU1_SA_DQ<11>")
	)
	(gr_poly
		(pts
			(xy 143.890746 -226.189032) (xy 143.853916 -226.05238) (xy 143.815562 -226.030028) (xy 143.715486 -226.203256)
			(xy 143.754094 -226.225608)
		)
		(stroke
			(width 0)
			(type solid)
		)
		(fill yes)
		(layer "In4.Cu")
		(net "M_J_CPU1_SA_DQ<6>")
	)
	(gr_poly
		(pts
			(xy 144.053814 -293.874952) (xy 143.953738 -293.701724) (xy 143.915384 -293.724076) (xy 143.878554 -293.860728)
			(xy 144.015206 -293.897304)
		)
		(stroke
			(width 0)
			(type solid)
		)
		(fill yes)
		(layer "In4.Cu")
		(net "M_J_CPU1_SB_DQ<31>")
	)
	(gr_poly
		(pts
			(xy 144.053814 -268.877542) (xy 144.015206 -268.85519) (xy 143.878554 -268.891766) (xy 143.915384 -269.028418)
			(xy 143.953738 -269.05077)
		)
		(stroke
			(width 0)
			(type solid)
		)
		(fill yes)
		(layer "In4.Cu")
		(net "M_J_CPU1_SB_CB<4>")
	)
	(gr_poly
		(pts
			(xy 144.119346 -290.488116) (xy 144.019524 -290.38804) (xy 143.919448 -290.488116) (xy 143.919448 -290.535614)
			(xy 144.119346 -290.535614)
		)
		(stroke
			(width 0)
			(type solid)
		)
		(fill yes)
		(layer "In4.Cu")
		(net "M_J_CPU1_SB_DQS_DP<3>")
	)
	(gr_poly
		(pts
			(xy 144.119346 -285.628334) (xy 144.019524 -285.528258) (xy 143.919448 -285.628334) (xy 143.919448 -285.675832)
			(xy 144.119346 -285.675832)
		)
		(stroke
			(width 0)
			(type solid)
		)
		(fill yes)
		(layer "In4.Cu")
		(net "M_J_CPU1_SB_DQS_DP<2>")
	)
	(gr_poly
		(pts
			(xy 144.119346 -280.768298) (xy 144.019524 -280.668222) (xy 143.919448 -280.768298) (xy 143.919448 -280.815796)
			(xy 144.119346 -280.815796)
		)
		(stroke
			(width 0)
			(type solid)
		)
		(fill yes)
		(layer "In4.Cu")
		(net "M_J_CPU1_SB_DQS_DP<1>")
	)
	(gr_poly
		(pts
			(xy 144.119346 -275.908262) (xy 144.019524 -275.808186) (xy 143.919448 -275.908262) (xy 143.919448 -275.95576)
			(xy 144.119346 -275.95576)
		)
		(stroke
			(width 0)
			(type solid)
		)
		(fill yes)
		(layer "In4.Cu")
		(net "M_J_CPU1_SB_DQS_DP<0>")
	)
	(gr_poly
		(pts
			(xy 144.119346 -271.048226) (xy 144.019524 -270.94815) (xy 143.919448 -271.048226) (xy 143.919448 -271.095724)
			(xy 144.119346 -271.095724)
		)
		(stroke
			(width 0)
			(type solid)
		)
		(fill yes)
		(layer "In4.Cu")
		(net "M_J_CPU1_SB_DQS_DP<9>")
	)
	(gr_poly
		(pts
			(xy 144.121632 -288.868358) (xy 144.021556 -288.768282) (xy 143.92148 -288.868358) (xy 143.92148 -288.912808)
			(xy 144.121632 -288.912808)
		)
		(stroke
			(width 0)
			(type solid)
		)
		(fill yes)
		(layer "In4.Cu")
		(net "M_J_CPU1_SB_DQ<24>")
	)
	(gr_poly
		(pts
			(xy 144.121632 -284.008576) (xy 144.021556 -283.9085) (xy 143.92148 -284.008576) (xy 143.92148 -284.053026)
			(xy 144.121632 -284.053026)
		)
		(stroke
			(width 0)
			(type solid)
		)
		(fill yes)
		(layer "In4.Cu")
		(net "M_J_CPU1_SB_DQ<16>")
	)
	(gr_poly
		(pts
			(xy 144.121632 -282.388564) (xy 144.021556 -282.288488) (xy 143.92148 -282.388564) (xy 143.92148 -282.433014)
			(xy 144.121632 -282.433014)
		)
		(stroke
			(width 0)
			(type solid)
		)
		(fill yes)
		(layer "In4.Cu")
		(net "M_J_CPU1_SB_DQ<12>")
	)
	(gr_poly
		(pts
			(xy 144.121632 -279.14854) (xy 144.021556 -279.048464) (xy 143.92148 -279.14854) (xy 143.92148 -279.19299)
			(xy 144.121632 -279.19299)
		)
		(stroke
			(width 0)
			(type solid)
		)
		(fill yes)
		(layer "In4.Cu")
		(net "M_J_CPU1_SB_DQ<8>")
	)
	(gr_poly
		(pts
			(xy 144.121632 -277.528528) (xy 144.021556 -277.428452) (xy 143.92148 -277.528528) (xy 143.92148 -277.572978)
			(xy 144.121632 -277.572978)
		)
		(stroke
			(width 0)
			(type solid)
		)
		(fill yes)
		(layer "In4.Cu")
		(net "M_J_CPU1_SB_DQ<4>")
	)
	(gr_poly
		(pts
			(xy 144.121632 -274.288504) (xy 144.021556 -274.188428) (xy 143.92148 -274.288504) (xy 143.92148 -274.332954)
			(xy 144.121632 -274.332954)
		)
		(stroke
			(width 0)
			(type solid)
		)
		(fill yes)
		(layer "In4.Cu")
		(net "M_J_CPU1_SB_DQ<0>")
	)
	(gr_poly
		(pts
			(xy 144.121632 -272.668492) (xy 144.021556 -272.568416) (xy 143.92148 -272.668492) (xy 143.92148 -272.712942)
			(xy 144.121632 -272.712942)
		)
		(stroke
			(width 0)
			(type solid)
		)
		(fill yes)
		(layer "In4.Cu")
		(net "M_J_CPU1_SB_CB<0>")
	)
	(gr_poly
		(pts
			(xy 144.121632 -267.808456) (xy 144.021556 -267.70838) (xy 143.92148 -267.808456) (xy 143.92148 -267.852906)
			(xy 144.121632 -267.852906)
		)
		(stroke
			(width 0)
			(type solid)
		)
		(fill yes)
		(layer "In4.Cu")
		(net "M_J_CPU1_SB_RSP<0>")
	)
	(gr_poly
		(pts
			(xy 144.121632 -264.568432) (xy 144.021556 -264.468356) (xy 143.92148 -264.568432) (xy 143.92148 -264.612882)
			(xy 144.121632 -264.612882)
		)
		(stroke
			(width 0)
			(type solid)
		)
		(fill yes)
		(layer "In4.Cu")
		(net "M_J_CPU1_SB_CA<6>")
	)
	(gr_poly
		(pts
			(xy 144.121632 -262.94842) (xy 144.021556 -262.848344) (xy 143.92148 -262.94842) (xy 143.92148 -262.99287)
			(xy 144.121632 -262.99287)
		)
		(stroke
			(width 0)
			(type solid)
		)
		(fill yes)
		(layer "In4.Cu")
		(net "M_J_CPU1_SB_CA<2>")
	)
	(gr_poly
		(pts
			(xy 144.13484 -292.108128) (xy 144.034764 -292.008052) (xy 143.934688 -292.108128) (xy 143.934688 -292.152578)
			(xy 144.13484 -292.152578)
		)
		(stroke
			(width 0)
			(type solid)
		)
		(fill yes)
		(layer "In4.Cu")
		(net "M_J_CPU1_SB_DQ<28>")
	)
	(gr_poly
		(pts
			(xy 144.13484 -291.704522) (xy 144.13484 -291.65677) (xy 143.934688 -291.65677) (xy 143.934688 -291.704522)
			(xy 144.034764 -291.804344)
		)
		(stroke
			(width 0)
			(type solid)
		)
		(fill yes)
		(layer "In4.Cu")
		(net "M_J_CPU1_SB_DQS_DP<8>")
	)
	(gr_poly
		(pts
			(xy 144.13484 -270.644366) (xy 144.13484 -270.599916) (xy 143.934688 -270.599916) (xy 143.934688 -270.644366)
			(xy 144.034764 -270.744442)
		)
		(stroke
			(width 0)
			(type solid)
		)
		(fill yes)
		(layer "In4.Cu")
		(net "M_J_CPU1_SB_CB<7>")
	)
	(gr_poly
		(pts
			(xy 144.140936 -286.844486) (xy 144.140936 -286.796988) (xy 143.941038 -286.796988) (xy 143.941038 -286.844486)
			(xy 144.04086 -286.944562)
		)
		(stroke
			(width 0)
			(type solid)
		)
		(fill yes)
		(layer "In4.Cu")
		(net "M_J_CPU1_SB_DQS_DP<7>")
	)
	(gr_poly
		(pts
			(xy 144.140936 -285.224474) (xy 144.140936 -285.180024) (xy 143.941038 -285.180024) (xy 143.941038 -285.224474)
			(xy 144.04086 -285.32455)
		)
		(stroke
			(width 0)
			(type solid)
		)
		(fill yes)
		(layer "In4.Cu")
		(net "M_J_CPU1_SB_DQ<19>")
	)
	(gr_poly
		(pts
			(xy 144.140936 -283.604462) (xy 144.140936 -283.560012) (xy 143.941038 -283.560012) (xy 143.941038 -283.604462)
			(xy 144.04086 -283.704538)
		)
		(stroke
			(width 0)
			(type solid)
		)
		(fill yes)
		(layer "In4.Cu")
		(net "M_J_CPU1_SB_DQ<15>")
	)
	(gr_poly
		(pts
			(xy 144.140936 -281.984704) (xy 144.140936 -281.937206) (xy 143.941038 -281.937206) (xy 143.941038 -281.984704)
			(xy 144.04086 -282.08478)
		)
		(stroke
			(width 0)
			(type solid)
		)
		(fill yes)
		(layer "In4.Cu")
		(net "M_J_CPU1_SB_DQS_DP<6>")
	)
	(gr_poly
		(pts
			(xy 144.140936 -280.364438) (xy 144.140936 -280.319988) (xy 143.941038 -280.319988) (xy 143.941038 -280.364438)
			(xy 144.04086 -280.464514)
		)
		(stroke
			(width 0)
			(type solid)
		)
		(fill yes)
		(layer "In4.Cu")
		(net "M_J_CPU1_SB_DQ<11>")
	)
	(gr_poly
		(pts
			(xy 144.140936 -278.744426) (xy 144.140936 -278.699976) (xy 143.941038 -278.699976) (xy 143.941038 -278.744426)
			(xy 144.04086 -278.844502)
		)
		(stroke
			(width 0)
			(type solid)
		)
		(fill yes)
		(layer "In4.Cu")
		(net "M_J_CPU1_SB_DQ<7>")
	)
	(gr_poly
		(pts
			(xy 144.140936 -277.124668) (xy 144.140936 -277.07717) (xy 143.941038 -277.07717) (xy 143.941038 -277.124668)
			(xy 144.04086 -277.224744)
		)
		(stroke
			(width 0)
			(type solid)
		)
		(fill yes)
		(layer "In4.Cu")
		(net "M_J_CPU1_SB_DQS_DP<5>")
	)
	(gr_poly
		(pts
			(xy 144.140936 -275.504402) (xy 144.140936 -275.459952) (xy 143.941038 -275.459952) (xy 143.941038 -275.504402)
			(xy 144.04086 -275.604478)
		)
		(stroke
			(width 0)
			(type solid)
		)
		(fill yes)
		(layer "In4.Cu")
		(net "M_J_CPU1_SB_DQ<3>")
	)
	(gr_poly
		(pts
			(xy 144.140936 -273.88439) (xy 144.140936 -273.83994) (xy 143.941038 -273.83994) (xy 143.941038 -273.88439)
			(xy 144.04086 -273.984466)
		)
		(stroke
			(width 0)
			(type solid)
		)
		(fill yes)
		(layer "In4.Cu")
		(net "M_J_CPU1_SB_CB<3>")
	)
	(gr_poly
		(pts
			(xy 144.140936 -272.264632) (xy 144.140936 -272.217134) (xy 143.941038 -272.217134) (xy 143.941038 -272.264632)
			(xy 144.04086 -272.364708)
		)
		(stroke
			(width 0)
			(type solid)
		)
		(fill yes)
		(layer "In4.Cu")
		(net "M_J_CPU1_SB_DQS_DP<4>")
	)
	(gr_poly
		(pts
			(xy 144.140936 -265.78433) (xy 144.140936 -265.73988) (xy 143.941038 -265.73988) (xy 143.941038 -265.78433)
			(xy 144.04086 -265.884406)
		)
		(stroke
			(width 0)
			(type solid)
		)
		(fill yes)
		(layer "In4.Cu")
		(net "M_J_CPU1_SB_CS_N<0>")
	)
	(gr_poly
		(pts
			(xy 144.140936 -264.164318) (xy 144.140936 -264.119868) (xy 143.941038 -264.119868) (xy 143.941038 -264.164318)
			(xy 144.04086 -264.264394)
		)
		(stroke
			(width 0)
			(type solid)
		)
		(fill yes)
		(layer "In4.Cu")
		(net "M_J_CPU1_SB_CA<5>")
	)
	(gr_poly
		(pts
			(xy 144.140936 -262.544306) (xy 144.140936 -262.499856) (xy 143.941038 -262.499856) (xy 143.941038 -262.544306)
			(xy 144.04086 -262.644382)
		)
		(stroke
			(width 0)
			(type solid)
		)
		(fill yes)
		(layer "In4.Cu")
		(net "M_J_CPU1_SB_CA<1>")
	)
	(gr_poly
		(pts
			(xy 144.15389 -293.328344) (xy 144.190466 -293.191692) (xy 144.054068 -293.155116) (xy 144.01546 -293.177468)
			(xy 144.115536 -293.350696)
		)
		(stroke
			(width 0)
			(type solid)
		)
		(fill yes)
		(layer "In4.Cu")
		(net "M_J_CPU1_SB_DQ<29>")
	)
	(gr_poly
		(pts
			(xy 144.190466 -269.560802) (xy 144.15389 -269.42415) (xy 144.115536 -269.401798) (xy 144.01546 -269.575026)
			(xy 144.054068 -269.597378)
		)
		(stroke
			(width 0)
			(type solid)
		)
		(fill yes)
		(layer "In4.Cu")
		(net "M_J_CPU1_SB_CB<6>")
	)
	(gr_poly
		(pts
			(xy 144.223994 -224.695766) (xy 144.185386 -224.673414) (xy 144.048734 -224.70999) (xy 144.085564 -224.846642)
			(xy 144.123918 -224.868994)
		)
		(stroke
			(width 0)
			(type solid)
		)
		(fill yes)
		(layer "In4.Cu")
		(net "M_J_CPU1_SA_DQ<4>")
	)
	(gr_poly
		(pts
			(xy 144.226788 -223.076516) (xy 144.18564 -223.05264) (xy 144.048988 -223.08947) (xy 144.085564 -223.225868)
			(xy 144.126966 -223.249744)
		)
		(stroke
			(width 0)
			(type solid)
		)
		(fill yes)
		(layer "In4.Cu")
		(net "M_J_CPU1_SA_DQS_DN<5>")
	)
	(gr_poly
		(pts
			(xy 144.286732 -236.586522) (xy 144.186656 -236.486446) (xy 144.086834 -236.586522) (xy 144.086834 -236.63402)
			(xy 144.286732 -236.63402)
		)
		(stroke
			(width 0)
			(type solid)
		)
		(fill yes)
		(layer "In4.Cu")
		(net "M_J_CPU1_SA_DQS_DP<2>")
	)
	(gr_poly
		(pts
			(xy 144.296892 -255.622806) (xy 144.296892 -255.578356) (xy 144.096994 -255.578356) (xy 144.096994 -255.622806)
			(xy 144.19707 -255.722628)
		)
		(stroke
			(width 0)
			(type solid)
		)
		(fill yes)
		(layer "In4.Cu")
		(net "M_J_CPU1_SA_PAR")
	)
	(gr_poly
		(pts
			(xy 144.296892 -254.002794) (xy 144.296892 -253.958344) (xy 144.096994 -253.958344) (xy 144.096994 -254.002794)
			(xy 144.19707 -254.10287)
		)
		(stroke
			(width 0)
			(type solid)
		)
		(fill yes)
		(layer "In4.Cu")
		(net "M_J_CPU1_SA_CA<3>")
	)
	(gr_poly
		(pts
			(xy 144.296892 -250.76277) (xy 144.296892 -250.71832) (xy 144.096994 -250.71832) (xy 144.096994 -250.76277)
			(xy 144.19707 -250.862592)
		)
		(stroke
			(width 0)
			(type solid)
		)
		(fill yes)
		(layer "In4.Cu")
		(net "M_J_CPU1_RESET_N")
	)
	(gr_poly
		(pts
			(xy 144.296892 -249.142758) (xy 144.296892 -249.098308) (xy 144.096994 -249.098308) (xy 144.096994 -249.142758)
			(xy 144.19707 -249.242834)
		)
		(stroke
			(width 0)
			(type solid)
		)
		(fill yes)
		(layer "In4.Cu")
		(net "M_J_CPU1_SA_CB<7>")
	)
	(gr_poly
		(pts
			(xy 144.296892 -247.523) (xy 144.296892 -247.475248) (xy 144.096994 -247.475248) (xy 144.096994 -247.523)
			(xy 144.19707 -247.622822)
		)
		(stroke
			(width 0)
			(type solid)
		)
		(fill yes)
		(layer "In4.Cu")
		(net "M_J_CPU1_SA_DQS_DP<9>")
	)
	(gr_poly
		(pts
			(xy 144.296892 -245.902734) (xy 144.296892 -245.858284) (xy 144.096994 -245.858284) (xy 144.096994 -245.902734)
			(xy 144.19707 -246.002556)
		)
		(stroke
			(width 0)
			(type solid)
		)
		(fill yes)
		(layer "In4.Cu")
		(net "M_J_CPU1_SA_CB<3>")
	)
	(gr_poly
		(pts
			(xy 144.296892 -244.282722) (xy 144.296892 -244.238272) (xy 144.096994 -244.238272) (xy 144.096994 -244.282722)
			(xy 144.19707 -244.382544)
		)
		(stroke
			(width 0)
			(type solid)
		)
		(fill yes)
		(layer "In4.Cu")
		(net "M_J_CPU1_SA_DQ<31>")
	)
	(gr_poly
		(pts
			(xy 144.296892 -241.042698) (xy 144.296892 -240.998248) (xy 144.096994 -240.998248) (xy 144.096994 -241.042698)
			(xy 144.19707 -241.14252)
		)
		(stroke
			(width 0)
			(type solid)
		)
		(fill yes)
		(layer "In4.Cu")
		(net "M_J_CPU1_SA_DQ<27>")
	)
	(gr_poly
		(pts
			(xy 144.296892 -239.422686) (xy 144.296892 -239.378236) (xy 144.096994 -239.378236) (xy 144.096994 -239.422686)
			(xy 144.19707 -239.522508)
		)
		(stroke
			(width 0)
			(type solid)
		)
		(fill yes)
		(layer "In4.Cu")
		(net "M_J_CPU1_SA_DQ<23>")
	)
	(gr_poly
		(pts
			(xy 144.299178 -254.4064) (xy 144.199356 -254.306324) (xy 144.09928 -254.4064) (xy 144.09928 -254.45085)
			(xy 144.299178 -254.45085)
		)
		(stroke
			(width 0)
			(type solid)
		)
		(fill yes)
		(layer "In4.Cu")
		(net "M_J_CPU1_SA_CA<4>")
	)
	(gr_poly
		(pts
			(xy 144.299178 -252.786388) (xy 144.199356 -252.686312) (xy 144.09928 -252.786388) (xy 144.09928 -252.830838)
			(xy 144.299178 -252.830838)
		)
		(stroke
			(width 0)
			(type solid)
		)
		(fill yes)
		(layer "In4.Cu")
		(net "M_J_CPU1_SA_CA<0>")
	)
	(gr_poly
		(pts
			(xy 144.299178 -251.166376) (xy 144.199356 -251.0663) (xy 144.09928 -251.166376) (xy 144.09928 -251.210826)
			(xy 144.299178 -251.210826)
		)
		(stroke
			(width 0)
			(type solid)
		)
		(fill yes)
		(layer "In4.Cu")
		(net "M_J_CPU1_SA_CS_N<0>")
	)
	(gr_poly
		(pts
			(xy 144.299178 -247.926352) (xy 144.199356 -247.826276) (xy 144.09928 -247.926352) (xy 144.09928 -247.970802)
			(xy 144.299178 -247.970802)
		)
		(stroke
			(width 0)
			(type solid)
		)
		(fill yes)
		(layer "In4.Cu")
		(net "M_J_CPU1_SA_CB<4>")
	)
	(gr_poly
		(pts
			(xy 144.299178 -246.306086) (xy 144.199356 -246.20601) (xy 144.09928 -246.306086) (xy 144.09928 -246.353584)
			(xy 144.299178 -246.353584)
		)
		(stroke
			(width 0)
			(type solid)
		)
		(fill yes)
		(layer "In4.Cu")
		(net "M_J_CPU1_SA_DQS_DP<4>")
	)
	(gr_poly
		(pts
			(xy 144.299178 -244.686328) (xy 144.199356 -244.586252) (xy 144.09928 -244.686328) (xy 144.09928 -244.730778)
			(xy 144.299178 -244.730778)
		)
		(stroke
			(width 0)
			(type solid)
		)
		(fill yes)
		(layer "In4.Cu")
		(net "M_J_CPU1_SA_CB<0>")
	)
	(gr_poly
		(pts
			(xy 144.299178 -243.066316) (xy 144.199356 -242.96624) (xy 144.09928 -243.066316) (xy 144.09928 -243.110766)
			(xy 144.299178 -243.110766)
		)
		(stroke
			(width 0)
			(type solid)
		)
		(fill yes)
		(layer "In4.Cu")
		(net "M_J_CPU1_SA_DQ<28>")
	)
	(gr_poly
		(pts
			(xy 144.299178 -241.44605) (xy 144.199356 -241.345974) (xy 144.09928 -241.44605) (xy 144.09928 -241.493548)
			(xy 144.299178 -241.493548)
		)
		(stroke
			(width 0)
			(type solid)
		)
		(fill yes)
		(layer "In4.Cu")
		(net "M_J_CPU1_SA_DQS_DP<3>")
	)
	(gr_poly
		(pts
			(xy 144.299178 -239.826292) (xy 144.199356 -239.726216) (xy 144.09928 -239.826292) (xy 144.09928 -239.870742)
			(xy 144.299178 -239.870742)
		)
		(stroke
			(width 0)
			(type solid)
		)
		(fill yes)
		(layer "In4.Cu")
		(net "M_J_CPU1_SA_DQ<24>")
	)
	(gr_poly
		(pts
			(xy 144.299178 -238.20628) (xy 144.199356 -238.106204) (xy 144.09928 -238.20628) (xy 144.09928 -238.25073)
			(xy 144.299178 -238.25073)
		)
		(stroke
			(width 0)
			(type solid)
		)
		(fill yes)
		(layer "In4.Cu")
		(net "M_J_CPU1_SA_DQ<20>")
	)
	(gr_poly
		(pts
			(xy 144.310608 -237.802674) (xy 144.310608 -237.754922) (xy 144.11071 -237.754922) (xy 144.11071 -237.802674)
			(xy 144.210532 -237.902496)
		)
		(stroke
			(width 0)
			(type solid)
		)
		(fill yes)
		(layer "In4.Cu")
		(net "M_J_CPU1_SA_DQS_DP<7>")
	)
	(gr_poly
		(pts
			(xy 144.313402 -256.025904) (xy 144.213326 -255.926082) (xy 144.113504 -256.025904) (xy 144.113504 -256.073656)
			(xy 144.313402 -256.073656)
		)
		(stroke
			(width 0)
			(type solid)
		)
		(fill yes)
		(layer "In4.Cu")
		(net "M_J_CPU1_CLK_DP<0>")
	)
	(gr_poly
		(pts
			(xy 144.360646 -225.379026) (xy 144.32407 -225.242374) (xy 144.285716 -225.220022) (xy 144.18564 -225.39325)
			(xy 144.224248 -225.415602)
		)
		(stroke
			(width 0)
			(type solid)
		)
		(fill yes)
		(layer "In4.Cu")
		(net "M_J_CPU1_SA_DQ<6>")
	)
	(gr_poly
		(pts
			(xy 144.360646 -223.759522) (xy 144.32407 -223.623124) (xy 144.282668 -223.599248) (xy 144.182846 -223.772476)
			(xy 144.223994 -223.796352)
		)
		(stroke
			(width 0)
			(type solid)
		)
		(fill yes)
		(layer "In4.Cu")
		(net "M_J_CPU1_SA_DQS_DP<5>")
	)
	(gr_poly
		(pts
			(xy 144.360646 -222.139002) (xy 144.32407 -222.00235) (xy 144.282922 -221.978474) (xy 144.182846 -222.151702)
			(xy 144.223994 -222.175578)
		)
		(stroke
			(width 0)
			(type solid)
		)
		(fill yes)
		(layer "In4.Cu")
		(net "M_J_CPU1_SA_DQS_DN<0>")
	)
	(gr_poly
		(pts
			(xy 144.523714 -294.684958) (xy 144.423638 -294.51173) (xy 144.385284 -294.534082) (xy 144.348454 -294.670734)
			(xy 144.485106 -294.70731)
		)
		(stroke
			(width 0)
			(type solid)
		)
		(fill yes)
		(layer "In4.Cu")
		(net "M_J_CPU1_SB_DQ<31>")
	)
	(gr_poly
		(pts
			(xy 144.523968 -293.064946) (xy 144.423892 -292.891718) (xy 144.385538 -292.91407) (xy 144.348962 -293.050722)
			(xy 144.48536 -293.087298)
		)
		(stroke
			(width 0)
			(type solid)
		)
		(fill yes)
		(layer "In4.Cu")
		(net "M_J_CPU1_SB_DQ<30>")
	)
	(gr_poly
		(pts
			(xy 144.523968 -269.687548) (xy 144.48536 -269.665196) (xy 144.348962 -269.701772) (xy 144.385538 -269.838424)
			(xy 144.423892 -269.860776)
		)
		(stroke
			(width 0)
			(type solid)
		)
		(fill yes)
		(layer "In4.Cu")
		(net "M_J_CPU1_SB_CB<5>")
	)
	(gr_poly
		(pts
			(xy 144.599406 -284.818328) (xy 144.49933 -284.718252) (xy 144.399254 -284.818328) (xy 144.399254 -284.862778)
			(xy 144.599406 -284.862778)
		)
		(stroke
			(width 0)
			(type solid)
		)
		(fill yes)
		(layer "In4.Cu")
		(net "M_J_CPU1_SB_DQ<17>")
	)
	(gr_poly
		(pts
			(xy 144.599406 -283.198316) (xy 144.49933 -283.09824) (xy 144.399254 -283.198316) (xy 144.399254 -283.242766)
			(xy 144.599406 -283.242766)
		)
		(stroke
			(width 0)
			(type solid)
		)
		(fill yes)
		(layer "In4.Cu")
		(net "M_J_CPU1_SB_DQ<13>")
	)
	(gr_poly
		(pts
			(xy 144.599406 -281.57805) (xy 144.49933 -281.477974) (xy 144.399254 -281.57805) (xy 144.399254 -281.625548)
			(xy 144.599406 -281.625548)
		)
		(stroke
			(width 0)
			(type solid)
		)
		(fill yes)
		(layer "In4.Cu")
		(net "M_J_CPU1_SB_DQS_DN<6>")
	)
	(gr_poly
		(pts
			(xy 144.599406 -279.958292) (xy 144.49933 -279.858216) (xy 144.399254 -279.958292) (xy 144.399254 -280.002742)
			(xy 144.599406 -280.002742)
		)
		(stroke
			(width 0)
			(type solid)
		)
		(fill yes)
		(layer "In4.Cu")
		(net "M_J_CPU1_SB_DQ<9>")
	)
	(gr_poly
		(pts
			(xy 144.599406 -278.33828) (xy 144.49933 -278.238204) (xy 144.399254 -278.33828) (xy 144.399254 -278.38273)
			(xy 144.599406 -278.38273)
		)
		(stroke
			(width 0)
			(type solid)
		)
		(fill yes)
		(layer "In4.Cu")
		(net "M_J_CPU1_SB_DQ<5>")
	)
	(gr_poly
		(pts
			(xy 144.599406 -276.718014) (xy 144.49933 -276.617938) (xy 144.399254 -276.718014) (xy 144.399254 -276.765512)
			(xy 144.599406 -276.765512)
		)
		(stroke
			(width 0)
			(type solid)
		)
		(fill yes)
		(layer "In4.Cu")
		(net "M_J_CPU1_SB_DQS_DN<5>")
	)
	(gr_poly
		(pts
			(xy 144.599406 -275.098256) (xy 144.49933 -274.99818) (xy 144.399254 -275.098256) (xy 144.399254 -275.142706)
			(xy 144.599406 -275.142706)
		)
		(stroke
			(width 0)
			(type solid)
		)
		(fill yes)
		(layer "In4.Cu")
		(net "M_J_CPU1_SB_DQ<1>")
	)
	(gr_poly
		(pts
			(xy 144.599406 -273.478244) (xy 144.49933 -273.378168) (xy 144.399254 -273.478244) (xy 144.399254 -273.522694)
			(xy 144.599406 -273.522694)
		)
		(stroke
			(width 0)
			(type solid)
		)
		(fill yes)
		(layer "In4.Cu")
		(net "M_J_CPU1_SB_CB<1>")
	)
	(gr_poly
		(pts
			(xy 144.599406 -266.998196) (xy 144.49933 -266.89812) (xy 144.399254 -266.998196) (xy 144.399254 -267.042646)
			(xy 144.599406 -267.042646)
		)
		(stroke
			(width 0)
			(type solid)
		)
		(fill yes)
		(layer "In4.Cu")
		(net "M_J_CPU1_SA_RSP<0>")
	)
	(gr_poly
		(pts
			(xy 144.599406 -265.378184) (xy 144.49933 -265.278108) (xy 144.399254 -265.378184) (xy 144.399254 -265.422634)
			(xy 144.599406 -265.422634)
		)
		(stroke
			(width 0)
			(type solid)
		)
		(fill yes)
		(layer "In4.Cu")
		(net "M_J_CPU1_SB_PAR")
	)
	(gr_poly
		(pts
			(xy 144.599406 -263.758172) (xy 144.49933 -263.658096) (xy 144.399254 -263.758172) (xy 144.399254 -263.802622)
			(xy 144.599406 -263.802622)
		)
		(stroke
			(width 0)
			(type solid)
		)
		(fill yes)
		(layer "In4.Cu")
		(net "M_J_CPU1_SB_CA<4>")
	)
	(gr_poly
		(pts
			(xy 144.599406 -262.13816) (xy 144.49933 -262.038084) (xy 144.399254 -262.13816) (xy 144.399254 -262.18261)
			(xy 144.599406 -262.18261)
		)
		(stroke
			(width 0)
			(type solid)
		)
		(fill yes)
		(layer "In4.Cu")
		(net "M_J_CPU1_SB_CA<0>")
	)
	(gr_poly
		(pts
			(xy 144.60474 -291.297868) (xy 144.504664 -291.198046) (xy 144.404588 -291.297868) (xy 144.404588 -291.34562)
			(xy 144.60474 -291.34562)
		)
		(stroke
			(width 0)
			(type solid)
		)
		(fill yes)
		(layer "In4.Cu")
		(net "M_J_CPU1_SB_DQS_DN<8>")
	)
	(gr_poly
		(pts
			(xy 144.60474 -271.454626) (xy 144.60474 -271.406874) (xy 144.404588 -271.406874) (xy 144.404588 -271.454626)
			(xy 144.504664 -271.554448)
		)
		(stroke
			(width 0)
			(type solid)
		)
		(fill yes)
		(layer "In4.Cu")
		(net "M_J_CPU1_SB_DQS_DN<9>")
	)
	(gr_poly
		(pts
			(xy 144.60474 -268.618208) (xy 144.504664 -268.518132) (xy 144.404588 -268.618208) (xy 144.404588 -268.662658)
			(xy 144.60474 -268.662658)
		)
		(stroke
			(width 0)
			(type solid)
		)
		(fill yes)
		(layer "In4.Cu")
		(net "M_J_CPU1_SB_CB<4>")
	)
	(gr_poly
		(pts
			(xy 144.615662 -284.414214) (xy 144.615662 -284.369764) (xy 144.41551 -284.369764) (xy 144.41551 -284.414214)
			(xy 144.515586 -284.51429)
		)
		(stroke
			(width 0)
			(type solid)
		)
		(fill yes)
		(layer "In4.Cu")
		(net "M_J_CPU1_SB_DQ<18>")
	)
	(gr_poly
		(pts
			(xy 144.615662 -282.794202) (xy 144.615662 -282.749752) (xy 144.41551 -282.749752) (xy 144.41551 -282.794202)
			(xy 144.515586 -282.894278)
		)
		(stroke
			(width 0)
			(type solid)
		)
		(fill yes)
		(layer "In4.Cu")
		(net "M_J_CPU1_SB_DQ<14>")
	)
	(gr_poly
		(pts
			(xy 144.615662 -279.554178) (xy 144.615662 -279.509728) (xy 144.41551 -279.509728) (xy 144.41551 -279.554178)
			(xy 144.515586 -279.654254)
		)
		(stroke
			(width 0)
			(type solid)
		)
		(fill yes)
		(layer "In4.Cu")
		(net "M_J_CPU1_SB_DQ<10>")
	)
	(gr_poly
		(pts
			(xy 144.615662 -277.934166) (xy 144.615662 -277.889716) (xy 144.41551 -277.889716) (xy 144.41551 -277.934166)
			(xy 144.515586 -278.034242)
		)
		(stroke
			(width 0)
			(type solid)
		)
		(fill yes)
		(layer "In4.Cu")
		(net "M_J_CPU1_SB_DQ<6>")
	)
	(gr_poly
		(pts
			(xy 144.615662 -274.694142) (xy 144.615662 -274.649692) (xy 144.41551 -274.649692) (xy 144.41551 -274.694142)
			(xy 144.515586 -274.794218)
		)
		(stroke
			(width 0)
			(type solid)
		)
		(fill yes)
		(layer "In4.Cu")
		(net "M_J_CPU1_SB_DQ<2>")
	)
	(gr_poly
		(pts
			(xy 144.615662 -273.07413) (xy 144.615662 -273.02968) (xy 144.41551 -273.02968) (xy 144.41551 -273.07413)
			(xy 144.515586 -273.174206)
		)
		(stroke
			(width 0)
			(type solid)
		)
		(fill yes)
		(layer "In4.Cu")
		(net "M_J_CPU1_SB_CB<2>")
	)
	(gr_poly
		(pts
			(xy 144.615662 -266.594082) (xy 144.615662 -266.549632) (xy 144.41551 -266.549632) (xy 144.41551 -266.594082)
			(xy 144.515586 -266.694158)
		)
		(stroke
			(width 0)
			(type solid)
		)
		(fill yes)
		(layer "In4.Cu")
		(net "M_J_CPU1_SB_CS_N<1>")
	)
	(gr_poly
		(pts
			(xy 144.615662 -263.354058) (xy 144.615662 -263.309608) (xy 144.41551 -263.309608) (xy 144.41551 -263.354058)
			(xy 144.515586 -263.454134)
		)
		(stroke
			(width 0)
			(type solid)
		)
		(fill yes)
		(layer "In4.Cu")
		(net "M_J_CPU1_SB_CA<3>")
	)
	(gr_poly
		(pts
			(xy 144.617694 -290.894262) (xy 144.617694 -290.846764) (xy 144.417796 -290.846764) (xy 144.417796 -290.894262)
			(xy 144.517618 -290.994338)
		)
		(stroke
			(width 0)
			(type solid)
		)
		(fill yes)
		(layer "In4.Cu")
		(net "M_J_CPU1_SB_DQS_DN<3>")
	)
	(gr_poly
		(pts
			(xy 144.617694 -286.03448) (xy 144.617694 -285.986982) (xy 144.417796 -285.986982) (xy 144.417796 -286.03448)
			(xy 144.517618 -286.134556)
		)
		(stroke
			(width 0)
			(type solid)
		)
		(fill yes)
		(layer "In4.Cu")
		(net "M_J_CPU1_SB_DQS_DN<2>")
	)
	(gr_poly
		(pts
			(xy 144.617694 -281.174444) (xy 144.617694 -281.126946) (xy 144.417796 -281.126946) (xy 144.417796 -281.174444)
			(xy 144.517618 -281.27452)
		)
		(stroke
			(width 0)
			(type solid)
		)
		(fill yes)
		(layer "In4.Cu")
		(net "M_J_CPU1_SB_DQS_DN<1>")
	)
	(gr_poly
		(pts
			(xy 144.617694 -276.314408) (xy 144.617694 -276.26691) (xy 144.417796 -276.26691) (xy 144.417796 -276.314408)
			(xy 144.517618 -276.414484)
		)
		(stroke
			(width 0)
			(type solid)
		)
		(fill yes)
		(layer "In4.Cu")
		(net "M_J_CPU1_SB_DQS_DN<0>")
	)
	(gr_poly
		(pts
			(xy 144.62379 -294.13835) (xy 144.660366 -294.001698) (xy 144.523968 -293.965122) (xy 144.48536 -293.987474)
			(xy 144.585436 -294.160702)
		)
		(stroke
			(width 0)
			(type solid)
		)
		(fill yes)
		(layer "In4.Cu")
		(net "M_J_CPU1_SB_DQ<29>")
	)
	(gr_poly
		(pts
			(xy 144.624044 -292.518338) (xy 144.660874 -292.381686) (xy 144.524222 -292.34511) (xy 144.485614 -292.367462)
			(xy 144.58569 -292.54069)
		)
		(stroke
			(width 0)
			(type solid)
		)
		(fill yes)
		(layer "In4.Cu")
		(net "M_J_CPU1_SB_DQ<28>")
	)
	(gr_poly
		(pts
			(xy 144.660874 -270.370808) (xy 144.624044 -270.234156) (xy 144.58569 -270.211804) (xy 144.485614 -270.385032)
			(xy 144.524222 -270.407384)
		)
		(stroke
			(width 0)
			(type solid)
		)
		(fill yes)
		(layer "In4.Cu")
		(net "M_J_CPU1_SB_CB<7>")
	)
	(gr_poly
		(pts
			(xy 144.693894 -223.88576) (xy 144.655286 -223.863408) (xy 144.518634 -223.899984) (xy 144.555464 -224.036636)
			(xy 144.593818 -224.058988)
		)
		(stroke
			(width 0)
			(type solid)
		)
		(fill yes)
		(layer "In4.Cu")
		(net "M_J_CPU1_SA_DQ<4>")
	)
	(gr_poly
		(pts
			(xy 144.696688 -222.266764) (xy 144.65554 -222.243142) (xy 144.518888 -222.279718) (xy 144.555464 -222.41637)
			(xy 144.596612 -222.439992)
		)
		(stroke
			(width 0)
			(type solid)
		)
		(fill yes)
		(layer "In4.Cu")
		(net "M_J_CPU1_SA_DQS_DN<5>")
	)
	(gr_poly
		(pts
			(xy 144.762982 -256.432812) (xy 144.762982 -256.385314) (xy 144.563084 -256.385314) (xy 144.563084 -256.432812)
			(xy 144.66316 -256.532888)
		)
		(stroke
			(width 0)
			(type solid)
		)
		(fill yes)
		(layer "In4.Cu")
		(net "M_J_CPU1_CLK_DN<0>")
	)
	(gr_poly
		(pts
			(xy 144.766792 -247.116092) (xy 144.66697 -247.01627) (xy 144.566894 -247.116092) (xy 144.566894 -247.163844)
			(xy 144.766792 -247.163844)
		)
		(stroke
			(width 0)
			(type solid)
		)
		(fill yes)
		(layer "In4.Cu")
		(net "M_J_CPU1_SA_DQS_DN<9>")
	)
	(gr_poly
		(pts
			(xy 144.766792 -246.71274) (xy 144.766792 -246.664988) (xy 144.566894 -246.664988) (xy 144.566894 -246.71274)
			(xy 144.66697 -246.812562)
		)
		(stroke
			(width 0)
			(type solid)
		)
		(fill yes)
		(layer "In4.Cu")
		(net "M_J_CPU1_SA_DQS_DN<4>")
	)
	(gr_poly
		(pts
			(xy 144.766792 -241.852704) (xy 144.766792 -241.804952) (xy 144.566894 -241.804952) (xy 144.566894 -241.852704)
			(xy 144.66697 -241.952526)
		)
		(stroke
			(width 0)
			(type solid)
		)
		(fill yes)
		(layer "In4.Cu")
		(net "M_J_CPU1_SA_DQS_DN<3>")
	)
	(gr_poly
		(pts
			(xy 144.772126 -255.216406) (xy 144.67205 -255.11633) (xy 144.571974 -255.216406) (xy 144.571974 -255.260856)
			(xy 144.772126 -255.260856)
		)
		(stroke
			(width 0)
			(type solid)
		)
		(fill yes)
		(layer "In4.Cu")
		(net "M_J_CPU1_SA_CA<6>")
	)
	(gr_poly
		(pts
			(xy 144.772126 -254.812546) (xy 144.772126 -254.768096) (xy 144.571974 -254.768096) (xy 144.571974 -254.812546)
			(xy 144.67205 -254.912622)
		)
		(stroke
			(width 0)
			(type solid)
		)
		(fill yes)
		(layer "In4.Cu")
		(net "M_J_CPU1_SA_CA<5>")
	)
	(gr_poly
		(pts
			(xy 144.772126 -253.596394) (xy 144.67205 -253.496318) (xy 144.571974 -253.596394) (xy 144.571974 -253.640844)
			(xy 144.772126 -253.640844)
		)
		(stroke
			(width 0)
			(type solid)
		)
		(fill yes)
		(layer "In4.Cu")
		(net "M_J_CPU1_SA_CA<2>")
	)
	(gr_poly
		(pts
			(xy 144.772126 -253.192534) (xy 144.772126 -253.148084) (xy 144.571974 -253.148084) (xy 144.571974 -253.192534)
			(xy 144.67205 -253.29261)
		)
		(stroke
			(width 0)
			(type solid)
		)
		(fill yes)
		(layer "In4.Cu")
		(net "M_J_CPU1_SA_CA<1>")
	)
	(gr_poly
		(pts
			(xy 144.772126 -251.976382) (xy 144.67205 -251.876306) (xy 144.571974 -251.976382) (xy 144.571974 -252.020832)
			(xy 144.772126 -252.020832)
		)
		(stroke
			(width 0)
			(type solid)
		)
		(fill yes)
		(layer "In4.Cu")
		(net "M_J_CPU1_SA_CS_N<1>")
	)
	(gr_poly
		(pts
			(xy 144.772126 -250.35637) (xy 144.67205 -250.256294) (xy 144.571974 -250.35637) (xy 144.571974 -250.40082)
			(xy 144.772126 -250.40082)
		)
		(stroke
			(width 0)
			(type solid)
		)
		(fill yes)
		(layer "In4.Cu")
		(net "M_J_CPU1_ALERT_R_N")
	)
	(gr_poly
		(pts
			(xy 144.772126 -248.736358) (xy 144.67205 -248.636282) (xy 144.571974 -248.736358) (xy 144.571974 -248.780808)
			(xy 144.772126 -248.780808)
		)
		(stroke
			(width 0)
			(type solid)
		)
		(fill yes)
		(layer "In4.Cu")
		(net "M_J_CPU1_SA_CB<5>")
	)
	(gr_poly
		(pts
			(xy 144.772126 -248.332498) (xy 144.772126 -248.288048) (xy 144.571974 -248.288048) (xy 144.571974 -248.332498)
			(xy 144.67205 -248.432574)
		)
		(stroke
			(width 0)
			(type solid)
		)
		(fill yes)
		(layer "In4.Cu")
		(net "M_J_CPU1_SA_CB<6>")
	)
	(gr_poly
		(pts
			(xy 144.772126 -245.496334) (xy 144.67205 -245.396258) (xy 144.571974 -245.496334) (xy 144.571974 -245.540784)
			(xy 144.772126 -245.540784)
		)
		(stroke
			(width 0)
			(type solid)
		)
		(fill yes)
		(layer "In4.Cu")
		(net "M_J_CPU1_SA_CB<1>")
	)
	(gr_poly
		(pts
			(xy 144.772126 -245.092474) (xy 144.772126 -245.048024) (xy 144.571974 -245.048024) (xy 144.571974 -245.092474)
			(xy 144.67205 -245.19255)
		)
		(stroke
			(width 0)
			(type solid)
		)
		(fill yes)
		(layer "In4.Cu")
		(net "M_J_CPU1_SA_CB<2>")
	)
	(gr_poly
		(pts
			(xy 144.772126 -243.876322) (xy 144.67205 -243.776246) (xy 144.571974 -243.876322) (xy 144.571974 -243.920772)
			(xy 144.772126 -243.920772)
		)
		(stroke
			(width 0)
			(type solid)
		)
		(fill yes)
		(layer "In4.Cu")
		(net "M_J_CPU1_SA_DQ<29>")
	)
	(gr_poly
		(pts
			(xy 144.772126 -243.472462) (xy 144.772126 -243.428012) (xy 144.571974 -243.428012) (xy 144.571974 -243.472462)
			(xy 144.67205 -243.572538)
		)
		(stroke
			(width 0)
			(type solid)
		)
		(fill yes)
		(layer "In4.Cu")
		(net "M_J_CPU1_SA_DQ<30>")
	)
	(gr_poly
		(pts
			(xy 144.772126 -240.636298) (xy 144.67205 -240.536222) (xy 144.571974 -240.636298) (xy 144.571974 -240.680748)
			(xy 144.772126 -240.680748)
		)
		(stroke
			(width 0)
			(type solid)
		)
		(fill yes)
		(layer "In4.Cu")
		(net "M_J_CPU1_SA_DQ<25>")
	)
	(gr_poly
		(pts
			(xy 144.772126 -240.232438) (xy 144.772126 -240.187988) (xy 144.571974 -240.187988) (xy 144.571974 -240.232438)
			(xy 144.67205 -240.332514)
		)
		(stroke
			(width 0)
			(type solid)
		)
		(fill yes)
		(layer "In4.Cu")
		(net "M_J_CPU1_SA_DQ<26>")
	)
	(gr_poly
		(pts
			(xy 144.772126 -239.016286) (xy 144.67205 -238.91621) (xy 144.571974 -239.016286) (xy 144.571974 -239.060736)
			(xy 144.772126 -239.060736)
		)
		(stroke
			(width 0)
			(type solid)
		)
		(fill yes)
		(layer "In4.Cu")
		(net "M_J_CPU1_SA_DQ<21>")
	)
	(gr_poly
		(pts
			(xy 144.772126 -238.612426) (xy 144.772126 -238.567976) (xy 144.571974 -238.567976) (xy 144.571974 -238.612426)
			(xy 144.67205 -238.712502)
		)
		(stroke
			(width 0)
			(type solid)
		)
		(fill yes)
		(layer "In4.Cu")
		(net "M_J_CPU1_SA_DQ<22>")
	)
	(gr_poly
		(pts
			(xy 144.780508 -237.39602) (xy 144.680432 -237.295944) (xy 144.58061 -237.39602) (xy 144.58061 -237.443518)
			(xy 144.780508 -237.443518)
		)
		(stroke
			(width 0)
			(type solid)
		)
		(fill yes)
		(layer "In4.Cu")
		(net "M_J_CPU1_SA_DQS_DN<7>")
	)
	(gr_poly
		(pts
			(xy 144.798796 -236.991906) (xy 144.798796 -236.944408) (xy 144.598898 -236.944408) (xy 144.598898 -236.991906)
			(xy 144.698974 -237.091982)
		)
		(stroke
			(width 0)
			(type solid)
		)
		(fill yes)
		(layer "In4.Cu")
		(net "M_J_CPU1_SA_DQS_DN<2>")
	)
	(gr_poly
		(pts
			(xy 144.828514 -222.952564) (xy 144.791938 -222.815912) (xy 144.750536 -222.792036) (xy 144.65046 -222.965264)
			(xy 144.691862 -222.98914)
		)
		(stroke
			(width 0)
			(type solid)
		)
		(fill yes)
		(layer "In4.Cu")
		(net "M_J_CPU1_SA_DQS_DP<5>")
	)
	(gr_poly
		(pts
			(xy 144.830546 -224.56902) (xy 144.79397 -224.432368) (xy 144.755616 -224.410016) (xy 144.65554 -224.583244)
			(xy 144.694148 -224.605596)
		)
		(stroke
			(width 0)
			(type solid)
		)
		(fill yes)
		(layer "In4.Cu")
		(net "M_J_CPU1_SA_DQ<6>")
	)
	(gr_poly
		(pts
			(xy 144.993868 -295.494964) (xy 144.893792 -295.321736) (xy 144.855438 -295.344088) (xy 144.818862 -295.48074)
			(xy 144.95526 -295.517316)
		)
		(stroke
			(width 0)
			(type solid)
		)
		(fill yes)
		(layer "In4.Cu")
		(net "M_J_CPU1_SB_DQ<31>")
	)
	(gr_poly
		(pts
			(xy 144.993868 -293.874952) (xy 144.893792 -293.701724) (xy 144.855438 -293.724076) (xy 144.818862 -293.860728)
			(xy 144.95526 -293.897304)
		)
		(stroke
			(width 0)
			(type solid)
		)
		(fill yes)
		(layer "In4.Cu")
		(net "M_J_CPU1_SB_DQ<30>")
	)
	(gr_poly
		(pts
			(xy 144.996662 -270.498316) (xy 144.955514 -270.47444) (xy 144.818862 -270.51127) (xy 144.855438 -270.647668)
			(xy 144.89684 -270.671544)
		)
		(stroke
			(width 0)
			(type solid)
		)
		(fill yes)
		(layer "In4.Cu")
		(net "M_J_CPU1_SB_DQS_DP<9>")
	)
	(gr_poly
		(pts
			(xy 145.056098 -277.12162) (xy 145.056098 -277.074122) (xy 144.855946 -277.074122) (xy 144.855946 -277.12162)
			(xy 144.956022 -277.221696)
		)
		(stroke
			(width 0)
			(type solid)
		)
		(fill yes)
		(layer "In4.Cu")
		(net "M_J_CPU1_SB_DQS_DP<5>")
	)
	(gr_poly
		(pts
			(xy 145.066766 -281.984704) (xy 145.066766 -281.936952) (xy 144.866868 -281.936952) (xy 144.866868 -281.984704)
			(xy 144.966944 -282.084526)
		)
		(stroke
			(width 0)
			(type solid)
		)
		(fill yes)
		(layer "In4.Cu")
		(net "M_J_CPU1_SB_DQS_DP<6>")
	)
	(gr_poly
		(pts
			(xy 145.0721 -285.224474) (xy 145.0721 -285.180024) (xy 144.871948 -285.180024) (xy 144.871948 -285.224474)
			(xy 144.972024 -285.32455)
		)
		(stroke
			(width 0)
			(type solid)
		)
		(fill yes)
		(layer "In4.Cu")
		(net "M_J_CPU1_SB_DQ<19>")
	)
	(gr_poly
		(pts
			(xy 145.0721 -283.604462) (xy 145.0721 -283.560012) (xy 144.871948 -283.560012) (xy 144.871948 -283.604462)
			(xy 144.972024 -283.704538)
		)
		(stroke
			(width 0)
			(type solid)
		)
		(fill yes)
		(layer "In4.Cu")
		(net "M_J_CPU1_SB_DQ<15>")
	)
	(gr_poly
		(pts
			(xy 145.0721 -280.364438) (xy 145.0721 -280.319988) (xy 144.871948 -280.319988) (xy 144.871948 -280.364438)
			(xy 144.972024 -280.464514)
		)
		(stroke
			(width 0)
			(type solid)
		)
		(fill yes)
		(layer "In4.Cu")
		(net "M_J_CPU1_SB_DQ<11>")
	)
	(gr_poly
		(pts
			(xy 145.0721 -278.744426) (xy 145.0721 -278.699976) (xy 144.871948 -278.699976) (xy 144.871948 -278.744426)
			(xy 144.972024 -278.844502)
		)
		(stroke
			(width 0)
			(type solid)
		)
		(fill yes)
		(layer "In4.Cu")
		(net "M_J_CPU1_SB_DQ<7>")
	)
	(gr_poly
		(pts
			(xy 145.0721 -275.504402) (xy 145.0721 -275.459952) (xy 144.871948 -275.459952) (xy 144.871948 -275.504402)
			(xy 144.972024 -275.604478)
		)
		(stroke
			(width 0)
			(type solid)
		)
		(fill yes)
		(layer "In4.Cu")
		(net "M_J_CPU1_SB_DQ<3>")
	)
	(gr_poly
		(pts
			(xy 145.0721 -273.88439) (xy 145.0721 -273.83994) (xy 144.871948 -273.83994) (xy 144.871948 -273.88439)
			(xy 144.972024 -273.984466)
		)
		(stroke
			(width 0)
			(type solid)
		)
		(fill yes)
		(layer "In4.Cu")
		(net "M_J_CPU1_SB_CB<3>")
	)
	(gr_poly
		(pts
			(xy 145.0721 -265.78433) (xy 145.0721 -265.73988) (xy 144.871948 -265.73988) (xy 144.871948 -265.78433)
			(xy 144.972024 -265.884406)
		)
		(stroke
			(width 0)
			(type solid)
		)
		(fill yes)
		(layer "In4.Cu")
		(net "M_J_CPU1_SB_CS_N<0>")
	)
	(gr_poly
		(pts
			(xy 145.0721 -264.164318) (xy 145.0721 -264.119868) (xy 144.871948 -264.119868) (xy 144.871948 -264.164318)
			(xy 144.972024 -264.264394)
		)
		(stroke
			(width 0)
			(type solid)
		)
		(fill yes)
		(layer "In4.Cu")
		(net "M_J_CPU1_SB_CA<5>")
	)
	(gr_poly
		(pts
			(xy 145.0721 -262.544306) (xy 145.0721 -262.499856) (xy 144.871948 -262.499856) (xy 144.871948 -262.544306)
			(xy 144.972024 -262.644382)
		)
		(stroke
			(width 0)
			(type solid)
		)
		(fill yes)
		(layer "In4.Cu")
		(net "M_J_CPU1_SB_CA<1>")
	)
	(gr_poly
		(pts
			(xy 145.074894 -269.428214) (xy 144.974818 -269.328138) (xy 144.874742 -269.428214) (xy 144.874742 -269.472664)
			(xy 145.074894 -269.472664)
		)
		(stroke
			(width 0)
			(type solid)
		)
		(fill yes)
		(layer "In4.Cu")
		(net "M_J_CPU1_SB_CB<5>")
	)
	(gr_poly
		(pts
			(xy 145.074894 -269.024354) (xy 145.074894 -268.979904) (xy 144.874742 -268.979904) (xy 144.874742 -269.024354)
			(xy 144.974818 -269.12443)
		)
		(stroke
			(width 0)
			(type solid)
		)
		(fill yes)
		(layer "In4.Cu")
		(net "M_J_CPU1_SB_CB<6>")
	)
	(gr_poly
		(pts
			(xy 145.086324 -290.487608) (xy 144.986248 -290.387532) (xy 144.886426 -290.487608) (xy 144.886426 -290.535106)
			(xy 145.086324 -290.535106)
		)
		(stroke
			(width 0)
			(type solid)
		)
		(fill yes)
		(layer "In4.Cu")
		(net "M_J_CPU1_SB_DQS_DP<3>")
	)
	(gr_poly
		(pts
			(xy 145.086324 -285.627826) (xy 144.986248 -285.52775) (xy 144.886426 -285.627826) (xy 144.886426 -285.675324)
			(xy 145.086324 -285.675324)
		)
		(stroke
			(width 0)
			(type solid)
		)
		(fill yes)
		(layer "In4.Cu")
		(net "M_J_CPU1_SB_DQS_DP<2>")
	)
	(gr_poly
		(pts
			(xy 145.086324 -284.007814) (xy 144.986248 -283.907738) (xy 144.886426 -284.007814) (xy 144.886426 -284.052264)
			(xy 145.086324 -284.052264)
		)
		(stroke
			(width 0)
			(type solid)
		)
		(fill yes)
		(layer "In4.Cu")
		(net "M_J_CPU1_SB_DQ<16>")
	)
	(gr_poly
		(pts
			(xy 145.086324 -282.387802) (xy 144.986248 -282.287726) (xy 144.886426 -282.387802) (xy 144.886426 -282.432252)
			(xy 145.086324 -282.432252)
		)
		(stroke
			(width 0)
			(type solid)
		)
		(fill yes)
		(layer "In4.Cu")
		(net "M_J_CPU1_SB_DQ<12>")
	)
	(gr_poly
		(pts
			(xy 145.086324 -280.76779) (xy 144.986248 -280.667714) (xy 144.886426 -280.76779) (xy 144.886426 -280.815288)
			(xy 145.086324 -280.815288)
		)
		(stroke
			(width 0)
			(type solid)
		)
		(fill yes)
		(layer "In4.Cu")
		(net "M_J_CPU1_SB_DQS_DP<1>")
	)
	(gr_poly
		(pts
			(xy 145.086324 -279.147778) (xy 144.986248 -279.047702) (xy 144.886426 -279.147778) (xy 144.886426 -279.192228)
			(xy 145.086324 -279.192228)
		)
		(stroke
			(width 0)
			(type solid)
		)
		(fill yes)
		(layer "In4.Cu")
		(net "M_J_CPU1_SB_DQ<8>")
	)
	(gr_poly
		(pts
			(xy 145.086324 -277.527766) (xy 144.986248 -277.42769) (xy 144.886426 -277.527766) (xy 144.886426 -277.572216)
			(xy 145.086324 -277.572216)
		)
		(stroke
			(width 0)
			(type solid)
		)
		(fill yes)
		(layer "In4.Cu")
		(net "M_J_CPU1_SB_DQ<4>")
	)
	(gr_poly
		(pts
			(xy 145.086324 -275.907754) (xy 144.986248 -275.807678) (xy 144.886426 -275.907754) (xy 144.886426 -275.955252)
			(xy 145.086324 -275.955252)
		)
		(stroke
			(width 0)
			(type solid)
		)
		(fill yes)
		(layer "In4.Cu")
		(net "M_J_CPU1_SB_DQS_DP<0>")
	)
	(gr_poly
		(pts
			(xy 145.086324 -274.287742) (xy 144.986248 -274.187666) (xy 144.886426 -274.287742) (xy 144.886426 -274.332192)
			(xy 145.086324 -274.332192)
		)
		(stroke
			(width 0)
			(type solid)
		)
		(fill yes)
		(layer "In4.Cu")
		(net "M_J_CPU1_SB_DQ<0>")
	)
	(gr_poly
		(pts
			(xy 145.086324 -272.66773) (xy 144.986248 -272.567654) (xy 144.886426 -272.66773) (xy 144.886426 -272.71218)
			(xy 145.086324 -272.71218)
		)
		(stroke
			(width 0)
			(type solid)
		)
		(fill yes)
		(layer "In4.Cu")
		(net "M_J_CPU1_SB_CB<0>")
	)
	(gr_poly
		(pts
			(xy 145.086324 -267.807694) (xy 144.986248 -267.707618) (xy 144.886426 -267.807694) (xy 144.886426 -267.852144)
			(xy 145.086324 -267.852144)
		)
		(stroke
			(width 0)
			(type solid)
		)
		(fill yes)
		(layer "In4.Cu")
		(net "M_J_CPU1_SB_RSP<0>")
	)
	(gr_poly
		(pts
			(xy 145.086324 -264.56767) (xy 144.986248 -264.467594) (xy 144.886426 -264.56767) (xy 144.886426 -264.61212)
			(xy 145.086324 -264.61212)
		)
		(stroke
			(width 0)
			(type solid)
		)
		(fill yes)
		(layer "In4.Cu")
		(net "M_J_CPU1_SB_CA<6>")
	)
	(gr_poly
		(pts
			(xy 145.086324 -262.947658) (xy 144.986248 -262.847582) (xy 144.886426 -262.947658) (xy 144.886426 -262.992108)
			(xy 145.086324 -262.992108)
		)
		(stroke
			(width 0)
			(type solid)
		)
		(fill yes)
		(layer "In4.Cu")
		(net "M_J_CPU1_SB_CA<2>")
	)
	(gr_poly
		(pts
			(xy 145.09369 -294.948356) (xy 145.130266 -294.811704) (xy 144.993868 -294.775128) (xy 144.95526 -294.79748)
			(xy 145.055336 -294.970708)
		)
		(stroke
			(width 0)
			(type solid)
		)
		(fill yes)
		(layer "In4.Cu")
		(net "M_J_CPU1_SB_DQ<29>")
	)
	(gr_poly
		(pts
			(xy 145.093944 -293.328344) (xy 145.130774 -293.191692) (xy 144.994122 -293.155116) (xy 144.955514 -293.177468)
			(xy 145.05559 -293.350696)
		)
		(stroke
			(width 0)
			(type solid)
		)
		(fill yes)
		(layer "In4.Cu")
		(net "M_J_CPU1_SB_DQ<28>")
	)
	(gr_poly
		(pts
			(xy 145.093944 -291.70757) (xy 145.13052 -291.571172) (xy 144.993868 -291.534596) (xy 144.95272 -291.558218)
			(xy 145.052542 -291.731446)
		)
		(stroke
			(width 0)
			(type solid)
		)
		(fill yes)
		(layer "In4.Cu")
		(net "M_J_CPU1_SB_DQS_DN<8>")
	)
	(gr_poly
		(pts
			(xy 145.13052 -271.181322) (xy 145.093944 -271.044924) (xy 145.052542 -271.021048) (xy 144.95272 -271.194276)
			(xy 144.993868 -271.218152)
		)
		(stroke
			(width 0)
			(type solid)
		)
		(fill yes)
		(layer "In4.Cu")
		(net "M_J_CPU1_SB_DQS_DN<9>")
	)
	(gr_poly
		(pts
			(xy 145.164556 -223.074738) (xy 145.125948 -223.05264) (xy 144.989296 -223.089216) (xy 145.025872 -223.225868)
			(xy 145.06448 -223.24822)
		)
		(stroke
			(width 0)
			(type solid)
		)
		(fill yes)
		(layer "In4.Cu")
		(net "M_J_CPU1_SA_DQ<4>")
	)
	(gr_poly
		(pts
			(xy 145.23593 -237.802674) (xy 145.23593 -237.755176) (xy 145.036032 -237.755176) (xy 145.036032 -237.802674)
			(xy 145.136108 -237.90275)
		)
		(stroke
			(width 0)
			(type solid)
		)
		(fill yes)
		(layer "In4.Cu")
		(net "M_J_CPU1_SA_DQS_DP<7>")
	)
	(gr_poly
		(pts
			(xy 145.254218 -254.406146) (xy 145.154396 -254.306324) (xy 145.05432 -254.406146) (xy 145.05432 -254.450596)
			(xy 145.254218 -254.450596)
		)
		(stroke
			(width 0)
			(type solid)
		)
		(fill yes)
		(layer "In4.Cu")
		(net "M_J_CPU1_SA_CA<4>")
	)
	(gr_poly
		(pts
			(xy 145.254218 -254.002794) (xy 145.254218 -253.958344) (xy 145.05432 -253.958344) (xy 145.05432 -254.002794)
			(xy 145.154396 -254.102616)
		)
		(stroke
			(width 0)
			(type solid)
		)
		(fill yes)
		(layer "In4.Cu")
		(net "M_J_CPU1_SA_CA<3>")
	)
	(gr_poly
		(pts
			(xy 145.254218 -252.786134) (xy 145.154396 -252.686312) (xy 145.05432 -252.786134) (xy 145.05432 -252.830584)
			(xy 145.254218 -252.830584)
		)
		(stroke
			(width 0)
			(type solid)
		)
		(fill yes)
		(layer "In4.Cu")
		(net "M_J_CPU1_SA_CA<0>")
	)
	(gr_poly
		(pts
			(xy 145.254218 -251.166122) (xy 145.154396 -251.0663) (xy 145.05432 -251.166122) (xy 145.05432 -251.210572)
			(xy 145.254218 -251.210572)
		)
		(stroke
			(width 0)
			(type solid)
		)
		(fill yes)
		(layer "In4.Cu")
		(net "M_J_CPU1_SA_CS_N<0>")
	)
	(gr_poly
		(pts
			(xy 145.254218 -249.142758) (xy 145.254218 -249.098308) (xy 145.05432 -249.098308) (xy 145.05432 -249.142758)
			(xy 145.154396 -249.24258)
		)
		(stroke
			(width 0)
			(type solid)
		)
		(fill yes)
		(layer "In4.Cu")
		(net "M_J_CPU1_SA_CB<7>")
	)
	(gr_poly
		(pts
			(xy 145.254218 -247.926098) (xy 145.154396 -247.826276) (xy 145.05432 -247.926098) (xy 145.05432 -247.970548)
			(xy 145.254218 -247.970548)
		)
		(stroke
			(width 0)
			(type solid)
		)
		(fill yes)
		(layer "In4.Cu")
		(net "M_J_CPU1_SA_CB<4>")
	)
	(gr_poly
		(pts
			(xy 145.254218 -245.902734) (xy 145.254218 -245.858284) (xy 145.05432 -245.858284) (xy 145.05432 -245.902734)
			(xy 145.154396 -246.002556)
		)
		(stroke
			(width 0)
			(type solid)
		)
		(fill yes)
		(layer "In4.Cu")
		(net "M_J_CPU1_SA_CB<3>")
	)
	(gr_poly
		(pts
			(xy 145.257266 -256.026158) (xy 145.15719 -255.926082) (xy 145.057114 -256.026158) (xy 145.057114 -256.073656)
			(xy 145.257266 -256.073656)
		)
		(stroke
			(width 0)
			(type solid)
		)
		(fill yes)
		(layer "In4.Cu")
		(net "M_J_CPU1_CLK_DP<0>")
	)
	(gr_poly
		(pts
			(xy 145.257266 -247.522746) (xy 145.257266 -247.475248) (xy 145.057114 -247.475248) (xy 145.057114 -247.522746)
			(xy 145.15719 -247.622822)
		)
		(stroke
			(width 0)
			(type solid)
		)
		(fill yes)
		(layer "In4.Cu")
		(net "M_J_CPU1_SA_DQS_DP<9>")
	)
	(gr_poly
		(pts
			(xy 145.257266 -246.306086) (xy 145.15719 -246.20601) (xy 145.057114 -246.306086) (xy 145.057114 -246.353584)
			(xy 145.257266 -246.353584)
		)
		(stroke
			(width 0)
			(type solid)
		)
		(fill yes)
		(layer "In4.Cu")
		(net "M_J_CPU1_SA_DQS_DP<4>")
	)
	(gr_poly
		(pts
			(xy 145.299938 -223.760284) (xy 145.263362 -223.623632) (xy 145.224754 -223.601534) (xy 145.124678 -223.774762)
			(xy 145.163286 -223.79686)
		)
		(stroke
			(width 0)
			(type solid)
		)
		(fill yes)
		(layer "In4.Cu")
		(net "M_J_CPU1_SA_DQ<6>")
	)
	(gr_poly
		(pts
			(xy 145.523458 -276.314916) (xy 145.523458 -276.267164) (xy 145.32356 -276.267164) (xy 145.32356 -276.314916)
			(xy 145.423636 -276.414992)
		)
		(stroke
			(width 0)
			(type solid)
		)
		(fill yes)
		(layer "In4.Cu")
		(net "M_J_CPU1_SB_DQS_DN<0>")
	)
	(gr_poly
		(pts
			(xy 145.524982 -273.074638) (xy 145.524982 -273.030188) (xy 145.325084 -273.030188) (xy 145.325084 -273.074638)
			(xy 145.42516 -273.174714)
		)
		(stroke
			(width 0)
			(type solid)
		)
		(fill yes)
		(layer "In4.Cu")
		(net "M_J_CPU1_SB_CB<2>")
	)
	(gr_poly
		(pts
			(xy 145.544794 -269.83436) (xy 145.544794 -269.78991) (xy 145.344642 -269.78991) (xy 145.344642 -269.83436)
			(xy 145.444718 -269.934436)
		)
		(stroke
			(width 0)
			(type solid)
		)
		(fill yes)
		(layer "In4.Cu")
		(net "M_J_CPU1_SB_CB<7>")
	)
	(gr_poly
		(pts
			(xy 145.563844 -294.13835) (xy 145.600674 -294.001698) (xy 145.464022 -293.965122) (xy 145.425414 -293.987474)
			(xy 145.52549 -294.160702)
		)
		(stroke
			(width 0)
			(type solid)
		)
		(fill yes)
		(layer "In4.Cu")
		(net "M_J_CPU1_SB_DQ<28>")
	)
	(gr_poly
		(pts
			(xy 145.706846 -253.59614) (xy 145.607024 -253.496064) (xy 145.506948 -253.59614) (xy 145.506948 -253.64059)
			(xy 145.706846 -253.64059)
		)
		(stroke
			(width 0)
			(type solid)
		)
		(fill yes)
		(layer "In4.Cu")
		(net "M_J_CPU1_SA_CA<2>")
	)
	(gr_poly
		(pts
			(xy 145.706846 -248.736104) (xy 145.607024 -248.636028) (xy 145.506948 -248.736104) (xy 145.506948 -248.780554)
			(xy 145.706846 -248.780554)
		)
		(stroke
			(width 0)
			(type solid)
		)
		(fill yes)
		(layer "In4.Cu")
		(net "M_J_CPU1_SA_CB<5>")
	)
	(gr_poly
		(pts
			(xy 145.706846 -245.49608) (xy 145.607024 -245.396004) (xy 145.506948 -245.49608) (xy 145.506948 -245.54053)
			(xy 145.706846 -245.54053)
		)
		(stroke
			(width 0)
			(type solid)
		)
		(fill yes)
		(layer "In4.Cu")
		(net "M_J_CPU1_SA_CB<1>")
	)
	(gr_poly
		(pts
			(xy 145.708116 -247.115838) (xy 145.608294 -247.016016) (xy 145.508218 -247.115838) (xy 145.508218 -247.16359)
			(xy 145.708116 -247.16359)
		)
		(stroke
			(width 0)
			(type solid)
		)
		(fill yes)
		(layer "In4.Cu")
		(net "M_J_CPU1_SA_DQS_DN<9>")
	)
	(gr_poly
		(pts
			(xy 326.204072 -294.781478) (xy 326.165718 -294.759126) (xy 326.029066 -294.795702) (xy 326.065642 -294.932354)
			(xy 326.10425 -294.954706)
		)
		(stroke
			(width 0)
			(type solid)
		)
		(fill yes)
		(layer "In4.Cu")
		(net "M_D_CPU0_SB_DQ<28>")
	)
	(gr_poly
		(pts
			(xy 326.325484 -223.72828) (xy 326.257158 -223.54032) (xy 326.215248 -223.55556) (xy 326.155558 -223.68383)
			(xy 326.283828 -223.74352)
		)
		(stroke
			(width 0)
			(type solid)
		)
		(fill yes)
		(layer "In4.Cu")
		(net "M_D_CPU0_SA_DQ<6>")
	)
	(gr_poly
		(pts
			(xy 326.438514 -247.522492) (xy 326.438514 -247.474994) (xy 326.238616 -247.474994) (xy 326.238616 -247.522492)
			(xy 326.338692 -247.622568)
		)
		(stroke
			(width 0)
			(type solid)
		)
		(fill yes)
		(layer "In4.Cu")
		(net "M_D_CPU0_SA_DQS_DP<9>")
	)
	(gr_poly
		(pts
			(xy 326.438514 -242.662456) (xy 326.438514 -242.614958) (xy 326.238616 -242.614958) (xy 326.238616 -242.662456)
			(xy 326.338692 -242.762532)
		)
		(stroke
			(width 0)
			(type solid)
		)
		(fill yes)
		(layer "In4.Cu")
		(net "M_D_CPU0_SA_DQS_DP<8>")
	)
	(gr_poly
		(pts
			(xy 326.441562 -254.00254) (xy 326.441562 -253.95809) (xy 326.24141 -253.95809) (xy 326.24141 -254.00254)
			(xy 326.341486 -254.102362)
		)
		(stroke
			(width 0)
			(type solid)
		)
		(fill yes)
		(layer "In4.Cu")
		(net "M_D_CPU0_SA_CA<3>")
	)
	(gr_poly
		(pts
			(xy 326.441562 -252.382528) (xy 326.441562 -252.338078) (xy 326.24141 -252.338078) (xy 326.24141 -252.382528)
			(xy 326.341486 -252.48235)
		)
		(stroke
			(width 0)
			(type solid)
		)
		(fill yes)
		(layer "In4.Cu")
		(net "M_D_CPU0_SA_CS_N<1>")
	)
	(gr_poly
		(pts
			(xy 326.441562 -249.142504) (xy 326.441562 -249.098054) (xy 326.24141 -249.098054) (xy 326.24141 -249.142504)
			(xy 326.341486 -249.242326)
		)
		(stroke
			(width 0)
			(type solid)
		)
		(fill yes)
		(layer "In4.Cu")
		(net "M_D_CPU0_SA_CB<7>")
	)
	(gr_poly
		(pts
			(xy 326.441562 -245.90248) (xy 326.441562 -245.85803) (xy 326.24141 -245.85803) (xy 326.24141 -245.90248)
			(xy 326.341486 -246.002302)
		)
		(stroke
			(width 0)
			(type solid)
		)
		(fill yes)
		(layer "In4.Cu")
		(net "M_D_CPU0_SA_CB<3>")
	)
	(gr_poly
		(pts
			(xy 326.441562 -244.282468) (xy 326.441562 -244.238018) (xy 326.24141 -244.238018) (xy 326.24141 -244.282468)
			(xy 326.341486 -244.38229)
		)
		(stroke
			(width 0)
			(type solid)
		)
		(fill yes)
		(layer "In4.Cu")
		(net "M_D_CPU0_SA_DQ<31>")
	)
	(gr_poly
		(pts
			(xy 326.451214 -256.025904) (xy 326.351138 -255.926082) (xy 326.251062 -256.025904) (xy 326.251062 -256.073656)
			(xy 326.451214 -256.073656)
		)
		(stroke
			(width 0)
			(type solid)
		)
		(fill yes)
		(layer "In4.Cu")
		(net "M_D_CPU0_CLK_DP<0>")
	)
	(gr_poly
		(pts
			(xy 326.451214 -246.305832) (xy 326.351138 -246.20601) (xy 326.251062 -246.305832) (xy 326.251062 -246.353584)
			(xy 326.451214 -246.353584)
		)
		(stroke
			(width 0)
			(type solid)
		)
		(fill yes)
		(layer "In4.Cu")
		(net "M_D_CPU0_SA_DQS_DP<4>")
	)
	(gr_poly
		(pts
			(xy 326.468994 -223.223582) (xy 326.505824 -223.08693) (xy 326.369172 -223.050354) (xy 326.330564 -223.072706)
			(xy 326.43064 -223.245934)
		)
		(stroke
			(width 0)
			(type solid)
		)
		(fill yes)
		(layer "In4.Cu")
		(net "M_D_CPU0_SA_DQ<4>")
	)
	(gr_poly
		(pts
			(xy 326.470772 -254.405892) (xy 326.370696 -254.305816) (xy 326.270874 -254.405892) (xy 326.270874 -254.450342)
			(xy 326.470772 -254.450342)
		)
		(stroke
			(width 0)
			(type solid)
		)
		(fill yes)
		(layer "In4.Cu")
		(net "M_D_CPU0_SA_CA<4>")
	)
	(gr_poly
		(pts
			(xy 326.470772 -252.78588) (xy 326.370696 -252.685804) (xy 326.270874 -252.78588) (xy 326.270874 -252.83033)
			(xy 326.470772 -252.83033)
		)
		(stroke
			(width 0)
			(type solid)
		)
		(fill yes)
		(layer "In4.Cu")
		(net "M_D_CPU0_SA_CA<0>")
	)
	(gr_poly
		(pts
			(xy 326.470772 -247.925844) (xy 326.370696 -247.825768) (xy 326.270874 -247.925844) (xy 326.270874 -247.970294)
			(xy 326.470772 -247.970294)
		)
		(stroke
			(width 0)
			(type solid)
		)
		(fill yes)
		(layer "In4.Cu")
		(net "M_D_CPU0_SA_CB<4>")
	)
	(gr_poly
		(pts
			(xy 326.670416 -293.986458) (xy 326.632062 -293.964106) (xy 326.49541 -294.000682) (xy 326.531986 -294.137334)
			(xy 326.570594 -294.159686)
		)
		(stroke
			(width 0)
			(type solid)
		)
		(fill yes)
		(layer "In4.Cu")
		(net "M_D_CPU0_SB_DQ<28>")
	)
	(gr_poly
		(pts
			(xy 326.741536 -289.677602) (xy 326.64146 -289.57778) (xy 326.541638 -289.677602) (xy 326.541638 -289.722052)
			(xy 326.741536 -289.722052)
		)
		(stroke
			(width 0)
			(type solid)
		)
		(fill yes)
		(layer "In4.Cu")
		(net "M_D_CPU0_SB_DQ<25>")
	)
	(gr_poly
		(pts
			(xy 326.741536 -286.437578) (xy 326.64146 -286.337756) (xy 326.541638 -286.437578) (xy 326.541638 -286.48533)
			(xy 326.741536 -286.48533)
		)
		(stroke
			(width 0)
			(type solid)
		)
		(fill yes)
		(layer "In4.Cu")
		(net "M_D_CPU0_SB_DQS_DN<7>")
	)
	(gr_poly
		(pts
			(xy 326.741536 -284.81782) (xy 326.64146 -284.717998) (xy 326.541638 -284.81782) (xy 326.541638 -284.86227)
			(xy 326.741536 -284.86227)
		)
		(stroke
			(width 0)
			(type solid)
		)
		(fill yes)
		(layer "In4.Cu")
		(net "M_D_CPU0_SB_DQ<17>")
	)
	(gr_poly
		(pts
			(xy 326.741536 -273.074384) (xy 326.741536 -273.029934) (xy 326.541638 -273.029934) (xy 326.541638 -273.074384)
			(xy 326.64146 -273.174206)
		)
		(stroke
			(width 0)
			(type solid)
		)
		(fill yes)
		(layer "In4.Cu")
		(net "M_D_CPU0_SB_CB<2>")
	)
	(gr_poly
		(pts
			(xy 326.741536 -269.83436) (xy 326.741536 -269.78991) (xy 326.541638 -269.78991) (xy 326.541638 -269.83436)
			(xy 326.64146 -269.934182)
		)
		(stroke
			(width 0)
			(type solid)
		)
		(fill yes)
		(layer "In4.Cu")
		(net "M_D_CPU0_SB_CB<6>")
	)
	(gr_poly
		(pts
			(xy 326.742298 -288.05759) (xy 326.642476 -287.957768) (xy 326.5424 -288.05759) (xy 326.5424 -288.10204)
			(xy 326.742298 -288.10204)
		)
		(stroke
			(width 0)
			(type solid)
		)
		(fill yes)
		(layer "In4.Cu")
		(net "M_D_CPU0_SB_DQ<21>")
	)
	(gr_poly
		(pts
			(xy 326.759824 -281.174444) (xy 326.759824 -281.126946) (xy 326.559926 -281.126946) (xy 326.559926 -281.174444)
			(xy 326.659748 -281.27452)
		)
		(stroke
			(width 0)
			(type solid)
		)
		(fill yes)
		(layer "In4.Cu")
		(net "M_D_CPU0_SB_DQS_DN<1>")
	)
	(gr_poly
		(pts
			(xy 326.840088 -224.582482) (xy 326.740266 -224.409254) (xy 326.701658 -224.431352) (xy 326.665082 -224.568004)
			(xy 326.801734 -224.60458)
		)
		(stroke
			(width 0)
			(type solid)
		)
		(fill yes)
		(layer "In4.Cu")
		(net "M_D_CPU0_SA_DQ<6>")
	)
	(gr_poly
		(pts
			(xy 326.844914 -222.964248) (xy 326.744838 -222.79102) (xy 326.70369 -222.814896) (xy 326.667114 -222.951548)
			(xy 326.803766 -222.988124)
		)
		(stroke
			(width 0)
			(type solid)
		)
		(fill yes)
		(layer "In4.Cu")
		(net "M_D_CPU0_SA_DQS_DP<5>")
	)
	(gr_poly
		(pts
			(xy 326.902318 -256.432812) (xy 326.902318 -256.38506) (xy 326.70242 -256.38506) (xy 326.70242 -256.432812)
			(xy 326.802496 -256.532888)
		)
		(stroke
			(width 0)
			(type solid)
		)
		(fill yes)
		(layer "In4.Cu")
		(net "M_D_CPU0_CLK_DN<0>")
	)
	(gr_poly
		(pts
			(xy 326.907398 -239.015524) (xy 326.807322 -238.915448) (xy 326.707246 -239.015524) (xy 326.707246 -239.059974)
			(xy 326.907398 -239.059974)
		)
		(stroke
			(width 0)
			(type solid)
		)
		(fill yes)
		(layer "In4.Cu")
		(net "M_D_CPU0_SA_DQ<21>")
	)
	(gr_poly
		(pts
			(xy 326.90943 -254.8128) (xy 326.90943 -254.76835) (xy 326.709532 -254.76835) (xy 326.709532 -254.8128)
			(xy 326.809608 -254.912876)
		)
		(stroke
			(width 0)
			(type solid)
		)
		(fill yes)
		(layer "In4.Cu")
		(net "M_D_CPU0_SA_CA<5>")
	)
	(gr_poly
		(pts
			(xy 326.90943 -253.192788) (xy 326.90943 -253.148338) (xy 326.709532 -253.148338) (xy 326.709532 -253.192788)
			(xy 326.809608 -253.292864)
		)
		(stroke
			(width 0)
			(type solid)
		)
		(fill yes)
		(layer "In4.Cu")
		(net "M_D_CPU0_SA_CA<1>")
	)
	(gr_poly
		(pts
			(xy 326.90943 -248.332752) (xy 326.90943 -248.288302) (xy 326.709532 -248.288302) (xy 326.709532 -248.332752)
			(xy 326.809608 -248.432828)
		)
		(stroke
			(width 0)
			(type solid)
		)
		(fill yes)
		(layer "In4.Cu")
		(net "M_D_CPU0_SA_CB<6>")
	)
	(gr_poly
		(pts
			(xy 326.90943 -246.71274) (xy 326.90943 -246.665242) (xy 326.709532 -246.665242) (xy 326.709532 -246.71274)
			(xy 326.809608 -246.812816)
		)
		(stroke
			(width 0)
			(type solid)
		)
		(fill yes)
		(layer "In4.Cu")
		(net "M_D_CPU0_SA_DQS_DN<4>")
	)
	(gr_poly
		(pts
			(xy 326.90943 -245.092728) (xy 326.90943 -245.048278) (xy 326.709532 -245.048278) (xy 326.709532 -245.092728)
			(xy 326.809608 -245.192804)
		)
		(stroke
			(width 0)
			(type solid)
		)
		(fill yes)
		(layer "In4.Cu")
		(net "M_D_CPU0_SA_CB<2>")
	)
	(gr_poly
		(pts
			(xy 326.90943 -243.472716) (xy 326.90943 -243.428266) (xy 326.709532 -243.428266) (xy 326.709532 -243.472716)
			(xy 326.809608 -243.572792)
		)
		(stroke
			(width 0)
			(type solid)
		)
		(fill yes)
		(layer "In4.Cu")
		(net "M_D_CPU0_SA_DQ<30>")
	)
	(gr_poly
		(pts
			(xy 326.90943 -240.232692) (xy 326.90943 -240.188242) (xy 326.709532 -240.188242) (xy 326.709532 -240.232692)
			(xy 326.809608 -240.332768)
		)
		(stroke
			(width 0)
			(type solid)
		)
		(fill yes)
		(layer "In4.Cu")
		(net "M_D_CPU0_SA_DQ<26>")
	)
	(gr_poly
		(pts
			(xy 326.90943 -238.61268) (xy 326.90943 -238.56823) (xy 326.709532 -238.56823) (xy 326.709532 -238.61268)
			(xy 326.809608 -238.712756)
		)
		(stroke
			(width 0)
			(type solid)
		)
		(fill yes)
		(layer "In4.Cu")
		(net "M_D_CPU0_SA_DQ<22>")
	)
	(gr_poly
		(pts
			(xy 326.90943 -237.395258) (xy 326.809354 -237.295182) (xy 326.709532 -237.395258) (xy 326.709532 -237.44301)
			(xy 326.90943 -237.44301)
		)
		(stroke
			(width 0)
			(type solid)
		)
		(fill yes)
		(layer "In4.Cu")
		(net "M_D_CPU0_SA_DQS_DN<7>")
	)
	(gr_poly
		(pts
			(xy 326.90943 -236.992668) (xy 326.90943 -236.94517) (xy 326.709532 -236.94517) (xy 326.709532 -236.992668)
			(xy 326.809608 -237.092744)
		)
		(stroke
			(width 0)
			(type solid)
		)
		(fill yes)
		(layer "In4.Cu")
		(net "M_D_CPU0_SA_DQS_DN<2>")
	)
	(gr_poly
		(pts
			(xy 326.915018 -251.572268) (xy 326.915018 -251.527818) (xy 326.714866 -251.527818) (xy 326.714866 -251.572268)
			(xy 326.814942 -251.672344)
		)
		(stroke
			(width 0)
			(type solid)
		)
		(fill yes)
		(layer "In4.Cu")
		(net "M_D_CPU0_SA_CS_N<0>")
	)
	(gr_poly
		(pts
			(xy 326.915018 -240.636044) (xy 326.814942 -240.535968) (xy 326.714866 -240.636044) (xy 326.714866 -240.680494)
			(xy 326.915018 -240.680494)
		)
		(stroke
			(width 0)
			(type solid)
		)
		(fill yes)
		(layer "In4.Cu")
		(net "M_D_CPU0_SA_DQ<25>")
	)
	(gr_poly
		(pts
			(xy 326.921114 -250.356116) (xy 326.821038 -250.25604) (xy 326.720962 -250.356116) (xy 326.720962 -250.400566)
			(xy 326.921114 -250.400566)
		)
		(stroke
			(width 0)
			(type solid)
		)
		(fill yes)
		(layer "In4.Cu")
		(net "M_D_CPU0_ALERT_R_N")
	)
	(gr_poly
		(pts
			(xy 326.921114 -241.85245) (xy 326.921114 -241.804698) (xy 326.720962 -241.804698) (xy 326.720962 -241.85245)
			(xy 326.821038 -241.952272)
		)
		(stroke
			(width 0)
			(type solid)
		)
		(fill yes)
		(layer "In4.Cu")
		(net "M_D_CPU0_SA_DQS_DN<3>")
	)
	(gr_poly
		(pts
			(xy 326.923908 -255.216152) (xy 326.823832 -255.116076) (xy 326.723756 -255.216152) (xy 326.723756 -255.260602)
			(xy 326.923908 -255.260602)
		)
		(stroke
			(width 0)
			(type solid)
		)
		(fill yes)
		(layer "In4.Cu")
		(net "M_D_CPU0_SA_CA<6>")
	)
	(gr_poly
		(pts
			(xy 326.923908 -253.59614) (xy 326.823832 -253.496064) (xy 326.723756 -253.59614) (xy 326.723756 -253.64059)
			(xy 326.923908 -253.64059)
		)
		(stroke
			(width 0)
			(type solid)
		)
		(fill yes)
		(layer "In4.Cu")
		(net "M_D_CPU0_SA_CA<2>")
	)
	(gr_poly
		(pts
			(xy 326.923908 -248.736104) (xy 326.823832 -248.636028) (xy 326.723756 -248.736104) (xy 326.723756 -248.780554)
			(xy 326.923908 -248.780554)
		)
		(stroke
			(width 0)
			(type solid)
		)
		(fill yes)
		(layer "In4.Cu")
		(net "M_D_CPU0_SA_CB<5>")
	)
	(gr_poly
		(pts
			(xy 326.923908 -245.49608) (xy 326.823832 -245.396004) (xy 326.723756 -245.49608) (xy 326.723756 -245.54053)
			(xy 326.923908 -245.54053)
		)
		(stroke
			(width 0)
			(type solid)
		)
		(fill yes)
		(layer "In4.Cu")
		(net "M_D_CPU0_SA_CB<1>")
	)
	(gr_poly
		(pts
			(xy 326.923908 -243.876068) (xy 326.823832 -243.775992) (xy 326.723756 -243.876068) (xy 326.723756 -243.920518)
			(xy 326.923908 -243.920518)
		)
		(stroke
			(width 0)
			(type solid)
		)
		(fill yes)
		(layer "In4.Cu")
		(net "M_D_CPU0_SA_DQ<29>")
	)
	(gr_poly
		(pts
			(xy 326.928988 -247.115838) (xy 326.828912 -247.016016) (xy 326.72909 -247.115838) (xy 326.72909 -247.16359)
			(xy 326.928988 -247.16359)
		)
		(stroke
			(width 0)
			(type solid)
		)
		(fill yes)
		(layer "In4.Cu")
		(net "M_D_CPU0_SA_DQS_DN<9>")
	)
	(gr_poly
		(pts
			(xy 326.932798 -242.255802) (xy 326.832722 -242.155726) (xy 326.732646 -242.255802) (xy 326.732646 -242.3033)
			(xy 326.932798 -242.3033)
		)
		(stroke
			(width 0)
			(type solid)
		)
		(fill yes)
		(layer "In4.Cu")
		(net "M_D_CPU0_SA_DQS_DN<8>")
	)
	(gr_poly
		(pts
			(xy 326.935592 -224.045272) (xy 326.983852 -223.912176) (xy 326.85101 -223.863916) (xy 326.810624 -223.882712)
			(xy 326.895206 -224.063814)
		)
		(stroke
			(width 0)
			(type solid)
		)
		(fill yes)
		(layer "In4.Cu")
		(net "M_D_CPU0_SA_DQ<4>")
	)
	(gr_poly
		(pts
			(xy 326.940418 -222.416116) (xy 326.976994 -222.279464) (xy 326.840342 -222.242888) (xy 326.799194 -222.26651)
			(xy 326.89927 -222.439738)
		)
		(stroke
			(width 0)
			(type solid)
		)
		(fill yes)
		(layer "In4.Cu")
		(net "M_D_CPU0_SA_DQS_DN<5>")
	)
	(gr_poly
		(pts
			(xy 326.940672 -225.656902) (xy 326.977248 -225.52025) (xy 326.840596 -225.48342) (xy 326.802242 -225.505772)
			(xy 326.902064 -225.679)
		)
		(stroke
			(width 0)
			(type solid)
		)
		(fill yes)
		(layer "In4.Cu")
		(net "M_D_CPU0_SA_DQ<5>")
	)
	(gr_poly
		(pts
			(xy 327.140316 -293.177214) (xy 327.101708 -293.154862) (xy 326.96531 -293.191438) (xy 327.001886 -293.32809)
			(xy 327.04024 -293.350442)
		)
		(stroke
			(width 0)
			(type solid)
		)
		(fill yes)
		(layer "In4.Cu")
		(net "M_D_CPU0_SB_DQ<28>")
	)
	(gr_poly
		(pts
			(xy 327.207372 -283.604716) (xy 327.207372 -283.560266) (xy 327.00722 -283.560266) (xy 327.00722 -283.604716)
			(xy 327.107296 -283.704792)
		)
		(stroke
			(width 0)
			(type solid)
		)
		(fill yes)
		(layer "In4.Cu")
		(net "M_D_CPU0_SB_DQ<15>")
	)
	(gr_poly
		(pts
			(xy 327.212198 -287.247838) (xy 327.112376 -287.148016) (xy 327.0123 -287.247838) (xy 327.0123 -287.292288)
			(xy 327.212198 -287.292288)
		)
		(stroke
			(width 0)
			(type solid)
		)
		(fill yes)
		(layer "In4.Cu")
		(net "M_D_CPU0_SB_DQ<20>")
	)
	(gr_poly
		(pts
			(xy 327.215246 -285.627826) (xy 327.115424 -285.52775) (xy 327.015348 -285.627826) (xy 327.015348 -285.675324)
			(xy 327.215246 -285.675324)
		)
		(stroke
			(width 0)
			(type solid)
		)
		(fill yes)
		(layer "In4.Cu")
		(net "M_D_CPU0_SB_DQS_DP<2>")
	)
	(gr_poly
		(pts
			(xy 327.215246 -280.76779) (xy 327.115424 -280.667714) (xy 327.015348 -280.76779) (xy 327.015348 -280.815288)
			(xy 327.215246 -280.815288)
		)
		(stroke
			(width 0)
			(type solid)
		)
		(fill yes)
		(layer "In4.Cu")
		(net "M_D_CPU0_SB_DQS_DP<1>")
	)
	(gr_poly
		(pts
			(xy 327.221088 -288.464244) (xy 327.221088 -288.419794) (xy 327.020936 -288.419794) (xy 327.020936 -288.464244)
			(xy 327.121012 -288.56432)
		)
		(stroke
			(width 0)
			(type solid)
		)
		(fill yes)
		(layer "In4.Cu")
		(net "M_D_CPU0_SB_DQ<23>")
	)
	(gr_poly
		(pts
			(xy 327.223882 -290.084002) (xy 327.223882 -290.039552) (xy 327.02373 -290.039552) (xy 327.02373 -290.084002)
			(xy 327.123806 -290.184078)
		)
		(stroke
			(width 0)
			(type solid)
		)
		(fill yes)
		(layer "In4.Cu")
		(net "M_D_CPU0_SB_DQ<27>")
	)
	(gr_poly
		(pts
			(xy 327.223882 -286.844232) (xy 327.223882 -286.79648) (xy 327.02373 -286.79648) (xy 327.02373 -286.844232)
			(xy 327.123806 -286.944308)
		)
		(stroke
			(width 0)
			(type solid)
		)
		(fill yes)
		(layer "In4.Cu")
		(net "M_D_CPU0_SB_DQS_DP<7>")
	)
	(gr_poly
		(pts
			(xy 327.223882 -285.22422) (xy 327.223882 -285.17977) (xy 327.02373 -285.17977) (xy 327.02373 -285.22422)
			(xy 327.123806 -285.324296)
		)
		(stroke
			(width 0)
			(type solid)
		)
		(fill yes)
		(layer "In4.Cu")
		(net "M_D_CPU0_SB_DQ<19>")
	)
	(gr_poly
		(pts
			(xy 327.223882 -284.008068) (xy 327.123806 -283.907992) (xy 327.02373 -284.008068) (xy 327.02373 -284.052518)
			(xy 327.223882 -284.052518)
		)
		(stroke
			(width 0)
			(type solid)
		)
		(fill yes)
		(layer "In4.Cu")
		(net "M_D_CPU0_SB_DQ<16>")
	)
	(gr_poly
		(pts
			(xy 327.223882 -282.388056) (xy 327.123806 -282.28798) (xy 327.02373 -282.388056) (xy 327.02373 -282.432506)
			(xy 327.223882 -282.432506)
		)
		(stroke
			(width 0)
			(type solid)
		)
		(fill yes)
		(layer "In4.Cu")
		(net "M_D_CPU0_SB_DQ<12>")
	)
	(gr_poly
		(pts
			(xy 327.223882 -279.148032) (xy 327.123806 -279.047956) (xy 327.02373 -279.148032) (xy 327.02373 -279.192482)
			(xy 327.223882 -279.192482)
		)
		(stroke
			(width 0)
			(type solid)
		)
		(fill yes)
		(layer "In4.Cu")
		(net "M_D_CPU0_SB_DQ<8>")
	)
	(gr_poly
		(pts
			(xy 327.223882 -277.52802) (xy 327.123806 -277.427944) (xy 327.02373 -277.52802) (xy 327.02373 -277.57247)
			(xy 327.223882 -277.57247)
		)
		(stroke
			(width 0)
			(type solid)
		)
		(fill yes)
		(layer "In4.Cu")
		(net "M_D_CPU0_SB_DQ<4>")
	)
	(gr_poly
		(pts
			(xy 327.223882 -274.287996) (xy 327.123806 -274.18792) (xy 327.02373 -274.287996) (xy 327.02373 -274.332446)
			(xy 327.223882 -274.332446)
		)
		(stroke
			(width 0)
			(type solid)
		)
		(fill yes)
		(layer "In4.Cu")
		(net "M_D_CPU0_SB_DQ<0>")
	)
	(gr_poly
		(pts
			(xy 327.223882 -273.884136) (xy 327.223882 -273.839686) (xy 327.02373 -273.839686) (xy 327.02373 -273.884136)
			(xy 327.123806 -273.984212)
		)
		(stroke
			(width 0)
			(type solid)
		)
		(fill yes)
		(layer "In4.Cu")
		(net "M_D_CPU0_SB_CB<3>")
	)
	(gr_poly
		(pts
			(xy 327.223882 -272.667984) (xy 327.123806 -272.567908) (xy 327.02373 -272.667984) (xy 327.02373 -272.712434)
			(xy 327.223882 -272.712434)
		)
		(stroke
			(width 0)
			(type solid)
		)
		(fill yes)
		(layer "In4.Cu")
		(net "M_D_CPU0_SB_CB<0>")
	)
	(gr_poly
		(pts
			(xy 327.223882 -264.567924) (xy 327.123806 -264.467848) (xy 327.02373 -264.567924) (xy 327.02373 -264.612374)
			(xy 327.223882 -264.612374)
		)
		(stroke
			(width 0)
			(type solid)
		)
		(fill yes)
		(layer "In4.Cu")
		(net "M_D_CPU0_SB_CA<6>")
	)
	(gr_poly
		(pts
			(xy 327.229978 -288.867596) (xy 327.129902 -288.767774) (xy 327.029826 -288.867596) (xy 327.029826 -288.912046)
			(xy 327.229978 -288.912046)
		)
		(stroke
			(width 0)
			(type solid)
		)
		(fill yes)
		(layer "In4.Cu")
		(net "M_D_CPU0_SB_DQ<24>")
	)
	(gr_poly
		(pts
			(xy 327.229978 -269.427706) (xy 327.129902 -269.327884) (xy 327.029826 -269.427706) (xy 327.029826 -269.472156)
			(xy 327.229978 -269.472156)
		)
		(stroke
			(width 0)
			(type solid)
		)
		(fill yes)
		(layer "In4.Cu")
		(net "M_D_CPU0_SB_CB<4>")
	)
	(gr_poly
		(pts
			(xy 327.235058 -267.80109) (xy 327.134982 -267.701014) (xy 327.03516 -267.80109) (xy 327.03516 -267.84554)
			(xy 327.235058 -267.84554)
		)
		(stroke
			(width 0)
			(type solid)
		)
		(fill yes)
		(layer "In4.Cu")
		(net "M_D_CPU0_SB_RSP<0>")
	)
	(gr_poly
		(pts
			(xy 327.276968 -295.481248) (xy 327.240392 -295.344596) (xy 327.201784 -295.322244) (xy 327.101962 -295.495472)
			(xy 327.140316 -295.517824)
		)
		(stroke
			(width 0)
			(type solid)
		)
		(fill yes)
		(layer "In4.Cu")
		(net "M_D_CPU0_SB_DQ<30>")
	)
	(gr_poly
		(pts
			(xy 327.309988 -225.392488) (xy 327.209912 -225.21926) (xy 327.171558 -225.241612) (xy 327.134982 -225.37801)
			(xy 327.27138 -225.41484)
		)
		(stroke
			(width 0)
			(type solid)
		)
		(fill yes)
		(layer "In4.Cu")
		(net "M_D_CPU0_SA_DQ<6>")
	)
	(gr_poly
		(pts
			(xy 327.313036 -223.77146) (xy 327.213214 -223.598232) (xy 327.171812 -223.622108) (xy 327.135236 -223.75876)
			(xy 327.271888 -223.795336)
		)
		(stroke
			(width 0)
			(type solid)
		)
		(fill yes)
		(layer "In4.Cu")
		(net "M_D_CPU0_SA_DQS_DP<5>")
	)
	(gr_poly
		(pts
			(xy 327.37806 -246.306086) (xy 327.278238 -246.20601) (xy 327.178162 -246.306086) (xy 327.178162 -246.353584)
			(xy 327.37806 -246.353584)
		)
		(stroke
			(width 0)
			(type solid)
		)
		(fill yes)
		(layer "In4.Cu")
		(net "M_D_CPU0_SA_DQS_DP<4>")
	)
	(gr_poly
		(pts
			(xy 327.37806 -236.586014) (xy 327.278238 -236.485938) (xy 327.178162 -236.586014) (xy 327.178162 -236.633512)
			(xy 327.37806 -236.633512)
		)
		(stroke
			(width 0)
			(type solid)
		)
		(fill yes)
		(layer "In4.Cu")
		(net "M_D_CPU0_SA_DQS_DP<2>")
	)
	(gr_poly
		(pts
			(xy 327.37933 -239.421924) (xy 327.37933 -239.377728) (xy 327.179432 -239.377728) (xy 327.179432 -239.421924)
			(xy 327.279254 -239.522)
		)
		(stroke
			(width 0)
			(type solid)
		)
		(fill yes)
		(layer "In4.Cu")
		(net "M_D_CPU0_SA_DQ<23>")
	)
	(gr_poly
		(pts
			(xy 327.380346 -254.4064) (xy 327.28027 -254.306324) (xy 327.180194 -254.4064) (xy 327.180194 -254.45085)
			(xy 327.380346 -254.45085)
		)
		(stroke
			(width 0)
			(type solid)
		)
		(fill yes)
		(layer "In4.Cu")
		(net "M_D_CPU0_SA_CA<4>")
	)
	(gr_poly
		(pts
			(xy 327.380346 -252.786388) (xy 327.28027 -252.686312) (xy 327.180194 -252.786388) (xy 327.180194 -252.830838)
			(xy 327.380346 -252.830838)
		)
		(stroke
			(width 0)
			(type solid)
		)
		(fill yes)
		(layer "In4.Cu")
		(net "M_D_CPU0_SA_CA<0>")
	)
	(gr_poly
		(pts
			(xy 327.380346 -247.926352) (xy 327.28027 -247.826276) (xy 327.180194 -247.926352) (xy 327.180194 -247.970802)
			(xy 327.380346 -247.970802)
		)
		(stroke
			(width 0)
			(type solid)
		)
		(fill yes)
		(layer "In4.Cu")
		(net "M_D_CPU0_SA_CB<4>")
	)
	(gr_poly
		(pts
			(xy 327.380346 -244.686328) (xy 327.28027 -244.586252) (xy 327.180194 -244.686328) (xy 327.180194 -244.730778)
			(xy 327.380346 -244.730778)
		)
		(stroke
			(width 0)
			(type solid)
		)
		(fill yes)
		(layer "In4.Cu")
		(net "M_D_CPU0_SA_CB<0>")
	)
	(gr_poly
		(pts
			(xy 327.380346 -243.066316) (xy 327.28027 -242.96624) (xy 327.180194 -243.066316) (xy 327.180194 -243.110766)
			(xy 327.380346 -243.110766)
		)
		(stroke
			(width 0)
			(type solid)
		)
		(fill yes)
		(layer "In4.Cu")
		(net "M_D_CPU0_SA_DQ<28>")
	)
	(gr_poly
		(pts
			(xy 327.380346 -239.826292) (xy 327.28027 -239.726216) (xy 327.180194 -239.826292) (xy 327.180194 -239.870742)
			(xy 327.380346 -239.870742)
		)
		(stroke
			(width 0)
			(type solid)
		)
		(fill yes)
		(layer "In4.Cu")
		(net "M_D_CPU0_SA_DQ<24>")
	)
	(gr_poly
		(pts
			(xy 327.380346 -238.20628) (xy 327.28027 -238.106204) (xy 327.180194 -238.20628) (xy 327.180194 -238.25073)
			(xy 327.380346 -238.25073)
		)
		(stroke
			(width 0)
			(type solid)
		)
		(fill yes)
		(layer "In4.Cu")
		(net "M_D_CPU0_SA_DQ<20>")
	)
	(gr_poly
		(pts
			(xy 327.382378 -242.66271) (xy 327.382378 -242.614958) (xy 327.18248 -242.614958) (xy 327.18248 -242.66271)
			(xy 327.282556 -242.762532)
		)
		(stroke
			(width 0)
			(type solid)
		)
		(fill yes)
		(layer "In4.Cu")
		(net "M_D_CPU0_SA_DQS_DP<8>")
	)
	(gr_poly
		(pts
			(xy 327.391268 -250.762262) (xy 327.391268 -250.717812) (xy 327.191116 -250.717812) (xy 327.191116 -250.762262)
			(xy 327.291192 -250.862338)
		)
		(stroke
			(width 0)
			(type solid)
		)
		(fill yes)
		(layer "In4.Cu")
		(net "M_D_CPU0_RESET_N")
	)
	(gr_poly
		(pts
			(xy 327.391268 -241.445796) (xy 327.291192 -241.345974) (xy 327.191116 -241.445796) (xy 327.191116 -241.493548)
			(xy 327.391268 -241.493548)
		)
		(stroke
			(width 0)
			(type solid)
		)
		(fill yes)
		(layer "In4.Cu")
		(net "M_D_CPU0_SA_DQS_DP<3>")
	)
	(gr_poly
		(pts
			(xy 327.391268 -237.80242) (xy 327.391268 -237.754668) (xy 327.191116 -237.754668) (xy 327.191116 -237.80242)
			(xy 327.291192 -237.902242)
		)
		(stroke
			(width 0)
			(type solid)
		)
		(fill yes)
		(layer "In4.Cu")
		(net "M_D_CPU0_SA_DQS_DP<7>")
	)
	(gr_poly
		(pts
			(xy 327.396602 -255.622298) (xy 327.396602 -255.577848) (xy 327.19645 -255.577848) (xy 327.19645 -255.622298)
			(xy 327.296526 -255.722374)
		)
		(stroke
			(width 0)
			(type solid)
		)
		(fill yes)
		(layer "In4.Cu")
		(net "M_D_CPU0_SA_PAR")
	)
	(gr_poly
		(pts
			(xy 327.396602 -254.002286) (xy 327.396602 -253.957836) (xy 327.19645 -253.957836) (xy 327.19645 -254.002286)
			(xy 327.296526 -254.102362)
		)
		(stroke
			(width 0)
			(type solid)
		)
		(fill yes)
		(layer "In4.Cu")
		(net "M_D_CPU0_SA_CA<3>")
	)
	(gr_poly
		(pts
			(xy 327.396602 -252.382274) (xy 327.396602 -252.337824) (xy 327.19645 -252.337824) (xy 327.19645 -252.382274)
			(xy 327.296526 -252.48235)
		)
		(stroke
			(width 0)
			(type solid)
		)
		(fill yes)
		(layer "In4.Cu")
		(net "M_D_CPU0_SA_CS_N<1>")
	)
	(gr_poly
		(pts
			(xy 327.396602 -249.14225) (xy 327.396602 -249.0978) (xy 327.19645 -249.0978) (xy 327.19645 -249.14225)
			(xy 327.296526 -249.242326)
		)
		(stroke
			(width 0)
			(type solid)
		)
		(fill yes)
		(layer "In4.Cu")
		(net "M_D_CPU0_SA_CB<7>")
	)
	(gr_poly
		(pts
			(xy 327.396602 -247.522492) (xy 327.396602 -247.474994) (xy 327.19645 -247.474994) (xy 327.19645 -247.522492)
			(xy 327.296526 -247.622568)
		)
		(stroke
			(width 0)
			(type solid)
		)
		(fill yes)
		(layer "In4.Cu")
		(net "M_D_CPU0_SA_DQS_DP<9>")
	)
	(gr_poly
		(pts
			(xy 327.396602 -245.902226) (xy 327.396602 -245.857776) (xy 327.19645 -245.857776) (xy 327.19645 -245.902226)
			(xy 327.296526 -246.002302)
		)
		(stroke
			(width 0)
			(type solid)
		)
		(fill yes)
		(layer "In4.Cu")
		(net "M_D_CPU0_SA_CB<3>")
	)
	(gr_poly
		(pts
			(xy 327.396602 -244.282214) (xy 327.396602 -244.237764) (xy 327.19645 -244.237764) (xy 327.19645 -244.282214)
			(xy 327.296526 -244.38229)
		)
		(stroke
			(width 0)
			(type solid)
		)
		(fill yes)
		(layer "In4.Cu")
		(net "M_D_CPU0_SA_DQ<31>")
	)
	(gr_poly
		(pts
			(xy 327.399142 -241.04219) (xy 327.399142 -240.99774) (xy 327.199244 -240.99774) (xy 327.199244 -241.04219)
			(xy 327.299066 -241.142266)
		)
		(stroke
			(width 0)
			(type solid)
		)
		(fill yes)
		(layer "In4.Cu")
		(net "M_D_CPU0_SA_DQ<27>")
	)
	(gr_poly
		(pts
			(xy 327.404984 -223.235012) (xy 327.453498 -223.10217) (xy 327.320402 -223.053656) (xy 327.277476 -223.073976)
			(xy 327.361804 -223.255078)
		)
		(stroke
			(width 0)
			(type solid)
		)
		(fill yes)
		(layer "In4.Cu")
		(net "M_D_CPU0_SA_DQS_DN<5>")
	)
	(gr_poly
		(pts
			(xy 327.406508 -256.026158) (xy 327.306432 -255.926082) (xy 327.20661 -256.026158) (xy 327.20661 -256.073656)
			(xy 327.406508 -256.073656)
		)
		(stroke
			(width 0)
			(type solid)
		)
		(fill yes)
		(layer "In4.Cu")
		(net "M_D_CPU0_CLK_DP<0>")
	)
	(gr_poly
		(pts
			(xy 327.40981 -226.465638) (xy 327.446386 -226.328986) (xy 327.309734 -226.29241) (xy 327.27138 -226.314508)
			(xy 327.371456 -226.487736)
		)
		(stroke
			(width 0)
			(type solid)
		)
		(fill yes)
		(layer "In4.Cu")
		(net "M_D_CPU0_SA_DQ<5>")
	)
	(gr_poly
		(pts
			(xy 327.410064 -224.845626) (xy 327.44664 -224.708974) (xy 327.309988 -224.672398) (xy 327.271634 -224.69475)
			(xy 327.371456 -224.867978)
		)
		(stroke
			(width 0)
			(type solid)
		)
		(fill yes)
		(layer "In4.Cu")
		(net "M_D_CPU0_SA_DQ<4>")
	)
	(gr_poly
		(pts
			(xy 327.610216 -292.367208) (xy 327.571608 -292.344856) (xy 327.43521 -292.381432) (xy 327.471786 -292.518084)
			(xy 327.51014 -292.540436)
		)
		(stroke
			(width 0)
			(type solid)
		)
		(fill yes)
		(layer "In4.Cu")
		(net "M_D_CPU0_SB_DQ<28>")
	)
	(gr_poly
		(pts
			(xy 327.61047 -295.607232) (xy 327.571862 -295.58488) (xy 327.43521 -295.621456) (xy 327.47204 -295.758108)
			(xy 327.510394 -295.78046)
		)
		(stroke
			(width 0)
			(type solid)
		)
		(fill yes)
		(layer "In4.Cu")
		(net "M_D_CPU0_SB_DQ<29>")
	)
	(gr_poly
		(pts
			(xy 327.679304 -283.198316) (xy 327.579228 -283.09824) (xy 327.479406 -283.198316) (xy 327.479406 -283.242512)
			(xy 327.679304 -283.242512)
		)
		(stroke
			(width 0)
			(type solid)
		)
		(fill yes)
		(layer "In4.Cu")
		(net "M_D_CPU0_SB_DQ<13>")
	)
	(gr_poly
		(pts
			(xy 327.682352 -289.27425) (xy 327.682352 -289.2298) (xy 327.482454 -289.2298) (xy 327.482454 -289.27425)
			(xy 327.58253 -289.374072)
		)
		(stroke
			(width 0)
			(type solid)
		)
		(fill yes)
		(layer "In4.Cu")
		(net "M_D_CPU0_SB_DQ<26>")
	)
	(gr_poly
		(pts
			(xy 327.682352 -269.83436) (xy 327.682352 -269.78991) (xy 327.482454 -269.78991) (xy 327.482454 -269.83436)
			(xy 327.58253 -269.934436)
		)
		(stroke
			(width 0)
			(type solid)
		)
		(fill yes)
		(layer "In4.Cu")
		(net "M_D_CPU0_SB_CB<6>")
	)
	(gr_poly
		(pts
			(xy 327.685146 -286.03448) (xy 327.685146 -285.986728) (xy 327.485248 -285.986728) (xy 327.485248 -286.03448)
			(xy 327.585324 -286.134302)
		)
		(stroke
			(width 0)
			(type solid)
		)
		(fill yes)
		(layer "In4.Cu")
		(net "M_D_CPU0_SB_DQS_DN<2>")
	)
	(gr_poly
		(pts
			(xy 327.685146 -281.174444) (xy 327.685146 -281.126692) (xy 327.485248 -281.126692) (xy 327.485248 -281.174444)
			(xy 327.585324 -281.274266)
		)
		(stroke
			(width 0)
			(type solid)
		)
		(fill yes)
		(layer "In4.Cu")
		(net "M_D_CPU0_SB_DQS_DN<1>")
	)
	(gr_poly
		(pts
			(xy 327.691242 -288.057844) (xy 327.591166 -287.957768) (xy 327.49109 -288.057844) (xy 327.49109 -288.102294)
			(xy 327.691242 -288.102294)
		)
		(stroke
			(width 0)
			(type solid)
		)
		(fill yes)
		(layer "In4.Cu")
		(net "M_D_CPU0_SB_DQ<21>")
	)
	(gr_poly
		(pts
			(xy 327.696576 -284.414214) (xy 327.696576 -284.369764) (xy 327.496678 -284.369764) (xy 327.496678 -284.414214)
			(xy 327.5965 -284.51429)
		)
		(stroke
			(width 0)
			(type solid)
		)
		(fill yes)
		(layer "In4.Cu")
		(net "M_D_CPU0_SB_DQ<18>")
	)
	(gr_poly
		(pts
			(xy 327.696576 -282.794202) (xy 327.696576 -282.749752) (xy 327.496678 -282.749752) (xy 327.496678 -282.794202)
			(xy 327.5965 -282.894278)
		)
		(stroke
			(width 0)
			(type solid)
		)
		(fill yes)
		(layer "In4.Cu")
		(net "M_D_CPU0_SB_DQ<14>")
	)
	(gr_poly
		(pts
			(xy 327.696576 -279.554178) (xy 327.696576 -279.509728) (xy 327.496678 -279.509728) (xy 327.496678 -279.554178)
			(xy 327.5965 -279.654254)
		)
		(stroke
			(width 0)
			(type solid)
		)
		(fill yes)
		(layer "In4.Cu")
		(net "M_D_CPU0_SB_DQ<10>")
	)
	(gr_poly
		(pts
			(xy 327.696576 -277.934166) (xy 327.696576 -277.889716) (xy 327.496678 -277.889716) (xy 327.496678 -277.934166)
			(xy 327.5965 -278.034242)
		)
		(stroke
			(width 0)
			(type solid)
		)
		(fill yes)
		(layer "In4.Cu")
		(net "M_D_CPU0_SB_DQ<6>")
	)
	(gr_poly
		(pts
			(xy 327.696576 -274.694142) (xy 327.696576 -274.649692) (xy 327.496678 -274.649692) (xy 327.496678 -274.694142)
			(xy 327.5965 -274.794218)
		)
		(stroke
			(width 0)
			(type solid)
		)
		(fill yes)
		(layer "In4.Cu")
		(net "M_D_CPU0_SB_DQ<2>")
	)
	(gr_poly
		(pts
			(xy 327.696576 -273.07413) (xy 327.696576 -273.02968) (xy 327.496678 -273.02968) (xy 327.496678 -273.07413)
			(xy 327.5965 -273.174206)
		)
		(stroke
			(width 0)
			(type solid)
		)
		(fill yes)
		(layer "In4.Cu")
		(net "M_D_CPU0_SB_CB<2>")
	)
	(gr_poly
		(pts
			(xy 327.696576 -264.97407) (xy 327.696576 -264.92962) (xy 327.496678 -264.92962) (xy 327.496678 -264.97407)
			(xy 327.5965 -265.074146)
		)
		(stroke
			(width 0)
			(type solid)
		)
		(fill yes)
		(layer "In4.Cu")
		(net "M_D_CPU0_SB_PAR")
	)
	(gr_poly
		(pts
			(xy 327.698862 -289.677602) (xy 327.598786 -289.57778) (xy 327.498964 -289.677602) (xy 327.498964 -289.722052)
			(xy 327.698862 -289.722052)
		)
		(stroke
			(width 0)
			(type solid)
		)
		(fill yes)
		(layer "In4.Cu")
		(net "M_D_CPU0_SB_DQ<25>")
	)
	(gr_poly
		(pts
			(xy 327.698862 -286.437578) (xy 327.598786 -286.337756) (xy 327.498964 -286.437578) (xy 327.498964 -286.48533)
			(xy 327.698862 -286.48533)
		)
		(stroke
			(width 0)
			(type solid)
		)
		(fill yes)
		(layer "In4.Cu")
		(net "M_D_CPU0_SB_DQS_DN<7>")
	)
	(gr_poly
		(pts
			(xy 327.698862 -284.81782) (xy 327.598786 -284.717744) (xy 327.498964 -284.81782) (xy 327.498964 -284.86227)
			(xy 327.698862 -284.86227)
		)
		(stroke
			(width 0)
			(type solid)
		)
		(fill yes)
		(layer "In4.Cu")
		(net "M_D_CPU0_SB_DQ<17>")
	)
	(gr_poly
		(pts
			(xy 327.698862 -273.477736) (xy 327.598786 -273.37766) (xy 327.498964 -273.477736) (xy 327.498964 -273.522186)
			(xy 327.698862 -273.522186)
		)
		(stroke
			(width 0)
			(type solid)
		)
		(fill yes)
		(layer "In4.Cu")
		(net "M_D_CPU0_SB_CB<1>")
	)
	(gr_poly
		(pts
			(xy 327.701148 -287.654238) (xy 327.701148 -287.609788) (xy 327.50125 -287.609788) (xy 327.50125 -287.654238)
			(xy 327.601072 -287.75406)
		)
		(stroke
			(width 0)
			(type solid)
		)
		(fill yes)
		(layer "In4.Cu")
		(net "M_D_CPU0_SB_DQ<22>")
	)
	(gr_poly
		(pts
			(xy 327.746614 -294.67175) (xy 327.710038 -294.535098) (xy 327.67143 -294.513) (xy 327.571354 -294.686228)
			(xy 327.609962 -294.708326)
		)
		(stroke
			(width 0)
			(type solid)
		)
		(fill yes)
		(layer "In4.Cu")
		(net "M_D_CPU0_SB_DQ<30>")
	)
	(gr_poly
		(pts
			(xy 327.780396 -231.063038) (xy 327.68032 -230.88981) (xy 327.641966 -230.912162) (xy 327.60539 -231.048814)
			(xy 327.741788 -231.08539)
		)
		(stroke
			(width 0)
			(type solid)
		)
		(fill yes)
		(layer "In4.Cu")
		(net "M_D_CPU0_SA_DQ<11>")
	)
	(gr_poly
		(pts
			(xy 327.781412 -226.204526) (xy 327.681336 -226.031298) (xy 327.642728 -226.053396) (xy 327.606152 -226.190048)
			(xy 327.742804 -226.226624)
		)
		(stroke
			(width 0)
			(type solid)
		)
		(fill yes)
		(layer "In4.Cu")
		(net "M_D_CPU0_SA_DQ<6>")
	)
	(gr_poly
		(pts
			(xy 327.783444 -222.962216) (xy 327.683622 -222.788988) (xy 327.64222 -222.812864) (xy 327.605644 -222.949262)
			(xy 327.742296 -222.985838)
		)
		(stroke
			(width 0)
			(type solid)
		)
		(fill yes)
		(layer "In4.Cu")
		(net "M_D_CPU0_SA_DQS_DN<0>")
	)
	(gr_poly
		(pts
			(xy 327.784206 -224.583498) (xy 327.684384 -224.41027) (xy 327.642982 -224.434146) (xy 327.606406 -224.570798)
			(xy 327.743058 -224.607374)
		)
		(stroke
			(width 0)
			(type solid)
		)
		(fill yes)
		(layer "In4.Cu")
		(net "M_D_CPU0_SA_DQS_DP<5>")
	)
	(gr_poly
		(pts
			(xy 327.854818 -255.216152) (xy 327.754996 -255.116076) (xy 327.65492 -255.216152) (xy 327.65492 -255.260602)
			(xy 327.854818 -255.260602)
		)
		(stroke
			(width 0)
			(type solid)
		)
		(fill yes)
		(layer "In4.Cu")
		(net "M_D_CPU0_SA_CA<6>")
	)
	(gr_poly
		(pts
			(xy 327.854818 -253.59614) (xy 327.754996 -253.496064) (xy 327.65492 -253.59614) (xy 327.65492 -253.64059)
			(xy 327.854818 -253.64059)
		)
		(stroke
			(width 0)
			(type solid)
		)
		(fill yes)
		(layer "In4.Cu")
		(net "M_D_CPU0_SA_CA<2>")
	)
	(gr_poly
		(pts
			(xy 327.854818 -251.572268) (xy 327.854818 -251.527818) (xy 327.65492 -251.527818) (xy 327.65492 -251.572268)
			(xy 327.754996 -251.672344)
		)
		(stroke
			(width 0)
			(type solid)
		)
		(fill yes)
		(layer "In4.Cu")
		(net "M_D_CPU0_SA_CS_N<0>")
	)
	(gr_poly
		(pts
			(xy 327.854818 -248.736104) (xy 327.754996 -248.636028) (xy 327.65492 -248.736104) (xy 327.65492 -248.780554)
			(xy 327.854818 -248.780554)
		)
		(stroke
			(width 0)
			(type solid)
		)
		(fill yes)
		(layer "In4.Cu")
		(net "M_D_CPU0_SA_CB<5>")
	)
	(gr_poly
		(pts
			(xy 327.854818 -247.115838) (xy 327.754996 -247.015762) (xy 327.65492 -247.115838) (xy 327.65492 -247.163336)
			(xy 327.854818 -247.163336)
		)
		(stroke
			(width 0)
			(type solid)
		)
		(fill yes)
		(layer "In4.Cu")
		(net "M_D_CPU0_SA_DQS_DN<9>")
	)
	(gr_poly
		(pts
			(xy 327.854818 -245.49608) (xy 327.754996 -245.396004) (xy 327.65492 -245.49608) (xy 327.65492 -245.54053)
			(xy 327.854818 -245.54053)
		)
		(stroke
			(width 0)
			(type solid)
		)
		(fill yes)
		(layer "In4.Cu")
		(net "M_D_CPU0_SA_CB<1>")
	)
	(gr_poly
		(pts
			(xy 327.854818 -243.876068) (xy 327.754996 -243.775992) (xy 327.65492 -243.876068) (xy 327.65492 -243.920518)
			(xy 327.854818 -243.920518)
		)
		(stroke
			(width 0)
			(type solid)
		)
		(fill yes)
		(layer "In4.Cu")
		(net "M_D_CPU0_SA_DQ<29>")
	)
	(gr_poly
		(pts
			(xy 327.854818 -240.636044) (xy 327.754996 -240.535968) (xy 327.65492 -240.636044) (xy 327.65492 -240.680494)
			(xy 327.854818 -240.680494)
		)
		(stroke
			(width 0)
			(type solid)
		)
		(fill yes)
		(layer "In4.Cu")
		(net "M_D_CPU0_SA_DQ<25>")
	)
	(gr_poly
		(pts
			(xy 327.854818 -235.776008) (xy 327.754996 -235.675932) (xy 327.65492 -235.776008) (xy 327.65492 -235.820458)
			(xy 327.854818 -235.820458)
		)
		(stroke
			(width 0)
			(type solid)
		)
		(fill yes)
		(layer "In4.Cu")
		(net "M_D_CPU0_SA_DQ<17>")
	)
	(gr_poly
		(pts
			(xy 327.861168 -256.432558) (xy 327.861168 -256.384806) (xy 327.661016 -256.384806) (xy 327.661016 -256.432558)
			(xy 327.761092 -256.53238)
		)
		(stroke
			(width 0)
			(type solid)
		)
		(fill yes)
		(layer "In4.Cu")
		(net "M_D_CPU0_CLK_DN<0>")
	)
	(gr_poly
		(pts
			(xy 327.861168 -250.356116) (xy 327.761092 -250.25604) (xy 327.661016 -250.356116) (xy 327.661016 -250.400566)
			(xy 327.861168 -250.400566)
		)
		(stroke
			(width 0)
			(type solid)
		)
		(fill yes)
		(layer "In4.Cu")
		(net "M_D_CPU0_ALERT_R_N")
	)
	(gr_poly
		(pts
			(xy 327.861168 -242.255802) (xy 327.761092 -242.15598) (xy 327.661016 -242.255802) (xy 327.661016 -242.303554)
			(xy 327.861168 -242.303554)
		)
		(stroke
			(width 0)
			(type solid)
		)
		(fill yes)
		(layer "In4.Cu")
		(net "M_D_CPU0_SA_DQS_DN<8>")
	)
	(gr_poly
		(pts
			(xy 327.861168 -241.85245) (xy 327.861168 -241.804698) (xy 327.661016 -241.804698) (xy 327.661016 -241.85245)
			(xy 327.761092 -241.952272)
		)
		(stroke
			(width 0)
			(type solid)
		)
		(fill yes)
		(layer "In4.Cu")
		(net "M_D_CPU0_SA_DQS_DN<3>")
	)
	(gr_poly
		(pts
			(xy 327.861168 -232.132378) (xy 327.861168 -232.084626) (xy 327.661016 -232.084626) (xy 327.661016 -232.132378)
			(xy 327.761092 -232.2322)
		)
		(stroke
			(width 0)
			(type solid)
		)
		(fill yes)
		(layer "In4.Cu")
		(net "M_D_CPU0_SA_DQS_DN<1>")
	)
	(gr_poly
		(pts
			(xy 327.861422 -237.395766) (xy 327.761346 -237.295944) (xy 327.66127 -237.395766) (xy 327.66127 -237.443518)
			(xy 327.861422 -237.443518)
		)
		(stroke
			(width 0)
			(type solid)
		)
		(fill yes)
		(layer "In4.Cu")
		(net "M_D_CPU0_SA_DQS_DN<7>")
	)
	(gr_poly
		(pts
			(xy 327.874376 -254.812038) (xy 327.874376 -254.767588) (xy 327.674224 -254.767588) (xy 327.674224 -254.812038)
			(xy 327.7743 -254.912114)
		)
		(stroke
			(width 0)
			(type solid)
		)
		(fill yes)
		(layer "In4.Cu")
		(net "M_D_CPU0_SA_CA<5>")
	)
	(gr_poly
		(pts
			(xy 327.874376 -253.192026) (xy 327.874376 -253.147576) (xy 327.674224 -253.147576) (xy 327.674224 -253.192026)
			(xy 327.7743 -253.292102)
		)
		(stroke
			(width 0)
			(type solid)
		)
		(fill yes)
		(layer "In4.Cu")
		(net "M_D_CPU0_SA_CA<1>")
	)
	(gr_poly
		(pts
			(xy 327.874376 -248.33199) (xy 327.874376 -248.28754) (xy 327.674224 -248.28754) (xy 327.674224 -248.33199)
			(xy 327.7743 -248.432066)
		)
		(stroke
			(width 0)
			(type solid)
		)
		(fill yes)
		(layer "In4.Cu")
		(net "M_D_CPU0_SA_CB<6>")
	)
	(gr_poly
		(pts
			(xy 327.874376 -245.091966) (xy 327.874376 -245.047516) (xy 327.674224 -245.047516) (xy 327.674224 -245.091966)
			(xy 327.7743 -245.192042)
		)
		(stroke
			(width 0)
			(type solid)
		)
		(fill yes)
		(layer "In4.Cu")
		(net "M_D_CPU0_SA_CB<2>")
	)
	(gr_poly
		(pts
			(xy 327.874376 -243.471954) (xy 327.874376 -243.427504) (xy 327.674224 -243.427504) (xy 327.674224 -243.471954)
			(xy 327.7743 -243.57203)
		)
		(stroke
			(width 0)
			(type solid)
		)
		(fill yes)
		(layer "In4.Cu")
		(net "M_D_CPU0_SA_DQ<30>")
	)
	(gr_poly
		(pts
			(xy 327.874376 -240.23193) (xy 327.874376 -240.18748) (xy 327.674224 -240.18748) (xy 327.674224 -240.23193)
			(xy 327.7743 -240.332006)
		)
		(stroke
			(width 0)
			(type solid)
		)
		(fill yes)
		(layer "In4.Cu")
		(net "M_D_CPU0_SA_DQ<26>")
	)
	(gr_poly
		(pts
			(xy 327.874376 -238.611918) (xy 327.874376 -238.567468) (xy 327.674224 -238.567468) (xy 327.674224 -238.611918)
			(xy 327.7743 -238.711994)
		)
		(stroke
			(width 0)
			(type solid)
		)
		(fill yes)
		(layer "In4.Cu")
		(net "M_D_CPU0_SA_DQ<22>")
	)
	(gr_poly
		(pts
			(xy 327.874376 -235.371894) (xy 327.874376 -235.327444) (xy 327.674224 -235.327444) (xy 327.674224 -235.371894)
			(xy 327.7743 -235.47197)
		)
		(stroke
			(width 0)
			(type solid)
		)
		(fill yes)
		(layer "In4.Cu")
		(net "M_D_CPU0_SA_DQ<18>")
	)
	(gr_poly
		(pts
			(xy 327.874376 -233.751882) (xy 327.874376 -233.707432) (xy 327.674224 -233.707432) (xy 327.674224 -233.751882)
			(xy 327.7743 -233.851958)
		)
		(stroke
			(width 0)
			(type solid)
		)
		(fill yes)
		(layer "In4.Cu")
		(net "M_D_CPU0_SA_DQ<14>")
	)
	(gr_poly
		(pts
			(xy 327.875646 -239.016032) (xy 327.775824 -238.91621) (xy 327.675748 -239.016032) (xy 327.675748 -239.060736)
			(xy 327.875646 -239.060736)
		)
		(stroke
			(width 0)
			(type solid)
		)
		(fill yes)
		(layer "In4.Cu")
		(net "M_D_CPU0_SA_DQ<21>")
	)
	(gr_poly
		(pts
			(xy 327.876408 -246.712232) (xy 327.876408 -246.664734) (xy 327.67651 -246.664734) (xy 327.67651 -246.712232)
			(xy 327.776332 -246.812308)
		)
		(stroke
			(width 0)
			(type solid)
		)
		(fill yes)
		(layer "In4.Cu")
		(net "M_D_CPU0_SA_DQS_DN<4>")
	)
	(gr_poly
		(pts
			(xy 327.876408 -236.99216) (xy 327.876408 -236.944662) (xy 327.67651 -236.944662) (xy 327.67651 -236.99216)
			(xy 327.776332 -237.092236)
		)
		(stroke
			(width 0)
			(type solid)
		)
		(fill yes)
		(layer "In4.Cu")
		(net "M_D_CPU0_SA_DQS_DN<2>")
	)
	(gr_poly
		(pts
			(xy 327.87971 -224.035366) (xy 327.91654 -223.898714) (xy 327.779888 -223.862138) (xy 327.738486 -223.886014)
			(xy 327.838562 -224.059242)
		)
		(stroke
			(width 0)
			(type solid)
		)
		(fill yes)
		(layer "In4.Cu")
		(net "M_D_CPU0_SA_DQS_DN<5>")
	)
	(gr_poly
		(pts
			(xy 327.879964 -230.51516) (xy 327.91654 -230.378508) (xy 327.779888 -230.341932) (xy 327.74128 -230.36403)
			(xy 327.841356 -230.537258)
		)
		(stroke
			(width 0)
			(type solid)
		)
		(fill yes)
		(layer "In4.Cu")
		(net "M_D_CPU0_SA_DQ<9>")
	)
	(gr_poly
		(pts
			(xy 327.880218 -225.655632) (xy 327.916794 -225.51898) (xy 327.780142 -225.482404) (xy 327.741788 -225.504756)
			(xy 327.84161 -225.677984)
		)
		(stroke
			(width 0)
			(type solid)
		)
		(fill yes)
		(layer "In4.Cu")
		(net "M_D_CPU0_SA_DQ<4>")
	)
	(gr_poly
		(pts
			(xy 327.880472 -228.896418) (xy 327.917302 -228.759766) (xy 327.78065 -228.72319) (xy 327.742042 -228.745542)
			(xy 327.842118 -228.91877)
		)
		(stroke
			(width 0)
			(type solid)
		)
		(fill yes)
		(layer "In4.Cu")
		(net "M_D_CPU0_SA_DQ<8>")
	)
	(gr_poly
		(pts
			(xy 327.88098 -222.41637) (xy 327.917556 -222.279718) (xy 327.780904 -222.243142) (xy 327.739756 -222.266764)
			(xy 327.839578 -222.439992)
		)
		(stroke
			(width 0)
			(type solid)
		)
		(fill yes)
		(layer "In4.Cu")
		(net "M_D_CPU0_SA_DQS_DP<0>")
	)
	(gr_poly
		(pts
			(xy 328.081386 -294.795702) (xy 328.042778 -294.773604) (xy 327.906126 -294.81018) (xy 327.942702 -294.946832)
			(xy 327.98131 -294.96893)
		)
		(stroke
			(width 0)
			(type solid)
		)
		(fill yes)
		(layer "In4.Cu")
		(net "M_D_CPU0_SB_DQ<29>")
	)
	(gr_poly
		(pts
			(xy 328.152252 -290.084256) (xy 328.152252 -290.039806) (xy 327.952354 -290.039806) (xy 327.952354 -290.084256)
			(xy 328.05243 -290.184332)
		)
		(stroke
			(width 0)
			(type solid)
		)
		(fill yes)
		(layer "In4.Cu")
		(net "M_D_CPU0_SB_DQ<27>")
	)
	(gr_poly
		(pts
			(xy 328.152252 -286.844486) (xy 328.152252 -286.796734) (xy 327.952354 -286.796734) (xy 327.952354 -286.844486)
			(xy 328.05243 -286.944308)
		)
		(stroke
			(width 0)
			(type solid)
		)
		(fill yes)
		(layer "In4.Cu")
		(net "M_D_CPU0_SB_DQS_DP<7>")
	)
	(gr_poly
		(pts
			(xy 328.152252 -285.224474) (xy 328.152252 -285.180024) (xy 327.952354 -285.180024) (xy 327.952354 -285.224474)
			(xy 328.05243 -285.324296)
		)
		(stroke
			(width 0)
			(type solid)
		)
		(fill yes)
		(layer "In4.Cu")
		(net "M_D_CPU0_SB_DQ<19>")
	)
	(gr_poly
		(pts
			(xy 328.152252 -280.364438) (xy 328.152252 -280.319988) (xy 327.952354 -280.319988) (xy 327.952354 -280.364438)
			(xy 328.05243 -280.46426)
		)
		(stroke
			(width 0)
			(type solid)
		)
		(fill yes)
		(layer "In4.Cu")
		(net "M_D_CPU0_SB_DQ<11>")
	)
	(gr_poly
		(pts
			(xy 328.152252 -277.124668) (xy 328.152252 -277.076916) (xy 327.952354 -277.076916) (xy 327.952354 -277.124668)
			(xy 328.05243 -277.22449)
		)
		(stroke
			(width 0)
			(type solid)
		)
		(fill yes)
		(layer "In4.Cu")
		(net "M_D_CPU0_SB_DQS_DP<5>")
	)
	(gr_poly
		(pts
			(xy 328.152252 -275.504402) (xy 328.152252 -275.459952) (xy 327.952354 -275.459952) (xy 327.952354 -275.504402)
			(xy 328.05243 -275.604224)
		)
		(stroke
			(width 0)
			(type solid)
		)
		(fill yes)
		(layer "In4.Cu")
		(net "M_D_CPU0_SB_DQ<3>")
	)
	(gr_poly
		(pts
			(xy 328.152252 -273.88439) (xy 328.152252 -273.83994) (xy 327.952354 -273.83994) (xy 327.952354 -273.88439)
			(xy 328.05243 -273.984212)
		)
		(stroke
			(width 0)
			(type solid)
		)
		(fill yes)
		(layer "In4.Cu")
		(net "M_D_CPU0_SB_CB<3>")
	)
	(gr_poly
		(pts
			(xy 328.152252 -272.264632) (xy 328.152252 -272.21688) (xy 327.952354 -272.21688) (xy 327.952354 -272.264632)
			(xy 328.05243 -272.364454)
		)
		(stroke
			(width 0)
			(type solid)
		)
		(fill yes)
		(layer "In4.Cu")
		(net "M_D_CPU0_SB_DQS_DP<4>")
	)
	(gr_poly
		(pts
			(xy 328.152252 -270.644366) (xy 328.152252 -270.599916) (xy 327.952354 -270.599916) (xy 327.952354 -270.644366)
			(xy 328.05243 -270.744188)
		)
		(stroke
			(width 0)
			(type solid)
		)
		(fill yes)
		(layer "In4.Cu")
		(net "M_D_CPU0_SB_CB<7>")
	)
	(gr_poly
		(pts
			(xy 328.152252 -265.78433) (xy 328.152252 -265.73988) (xy 327.952354 -265.73988) (xy 327.952354 -265.78433)
			(xy 328.05243 -265.884152)
		)
		(stroke
			(width 0)
			(type solid)
		)
		(fill yes)
		(layer "In4.Cu")
		(net "M_D_CPU0_SB_CS_N<0>")
	)
	(gr_poly
		(pts
			(xy 328.152252 -264.164318) (xy 328.152252 -264.119868) (xy 327.952354 -264.119868) (xy 327.952354 -264.164318)
			(xy 328.05243 -264.26414)
		)
		(stroke
			(width 0)
			(type solid)
		)
		(fill yes)
		(layer "In4.Cu")
		(net "M_D_CPU0_SB_CA<5>")
	)
	(gr_poly
		(pts
			(xy 328.152252 -262.544306) (xy 328.152252 -262.499856) (xy 327.952354 -262.499856) (xy 327.952354 -262.544306)
			(xy 328.05243 -262.644128)
		)
		(stroke
			(width 0)
			(type solid)
		)
		(fill yes)
		(layer "In4.Cu")
		(net "M_D_CPU0_SB_CA<1>")
	)
	(gr_poly
		(pts
			(xy 328.154284 -281.984196) (xy 328.154284 -281.936444) (xy 327.954386 -281.936444) (xy 327.954386 -281.984196)
			(xy 328.054208 -282.084018)
		)
		(stroke
			(width 0)
			(type solid)
		)
		(fill yes)
		(layer "In4.Cu")
		(net "M_D_CPU0_SB_DQS_DP<6>")
	)
	(gr_poly
		(pts
			(xy 328.155046 -287.247838) (xy 328.05497 -287.147762) (xy 327.954894 -287.247838) (xy 327.954894 -287.292288)
			(xy 328.155046 -287.292288)
		)
		(stroke
			(width 0)
			(type solid)
		)
		(fill yes)
		(layer "In4.Cu")
		(net "M_D_CPU0_SB_DQ<20>")
	)
	(gr_poly
		(pts
			(xy 328.155046 -284.008068) (xy 328.05497 -283.907992) (xy 327.954894 -284.008068) (xy 327.954894 -284.052518)
			(xy 328.155046 -284.052518)
		)
		(stroke
			(width 0)
			(type solid)
		)
		(fill yes)
		(layer "In4.Cu")
		(net "M_D_CPU0_SB_DQ<16>")
	)
	(gr_poly
		(pts
			(xy 328.155046 -282.388056) (xy 328.05497 -282.28798) (xy 327.954894 -282.388056) (xy 327.954894 -282.432506)
			(xy 328.155046 -282.432506)
		)
		(stroke
			(width 0)
			(type solid)
		)
		(fill yes)
		(layer "In4.Cu")
		(net "M_D_CPU0_SB_DQ<12>")
	)
	(gr_poly
		(pts
			(xy 328.155046 -279.148032) (xy 328.05497 -279.047956) (xy 327.954894 -279.148032) (xy 327.954894 -279.192482)
			(xy 328.155046 -279.192482)
		)
		(stroke
			(width 0)
			(type solid)
		)
		(fill yes)
		(layer "In4.Cu")
		(net "M_D_CPU0_SB_DQ<8>")
	)
	(gr_poly
		(pts
			(xy 328.155046 -278.744172) (xy 328.155046 -278.699722) (xy 327.954894 -278.699722) (xy 327.954894 -278.744172)
			(xy 328.05497 -278.844248)
		)
		(stroke
			(width 0)
			(type solid)
		)
		(fill yes)
		(layer "In4.Cu")
		(net "M_D_CPU0_SB_DQ<7>")
	)
	(gr_poly
		(pts
			(xy 328.155046 -277.52802) (xy 328.05497 -277.427944) (xy 327.954894 -277.52802) (xy 327.954894 -277.57247)
			(xy 328.155046 -277.57247)
		)
		(stroke
			(width 0)
			(type solid)
		)
		(fill yes)
		(layer "In4.Cu")
		(net "M_D_CPU0_SB_DQ<4>")
	)
	(gr_poly
		(pts
			(xy 328.155046 -275.9075) (xy 328.05497 -275.807678) (xy 327.954894 -275.9075) (xy 327.954894 -275.955252)
			(xy 328.155046 -275.955252)
		)
		(stroke
			(width 0)
			(type solid)
		)
		(fill yes)
		(layer "In4.Cu")
		(net "M_D_CPU0_SB_DQS_DP<0>")
	)
	(gr_poly
		(pts
			(xy 328.155046 -274.287996) (xy 328.05497 -274.18792) (xy 327.954894 -274.287996) (xy 327.954894 -274.332446)
			(xy 328.155046 -274.332446)
		)
		(stroke
			(width 0)
			(type solid)
		)
		(fill yes)
		(layer "In4.Cu")
		(net "M_D_CPU0_SB_DQ<0>")
	)
	(gr_poly
		(pts
			(xy 328.155046 -272.667984) (xy 328.05497 -272.567908) (xy 327.954894 -272.667984) (xy 327.954894 -272.712434)
			(xy 328.155046 -272.712434)
		)
		(stroke
			(width 0)
			(type solid)
		)
		(fill yes)
		(layer "In4.Cu")
		(net "M_D_CPU0_SB_CB<0>")
	)
	(gr_poly
		(pts
			(xy 328.155046 -271.047718) (xy 328.05497 -270.947642) (xy 327.954894 -271.047718) (xy 327.954894 -271.095216)
			(xy 328.155046 -271.095216)
		)
		(stroke
			(width 0)
			(type solid)
		)
		(fill yes)
		(layer "In4.Cu")
		(net "M_D_CPU0_SB_DQS_DP<9>")
	)
	(gr_poly
		(pts
			(xy 328.155046 -264.567924) (xy 328.05497 -264.467848) (xy 327.954894 -264.567924) (xy 327.954894 -264.612374)
			(xy 328.155046 -264.612374)
		)
		(stroke
			(width 0)
			(type solid)
		)
		(fill yes)
		(layer "In4.Cu")
		(net "M_D_CPU0_SB_CA<6>")
	)
	(gr_poly
		(pts
			(xy 328.155046 -262.947912) (xy 328.05497 -262.847836) (xy 327.954894 -262.947912) (xy 327.954894 -262.992362)
			(xy 328.155046 -262.992362)
		)
		(stroke
			(width 0)
			(type solid)
		)
		(fill yes)
		(layer "In4.Cu")
		(net "M_D_CPU0_SB_CA<2>")
	)
	(gr_poly
		(pts
			(xy 328.161142 -292.107874) (xy 328.061066 -292.007798) (xy 327.96099 -292.107874) (xy 327.96099 -292.152324)
			(xy 328.161142 -292.152324)
		)
		(stroke
			(width 0)
			(type solid)
		)
		(fill yes)
		(layer "In4.Cu")
		(net "M_D_CPU0_SB_DQ<28>")
	)
	(gr_poly
		(pts
			(xy 328.161142 -288.86785) (xy 328.061066 -288.767774) (xy 327.96099 -288.86785) (xy 327.96099 -288.9123)
			(xy 328.161142 -288.9123)
		)
		(stroke
			(width 0)
			(type solid)
		)
		(fill yes)
		(layer "In4.Cu")
		(net "M_D_CPU0_SB_DQ<24>")
	)
	(gr_poly
		(pts
			(xy 328.161142 -288.464244) (xy 328.161142 -288.419794) (xy 327.96099 -288.419794) (xy 327.96099 -288.464244)
			(xy 328.061066 -288.56432)
		)
		(stroke
			(width 0)
			(type solid)
		)
		(fill yes)
		(layer "In4.Cu")
		(net "M_D_CPU0_SB_DQ<23>")
	)
	(gr_poly
		(pts
			(xy 328.161142 -269.42796) (xy 328.061066 -269.327884) (xy 327.96099 -269.42796) (xy 327.96099 -269.47241)
			(xy 328.161142 -269.47241)
		)
		(stroke
			(width 0)
			(type solid)
		)
		(fill yes)
		(layer "In4.Cu")
		(net "M_D_CPU0_SB_CB<4>")
	)
	(gr_poly
		(pts
			(xy 328.167238 -285.627826) (xy 328.067162 -285.528004) (xy 327.967086 -285.627826) (xy 327.967086 -285.675578)
			(xy 328.167238 -285.675578)
		)
		(stroke
			(width 0)
			(type solid)
		)
		(fill yes)
		(layer "In4.Cu")
		(net "M_D_CPU0_SB_DQS_DP<2>")
	)
	(gr_poly
		(pts
			(xy 328.167238 -280.76779) (xy 328.067162 -280.667968) (xy 327.967086 -280.76779) (xy 327.967086 -280.815542)
			(xy 328.167238 -280.815542)
		)
		(stroke
			(width 0)
			(type solid)
		)
		(fill yes)
		(layer "In4.Cu")
		(net "M_D_CPU0_SB_DQS_DP<1>")
	)
	(gr_poly
		(pts
			(xy 328.175112 -267.801598) (xy 328.075036 -267.701522) (xy 327.975214 -267.801598) (xy 327.975214 -267.846048)
			(xy 328.175112 -267.846048)
		)
		(stroke
			(width 0)
			(type solid)
		)
		(fill yes)
		(layer "In4.Cu")
		(net "M_D_CPU0_SB_RSP<0>")
	)
	(gr_poly
		(pts
			(xy 328.17562 -283.604208) (xy 328.17562 -283.559504) (xy 327.975722 -283.559504) (xy 327.975722 -283.604208)
			(xy 328.075798 -283.70403)
		)
		(stroke
			(width 0)
			(type solid)
		)
		(fill yes)
		(layer "In4.Cu")
		(net "M_D_CPU0_SB_DQ<15>")
	)
	(gr_poly
		(pts
			(xy 328.217022 -293.860474) (xy 328.180446 -293.723822) (xy 328.142092 -293.70147) (xy 328.042016 -293.874698)
			(xy 328.080624 -293.89705)
		)
		(stroke
			(width 0)
			(type solid)
		)
		(fill yes)
		(layer "In4.Cu")
		(net "M_D_CPU0_SB_DQ<30>")
	)
	(gr_poly
		(pts
			(xy 328.250296 -228.63302) (xy 328.15022 -228.459792) (xy 328.111866 -228.482144) (xy 328.07529 -228.618796)
			(xy 328.211688 -228.655372)
		)
		(stroke
			(width 0)
			(type solid)
		)
		(fill yes)
		(layer "In4.Cu")
		(net "M_D_CPU0_SA_DQ<7>")
	)
	(gr_poly
		(pts
			(xy 328.250296 -227.013008) (xy 328.15022 -226.83978) (xy 328.111866 -226.862132) (xy 328.07529 -226.998784)
			(xy 328.211688 -227.03536)
		)
		(stroke
			(width 0)
			(type solid)
		)
		(fill yes)
		(layer "In4.Cu")
		(net "M_D_CPU0_SA_DQ<6>")
	)
	(gr_poly
		(pts
			(xy 328.251058 -230.254302) (xy 328.150982 -230.081074) (xy 328.112374 -230.103172) (xy 328.075798 -230.239824)
			(xy 328.21245 -230.2764)
		)
		(stroke
			(width 0)
			(type solid)
		)
		(fill yes)
		(layer "In4.Cu")
		(net "M_D_CPU0_SA_DQ<10>")
	)
	(gr_poly
		(pts
			(xy 328.25309 -225.392234) (xy 328.153268 -225.219006) (xy 328.111866 -225.242882) (xy 328.07529 -225.37928)
			(xy 328.211942 -225.415856)
		)
		(stroke
			(width 0)
			(type solid)
		)
		(fill yes)
		(layer "In4.Cu")
		(net "M_D_CPU0_SA_DQS_DP<5>")
	)
	(gr_poly
		(pts
			(xy 328.254106 -223.773492) (xy 328.154284 -223.600264) (xy 328.112882 -223.62414) (xy 328.076306 -223.760792)
			(xy 328.212958 -223.797368)
		)
		(stroke
			(width 0)
			(type solid)
		)
		(fill yes)
		(layer "In4.Cu")
		(net "M_D_CPU0_SA_DQS_DN<0>")
	)
	(gr_poly
		(pts
			(xy 328.331322 -256.025904) (xy 328.231246 -255.926082) (xy 328.13117 -256.025904) (xy 328.13117 -256.073656)
			(xy 328.331322 -256.073656)
		)
		(stroke
			(width 0)
			(type solid)
		)
		(fill yes)
		(layer "In4.Cu")
		(net "M_D_CPU0_CLK_DP<0>")
	)
	(gr_poly
		(pts
			(xy 328.331322 -255.622298) (xy 328.331322 -255.577848) (xy 328.13117 -255.577848) (xy 328.13117 -255.622298)
			(xy 328.231246 -255.722374)
		)
		(stroke
			(width 0)
			(type solid)
		)
		(fill yes)
		(layer "In4.Cu")
		(net "M_D_CPU0_SA_PAR")
	)
	(gr_poly
		(pts
			(xy 328.331322 -254.406146) (xy 328.231246 -254.30607) (xy 328.13117 -254.406146) (xy 328.13117 -254.450596)
			(xy 328.331322 -254.450596)
		)
		(stroke
			(width 0)
			(type solid)
		)
		(fill yes)
		(layer "In4.Cu")
		(net "M_D_CPU0_SA_CA<4>")
	)
	(gr_poly
		(pts
			(xy 328.331322 -254.002286) (xy 328.331322 -253.957836) (xy 328.13117 -253.957836) (xy 328.13117 -254.002286)
			(xy 328.231246 -254.102362)
		)
		(stroke
			(width 0)
			(type solid)
		)
		(fill yes)
		(layer "In4.Cu")
		(net "M_D_CPU0_SA_CA<3>")
	)
	(gr_poly
		(pts
			(xy 328.331322 -252.786134) (xy 328.231246 -252.686058) (xy 328.13117 -252.786134) (xy 328.13117 -252.830584)
			(xy 328.331322 -252.830584)
		)
		(stroke
			(width 0)
			(type solid)
		)
		(fill yes)
		(layer "In4.Cu")
		(net "M_D_CPU0_SA_CA<0>")
	)
	(gr_poly
		(pts
			(xy 328.331322 -252.382274) (xy 328.331322 -252.337824) (xy 328.13117 -252.337824) (xy 328.13117 -252.382274)
			(xy 328.231246 -252.48235)
		)
		(stroke
			(width 0)
			(type solid)
		)
		(fill yes)
		(layer "In4.Cu")
		(net "M_D_CPU0_SA_CS_N<1>")
	)
	(gr_poly
		(pts
			(xy 328.331322 -250.762262) (xy 328.331322 -250.717812) (xy 328.13117 -250.717812) (xy 328.13117 -250.762262)
			(xy 328.231246 -250.862338)
		)
		(stroke
			(width 0)
			(type solid)
		)
		(fill yes)
		(layer "In4.Cu")
		(net "M_D_CPU0_RESET_N")
	)
	(gr_poly
		(pts
			(xy 328.331322 -249.14225) (xy 328.331322 -249.0978) (xy 328.13117 -249.0978) (xy 328.13117 -249.14225)
			(xy 328.231246 -249.242326)
		)
		(stroke
			(width 0)
			(type solid)
		)
		(fill yes)
		(layer "In4.Cu")
		(net "M_D_CPU0_SA_CB<7>")
	)
	(gr_poly
		(pts
			(xy 328.331322 -247.926098) (xy 328.231246 -247.826022) (xy 328.13117 -247.926098) (xy 328.13117 -247.970548)
			(xy 328.331322 -247.970548)
		)
		(stroke
			(width 0)
			(type solid)
		)
		(fill yes)
		(layer "In4.Cu")
		(net "M_D_CPU0_SA_CB<4>")
	)
	(gr_poly
		(pts
			(xy 328.331322 -247.522492) (xy 328.331322 -247.47474) (xy 328.13117 -247.47474) (xy 328.13117 -247.522492)
			(xy 328.231246 -247.622314)
		)
		(stroke
			(width 0)
			(type solid)
		)
		(fill yes)
		(layer "In4.Cu")
		(net "M_D_CPU0_SA_DQS_DP<9>")
	)
	(gr_poly
		(pts
			(xy 328.331322 -246.305832) (xy 328.231246 -246.20601) (xy 328.13117 -246.305832) (xy 328.13117 -246.353584)
			(xy 328.331322 -246.353584)
		)
		(stroke
			(width 0)
			(type solid)
		)
		(fill yes)
		(layer "In4.Cu")
		(net "M_D_CPU0_SA_DQS_DP<4>")
	)
	(gr_poly
		(pts
			(xy 328.331322 -245.902226) (xy 328.331322 -245.857776) (xy 328.13117 -245.857776) (xy 328.13117 -245.902226)
			(xy 328.231246 -246.002302)
		)
		(stroke
			(width 0)
			(type solid)
		)
		(fill yes)
		(layer "In4.Cu")
		(net "M_D_CPU0_SA_CB<3>")
	)
	(gr_poly
		(pts
			(xy 328.331322 -244.686074) (xy 328.231246 -244.585998) (xy 328.13117 -244.686074) (xy 328.13117 -244.730524)
			(xy 328.331322 -244.730524)
		)
		(stroke
			(width 0)
			(type solid)
		)
		(fill yes)
		(layer "In4.Cu")
		(net "M_D_CPU0_SA_CB<0>")
	)
	(gr_poly
		(pts
			(xy 328.331322 -244.282214) (xy 328.331322 -244.237764) (xy 328.13117 -244.237764) (xy 328.13117 -244.282214)
			(xy 328.231246 -244.38229)
		)
		(stroke
			(width 0)
			(type solid)
		)
		(fill yes)
		(layer "In4.Cu")
		(net "M_D_CPU0_SA_DQ<31>")
	)
	(gr_poly
		(pts
			(xy 328.331322 -243.066062) (xy 328.231246 -242.965986) (xy 328.13117 -243.066062) (xy 328.13117 -243.110512)
			(xy 328.331322 -243.110512)
		)
		(stroke
			(width 0)
			(type solid)
		)
		(fill yes)
		(layer "In4.Cu")
		(net "M_D_CPU0_SA_DQ<28>")
	)
	(gr_poly
		(pts
			(xy 328.331322 -242.662456) (xy 328.331322 -242.614704) (xy 328.13117 -242.614704) (xy 328.13117 -242.662456)
			(xy 328.231246 -242.762278)
		)
		(stroke
			(width 0)
			(type solid)
		)
		(fill yes)
		(layer "In4.Cu")
		(net "M_D_CPU0_SA_DQS_DP<8>")
	)
	(gr_poly
		(pts
			(xy 328.331322 -241.445796) (xy 328.231246 -241.345974) (xy 328.13117 -241.445796) (xy 328.13117 -241.493548)
			(xy 328.331322 -241.493548)
		)
		(stroke
			(width 0)
			(type solid)
		)
		(fill yes)
		(layer "In4.Cu")
		(net "M_D_CPU0_SA_DQS_DP<3>")
	)
	(gr_poly
		(pts
			(xy 328.331322 -241.04219) (xy 328.331322 -240.99774) (xy 328.13117 -240.99774) (xy 328.13117 -241.04219)
			(xy 328.231246 -241.142266)
		)
		(stroke
			(width 0)
			(type solid)
		)
		(fill yes)
		(layer "In4.Cu")
		(net "M_D_CPU0_SA_DQ<27>")
	)
	(gr_poly
		(pts
			(xy 328.331322 -239.826038) (xy 328.231246 -239.725962) (xy 328.13117 -239.826038) (xy 328.13117 -239.870488)
			(xy 328.331322 -239.870488)
		)
		(stroke
			(width 0)
			(type solid)
		)
		(fill yes)
		(layer "In4.Cu")
		(net "M_D_CPU0_SA_DQ<24>")
	)
	(gr_poly
		(pts
			(xy 328.331322 -239.422178) (xy 328.331322 -239.377728) (xy 328.13117 -239.377728) (xy 328.13117 -239.422178)
			(xy 328.231246 -239.522254)
		)
		(stroke
			(width 0)
			(type solid)
		)
		(fill yes)
		(layer "In4.Cu")
		(net "M_D_CPU0_SA_DQ<23>")
	)
	(gr_poly
		(pts
			(xy 328.331322 -238.206026) (xy 328.231246 -238.10595) (xy 328.13117 -238.206026) (xy 328.13117 -238.250476)
			(xy 328.331322 -238.250476)
		)
		(stroke
			(width 0)
			(type solid)
		)
		(fill yes)
		(layer "In4.Cu")
		(net "M_D_CPU0_SA_DQ<20>")
	)
	(gr_poly
		(pts
			(xy 328.331322 -237.80242) (xy 328.331322 -237.754668) (xy 328.13117 -237.754668) (xy 328.13117 -237.80242)
			(xy 328.231246 -237.902242)
		)
		(stroke
			(width 0)
			(type solid)
		)
		(fill yes)
		(layer "In4.Cu")
		(net "M_D_CPU0_SA_DQS_DP<7>")
	)
	(gr_poly
		(pts
			(xy 328.331322 -236.58576) (xy 328.231246 -236.485938) (xy 328.13117 -236.58576) (xy 328.13117 -236.633512)
			(xy 328.331322 -236.633512)
		)
		(stroke
			(width 0)
			(type solid)
		)
		(fill yes)
		(layer "In4.Cu")
		(net "M_D_CPU0_SA_DQS_DP<2>")
	)
	(gr_poly
		(pts
			(xy 328.331322 -236.182154) (xy 328.331322 -236.137704) (xy 328.13117 -236.137704) (xy 328.13117 -236.182154)
			(xy 328.231246 -236.28223)
		)
		(stroke
			(width 0)
			(type solid)
		)
		(fill yes)
		(layer "In4.Cu")
		(net "M_D_CPU0_SA_DQ<19>")
	)
	(gr_poly
		(pts
			(xy 328.331322 -234.966002) (xy 328.231246 -234.865926) (xy 328.13117 -234.966002) (xy 328.13117 -235.010452)
			(xy 328.331322 -235.010452)
		)
		(stroke
			(width 0)
			(type solid)
		)
		(fill yes)
		(layer "In4.Cu")
		(net "M_D_CPU0_SA_DQ<16>")
	)
	(gr_poly
		(pts
			(xy 328.331322 -234.562142) (xy 328.331322 -234.517692) (xy 328.13117 -234.517692) (xy 328.13117 -234.562142)
			(xy 328.231246 -234.662218)
		)
		(stroke
			(width 0)
			(type solid)
		)
		(fill yes)
		(layer "In4.Cu")
		(net "M_D_CPU0_SA_DQ<15>")
	)
	(gr_poly
		(pts
			(xy 328.331322 -233.34599) (xy 328.231246 -233.245914) (xy 328.13117 -233.34599) (xy 328.13117 -233.39044)
			(xy 328.331322 -233.39044)
		)
		(stroke
			(width 0)
			(type solid)
		)
		(fill yes)
		(layer "In4.Cu")
		(net "M_D_CPU0_SA_DQ<12>")
	)
	(gr_poly
		(pts
			(xy 328.331322 -232.942384) (xy 328.331322 -232.894632) (xy 328.13117 -232.894632) (xy 328.13117 -232.942384)
			(xy 328.231246 -233.042206)
		)
		(stroke
			(width 0)
			(type solid)
		)
		(fill yes)
		(layer "In4.Cu")
		(net "M_D_CPU0_SA_DQS_DP<6>")
	)
	(gr_poly
		(pts
			(xy 328.331322 -231.725724) (xy 328.231246 -231.625902) (xy 328.13117 -231.725724) (xy 328.13117 -231.773476)
			(xy 328.331322 -231.773476)
		)
		(stroke
			(width 0)
			(type solid)
		)
		(fill yes)
		(layer "In4.Cu")
		(net "M_D_CPU0_SA_DQS_DP<1>")
	)
	(gr_poly
		(pts
			(xy 328.331322 -231.322372) (xy 328.331322 -231.277922) (xy 328.13117 -231.277922) (xy 328.13117 -231.322372)
			(xy 328.231246 -231.422448)
		)
		(stroke
			(width 0)
			(type solid)
		)
		(fill yes)
		(layer "In4.Cu")
		(net "M_D_CPU0_SA_DQ<11>")
	)
	(gr_poly
		(pts
			(xy 328.34961 -223.224344) (xy 328.386186 -223.087692) (xy 328.249534 -223.051116) (xy 328.208386 -223.074992)
			(xy 328.308208 -223.24822)
		)
		(stroke
			(width 0)
			(type solid)
		)
		(fill yes)
		(layer "In4.Cu")
		(net "M_D_CPU0_SA_DQS_DP<0>")
	)
	(gr_poly
		(pts
			(xy 328.350118 -224.846134) (xy 328.386694 -224.709482) (xy 328.250042 -224.672906) (xy 328.20864 -224.696782)
			(xy 328.308716 -224.87001)
		)
		(stroke
			(width 0)
			(type solid)
		)
		(fill yes)
		(layer "In4.Cu")
		(net "M_D_CPU0_SA_DQS_DN<5>")
	)
	(gr_poly
		(pts
			(xy 328.350372 -229.70617) (xy 328.387202 -229.569518) (xy 328.25055 -229.532942) (xy 328.211942 -229.555294)
			(xy 328.312018 -229.728522)
		)
		(stroke
			(width 0)
			(type solid)
		)
		(fill yes)
		(layer "In4.Cu")
		(net "M_D_CPU0_SA_DQ<8>")
	)
	(gr_poly
		(pts
			(xy 328.350372 -228.086412) (xy 328.387202 -227.94976) (xy 328.25055 -227.913184) (xy 328.211942 -227.935536)
			(xy 328.312018 -228.108764)
		)
		(stroke
			(width 0)
			(type solid)
		)
		(fill yes)
		(layer "In4.Cu")
		(net "M_D_CPU0_SA_DQ<5>")
	)
	(gr_poly
		(pts
			(xy 328.350372 -226.4664) (xy 328.387202 -226.329748) (xy 328.25055 -226.293172) (xy 328.211942 -226.315524)
			(xy 328.312018 -226.488752)
		)
		(stroke
			(width 0)
			(type solid)
		)
		(fill yes)
		(layer "In4.Cu")
		(net "M_D_CPU0_SA_DQ<4>")
	)
	(gr_poly
		(pts
			(xy 328.55027 -293.98722) (xy 328.511662 -293.964868) (xy 328.37501 -294.001444) (xy 328.41184 -294.138096)
			(xy 328.450194 -294.160448)
		)
		(stroke
			(width 0)
			(type solid)
		)
		(fill yes)
		(layer "In4.Cu")
		(net "M_D_CPU0_SB_DQ<29>")
	)
	(gr_poly
		(pts
			(xy 328.624946 -266.991592) (xy 328.52487 -266.891516) (xy 328.425048 -266.991592) (xy 328.425048 -267.036042)
			(xy 328.624946 -267.036042)
		)
		(stroke
			(width 0)
			(type solid)
		)
		(fill yes)
		(layer "In4.Cu")
		(net "M_D_CPU0_SA_RSP<0>")
	)
	(gr_poly
		(pts
			(xy 328.631296 -291.297614) (xy 328.53122 -291.197792) (xy 328.431144 -291.297614) (xy 328.431144 -291.345366)
			(xy 328.631296 -291.345366)
		)
		(stroke
			(width 0)
			(type solid)
		)
		(fill yes)
		(layer "In4.Cu")
		(net "M_D_CPU0_SB_DQS_DN<8>")
	)
	(gr_poly
		(pts
			(xy 328.631296 -290.894262) (xy 328.631296 -290.84651) (xy 328.431144 -290.84651) (xy 328.431144 -290.894262)
			(xy 328.53122 -290.994084)
		)
		(stroke
			(width 0)
			(type solid)
		)
		(fill yes)
		(layer "In4.Cu")
		(net "M_D_CPU0_SB_DQS_DN<3>")
	)
	(gr_poly
		(pts
			(xy 328.631296 -289.677856) (xy 328.53122 -289.57778) (xy 328.431144 -289.677856) (xy 328.431144 -289.722306)
			(xy 328.631296 -289.722306)
		)
		(stroke
			(width 0)
			(type solid)
		)
		(fill yes)
		(layer "In4.Cu")
		(net "M_D_CPU0_SB_DQ<25>")
	)
	(gr_poly
		(pts
			(xy 328.631296 -289.273996) (xy 328.631296 -289.229546) (xy 328.431144 -289.229546) (xy 328.431144 -289.273996)
			(xy 328.53122 -289.374072)
		)
		(stroke
			(width 0)
			(type solid)
		)
		(fill yes)
		(layer "In4.Cu")
		(net "M_D_CPU0_SB_DQ<26>")
	)
	(gr_poly
		(pts
			(xy 328.631296 -288.057844) (xy 328.53122 -287.957768) (xy 328.431144 -288.057844) (xy 328.431144 -288.102294)
			(xy 328.631296 -288.102294)
		)
		(stroke
			(width 0)
			(type solid)
		)
		(fill yes)
		(layer "In4.Cu")
		(net "M_D_CPU0_SB_DQ<21>")
	)
	(gr_poly
		(pts
			(xy 328.631296 -287.654238) (xy 328.631296 -287.609788) (xy 328.431144 -287.609788) (xy 328.431144 -287.654238)
			(xy 328.53122 -287.75406)
		)
		(stroke
			(width 0)
			(type solid)
		)
		(fill yes)
		(layer "In4.Cu")
		(net "M_D_CPU0_SB_DQ<22>")
	)
	(gr_poly
		(pts
			(xy 328.631296 -286.437832) (xy 328.53122 -286.337756) (xy 328.431144 -286.437832) (xy 328.431144 -286.485584)
			(xy 328.631296 -286.485584)
		)
		(stroke
			(width 0)
			(type solid)
		)
		(fill yes)
		(layer "In4.Cu")
		(net "M_D_CPU0_SB_DQS_DN<7>")
	)
	(gr_poly
		(pts
			(xy 328.631296 -286.03448) (xy 328.631296 -285.986728) (xy 328.431144 -285.986728) (xy 328.431144 -286.03448)
			(xy 328.53122 -286.134302)
		)
		(stroke
			(width 0)
			(type solid)
		)
		(fill yes)
		(layer "In4.Cu")
		(net "M_D_CPU0_SB_DQS_DN<2>")
	)
	(gr_poly
		(pts
			(xy 328.631296 -284.818074) (xy 328.53122 -284.717998) (xy 328.431144 -284.818074) (xy 328.431144 -284.862524)
			(xy 328.631296 -284.862524)
		)
		(stroke
			(width 0)
			(type solid)
		)
		(fill yes)
		(layer "In4.Cu")
		(net "M_D_CPU0_SB_DQ<17>")
	)
	(gr_poly
		(pts
			(xy 328.631296 -284.414214) (xy 328.631296 -284.369764) (xy 328.431144 -284.369764) (xy 328.431144 -284.414214)
			(xy 328.53122 -284.51429)
		)
		(stroke
			(width 0)
			(type solid)
		)
		(fill yes)
		(layer "In4.Cu")
		(net "M_D_CPU0_SB_DQ<18>")
	)
	(gr_poly
		(pts
			(xy 328.631296 -283.198062) (xy 328.53122 -283.097986) (xy 328.431144 -283.198062) (xy 328.431144 -283.242512)
			(xy 328.631296 -283.242512)
		)
		(stroke
			(width 0)
			(type solid)
		)
		(fill yes)
		(layer "In4.Cu")
		(net "M_D_CPU0_SB_DQ<13>")
	)
	(gr_poly
		(pts
			(xy 328.631296 -282.794202) (xy 328.631296 -282.749752) (xy 328.431144 -282.749752) (xy 328.431144 -282.794202)
			(xy 328.53122 -282.894278)
		)
		(stroke
			(width 0)
			(type solid)
		)
		(fill yes)
		(layer "In4.Cu")
		(net "M_D_CPU0_SB_DQ<14>")
	)
	(gr_poly
		(pts
			(xy 328.631296 -281.577796) (xy 328.53122 -281.477974) (xy 328.431144 -281.577796) (xy 328.431144 -281.625548)
			(xy 328.631296 -281.625548)
		)
		(stroke
			(width 0)
			(type solid)
		)
		(fill yes)
		(layer "In4.Cu")
		(net "M_D_CPU0_SB_DQS_DN<6>")
	)
	(gr_poly
		(pts
			(xy 328.631296 -281.174444) (xy 328.631296 -281.126692) (xy 328.431144 -281.126692) (xy 328.431144 -281.174444)
			(xy 328.53122 -281.274266)
		)
		(stroke
			(width 0)
			(type solid)
		)
		(fill yes)
		(layer "In4.Cu")
		(net "M_D_CPU0_SB_DQS_DN<1>")
	)
	(gr_poly
		(pts
			(xy 328.631296 -279.958038) (xy 328.53122 -279.857962) (xy 328.431144 -279.958038) (xy 328.431144 -280.002488)
			(xy 328.631296 -280.002488)
		)
		(stroke
			(width 0)
			(type solid)
		)
		(fill yes)
		(layer "In4.Cu")
		(net "M_D_CPU0_SB_DQ<9>")
	)
	(gr_poly
		(pts
			(xy 328.631296 -279.554178) (xy 328.631296 -279.509728) (xy 328.431144 -279.509728) (xy 328.431144 -279.554178)
			(xy 328.53122 -279.654254)
		)
		(stroke
			(width 0)
			(type solid)
		)
		(fill yes)
		(layer "In4.Cu")
		(net "M_D_CPU0_SB_DQ<10>")
	)
	(gr_poly
		(pts
			(xy 328.631296 -278.338026) (xy 328.53122 -278.23795) (xy 328.431144 -278.338026) (xy 328.431144 -278.382476)
			(xy 328.631296 -278.382476)
		)
		(stroke
			(width 0)
			(type solid)
		)
		(fill yes)
		(layer "In4.Cu")
		(net "M_D_CPU0_SB_DQ<5>")
	)
	(gr_poly
		(pts
			(xy 328.631296 -277.934166) (xy 328.631296 -277.889716) (xy 328.431144 -277.889716) (xy 328.431144 -277.934166)
			(xy 328.53122 -278.034242)
		)
		(stroke
			(width 0)
			(type solid)
		)
		(fill yes)
		(layer "In4.Cu")
		(net "M_D_CPU0_SB_DQ<6>")
	)
	(gr_poly
		(pts
			(xy 328.631296 -276.71776) (xy 328.53122 -276.617938) (xy 328.431144 -276.71776) (xy 328.431144 -276.765512)
			(xy 328.631296 -276.765512)
		)
		(stroke
			(width 0)
			(type solid)
		)
		(fill yes)
		(layer "In4.Cu")
		(net "M_D_CPU0_SB_DQS_DN<5>")
	)
	(gr_poly
		(pts
			(xy 328.631296 -276.314408) (xy 328.631296 -276.266656) (xy 328.431144 -276.266656) (xy 328.431144 -276.314408)
			(xy 328.53122 -276.41423)
		)
		(stroke
			(width 0)
			(type solid)
		)
		(fill yes)
		(layer "In4.Cu")
		(net "M_D_CPU0_SB_DQS_DN<0>")
	)
	(gr_poly
		(pts
			(xy 328.631296 -275.098002) (xy 328.53122 -274.997926) (xy 328.431144 -275.098002) (xy 328.431144 -275.142452)
			(xy 328.631296 -275.142452)
		)
		(stroke
			(width 0)
			(type solid)
		)
		(fill yes)
		(layer "In4.Cu")
		(net "M_D_CPU0_SB_DQ<1>")
	)
	(gr_poly
		(pts
			(xy 328.631296 -274.694142) (xy 328.631296 -274.649692) (xy 328.431144 -274.649692) (xy 328.431144 -274.694142)
			(xy 328.53122 -274.794218)
		)
		(stroke
			(width 0)
			(type solid)
		)
		(fill yes)
		(layer "In4.Cu")
		(net "M_D_CPU0_SB_DQ<2>")
	)
	(gr_poly
		(pts
			(xy 328.631296 -273.47799) (xy 328.53122 -273.377914) (xy 328.431144 -273.47799) (xy 328.431144 -273.52244)
			(xy 328.631296 -273.52244)
		)
		(stroke
			(width 0)
			(type solid)
		)
		(fill yes)
		(layer "In4.Cu")
		(net "M_D_CPU0_SB_CB<1>")
	)
	(gr_poly
		(pts
			(xy 328.631296 -273.07413) (xy 328.631296 -273.02968) (xy 328.431144 -273.02968) (xy 328.431144 -273.07413)
			(xy 328.53122 -273.174206)
		)
		(stroke
			(width 0)
			(type solid)
		)
		(fill yes)
		(layer "In4.Cu")
		(net "M_D_CPU0_SB_CB<2>")
	)
	(gr_poly
		(pts
			(xy 328.631296 -271.857724) (xy 328.53122 -271.757902) (xy 328.431144 -271.857724) (xy 328.431144 -271.905476)
			(xy 328.631296 -271.905476)
		)
		(stroke
			(width 0)
			(type solid)
		)
		(fill yes)
		(layer "In4.Cu")
		(net "M_D_CPU0_SB_DQS_DN<4>")
	)
	(gr_poly
		(pts
			(xy 328.631296 -271.454372) (xy 328.631296 -271.40662) (xy 328.431144 -271.40662) (xy 328.431144 -271.454372)
			(xy 328.53122 -271.554194)
		)
		(stroke
			(width 0)
			(type solid)
		)
		(fill yes)
		(layer "In4.Cu")
		(net "M_D_CPU0_SB_DQS_DN<9>")
	)
	(gr_poly
		(pts
			(xy 328.631296 -270.237966) (xy 328.53122 -270.13789) (xy 328.431144 -270.237966) (xy 328.431144 -270.282416)
			(xy 328.631296 -270.282416)
		)
		(stroke
			(width 0)
			(type solid)
		)
		(fill yes)
		(layer "In4.Cu")
		(net "M_D_CPU0_SB_CB<5>")
	)
	(gr_poly
		(pts
			(xy 328.631296 -269.834106) (xy 328.631296 -269.789656) (xy 328.431144 -269.789656) (xy 328.431144 -269.834106)
			(xy 328.53122 -269.934182)
		)
		(stroke
			(width 0)
			(type solid)
		)
		(fill yes)
		(layer "In4.Cu")
		(net "M_D_CPU0_SB_CB<6>")
	)
	(gr_poly
		(pts
			(xy 328.631296 -266.594082) (xy 328.631296 -266.549632) (xy 328.431144 -266.549632) (xy 328.431144 -266.594082)
			(xy 328.53122 -266.694158)
		)
		(stroke
			(width 0)
			(type solid)
		)
		(fill yes)
		(layer "In4.Cu")
		(net "M_D_CPU0_SB_CS_N<1>")
	)
	(gr_poly
		(pts
			(xy 328.631296 -264.97407) (xy 328.631296 -264.92962) (xy 328.431144 -264.92962) (xy 328.431144 -264.97407)
			(xy 328.53122 -265.074146)
		)
		(stroke
			(width 0)
			(type solid)
		)
		(fill yes)
		(layer "In4.Cu")
		(net "M_D_CPU0_SB_PAR")
	)
	(gr_poly
		(pts
			(xy 328.631296 -263.757918) (xy 328.53122 -263.657842) (xy 328.431144 -263.757918) (xy 328.431144 -263.802368)
			(xy 328.631296 -263.802368)
		)
		(stroke
			(width 0)
			(type solid)
		)
		(fill yes)
		(layer "In4.Cu")
		(net "M_D_CPU0_SB_CA<4>")
	)
	(gr_poly
		(pts
			(xy 328.631296 -263.354058) (xy 328.631296 -263.309608) (xy 328.431144 -263.309608) (xy 328.431144 -263.354058)
			(xy 328.53122 -263.454134)
		)
		(stroke
			(width 0)
			(type solid)
		)
		(fill yes)
		(layer "In4.Cu")
		(net "M_D_CPU0_SB_CA<3>")
	)
	(gr_poly
		(pts
			(xy 328.631296 -262.137906) (xy 328.53122 -262.03783) (xy 328.431144 -262.137906) (xy 328.431144 -262.182356)
			(xy 328.631296 -262.182356)
		)
		(stroke
			(width 0)
			(type solid)
		)
		(fill yes)
		(layer "In4.Cu")
		(net "M_D_CPU0_SB_CA<0>")
	)
	(gr_poly
		(pts
			(xy 328.686922 -293.050468) (xy 328.650346 -292.913816) (xy 328.611992 -292.891464) (xy 328.511916 -293.064692)
			(xy 328.550524 -293.087044)
		)
		(stroke
			(width 0)
			(type solid)
		)
		(fill yes)
		(layer "In4.Cu")
		(net "M_D_CPU0_SB_DQ<30>")
	)
	(gr_poly
		(pts
			(xy 328.68743 -296.28973) (xy 328.6506 -296.153332) (xy 328.612246 -296.13098) (xy 328.51217 -296.304208)
			(xy 328.550778 -296.32656)
		)
		(stroke
			(width 0)
			(type solid)
		)
		(fill yes)
		(layer "In4.Cu")
		(net "M_D_CPU0_SB_DQ<31>")
	)
	(gr_poly
		(pts
			(xy 328.721212 -229.44455) (xy 328.621136 -229.271322) (xy 328.582528 -229.29342) (xy 328.545952 -229.430072)
			(xy 328.682604 -229.466648)
		)
		(stroke
			(width 0)
			(type solid)
		)
		(fill yes)
		(layer "In4.Cu")
		(net "M_D_CPU0_SA_DQ<7>")
	)
	(gr_poly
		(pts
			(xy 328.721212 -227.824538) (xy 328.621136 -227.65131) (xy 328.582528 -227.673408) (xy 328.545952 -227.81006)
			(xy 328.682604 -227.846636)
		)
		(stroke
			(width 0)
			(type solid)
		)
		(fill yes)
		(layer "In4.Cu")
		(net "M_D_CPU0_SA_DQ<6>")
	)
	(gr_poly
		(pts
			(xy 328.721212 -222.964502) (xy 328.621136 -222.791274) (xy 328.582528 -222.813372) (xy 328.545952 -222.950024)
			(xy 328.682604 -222.9866)
		)
		(stroke
			(width 0)
			(type solid)
		)
		(fill yes)
		(layer "In4.Cu")
		(net "M_D_CPU0_SA_DQ<3>")
	)
	(gr_poly
		(pts
			(xy 328.724006 -226.20351) (xy 328.624184 -226.030282) (xy 328.582782 -226.054158) (xy 328.546206 -226.19081)
			(xy 328.682858 -226.227386)
		)
		(stroke
			(width 0)
			(type solid)
		)
		(fill yes)
		(layer "In4.Cu")
		(net "M_D_CPU0_SA_DQS_DP<5>")
	)
	(gr_poly
		(pts
			(xy 328.724006 -224.583498) (xy 328.624184 -224.41027) (xy 328.582782 -224.434146) (xy 328.546206 -224.570798)
			(xy 328.682858 -224.607374)
		)
		(stroke
			(width 0)
			(type solid)
		)
		(fill yes)
		(layer "In4.Cu")
		(net "M_D_CPU0_SA_DQS_DN<0>")
	)
	(gr_poly
		(pts
			(xy 328.801222 -256.432558) (xy 328.801222 -256.384806) (xy 328.60107 -256.384806) (xy 328.60107 -256.432558)
			(xy 328.701146 -256.53238)
		)
		(stroke
			(width 0)
			(type solid)
		)
		(fill yes)
		(layer "In4.Cu")
		(net "M_D_CPU0_CLK_DN<0>")
	)
	(gr_poly
		(pts
			(xy 328.801222 -255.216152) (xy 328.701146 -255.116076) (xy 328.60107 -255.216152) (xy 328.60107 -255.260602)
			(xy 328.801222 -255.260602)
		)
		(stroke
			(width 0)
			(type solid)
		)
		(fill yes)
		(layer "In4.Cu")
		(net "M_D_CPU0_SA_CA<6>")
	)
	(gr_poly
		(pts
			(xy 328.801222 -254.812292) (xy 328.801222 -254.767842) (xy 328.60107 -254.767842) (xy 328.60107 -254.812292)
			(xy 328.701146 -254.912368)
		)
		(stroke
			(width 0)
			(type solid)
		)
		(fill yes)
		(layer "In4.Cu")
		(net "M_D_CPU0_SA_CA<5>")
	)
	(gr_poly
		(pts
			(xy 328.801222 -253.59614) (xy 328.701146 -253.496064) (xy 328.60107 -253.59614) (xy 328.60107 -253.64059)
			(xy 328.801222 -253.64059)
		)
		(stroke
			(width 0)
			(type solid)
		)
		(fill yes)
		(layer "In4.Cu")
		(net "M_D_CPU0_SA_CA<2>")
	)
	(gr_poly
		(pts
			(xy 328.801222 -253.19228) (xy 328.801222 -253.14783) (xy 328.60107 -253.14783) (xy 328.60107 -253.19228)
			(xy 328.701146 -253.292356)
		)
		(stroke
			(width 0)
			(type solid)
		)
		(fill yes)
		(layer "In4.Cu")
		(net "M_D_CPU0_SA_CA<1>")
	)
	(gr_poly
		(pts
			(xy 328.801222 -251.572268) (xy 328.801222 -251.527818) (xy 328.60107 -251.527818) (xy 328.60107 -251.572268)
			(xy 328.701146 -251.672344)
		)
		(stroke
			(width 0)
			(type solid)
		)
		(fill yes)
		(layer "In4.Cu")
		(net "M_D_CPU0_SA_CS_N<0>")
	)
	(gr_poly
		(pts
			(xy 328.801222 -250.356116) (xy 328.701146 -250.25604) (xy 328.60107 -250.356116) (xy 328.60107 -250.400566)
			(xy 328.801222 -250.400566)
		)
		(stroke
			(width 0)
			(type solid)
		)
		(fill yes)
		(layer "In4.Cu")
		(net "M_D_CPU0_ALERT_R_N")
	)
	(gr_poly
		(pts
			(xy 328.801222 -248.736104) (xy 328.701146 -248.636028) (xy 328.60107 -248.736104) (xy 328.60107 -248.780554)
			(xy 328.801222 -248.780554)
		)
		(stroke
			(width 0)
			(type solid)
		)
		(fill yes)
		(layer "In4.Cu")
		(net "M_D_CPU0_SA_CB<5>")
	)
	(gr_poly
		(pts
			(xy 328.801222 -248.332244) (xy 328.801222 -248.287794) (xy 328.60107 -248.287794) (xy 328.60107 -248.332244)
			(xy 328.701146 -248.43232)
		)
		(stroke
			(width 0)
			(type solid)
		)
		(fill yes)
		(layer "In4.Cu")
		(net "M_D_CPU0_SA_CB<6>")
	)
	(gr_poly
		(pts
			(xy 328.801222 -247.115838) (xy 328.701146 -247.016016) (xy 328.60107 -247.115838) (xy 328.60107 -247.16359)
			(xy 328.801222 -247.16359)
		)
		(stroke
			(width 0)
			(type solid)
		)
		(fill yes)
		(layer "In4.Cu")
		(net "M_D_CPU0_SA_DQS_DN<9>")
	)
	(gr_poly
		(pts
			(xy 328.801222 -246.712486) (xy 328.801222 -246.664734) (xy 328.60107 -246.664734) (xy 328.60107 -246.712486)
			(xy 328.701146 -246.812308)
		)
		(stroke
			(width 0)
			(type solid)
		)
		(fill yes)
		(layer "In4.Cu")
		(net "M_D_CPU0_SA_DQS_DN<4>")
	)
	(gr_poly
		(pts
			(xy 328.801222 -245.49608) (xy 328.701146 -245.396004) (xy 328.60107 -245.49608) (xy 328.60107 -245.54053)
			(xy 328.801222 -245.54053)
		)
		(stroke
			(width 0)
			(type solid)
		)
		(fill yes)
		(layer "In4.Cu")
		(net "M_D_CPU0_SA_CB<1>")
	)
	(gr_poly
		(pts
			(xy 328.801222 -245.09222) (xy 328.801222 -245.04777) (xy 328.60107 -245.04777) (xy 328.60107 -245.09222)
			(xy 328.701146 -245.192296)
		)
		(stroke
			(width 0)
			(type solid)
		)
		(fill yes)
		(layer "In4.Cu")
		(net "M_D_CPU0_SA_CB<2>")
	)
	(gr_poly
		(pts
			(xy 328.801222 -243.876068) (xy 328.701146 -243.775992) (xy 328.60107 -243.876068) (xy 328.60107 -243.920518)
			(xy 328.801222 -243.920518)
		)
		(stroke
			(width 0)
			(type solid)
		)
		(fill yes)
		(layer "In4.Cu")
		(net "M_D_CPU0_SA_DQ<29>")
	)
	(gr_poly
		(pts
			(xy 328.801222 -243.472208) (xy 328.801222 -243.427758) (xy 328.60107 -243.427758) (xy 328.60107 -243.472208)
			(xy 328.701146 -243.572284)
		)
		(stroke
			(width 0)
			(type solid)
		)
		(fill yes)
		(layer "In4.Cu")
		(net "M_D_CPU0_SA_DQ<30>")
	)
	(gr_poly
		(pts
			(xy 328.801222 -242.255802) (xy 328.701146 -242.15598) (xy 328.60107 -242.255802) (xy 328.60107 -242.303554)
			(xy 328.801222 -242.303554)
		)
		(stroke
			(width 0)
			(type solid)
		)
		(fill yes)
		(layer "In4.Cu")
		(net "M_D_CPU0_SA_DQS_DN<8>")
	)
	(gr_poly
		(pts
			(xy 328.801222 -241.85245) (xy 328.801222 -241.804698) (xy 328.60107 -241.804698) (xy 328.60107 -241.85245)
			(xy 328.701146 -241.952272)
		)
		(stroke
			(width 0)
			(type solid)
		)
		(fill yes)
		(layer "In4.Cu")
		(net "M_D_CPU0_SA_DQS_DN<3>")
	)
	(gr_poly
		(pts
			(xy 328.801222 -240.636044) (xy 328.701146 -240.535968) (xy 328.60107 -240.636044) (xy 328.60107 -240.680494)
			(xy 328.801222 -240.680494)
		)
		(stroke
			(width 0)
			(type solid)
		)
		(fill yes)
		(layer "In4.Cu")
		(net "M_D_CPU0_SA_DQ<25>")
	)
	(gr_poly
		(pts
			(xy 328.801222 -240.232184) (xy 328.801222 -240.187734) (xy 328.60107 -240.187734) (xy 328.60107 -240.232184)
			(xy 328.701146 -240.33226)
		)
		(stroke
			(width 0)
			(type solid)
		)
		(fill yes)
		(layer "In4.Cu")
		(net "M_D_CPU0_SA_DQ<26>")
	)
	(gr_poly
		(pts
			(xy 328.801222 -239.016032) (xy 328.701146 -238.915956) (xy 328.60107 -239.016032) (xy 328.60107 -239.060482)
			(xy 328.801222 -239.060482)
		)
		(stroke
			(width 0)
			(type solid)
		)
		(fill yes)
		(layer "In4.Cu")
		(net "M_D_CPU0_SA_DQ<21>")
	)
	(gr_poly
		(pts
			(xy 328.801222 -238.612172) (xy 328.801222 -238.567722) (xy 328.60107 -238.567722) (xy 328.60107 -238.612172)
			(xy 328.701146 -238.712248)
		)
		(stroke
			(width 0)
			(type solid)
		)
		(fill yes)
		(layer "In4.Cu")
		(net "M_D_CPU0_SA_DQ<22>")
	)
	(gr_poly
		(pts
			(xy 328.801222 -237.395766) (xy 328.701146 -237.295944) (xy 328.60107 -237.395766) (xy 328.60107 -237.443518)
			(xy 328.801222 -237.443518)
		)
		(stroke
			(width 0)
			(type solid)
		)
		(fill yes)
		(layer "In4.Cu")
		(net "M_D_CPU0_SA_DQS_DN<7>")
	)
	(gr_poly
		(pts
			(xy 328.801222 -236.992414) (xy 328.801222 -236.944662) (xy 328.60107 -236.944662) (xy 328.60107 -236.992414)
			(xy 328.701146 -237.092236)
		)
		(stroke
			(width 0)
			(type solid)
		)
		(fill yes)
		(layer "In4.Cu")
		(net "M_D_CPU0_SA_DQS_DN<2>")
	)
	(gr_poly
		(pts
			(xy 328.801222 -235.776008) (xy 328.701146 -235.675932) (xy 328.60107 -235.776008) (xy 328.60107 -235.820458)
			(xy 328.801222 -235.820458)
		)
		(stroke
			(width 0)
			(type solid)
		)
		(fill yes)
		(layer "In4.Cu")
		(net "M_D_CPU0_SA_DQ<17>")
	)
	(gr_poly
		(pts
			(xy 328.801222 -235.372148) (xy 328.801222 -235.327698) (xy 328.60107 -235.327698) (xy 328.60107 -235.372148)
			(xy 328.701146 -235.472224)
		)
		(stroke
			(width 0)
			(type solid)
		)
		(fill yes)
		(layer "In4.Cu")
		(net "M_D_CPU0_SA_DQ<18>")
	)
	(gr_poly
		(pts
			(xy 328.801222 -234.155996) (xy 328.701146 -234.05592) (xy 328.60107 -234.155996) (xy 328.60107 -234.200446)
			(xy 328.801222 -234.200446)
		)
		(stroke
			(width 0)
			(type solid)
		)
		(fill yes)
		(layer "In4.Cu")
		(net "M_D_CPU0_SA_DQ<13>")
	)
	(gr_poly
		(pts
			(xy 328.801222 -233.752136) (xy 328.801222 -233.707686) (xy 328.60107 -233.707686) (xy 328.60107 -233.752136)
			(xy 328.701146 -233.852212)
		)
		(stroke
			(width 0)
			(type solid)
		)
		(fill yes)
		(layer "In4.Cu")
		(net "M_D_CPU0_SA_DQ<14>")
	)
	(gr_poly
		(pts
			(xy 328.801222 -232.53573) (xy 328.701146 -232.435908) (xy 328.60107 -232.53573) (xy 328.60107 -232.583482)
			(xy 328.801222 -232.583482)
		)
		(stroke
			(width 0)
			(type solid)
		)
		(fill yes)
		(layer "In4.Cu")
		(net "M_D_CPU0_SA_DQS_DN<6>")
	)
	(gr_poly
		(pts
			(xy 328.801222 -232.132378) (xy 328.801222 -232.084626) (xy 328.60107 -232.084626) (xy 328.60107 -232.132378)
			(xy 328.701146 -232.2322)
		)
		(stroke
			(width 0)
			(type solid)
		)
		(fill yes)
		(layer "In4.Cu")
		(net "M_D_CPU0_SA_DQS_DN<1>")
	)
	(gr_poly
		(pts
			(xy 328.801222 -230.915972) (xy 328.701146 -230.815896) (xy 328.60107 -230.915972) (xy 328.60107 -230.960422)
			(xy 328.801222 -230.960422)
		)
		(stroke
			(width 0)
			(type solid)
		)
		(fill yes)
		(layer "In4.Cu")
		(net "M_D_CPU0_SA_DQ<9>")
	)
	(gr_poly
		(pts
			(xy 328.801222 -230.512366) (xy 328.801222 -230.467916) (xy 328.60107 -230.467916) (xy 328.60107 -230.512366)
			(xy 328.701146 -230.612188)
		)
		(stroke
			(width 0)
			(type solid)
		)
		(fill yes)
		(layer "In4.Cu")
		(net "M_D_CPU0_SA_DQ<10>")
	)
	(gr_poly
		(pts
			(xy 328.81951 -224.03435) (xy 328.856086 -223.897698) (xy 328.719434 -223.861122) (xy 328.678286 -223.884998)
			(xy 328.778108 -224.058226)
		)
		(stroke
			(width 0)
			(type solid)
		)
		(fill yes)
		(layer "In4.Cu")
		(net "M_D_CPU0_SA_DQS_DP<0>")
	)
	(gr_poly
		(pts
			(xy 328.819764 -228.895148) (xy 328.85634 -228.758496) (xy 328.719688 -228.72192) (xy 328.68108 -228.744018)
			(xy 328.781156 -228.917246)
		)
		(stroke
			(width 0)
			(type solid)
		)
		(fill yes)
		(layer "In4.Cu")
		(net "M_D_CPU0_SA_DQ<5>")
	)
	(gr_poly
		(pts
			(xy 328.819764 -227.275136) (xy 328.85634 -227.138484) (xy 328.719688 -227.101908) (xy 328.68108 -227.124006)
			(xy 328.781156 -227.297234)
		)
		(stroke
			(width 0)
			(type solid)
		)
		(fill yes)
		(layer "In4.Cu")
		(net "M_D_CPU0_SA_DQ<4>")
	)
	(gr_poly
		(pts
			(xy 328.820018 -222.4151) (xy 328.856594 -222.278448) (xy 328.719942 -222.241872) (xy 328.681334 -222.26397)
			(xy 328.78141 -222.437198)
		)
		(stroke
			(width 0)
			(type solid)
		)
		(fill yes)
		(layer "In4.Cu")
		(net "M_D_CPU0_SA_DQ<1>")
	)
	(gr_poly
		(pts
			(xy 328.820526 -225.656648) (xy 328.857102 -225.519996) (xy 328.72045 -225.48342) (xy 328.679302 -225.507042)
			(xy 328.779124 -225.68027)
		)
		(stroke
			(width 0)
			(type solid)
		)
		(fill yes)
		(layer "In4.Cu")
		(net "M_D_CPU0_SA_DQS_DN<5>")
	)
	(gr_poly
		(pts
			(xy 329.021186 -293.17569) (xy 328.982578 -293.153592) (xy 328.845926 -293.190168) (xy 328.882502 -293.32682)
			(xy 328.92111 -293.348918)
		)
		(stroke
			(width 0)
			(type solid)
		)
		(fill yes)
		(layer "In4.Cu")
		(net "M_D_CPU0_SB_DQ<29>")
	)
	(gr_poly
		(pts
			(xy 329.101196 -292.107874) (xy 329.00112 -292.007798) (xy 328.901044 -292.107874) (xy 328.901044 -292.152324)
			(xy 329.101196 -292.152324)
		)
		(stroke
			(width 0)
			(type solid)
		)
		(fill yes)
		(layer "In4.Cu")
		(net "M_D_CPU0_SB_DQ<28>")
	)
	(gr_poly
		(pts
			(xy 329.101196 -291.704268) (xy 329.101196 -291.656516) (xy 328.901044 -291.656516) (xy 328.901044 -291.704268)
			(xy 329.00112 -291.80409)
		)
		(stroke
			(width 0)
			(type solid)
		)
		(fill yes)
		(layer "In4.Cu")
		(net "M_D_CPU0_SB_DQS_DP<8>")
	)
	(gr_poly
		(pts
			(xy 329.101196 -290.487608) (xy 329.00112 -290.387786) (xy 328.901044 -290.487608) (xy 328.901044 -290.53536)
			(xy 329.101196 -290.53536)
		)
		(stroke
			(width 0)
			(type solid)
		)
		(fill yes)
		(layer "In4.Cu")
		(net "M_D_CPU0_SB_DQS_DP<3>")
	)
	(gr_poly
		(pts
			(xy 329.101196 -290.084002) (xy 329.101196 -290.039552) (xy 328.901044 -290.039552) (xy 328.901044 -290.084002)
			(xy 329.00112 -290.184078)
		)
		(stroke
			(width 0)
			(type solid)
		)
		(fill yes)
		(layer "In4.Cu")
		(net "M_D_CPU0_SB_DQ<27>")
	)
	(gr_poly
		(pts
			(xy 329.101196 -288.86785) (xy 329.00112 -288.767774) (xy 328.901044 -288.86785) (xy 328.901044 -288.9123)
			(xy 329.101196 -288.9123)
		)
		(stroke
			(width 0)
			(type solid)
		)
		(fill yes)
		(layer "In4.Cu")
		(net "M_D_CPU0_SB_DQ<24>")
	)
	(gr_poly
		(pts
			(xy 329.101196 -288.464244) (xy 329.101196 -288.419794) (xy 328.901044 -288.419794) (xy 328.901044 -288.464244)
			(xy 329.00112 -288.56432)
		)
		(stroke
			(width 0)
			(type solid)
		)
		(fill yes)
		(layer "In4.Cu")
		(net "M_D_CPU0_SB_DQ<23>")
	)
	(gr_poly
		(pts
			(xy 329.101196 -287.247838) (xy 329.00112 -287.148016) (xy 328.901044 -287.247838) (xy 328.901044 -287.292288)
			(xy 329.101196 -287.292288)
		)
		(stroke
			(width 0)
			(type solid)
		)
		(fill yes)
		(layer "In4.Cu")
		(net "M_D_CPU0_SB_DQ<20>")
	)
	(gr_poly
		(pts
			(xy 329.101196 -286.844232) (xy 329.101196 -286.79648) (xy 328.901044 -286.79648) (xy 328.901044 -286.844232)
			(xy 329.00112 -286.944308)
		)
		(stroke
			(width 0)
			(type solid)
		)
		(fill yes)
		(layer "In4.Cu")
		(net "M_D_CPU0_SB_DQS_DP<7>")
	)
	(gr_poly
		(pts
			(xy 329.101196 -285.627826) (xy 329.00112 -285.528004) (xy 328.901044 -285.627826) (xy 328.901044 -285.675578)
			(xy 329.101196 -285.675578)
		)
		(stroke
			(width 0)
			(type solid)
		)
		(fill yes)
		(layer "In4.Cu")
		(net "M_D_CPU0_SB_DQS_DP<2>")
	)
	(gr_poly
		(pts
			(xy 329.101196 -285.22422) (xy 329.101196 -285.17977) (xy 328.901044 -285.17977) (xy 328.901044 -285.22422)
			(xy 329.00112 -285.324296)
		)
		(stroke
			(width 0)
			(type solid)
		)
		(fill yes)
		(layer "In4.Cu")
		(net "M_D_CPU0_SB_DQ<19>")
	)
	(gr_poly
		(pts
			(xy 329.101196 -284.008068) (xy 329.00112 -283.907992) (xy 328.901044 -284.008068) (xy 328.901044 -284.052518)
			(xy 329.101196 -284.052518)
		)
		(stroke
			(width 0)
			(type solid)
		)
		(fill yes)
		(layer "In4.Cu")
		(net "M_D_CPU0_SB_DQ<16>")
	)
	(gr_poly
		(pts
			(xy 329.101196 -283.604208) (xy 329.101196 -283.559758) (xy 328.901044 -283.559758) (xy 328.901044 -283.604208)
			(xy 329.00112 -283.704284)
		)
		(stroke
			(width 0)
			(type solid)
		)
		(fill yes)
		(layer "In4.Cu")
		(net "M_D_CPU0_SB_DQ<15>")
	)
	(gr_poly
		(pts
			(xy 329.101196 -282.388056) (xy 329.00112 -282.28798) (xy 328.901044 -282.388056) (xy 328.901044 -282.432506)
			(xy 329.101196 -282.432506)
		)
		(stroke
			(width 0)
			(type solid)
		)
		(fill yes)
		(layer "In4.Cu")
		(net "M_D_CPU0_SB_DQ<12>")
	)
	(gr_poly
		(pts
			(xy 329.101196 -281.98445) (xy 329.101196 -281.936698) (xy 328.901044 -281.936698) (xy 328.901044 -281.98445)
			(xy 329.00112 -282.084272)
		)
		(stroke
			(width 0)
			(type solid)
		)
		(fill yes)
		(layer "In4.Cu")
		(net "M_D_CPU0_SB_DQS_DP<6>")
	)
	(gr_poly
		(pts
			(xy 329.101196 -280.76779) (xy 329.00112 -280.667968) (xy 328.901044 -280.76779) (xy 328.901044 -280.815542)
			(xy 329.101196 -280.815542)
		)
		(stroke
			(width 0)
			(type solid)
		)
		(fill yes)
		(layer "In4.Cu")
		(net "M_D_CPU0_SB_DQS_DP<1>")
	)
	(gr_poly
		(pts
			(xy 329.101196 -280.364184) (xy 329.101196 -280.319734) (xy 328.901044 -280.319734) (xy 328.901044 -280.364184)
			(xy 329.00112 -280.46426)
		)
		(stroke
			(width 0)
			(type solid)
		)
		(fill yes)
		(layer "In4.Cu")
		(net "M_D_CPU0_SB_DQ<11>")
	)
	(gr_poly
		(pts
			(xy 329.101196 -279.148032) (xy 329.00112 -279.047956) (xy 328.901044 -279.148032) (xy 328.901044 -279.192482)
			(xy 329.101196 -279.192482)
		)
		(stroke
			(width 0)
			(type solid)
		)
		(fill yes)
		(layer "In4.Cu")
		(net "M_D_CPU0_SB_DQ<8>")
	)
	(gr_poly
		(pts
			(xy 329.101196 -278.744172) (xy 329.101196 -278.699722) (xy 328.901044 -278.699722) (xy 328.901044 -278.744172)
			(xy 329.00112 -278.844248)
		)
		(stroke
			(width 0)
			(type solid)
		)
		(fill yes)
		(layer "In4.Cu")
		(net "M_D_CPU0_SB_DQ<7>")
	)
	(gr_poly
		(pts
			(xy 329.101196 -277.52802) (xy 329.00112 -277.427944) (xy 328.901044 -277.52802) (xy 328.901044 -277.57247)
			(xy 329.101196 -277.57247)
		)
		(stroke
			(width 0)
			(type solid)
		)
		(fill yes)
		(layer "In4.Cu")
		(net "M_D_CPU0_SB_DQ<4>")
	)
	(gr_poly
		(pts
			(xy 329.101196 -277.12416) (xy 329.101196 -277.076662) (xy 328.901044 -277.076662) (xy 328.901044 -277.12416)
			(xy 329.00112 -277.224236)
		)
		(stroke
			(width 0)
			(type solid)
		)
		(fill yes)
		(layer "In4.Cu")
		(net "M_D_CPU0_SB_DQS_DP<5>")
	)
	(gr_poly
		(pts
			(xy 329.101196 -275.908008) (xy 329.00112 -275.807932) (xy 328.901044 -275.908008) (xy 328.901044 -275.955506)
			(xy 329.101196 -275.955506)
		)
		(stroke
			(width 0)
			(type solid)
		)
		(fill yes)
		(layer "In4.Cu")
		(net "M_D_CPU0_SB_DQS_DP<0>")
	)
	(gr_poly
		(pts
			(xy 329.101196 -275.504148) (xy 329.101196 -275.459698) (xy 328.901044 -275.459698) (xy 328.901044 -275.504148)
			(xy 329.00112 -275.604224)
		)
		(stroke
			(width 0)
			(type solid)
		)
		(fill yes)
		(layer "In4.Cu")
		(net "M_D_CPU0_SB_DQ<3>")
	)
	(gr_poly
		(pts
			(xy 329.101196 -274.287996) (xy 329.00112 -274.18792) (xy 328.901044 -274.287996) (xy 328.901044 -274.332446)
			(xy 329.101196 -274.332446)
		)
		(stroke
			(width 0)
			(type solid)
		)
		(fill yes)
		(layer "In4.Cu")
		(net "M_D_CPU0_SB_DQ<0>")
	)
	(gr_poly
		(pts
			(xy 329.101196 -273.884136) (xy 329.101196 -273.839686) (xy 328.901044 -273.839686) (xy 328.901044 -273.884136)
			(xy 329.00112 -273.984212)
		)
		(stroke
			(width 0)
			(type solid)
		)
		(fill yes)
		(layer "In4.Cu")
		(net "M_D_CPU0_SB_CB<3>")
	)
	(gr_poly
		(pts
			(xy 329.101196 -272.667984) (xy 329.00112 -272.567908) (xy 328.901044 -272.667984) (xy 328.901044 -272.712434)
			(xy 329.101196 -272.712434)
		)
		(stroke
			(width 0)
			(type solid)
		)
		(fill yes)
		(layer "In4.Cu")
		(net "M_D_CPU0_SB_CB<0>")
	)
	(gr_poly
		(pts
			(xy 329.101196 -272.264378) (xy 329.101196 -272.216626) (xy 328.901044 -272.216626) (xy 328.901044 -272.264378)
			(xy 329.00112 -272.3642)
		)
		(stroke
			(width 0)
			(type solid)
		)
		(fill yes)
		(layer "In4.Cu")
		(net "M_D_CPU0_SB_DQS_DP<4>")
	)
	(gr_poly
		(pts
			(xy 329.101196 -271.047718) (xy 329.00112 -270.947896) (xy 328.901044 -271.047718) (xy 328.901044 -271.09547)
			(xy 329.101196 -271.09547)
		)
		(stroke
			(width 0)
			(type solid)
		)
		(fill yes)
		(layer "In4.Cu")
		(net "M_D_CPU0_SB_DQS_DP<9>")
	)
	(gr_poly
		(pts
			(xy 329.101196 -270.644112) (xy 329.101196 -270.599662) (xy 328.901044 -270.599662) (xy 328.901044 -270.644112)
			(xy 329.00112 -270.744188)
		)
		(stroke
			(width 0)
			(type solid)
		)
		(fill yes)
		(layer "In4.Cu")
		(net "M_D_CPU0_SB_CB<7>")
	)
	(gr_poly
		(pts
			(xy 329.101196 -269.42796) (xy 329.00112 -269.327884) (xy 328.901044 -269.42796) (xy 328.901044 -269.47241)
			(xy 329.101196 -269.47241)
		)
		(stroke
			(width 0)
			(type solid)
		)
		(fill yes)
		(layer "In4.Cu")
		(net "M_D_CPU0_SB_CB<4>")
	)
	(gr_poly
		(pts
			(xy 329.101196 -267.801598) (xy 329.00112 -267.701522) (xy 328.901044 -267.801598) (xy 328.901044 -267.846048)
			(xy 329.101196 -267.846048)
		)
		(stroke
			(width 0)
			(type solid)
		)
		(fill yes)
		(layer "In4.Cu")
		(net "M_D_CPU0_SB_RSP<0>")
	)
	(gr_poly
		(pts
			(xy 329.101196 -265.784076) (xy 329.101196 -265.739626) (xy 328.901044 -265.739626) (xy 328.901044 -265.784076)
			(xy 329.00112 -265.884152)
		)
		(stroke
			(width 0)
			(type solid)
		)
		(fill yes)
		(layer "In4.Cu")
		(net "M_D_CPU0_SB_CS_N<0>")
	)
	(gr_poly
		(pts
			(xy 329.101196 -264.567924) (xy 329.00112 -264.467848) (xy 328.901044 -264.567924) (xy 328.901044 -264.612374)
			(xy 329.101196 -264.612374)
		)
		(stroke
			(width 0)
			(type solid)
		)
		(fill yes)
		(layer "In4.Cu")
		(net "M_D_CPU0_SB_CA<6>")
	)
	(gr_poly
		(pts
			(xy 329.101196 -264.164064) (xy 329.101196 -264.119614) (xy 328.901044 -264.119614) (xy 328.901044 -264.164064)
			(xy 329.00112 -264.26414)
		)
		(stroke
			(width 0)
			(type solid)
		)
		(fill yes)
		(layer "In4.Cu")
		(net "M_D_CPU0_SB_CA<5>")
	)
	(gr_poly
		(pts
			(xy 329.101196 -262.947912) (xy 329.00112 -262.847836) (xy 328.901044 -262.947912) (xy 328.901044 -262.992362)
			(xy 329.101196 -262.992362)
		)
		(stroke
			(width 0)
			(type solid)
		)
		(fill yes)
		(layer "In4.Cu")
		(net "M_D_CPU0_SB_CA<2>")
	)
	(gr_poly
		(pts
			(xy 329.101196 -262.544052) (xy 329.101196 -262.499602) (xy 328.901044 -262.499602) (xy 328.901044 -262.544052)
			(xy 329.00112 -262.644128)
		)
		(stroke
			(width 0)
			(type solid)
		)
		(fill yes)
		(layer "In4.Cu")
		(net "M_D_CPU0_SB_CA<1>")
	)
	(gr_poly
		(pts
			(xy 329.156822 -295.480486) (xy 329.120246 -295.343834) (xy 329.081892 -295.321482) (xy 328.981816 -295.49471)
			(xy 329.020424 -295.517062)
		)
		(stroke
			(width 0)
			(type solid)
		)
		(fill yes)
		(layer "In4.Cu")
		(net "M_D_CPU0_SB_DQ<31>")
	)
	(gr_poly
		(pts
			(xy 329.19035 -228.63302) (xy 329.090274 -228.459792) (xy 329.05192 -228.482144) (xy 329.01509 -228.618796)
			(xy 329.151742 -228.655372)
		)
		(stroke
			(width 0)
			(type solid)
		)
		(fill yes)
		(layer "In4.Cu")
		(net "M_D_CPU0_SA_DQ<6>")
	)
	(gr_poly
		(pts
			(xy 329.19035 -223.772984) (xy 329.090274 -223.599756) (xy 329.05192 -223.622108) (xy 329.01509 -223.75876)
			(xy 329.151742 -223.795336)
		)
		(stroke
			(width 0)
			(type solid)
		)
		(fill yes)
		(layer "In4.Cu")
		(net "M_D_CPU0_SA_DQ<3>")
	)
	(gr_poly
		(pts
			(xy 329.193144 -227.012246) (xy 329.093322 -226.839018) (xy 329.05192 -226.862894) (xy 329.015344 -226.999292)
			(xy 329.151996 -227.035868)
		)
		(stroke
			(width 0)
			(type solid)
		)
		(fill yes)
		(layer "In4.Cu")
		(net "M_D_CPU0_SA_DQS_DP<5>")
	)
	(gr_poly
		(pts
			(xy 329.193144 -225.392234) (xy 329.093322 -225.219006) (xy 329.05192 -225.242882) (xy 329.015344 -225.37928)
			(xy 329.151996 -225.415856)
		)
		(stroke
			(width 0)
			(type solid)
		)
		(fill yes)
		(layer "In4.Cu")
		(net "M_D_CPU0_SA_DQS_DN<0>")
	)
	(gr_poly
		(pts
			(xy 329.271122 -256.025904) (xy 329.171046 -255.926082) (xy 329.07097 -256.025904) (xy 329.07097 -256.073656)
			(xy 329.271122 -256.073656)
		)
		(stroke
			(width 0)
			(type solid)
		)
		(fill yes)
		(layer "In4.Cu")
		(net "M_D_CPU0_CLK_DP<0>")
	)
	(gr_poly
		(pts
			(xy 329.271122 -255.622298) (xy 329.271122 -255.577848) (xy 329.07097 -255.577848) (xy 329.07097 -255.622298)
			(xy 329.171046 -255.722374)
		)
		(stroke
			(width 0)
			(type solid)
		)
		(fill yes)
		(layer "In4.Cu")
		(net "M_D_CPU0_SA_PAR")
	)
	(gr_poly
		(pts
			(xy 329.271122 -254.406146) (xy 329.171046 -254.30607) (xy 329.07097 -254.406146) (xy 329.07097 -254.450596)
			(xy 329.271122 -254.450596)
		)
		(stroke
			(width 0)
			(type solid)
		)
		(fill yes)
		(layer "In4.Cu")
		(net "M_D_CPU0_SA_CA<4>")
	)
	(gr_poly
		(pts
			(xy 329.271122 -254.002286) (xy 329.271122 -253.957836) (xy 329.07097 -253.957836) (xy 329.07097 -254.002286)
			(xy 329.171046 -254.102362)
		)
		(stroke
			(width 0)
			(type solid)
		)
		(fill yes)
		(layer "In4.Cu")
		(net "M_D_CPU0_SA_CA<3>")
	)
	(gr_poly
		(pts
			(xy 329.271122 -252.786134) (xy 329.171046 -252.686058) (xy 329.07097 -252.786134) (xy 329.07097 -252.830584)
			(xy 329.271122 -252.830584)
		)
		(stroke
			(width 0)
			(type solid)
		)
		(fill yes)
		(layer "In4.Cu")
		(net "M_D_CPU0_SA_CA<0>")
	)
	(gr_poly
		(pts
			(xy 329.271122 -252.382274) (xy 329.271122 -252.337824) (xy 329.07097 -252.337824) (xy 329.07097 -252.382274)
			(xy 329.171046 -252.48235)
		)
		(stroke
			(width 0)
			(type solid)
		)
		(fill yes)
		(layer "In4.Cu")
		(net "M_D_CPU0_SA_CS_N<1>")
	)
	(gr_poly
		(pts
			(xy 329.271122 -250.762262) (xy 329.271122 -250.717812) (xy 329.07097 -250.717812) (xy 329.07097 -250.762262)
			(xy 329.171046 -250.862338)
		)
		(stroke
			(width 0)
			(type solid)
		)
		(fill yes)
		(layer "In4.Cu")
		(net "M_D_CPU0_RESET_N")
	)
	(gr_poly
		(pts
			(xy 329.271122 -249.14225) (xy 329.271122 -249.0978) (xy 329.07097 -249.0978) (xy 329.07097 -249.14225)
			(xy 329.171046 -249.242326)
		)
		(stroke
			(width 0)
			(type solid)
		)
		(fill yes)
		(layer "In4.Cu")
		(net "M_D_CPU0_SA_CB<7>")
	)
	(gr_poly
		(pts
			(xy 329.271122 -247.926098) (xy 329.171046 -247.826022) (xy 329.07097 -247.926098) (xy 329.07097 -247.970548)
			(xy 329.271122 -247.970548)
		)
		(stroke
			(width 0)
			(type solid)
		)
		(fill yes)
		(layer "In4.Cu")
		(net "M_D_CPU0_SA_CB<4>")
	)
	(gr_poly
		(pts
			(xy 329.271122 -247.522492) (xy 329.271122 -247.47474) (xy 329.07097 -247.47474) (xy 329.07097 -247.522492)
			(xy 329.171046 -247.622314)
		)
		(stroke
			(width 0)
			(type solid)
		)
		(fill yes)
		(layer "In4.Cu")
		(net "M_D_CPU0_SA_DQS_DP<9>")
	)
	(gr_poly
		(pts
			(xy 329.271122 -246.305832) (xy 329.171046 -246.20601) (xy 329.07097 -246.305832) (xy 329.07097 -246.353584)
			(xy 329.271122 -246.353584)
		)
		(stroke
			(width 0)
			(type solid)
		)
		(fill yes)
		(layer "In4.Cu")
		(net "M_D_CPU0_SA_DQS_DP<4>")
	)
	(gr_poly
		(pts
			(xy 329.271122 -245.902226) (xy 329.271122 -245.857776) (xy 329.07097 -245.857776) (xy 329.07097 -245.902226)
			(xy 329.171046 -246.002302)
		)
		(stroke
			(width 0)
			(type solid)
		)
		(fill yes)
		(layer "In4.Cu")
		(net "M_D_CPU0_SA_CB<3>")
	)
	(gr_poly
		(pts
			(xy 329.271122 -244.686074) (xy 329.171046 -244.585998) (xy 329.07097 -244.686074) (xy 329.07097 -244.730524)
			(xy 329.271122 -244.730524)
		)
		(stroke
			(width 0)
			(type solid)
		)
		(fill yes)
		(layer "In4.Cu")
		(net "M_D_CPU0_SA_CB<0>")
	)
	(gr_poly
		(pts
			(xy 329.271122 -244.282214) (xy 329.271122 -244.237764) (xy 329.07097 -244.237764) (xy 329.07097 -244.282214)
			(xy 329.171046 -244.38229)
		)
		(stroke
			(width 0)
			(type solid)
		)
		(fill yes)
		(layer "In4.Cu")
		(net "M_D_CPU0_SA_DQ<31>")
	)
	(gr_poly
		(pts
			(xy 329.271122 -243.066062) (xy 329.171046 -242.965986) (xy 329.07097 -243.066062) (xy 329.07097 -243.110512)
			(xy 329.271122 -243.110512)
		)
		(stroke
			(width 0)
			(type solid)
		)
		(fill yes)
		(layer "In4.Cu")
		(net "M_D_CPU0_SA_DQ<28>")
	)
	(gr_poly
		(pts
			(xy 329.271122 -242.662456) (xy 329.271122 -242.614704) (xy 329.07097 -242.614704) (xy 329.07097 -242.662456)
			(xy 329.171046 -242.762278)
		)
		(stroke
			(width 0)
			(type solid)
		)
		(fill yes)
		(layer "In4.Cu")
		(net "M_D_CPU0_SA_DQS_DP<8>")
	)
	(gr_poly
		(pts
			(xy 329.271122 -241.445796) (xy 329.171046 -241.345974) (xy 329.07097 -241.445796) (xy 329.07097 -241.493548)
			(xy 329.271122 -241.493548)
		)
		(stroke
			(width 0)
			(type solid)
		)
		(fill yes)
		(layer "In4.Cu")
		(net "M_D_CPU0_SA_DQS_DP<3>")
	)
	(gr_poly
		(pts
			(xy 329.271122 -241.04219) (xy 329.271122 -240.99774) (xy 329.07097 -240.99774) (xy 329.07097 -241.04219)
			(xy 329.171046 -241.142266)
		)
		(stroke
			(width 0)
			(type solid)
		)
		(fill yes)
		(layer "In4.Cu")
		(net "M_D_CPU0_SA_DQ<27>")
	)
	(gr_poly
		(pts
			(xy 329.271122 -239.826038) (xy 329.171046 -239.725962) (xy 329.07097 -239.826038) (xy 329.07097 -239.870488)
			(xy 329.271122 -239.870488)
		)
		(stroke
			(width 0)
			(type solid)
		)
		(fill yes)
		(layer "In4.Cu")
		(net "M_D_CPU0_SA_DQ<24>")
	)
	(gr_poly
		(pts
			(xy 329.271122 -239.422178) (xy 329.271122 -239.377728) (xy 329.07097 -239.377728) (xy 329.07097 -239.422178)
			(xy 329.171046 -239.522254)
		)
		(stroke
			(width 0)
			(type solid)
		)
		(fill yes)
		(layer "In4.Cu")
		(net "M_D_CPU0_SA_DQ<23>")
	)
	(gr_poly
		(pts
			(xy 329.271122 -238.206026) (xy 329.171046 -238.10595) (xy 329.07097 -238.206026) (xy 329.07097 -238.250476)
			(xy 329.271122 -238.250476)
		)
		(stroke
			(width 0)
			(type solid)
		)
		(fill yes)
		(layer "In4.Cu")
		(net "M_D_CPU0_SA_DQ<20>")
	)
	(gr_poly
		(pts
			(xy 329.271122 -237.80242) (xy 329.271122 -237.754668) (xy 329.07097 -237.754668) (xy 329.07097 -237.80242)
			(xy 329.171046 -237.902242)
		)
		(stroke
			(width 0)
			(type solid)
		)
		(fill yes)
		(layer "In4.Cu")
		(net "M_D_CPU0_SA_DQS_DP<7>")
	)
	(gr_poly
		(pts
			(xy 329.271122 -236.58576) (xy 329.171046 -236.485938) (xy 329.07097 -236.58576) (xy 329.07097 -236.633512)
			(xy 329.271122 -236.633512)
		)
		(stroke
			(width 0)
			(type solid)
		)
		(fill yes)
		(layer "In4.Cu")
		(net "M_D_CPU0_SA_DQS_DP<2>")
	)
	(gr_poly
		(pts
			(xy 329.271122 -236.182154) (xy 329.271122 -236.137704) (xy 329.07097 -236.137704) (xy 329.07097 -236.182154)
			(xy 329.171046 -236.28223)
		)
		(stroke
			(width 0)
			(type solid)
		)
		(fill yes)
		(layer "In4.Cu")
		(net "M_D_CPU0_SA_DQ<19>")
	)
	(gr_poly
		(pts
			(xy 329.271122 -234.966002) (xy 329.171046 -234.865926) (xy 329.07097 -234.966002) (xy 329.07097 -235.010452)
			(xy 329.271122 -235.010452)
		)
		(stroke
			(width 0)
			(type solid)
		)
		(fill yes)
		(layer "In4.Cu")
		(net "M_D_CPU0_SA_DQ<16>")
	)
	(gr_poly
		(pts
			(xy 329.271122 -234.562142) (xy 329.271122 -234.517692) (xy 329.07097 -234.517692) (xy 329.07097 -234.562142)
			(xy 329.171046 -234.662218)
		)
		(stroke
			(width 0)
			(type solid)
		)
		(fill yes)
		(layer "In4.Cu")
		(net "M_D_CPU0_SA_DQ<15>")
	)
	(gr_poly
		(pts
			(xy 329.271122 -233.34599) (xy 329.171046 -233.245914) (xy 329.07097 -233.34599) (xy 329.07097 -233.39044)
			(xy 329.271122 -233.39044)
		)
		(stroke
			(width 0)
			(type solid)
		)
		(fill yes)
		(layer "In4.Cu")
		(net "M_D_CPU0_SA_DQ<12>")
	)
	(gr_poly
		(pts
			(xy 329.271122 -232.942384) (xy 329.271122 -232.894632) (xy 329.07097 -232.894632) (xy 329.07097 -232.942384)
			(xy 329.171046 -233.042206)
		)
		(stroke
			(width 0)
			(type solid)
		)
		(fill yes)
		(layer "In4.Cu")
		(net "M_D_CPU0_SA_DQS_DP<6>")
	)
	(gr_poly
		(pts
			(xy 329.271122 -231.725724) (xy 329.171046 -231.625902) (xy 329.07097 -231.725724) (xy 329.07097 -231.773476)
			(xy 329.271122 -231.773476)
		)
		(stroke
			(width 0)
			(type solid)
		)
		(fill yes)
		(layer "In4.Cu")
		(net "M_D_CPU0_SA_DQS_DP<1>")
	)
	(gr_poly
		(pts
			(xy 329.271122 -231.322372) (xy 329.271122 -231.277922) (xy 329.07097 -231.277922) (xy 329.07097 -231.322372)
			(xy 329.171046 -231.422448)
		)
		(stroke
			(width 0)
			(type solid)
		)
		(fill yes)
		(layer "In4.Cu")
		(net "M_D_CPU0_SA_DQ<11>")
	)
	(gr_poly
		(pts
			(xy 329.271122 -230.105966) (xy 329.171046 -230.006144) (xy 329.07097 -230.105966) (xy 329.07097 -230.150416)
			(xy 329.271122 -230.150416)
		)
		(stroke
			(width 0)
			(type solid)
		)
		(fill yes)
		(layer "In4.Cu")
		(net "M_D_CPU0_SA_DQ<8>")
	)
	(gr_poly
		(pts
			(xy 329.271122 -229.70236) (xy 329.271122 -229.65791) (xy 329.07097 -229.65791) (xy 329.07097 -229.70236)
			(xy 329.171046 -229.802436)
		)
		(stroke
			(width 0)
			(type solid)
		)
		(fill yes)
		(layer "In4.Cu")
		(net "M_D_CPU0_SA_DQ<7>")
	)
	(gr_poly
		(pts
			(xy 329.290426 -228.086412) (xy 329.327002 -227.94976) (xy 329.190604 -227.913184) (xy 329.151996 -227.935536)
			(xy 329.252072 -228.108764)
		)
		(stroke
			(width 0)
			(type solid)
		)
		(fill yes)
		(layer "In4.Cu")
		(net "M_D_CPU0_SA_DQ<4>")
	)
	(gr_poly
		(pts
			(xy 329.290426 -226.4664) (xy 329.327002 -226.330002) (xy 329.19035 -226.293426) (xy 329.149202 -226.317048)
			(xy 329.249024 -226.490276)
		)
		(stroke
			(width 0)
			(type solid)
		)
		(fill yes)
		(layer "In4.Cu")
		(net "M_D_CPU0_SA_DQS_DN<5>")
	)
	(gr_poly
		(pts
			(xy 329.290426 -224.845626) (xy 329.327002 -224.709228) (xy 329.19035 -224.672652) (xy 329.149202 -224.696274)
			(xy 329.249024 -224.869502)
		)
		(stroke
			(width 0)
			(type solid)
		)
		(fill yes)
		(layer "In4.Cu")
		(net "M_D_CPU0_SA_DQS_DP<0>")
	)
	(gr_poly
		(pts
			(xy 329.290426 -223.226376) (xy 329.327002 -223.089724) (xy 329.190604 -223.053148) (xy 329.151996 -223.0755)
			(xy 329.252072 -223.248728)
		)
		(stroke
			(width 0)
			(type solid)
		)
		(fill yes)
		(layer "In4.Cu")
		(net "M_D_CPU0_SA_DQ<1>")
	)
	(gr_poly
		(pts
			(xy 329.571096 -292.51402) (xy 329.571096 -292.46957) (xy 329.370944 -292.46957) (xy 329.370944 -292.51402)
			(xy 329.47102 -292.614096)
		)
		(stroke
			(width 0)
			(type solid)
		)
		(fill yes)
		(layer "In4.Cu")
		(net "M_D_CPU0_SB_DQ<30>")
	)
	(gr_poly
		(pts
			(xy 329.571096 -291.297614) (xy 329.47102 -291.197792) (xy 329.370944 -291.297614) (xy 329.370944 -291.345366)
			(xy 329.571096 -291.345366)
		)
		(stroke
			(width 0)
			(type solid)
		)
		(fill yes)
		(layer "In4.Cu")
		(net "M_D_CPU0_SB_DQS_DN<8>")
	)
	(gr_poly
		(pts
			(xy 329.571096 -290.894262) (xy 329.571096 -290.84651) (xy 329.370944 -290.84651) (xy 329.370944 -290.894262)
			(xy 329.47102 -290.994084)
		)
		(stroke
			(width 0)
			(type solid)
		)
		(fill yes)
		(layer "In4.Cu")
		(net "M_D_CPU0_SB_DQS_DN<3>")
	)
	(gr_poly
		(pts
			(xy 329.571096 -289.677856) (xy 329.47102 -289.57778) (xy 329.370944 -289.677856) (xy 329.370944 -289.722306)
			(xy 329.571096 -289.722306)
		)
		(stroke
			(width 0)
			(type solid)
		)
		(fill yes)
		(layer "In4.Cu")
		(net "M_D_CPU0_SB_DQ<25>")
	)
	(gr_poly
		(pts
			(xy 329.571096 -289.273996) (xy 329.571096 -289.229546) (xy 329.370944 -289.229546) (xy 329.370944 -289.273996)
			(xy 329.47102 -289.374072)
		)
		(stroke
			(width 0)
			(type solid)
		)
		(fill yes)
		(layer "In4.Cu")
		(net "M_D_CPU0_SB_DQ<26>")
	)
	(gr_poly
		(pts
			(xy 329.571096 -288.057844) (xy 329.47102 -287.957768) (xy 329.370944 -288.057844) (xy 329.370944 -288.102294)
			(xy 329.571096 -288.102294)
		)
		(stroke
			(width 0)
			(type solid)
		)
		(fill yes)
		(layer "In4.Cu")
		(net "M_D_CPU0_SB_DQ<21>")
	)
	(gr_poly
		(pts
			(xy 329.571096 -287.654238) (xy 329.571096 -287.609788) (xy 329.370944 -287.609788) (xy 329.370944 -287.654238)
			(xy 329.47102 -287.75406)
		)
		(stroke
			(width 0)
			(type solid)
		)
		(fill yes)
		(layer "In4.Cu")
		(net "M_D_CPU0_SB_DQ<22>")
	)
	(gr_poly
		(pts
			(xy 329.571096 -286.437832) (xy 329.47102 -286.337756) (xy 329.370944 -286.437832) (xy 329.370944 -286.485584)
			(xy 329.571096 -286.485584)
		)
		(stroke
			(width 0)
			(type solid)
		)
		(fill yes)
		(layer "In4.Cu")
		(net "M_D_CPU0_SB_DQS_DN<7>")
	)
	(gr_poly
		(pts
			(xy 329.571096 -286.03448) (xy 329.571096 -285.986728) (xy 329.370944 -285.986728) (xy 329.370944 -286.03448)
			(xy 329.47102 -286.134302)
		)
		(stroke
			(width 0)
			(type solid)
		)
		(fill yes)
		(layer "In4.Cu")
		(net "M_D_CPU0_SB_DQS_DN<2>")
	)
	(gr_poly
		(pts
			(xy 329.571096 -284.818074) (xy 329.47102 -284.717998) (xy 329.370944 -284.818074) (xy 329.370944 -284.862524)
			(xy 329.571096 -284.862524)
		)
		(stroke
			(width 0)
			(type solid)
		)
		(fill yes)
		(layer "In4.Cu")
		(net "M_D_CPU0_SB_DQ<17>")
	)
	(gr_poly
		(pts
			(xy 329.571096 -284.414214) (xy 329.571096 -284.369764) (xy 329.370944 -284.369764) (xy 329.370944 -284.414214)
			(xy 329.47102 -284.51429)
		)
		(stroke
			(width 0)
			(type solid)
		)
		(fill yes)
		(layer "In4.Cu")
		(net "M_D_CPU0_SB_DQ<18>")
	)
	(gr_poly
		(pts
			(xy 329.571096 -283.198062) (xy 329.47102 -283.097986) (xy 329.370944 -283.198062) (xy 329.370944 -283.242512)
			(xy 329.571096 -283.242512)
		)
		(stroke
			(width 0)
			(type solid)
		)
		(fill yes)
		(layer "In4.Cu")
		(net "M_D_CPU0_SB_DQ<13>")
	)
	(gr_poly
		(pts
			(xy 329.571096 -282.794202) (xy 329.571096 -282.749752) (xy 329.370944 -282.749752) (xy 329.370944 -282.794202)
			(xy 329.47102 -282.894278)
		)
		(stroke
			(width 0)
			(type solid)
		)
		(fill yes)
		(layer "In4.Cu")
		(net "M_D_CPU0_SB_DQ<14>")
	)
	(gr_poly
		(pts
			(xy 329.571096 -281.577796) (xy 329.47102 -281.477974) (xy 329.370944 -281.577796) (xy 329.370944 -281.625548)
			(xy 329.571096 -281.625548)
		)
		(stroke
			(width 0)
			(type solid)
		)
		(fill yes)
		(layer "In4.Cu")
		(net "M_D_CPU0_SB_DQS_DN<6>")
	)
	(gr_poly
		(pts
			(xy 329.571096 -281.174444) (xy 329.571096 -281.126692) (xy 329.370944 -281.126692) (xy 329.370944 -281.174444)
			(xy 329.47102 -281.274266)
		)
		(stroke
			(width 0)
			(type solid)
		)
		(fill yes)
		(layer "In4.Cu")
		(net "M_D_CPU0_SB_DQS_DN<1>")
	)
	(gr_poly
		(pts
			(xy 329.571096 -279.958038) (xy 329.47102 -279.857962) (xy 329.370944 -279.958038) (xy 329.370944 -280.002488)
			(xy 329.571096 -280.002488)
		)
		(stroke
			(width 0)
			(type solid)
		)
		(fill yes)
		(layer "In4.Cu")
		(net "M_D_CPU0_SB_DQ<9>")
	)
	(gr_poly
		(pts
			(xy 329.571096 -279.554178) (xy 329.571096 -279.509728) (xy 329.370944 -279.509728) (xy 329.370944 -279.554178)
			(xy 329.47102 -279.654254)
		)
		(stroke
			(width 0)
			(type solid)
		)
		(fill yes)
		(layer "In4.Cu")
		(net "M_D_CPU0_SB_DQ<10>")
	)
	(gr_poly
		(pts
			(xy 329.571096 -278.338026) (xy 329.47102 -278.23795) (xy 329.370944 -278.338026) (xy 329.370944 -278.382476)
			(xy 329.571096 -278.382476)
		)
		(stroke
			(width 0)
			(type solid)
		)
		(fill yes)
		(layer "In4.Cu")
		(net "M_D_CPU0_SB_DQ<5>")
	)
	(gr_poly
		(pts
			(xy 329.571096 -277.934166) (xy 329.571096 -277.889716) (xy 329.370944 -277.889716) (xy 329.370944 -277.934166)
			(xy 329.47102 -278.034242)
		)
		(stroke
			(width 0)
			(type solid)
		)
		(fill yes)
		(layer "In4.Cu")
		(net "M_D_CPU0_SB_DQ<6>")
	)
	(gr_poly
		(pts
			(xy 329.571096 -275.098002) (xy 329.47102 -274.997926) (xy 329.370944 -275.098002) (xy 329.370944 -275.142452)
			(xy 329.571096 -275.142452)
		)
		(stroke
			(width 0)
			(type solid)
		)
		(fill yes)
		(layer "In4.Cu")
		(net "M_D_CPU0_SB_DQ<1>")
	)
	(gr_poly
		(pts
			(xy 329.571096 -274.694142) (xy 329.571096 -274.649692) (xy 329.370944 -274.649692) (xy 329.370944 -274.694142)
			(xy 329.47102 -274.794218)
		)
		(stroke
			(width 0)
			(type solid)
		)
		(fill yes)
		(layer "In4.Cu")
		(net "M_D_CPU0_SB_DQ<2>")
	)
	(gr_poly
		(pts
			(xy 329.571096 -273.47799) (xy 329.47102 -273.377914) (xy 329.370944 -273.47799) (xy 329.370944 -273.52244)
			(xy 329.571096 -273.52244)
		)
		(stroke
			(width 0)
			(type solid)
		)
		(fill yes)
		(layer "In4.Cu")
		(net "M_D_CPU0_SB_CB<1>")
	)
	(gr_poly
		(pts
			(xy 329.571096 -273.07413) (xy 329.571096 -273.02968) (xy 329.370944 -273.02968) (xy 329.370944 -273.07413)
			(xy 329.47102 -273.174206)
		)
		(stroke
			(width 0)
			(type solid)
		)
		(fill yes)
		(layer "In4.Cu")
		(net "M_D_CPU0_SB_CB<2>")
	)
	(gr_poly
		(pts
			(xy 329.571096 -271.857724) (xy 329.47102 -271.757902) (xy 329.370944 -271.857724) (xy 329.370944 -271.905476)
			(xy 329.571096 -271.905476)
		)
		(stroke
			(width 0)
			(type solid)
		)
		(fill yes)
		(layer "In4.Cu")
		(net "M_D_CPU0_SB_DQS_DN<4>")
	)
	(gr_poly
		(pts
			(xy 329.571096 -271.454372) (xy 329.571096 -271.40662) (xy 329.370944 -271.40662) (xy 329.370944 -271.454372)
			(xy 329.47102 -271.554194)
		)
		(stroke
			(width 0)
			(type solid)
		)
		(fill yes)
		(layer "In4.Cu")
		(net "M_D_CPU0_SB_DQS_DN<9>")
	)
	(gr_poly
		(pts
			(xy 329.571096 -270.237966) (xy 329.47102 -270.13789) (xy 329.370944 -270.237966) (xy 329.370944 -270.282416)
			(xy 329.571096 -270.282416)
		)
		(stroke
			(width 0)
			(type solid)
		)
		(fill yes)
		(layer "In4.Cu")
		(net "M_D_CPU0_SB_CB<5>")
	)
	(gr_poly
		(pts
			(xy 329.571096 -269.834106) (xy 329.571096 -269.789656) (xy 329.370944 -269.789656) (xy 329.370944 -269.834106)
			(xy 329.47102 -269.934182)
		)
		(stroke
			(width 0)
			(type solid)
		)
		(fill yes)
		(layer "In4.Cu")
		(net "M_D_CPU0_SB_CB<6>")
	)
	(gr_poly
		(pts
			(xy 329.571096 -266.594082) (xy 329.571096 -266.549632) (xy 329.370944 -266.549632) (xy 329.370944 -266.594082)
			(xy 329.47102 -266.694158)
		)
		(stroke
			(width 0)
			(type solid)
		)
		(fill yes)
		(layer "In4.Cu")
		(net "M_D_CPU0_SB_CS_N<1>")
	)
	(gr_poly
		(pts
			(xy 329.571096 -264.97407) (xy 329.571096 -264.92962) (xy 329.370944 -264.92962) (xy 329.370944 -264.97407)
			(xy 329.47102 -265.074146)
		)
		(stroke
			(width 0)
			(type solid)
		)
		(fill yes)
		(layer "In4.Cu")
		(net "M_D_CPU0_SB_PAR")
	)
	(gr_poly
		(pts
			(xy 329.571096 -263.757918) (xy 329.47102 -263.657842) (xy 329.370944 -263.757918) (xy 329.370944 -263.802368)
			(xy 329.571096 -263.802368)
		)
		(stroke
			(width 0)
			(type solid)
		)
		(fill yes)
		(layer "In4.Cu")
		(net "M_D_CPU0_SB_CA<4>")
	)
	(gr_poly
		(pts
			(xy 329.571096 -263.354058) (xy 329.571096 -263.309608) (xy 329.370944 -263.309608) (xy 329.370944 -263.354058)
			(xy 329.47102 -263.454134)
		)
		(stroke
			(width 0)
			(type solid)
		)
		(fill yes)
		(layer "In4.Cu")
		(net "M_D_CPU0_SB_CA<3>")
	)
	(gr_poly
		(pts
			(xy 329.571096 -262.137906) (xy 329.47102 -262.03783) (xy 329.370944 -262.137906) (xy 329.370944 -262.182356)
			(xy 329.571096 -262.182356)
		)
		(stroke
			(width 0)
			(type solid)
		)
		(fill yes)
		(layer "In4.Cu")
		(net "M_D_CPU0_SB_CA<0>")
	)
	(gr_poly
		(pts
			(xy 329.577192 -266.991592) (xy 329.47737 -266.891516) (xy 329.377294 -266.991592) (xy 329.377294 -267.036042)
			(xy 329.577192 -267.036042)
		)
		(stroke
			(width 0)
			(type solid)
		)
		(fill yes)
		(layer "In4.Cu")
		(net "M_D_CPU0_SA_RSP<0>")
	)
	(gr_poly
		(pts
			(xy 329.578462 -276.71776) (xy 329.478386 -276.617938) (xy 329.37831 -276.71776) (xy 329.37831 -276.765512)
			(xy 329.578462 -276.765512)
		)
		(stroke
			(width 0)
			(type solid)
		)
		(fill yes)
		(layer "In4.Cu")
		(net "M_D_CPU0_SB_DQS_DN<5>")
	)
	(gr_poly
		(pts
			(xy 329.578462 -276.314408) (xy 329.578462 -276.266656) (xy 329.37831 -276.266656) (xy 329.37831 -276.314408)
			(xy 329.478386 -276.41423)
		)
		(stroke
			(width 0)
			(type solid)
		)
		(fill yes)
		(layer "In4.Cu")
		(net "M_D_CPU0_SB_DQS_DN<0>")
	)
	(gr_poly
		(pts
			(xy 329.62723 -294.67048) (xy 329.5904 -294.533828) (xy 329.552046 -294.511476) (xy 329.45197 -294.684704)
			(xy 329.490578 -294.707056)
		)
		(stroke
			(width 0)
			(type solid)
		)
		(fill yes)
		(layer "In4.Cu")
		(net "M_D_CPU0_SB_DQ<31>")
	)
	(gr_poly
		(pts
			(xy 329.66025 -224.58299) (xy 329.560174 -224.409762) (xy 329.52182 -224.432114) (xy 329.48499 -224.568766)
			(xy 329.621642 -224.605342)
		)
		(stroke
			(width 0)
			(type solid)
		)
		(fill yes)
		(layer "In4.Cu")
		(net "M_D_CPU0_SA_DQ<3>")
	)
	(gr_poly
		(pts
			(xy 329.66025 -222.962978) (xy 329.560174 -222.78975) (xy 329.52182 -222.812102) (xy 329.48499 -222.948754)
			(xy 329.621642 -222.98533)
		)
		(stroke
			(width 0)
			(type solid)
		)
		(fill yes)
		(layer "In4.Cu")
		(net "M_D_CPU0_SA_DQ<2>")
	)
	(gr_poly
		(pts
			(xy 329.663044 -227.822252) (xy 329.563222 -227.649024) (xy 329.52182 -227.6729) (xy 329.485244 -227.809298)
			(xy 329.621896 -227.846128)
		)
		(stroke
			(width 0)
			(type solid)
		)
		(fill yes)
		(layer "In4.Cu")
		(net "M_D_CPU0_SA_DQS_DP<5>")
	)
	(gr_poly
		(pts
			(xy 329.663044 -226.20224) (xy 329.563222 -226.029012) (xy 329.52182 -226.052888) (xy 329.485244 -226.189286)
			(xy 329.621896 -226.226116)
		)
		(stroke
			(width 0)
			(type solid)
		)
		(fill yes)
		(layer "In4.Cu")
		(net "M_D_CPU0_SA_DQS_DN<0>")
	)
	(gr_poly
		(pts
			(xy 329.741276 -256.432558) (xy 329.741276 -256.384806) (xy 329.541124 -256.384806) (xy 329.541124 -256.432558)
			(xy 329.6412 -256.53238)
		)
		(stroke
			(width 0)
			(type solid)
		)
		(fill yes)
		(layer "In4.Cu")
		(net "M_D_CPU0_CLK_DN<0>")
	)
	(gr_poly
		(pts
			(xy 329.741276 -255.216152) (xy 329.6412 -255.116076) (xy 329.541124 -255.216152) (xy 329.541124 -255.260602)
			(xy 329.741276 -255.260602)
		)
		(stroke
			(width 0)
			(type solid)
		)
		(fill yes)
		(layer "In4.Cu")
		(net "M_D_CPU0_SA_CA<6>")
	)
	(gr_poly
		(pts
			(xy 329.741276 -254.812292) (xy 329.741276 -254.767842) (xy 329.541124 -254.767842) (xy 329.541124 -254.812292)
			(xy 329.6412 -254.912368)
		)
		(stroke
			(width 0)
			(type solid)
		)
		(fill yes)
		(layer "In4.Cu")
		(net "M_D_CPU0_SA_CA<5>")
	)
	(gr_poly
		(pts
			(xy 329.741276 -253.59614) (xy 329.6412 -253.496064) (xy 329.541124 -253.59614) (xy 329.541124 -253.64059)
			(xy 329.741276 -253.64059)
		)
		(stroke
			(width 0)
			(type solid)
		)
		(fill yes)
		(layer "In4.Cu")
		(net "M_D_CPU0_SA_CA<2>")
	)
	(gr_poly
		(pts
			(xy 329.741276 -253.19228) (xy 329.741276 -253.14783) (xy 329.541124 -253.14783) (xy 329.541124 -253.19228)
			(xy 329.6412 -253.292356)
		)
		(stroke
			(width 0)
			(type solid)
		)
		(fill yes)
		(layer "In4.Cu")
		(net "M_D_CPU0_SA_CA<1>")
	)
	(gr_poly
		(pts
			(xy 329.741276 -251.572268) (xy 329.741276 -251.527818) (xy 329.541124 -251.527818) (xy 329.541124 -251.572268)
			(xy 329.6412 -251.672344)
		)
		(stroke
			(width 0)
			(type solid)
		)
		(fill yes)
		(layer "In4.Cu")
		(net "M_D_CPU0_SA_CS_N<0>")
	)
	(gr_poly
		(pts
			(xy 329.741276 -250.356116) (xy 329.6412 -250.25604) (xy 329.541124 -250.356116) (xy 329.541124 -250.400566)
			(xy 329.741276 -250.400566)
		)
		(stroke
			(width 0)
			(type solid)
		)
		(fill yes)
		(layer "In4.Cu")
		(net "M_D_CPU0_ALERT_R_N")
	)
	(gr_poly
		(pts
			(xy 329.741276 -248.736104) (xy 329.6412 -248.636028) (xy 329.541124 -248.736104) (xy 329.541124 -248.780554)
			(xy 329.741276 -248.780554)
		)
		(stroke
			(width 0)
			(type solid)
		)
		(fill yes)
		(layer "In4.Cu")
		(net "M_D_CPU0_SA_CB<5>")
	)
	(gr_poly
		(pts
			(xy 329.741276 -248.332244) (xy 329.741276 -248.287794) (xy 329.541124 -248.287794) (xy 329.541124 -248.332244)
			(xy 329.6412 -248.43232)
		)
		(stroke
			(width 0)
			(type solid)
		)
		(fill yes)
		(layer "In4.Cu")
		(net "M_D_CPU0_SA_CB<6>")
	)
	(gr_poly
		(pts
			(xy 329.741276 -247.115838) (xy 329.6412 -247.016016) (xy 329.541124 -247.115838) (xy 329.541124 -247.16359)
			(xy 329.741276 -247.16359)
		)
		(stroke
			(width 0)
			(type solid)
		)
		(fill yes)
		(layer "In4.Cu")
		(net "M_D_CPU0_SA_DQS_DN<9>")
	)
	(gr_poly
		(pts
			(xy 329.741276 -246.712486) (xy 329.741276 -246.664734) (xy 329.541124 -246.664734) (xy 329.541124 -246.712486)
			(xy 329.6412 -246.812308)
		)
		(stroke
			(width 0)
			(type solid)
		)
		(fill yes)
		(layer "In4.Cu")
		(net "M_D_CPU0_SA_DQS_DN<4>")
	)
	(gr_poly
		(pts
			(xy 329.741276 -245.49608) (xy 329.6412 -245.396004) (xy 329.541124 -245.49608) (xy 329.541124 -245.54053)
			(xy 329.741276 -245.54053)
		)
		(stroke
			(width 0)
			(type solid)
		)
		(fill yes)
		(layer "In4.Cu")
		(net "M_D_CPU0_SA_CB<1>")
	)
	(gr_poly
		(pts
			(xy 329.741276 -245.09222) (xy 329.741276 -245.04777) (xy 329.541124 -245.04777) (xy 329.541124 -245.09222)
			(xy 329.6412 -245.192296)
		)
		(stroke
			(width 0)
			(type solid)
		)
		(fill yes)
		(layer "In4.Cu")
		(net "M_D_CPU0_SA_CB<2>")
	)
	(gr_poly
		(pts
			(xy 329.741276 -243.876068) (xy 329.6412 -243.775992) (xy 329.541124 -243.876068) (xy 329.541124 -243.920518)
			(xy 329.741276 -243.920518)
		)
		(stroke
			(width 0)
			(type solid)
		)
		(fill yes)
		(layer "In4.Cu")
		(net "M_D_CPU0_SA_DQ<29>")
	)
	(gr_poly
		(pts
			(xy 329.741276 -243.472208) (xy 329.741276 -243.427758) (xy 329.541124 -243.427758) (xy 329.541124 -243.472208)
			(xy 329.6412 -243.572284)
		)
		(stroke
			(width 0)
			(type solid)
		)
		(fill yes)
		(layer "In4.Cu")
		(net "M_D_CPU0_SA_DQ<30>")
	)
	(gr_poly
		(pts
			(xy 329.741276 -242.255802) (xy 329.6412 -242.15598) (xy 329.541124 -242.255802) (xy 329.541124 -242.303554)
			(xy 329.741276 -242.303554)
		)
		(stroke
			(width 0)
			(type solid)
		)
		(fill yes)
		(layer "In4.Cu")
		(net "M_D_CPU0_SA_DQS_DN<8>")
	)
	(gr_poly
		(pts
			(xy 329.741276 -241.85245) (xy 329.741276 -241.804698) (xy 329.541124 -241.804698) (xy 329.541124 -241.85245)
			(xy 329.6412 -241.952272)
		)
		(stroke
			(width 0)
			(type solid)
		)
		(fill yes)
		(layer "In4.Cu")
		(net "M_D_CPU0_SA_DQS_DN<3>")
	)
	(gr_poly
		(pts
			(xy 329.741276 -240.636044) (xy 329.6412 -240.535968) (xy 329.541124 -240.636044) (xy 329.541124 -240.680494)
			(xy 329.741276 -240.680494)
		)
		(stroke
			(width 0)
			(type solid)
		)
		(fill yes)
		(layer "In4.Cu")
		(net "M_D_CPU0_SA_DQ<25>")
	)
	(gr_poly
		(pts
			(xy 329.741276 -240.232184) (xy 329.741276 -240.187734) (xy 329.541124 -240.187734) (xy 329.541124 -240.232184)
			(xy 329.6412 -240.33226)
		)
		(stroke
			(width 0)
			(type solid)
		)
		(fill yes)
		(layer "In4.Cu")
		(net "M_D_CPU0_SA_DQ<26>")
	)
	(gr_poly
		(pts
			(xy 329.741276 -239.016032) (xy 329.6412 -238.915956) (xy 329.541124 -239.016032) (xy 329.541124 -239.060482)
			(xy 329.741276 -239.060482)
		)
		(stroke
			(width 0)
			(type solid)
		)
		(fill yes)
		(layer "In4.Cu")
		(net "M_D_CPU0_SA_DQ<21>")
	)
	(gr_poly
		(pts
			(xy 329.741276 -238.612172) (xy 329.741276 -238.567722) (xy 329.541124 -238.567722) (xy 329.541124 -238.612172)
			(xy 329.6412 -238.712248)
		)
		(stroke
			(width 0)
			(type solid)
		)
		(fill yes)
		(layer "In4.Cu")
		(net "M_D_CPU0_SA_DQ<22>")
	)
	(gr_poly
		(pts
			(xy 329.741276 -237.395766) (xy 329.6412 -237.295944) (xy 329.541124 -237.395766) (xy 329.541124 -237.443518)
			(xy 329.741276 -237.443518)
		)
		(stroke
			(width 0)
			(type solid)
		)
		(fill yes)
		(layer "In4.Cu")
		(net "M_D_CPU0_SA_DQS_DN<7>")
	)
	(gr_poly
		(pts
			(xy 329.741276 -236.992414) (xy 329.741276 -236.944662) (xy 329.541124 -236.944662) (xy 329.541124 -236.992414)
			(xy 329.6412 -237.092236)
		)
		(stroke
			(width 0)
			(type solid)
		)
		(fill yes)
		(layer "In4.Cu")
		(net "M_D_CPU0_SA_DQS_DN<2>")
	)
	(gr_poly
		(pts
			(xy 329.741276 -235.776008) (xy 329.6412 -235.675932) (xy 329.541124 -235.776008) (xy 329.541124 -235.820458)
			(xy 329.741276 -235.820458)
		)
		(stroke
			(width 0)
			(type solid)
		)
		(fill yes)
		(layer "In4.Cu")
		(net "M_D_CPU0_SA_DQ<17>")
	)
	(gr_poly
		(pts
			(xy 329.741276 -235.372148) (xy 329.741276 -235.327698) (xy 329.541124 -235.327698) (xy 329.541124 -235.372148)
			(xy 329.6412 -235.472224)
		)
		(stroke
			(width 0)
			(type solid)
		)
		(fill yes)
		(layer "In4.Cu")
		(net "M_D_CPU0_SA_DQ<18>")
	)
	(gr_poly
		(pts
			(xy 329.741276 -234.155996) (xy 329.6412 -234.05592) (xy 329.541124 -234.155996) (xy 329.541124 -234.200446)
			(xy 329.741276 -234.200446)
		)
		(stroke
			(width 0)
			(type solid)
		)
		(fill yes)
		(layer "In4.Cu")
		(net "M_D_CPU0_SA_DQ<13>")
	)
	(gr_poly
		(pts
			(xy 329.741276 -233.752136) (xy 329.741276 -233.707686) (xy 329.541124 -233.707686) (xy 329.541124 -233.752136)
			(xy 329.6412 -233.852212)
		)
		(stroke
			(width 0)
			(type solid)
		)
		(fill yes)
		(layer "In4.Cu")
		(net "M_D_CPU0_SA_DQ<14>")
	)
	(gr_poly
		(pts
			(xy 329.741276 -232.53573) (xy 329.6412 -232.435908) (xy 329.541124 -232.53573) (xy 329.541124 -232.583482)
			(xy 329.741276 -232.583482)
		)
		(stroke
			(width 0)
			(type solid)
		)
		(fill yes)
		(layer "In4.Cu")
		(net "M_D_CPU0_SA_DQS_DN<6>")
	)
	(gr_poly
		(pts
			(xy 329.741276 -232.132378) (xy 329.741276 -232.084626) (xy 329.541124 -232.084626) (xy 329.541124 -232.132378)
			(xy 329.6412 -232.2322)
		)
		(stroke
			(width 0)
			(type solid)
		)
		(fill yes)
		(layer "In4.Cu")
		(net "M_D_CPU0_SA_DQS_DN<1>")
	)
	(gr_poly
		(pts
			(xy 329.741276 -230.915972) (xy 329.6412 -230.815896) (xy 329.541124 -230.915972) (xy 329.541124 -230.960422)
			(xy 329.741276 -230.960422)
		)
		(stroke
			(width 0)
			(type solid)
		)
		(fill yes)
		(layer "In4.Cu")
		(net "M_D_CPU0_SA_DQ<9>")
	)
	(gr_poly
		(pts
			(xy 329.741276 -230.512366) (xy 329.741276 -230.467916) (xy 329.541124 -230.467916) (xy 329.541124 -230.512366)
			(xy 329.6412 -230.612188)
		)
		(stroke
			(width 0)
			(type solid)
		)
		(fill yes)
		(layer "In4.Cu")
		(net "M_D_CPU0_SA_DQ<10>")
	)
	(gr_poly
		(pts
			(xy 329.741276 -229.29596) (xy 329.6412 -229.195884) (xy 329.541124 -229.29596) (xy 329.541124 -229.34041)
			(xy 329.741276 -229.34041)
		)
		(stroke
			(width 0)
			(type solid)
		)
		(fill yes)
		(layer "In4.Cu")
		(net "M_D_CPU0_SA_DQ<5>")
	)
	(gr_poly
		(pts
			(xy 329.741276 -228.892354) (xy 329.741276 -228.847904) (xy 329.541124 -228.847904) (xy 329.541124 -228.892354)
			(xy 329.6412 -228.99243)
		)
		(stroke
			(width 0)
			(type solid)
		)
		(fill yes)
		(layer "In4.Cu")
		(net "M_D_CPU0_SA_DQ<6>")
	)
	(gr_poly
		(pts
			(xy 329.759818 -227.276152) (xy 329.796648 -227.1395) (xy 329.659996 -227.102924) (xy 329.618594 -227.1268)
			(xy 329.71867 -227.300028)
		)
		(stroke
			(width 0)
			(type solid)
		)
		(fill yes)
		(layer "In4.Cu")
		(net "M_D_CPU0_SA_DQS_DN<5>")
	)
	(gr_poly
		(pts
			(xy 329.760326 -225.655632) (xy 329.796902 -225.519234) (xy 329.66025 -225.482404) (xy 329.619102 -225.50628)
			(xy 329.718924 -225.679508)
		)
		(stroke
			(width 0)
			(type solid)
		)
		(fill yes)
		(layer "In4.Cu")
		(net "M_D_CPU0_SA_DQS_DP<0>")
	)
	(gr_poly
		(pts
			(xy 329.760326 -224.036382) (xy 329.796902 -223.89973) (xy 329.660504 -223.863154) (xy 329.621896 -223.885506)
			(xy 329.721972 -224.058734)
		)
		(stroke
			(width 0)
			(type solid)
		)
		(fill yes)
		(layer "In4.Cu")
		(net "M_D_CPU0_SA_DQ<1>")
	)
	(gr_poly
		(pts
			(xy 330.0349 -267.801598) (xy 329.934824 -267.701522) (xy 329.835002 -267.801598) (xy 329.835002 -267.846048)
			(xy 330.0349 -267.846048)
		)
		(stroke
			(width 0)
			(type solid)
		)
		(fill yes)
		(layer "In4.Cu")
		(net "M_D_CPU0_SB_RSP<0>")
	)
	(gr_poly
		(pts
			(xy 330.04125 -292.107874) (xy 329.941174 -292.007798) (xy 329.841098 -292.107874) (xy 329.841098 -292.152324)
			(xy 330.04125 -292.152324)
		)
		(stroke
			(width 0)
			(type solid)
		)
		(fill yes)
		(layer "In4.Cu")
		(net "M_D_CPU0_SB_DQ<28>")
	)
	(gr_poly
		(pts
			(xy 330.04125 -291.704268) (xy 330.04125 -291.656516) (xy 329.841098 -291.656516) (xy 329.841098 -291.704268)
			(xy 329.941174 -291.80409)
		)
		(stroke
			(width 0)
			(type solid)
		)
		(fill yes)
		(layer "In4.Cu")
		(net "M_D_CPU0_SB_DQS_DP<8>")
	)
	(gr_poly
		(pts
			(xy 330.04125 -290.487608) (xy 329.941174 -290.387786) (xy 329.841098 -290.487608) (xy 329.841098 -290.53536)
			(xy 330.04125 -290.53536)
		)
		(stroke
			(width 0)
			(type solid)
		)
		(fill yes)
		(layer "In4.Cu")
		(net "M_D_CPU0_SB_DQS_DP<3>")
	)
	(gr_poly
		(pts
			(xy 330.04125 -290.084002) (xy 330.04125 -290.039552) (xy 329.841098 -290.039552) (xy 329.841098 -290.084002)
			(xy 329.941174 -290.184078)
		)
		(stroke
			(width 0)
			(type solid)
		)
		(fill yes)
		(layer "In4.Cu")
		(net "M_D_CPU0_SB_DQ<27>")
	)
	(gr_poly
		(pts
			(xy 330.04125 -288.86785) (xy 329.941174 -288.767774) (xy 329.841098 -288.86785) (xy 329.841098 -288.9123)
			(xy 330.04125 -288.9123)
		)
		(stroke
			(width 0)
			(type solid)
		)
		(fill yes)
		(layer "In4.Cu")
		(net "M_D_CPU0_SB_DQ<24>")
	)
	(gr_poly
		(pts
			(xy 330.04125 -288.464244) (xy 330.04125 -288.419794) (xy 329.841098 -288.419794) (xy 329.841098 -288.464244)
			(xy 329.941174 -288.56432)
		)
		(stroke
			(width 0)
			(type solid)
		)
		(fill yes)
		(layer "In4.Cu")
		(net "M_D_CPU0_SB_DQ<23>")
	)
	(gr_poly
		(pts
			(xy 330.04125 -287.247838) (xy 329.941174 -287.148016) (xy 329.841098 -287.247838) (xy 329.841098 -287.292288)
			(xy 330.04125 -287.292288)
		)
		(stroke
			(width 0)
			(type solid)
		)
		(fill yes)
		(layer "In4.Cu")
		(net "M_D_CPU0_SB_DQ<20>")
	)
	(gr_poly
		(pts
			(xy 330.04125 -286.844232) (xy 330.04125 -286.79648) (xy 329.841098 -286.79648) (xy 329.841098 -286.844232)
			(xy 329.941174 -286.944308)
		)
		(stroke
			(width 0)
			(type solid)
		)
		(fill yes)
		(layer "In4.Cu")
		(net "M_D_CPU0_SB_DQS_DP<7>")
	)
	(gr_poly
		(pts
			(xy 330.04125 -285.627826) (xy 329.941174 -285.528004) (xy 329.841098 -285.627826) (xy 329.841098 -285.675578)
			(xy 330.04125 -285.675578)
		)
		(stroke
			(width 0)
			(type solid)
		)
		(fill yes)
		(layer "In4.Cu")
		(net "M_D_CPU0_SB_DQS_DP<2>")
	)
	(gr_poly
		(pts
			(xy 330.04125 -285.22422) (xy 330.04125 -285.17977) (xy 329.841098 -285.17977) (xy 329.841098 -285.22422)
			(xy 329.941174 -285.324296)
		)
		(stroke
			(width 0)
			(type solid)
		)
		(fill yes)
		(layer "In4.Cu")
		(net "M_D_CPU0_SB_DQ<19>")
	)
	(gr_poly
		(pts
			(xy 330.04125 -284.008068) (xy 329.941174 -283.907992) (xy 329.841098 -284.008068) (xy 329.841098 -284.052518)
			(xy 330.04125 -284.052518)
		)
		(stroke
			(width 0)
			(type solid)
		)
		(fill yes)
		(layer "In4.Cu")
		(net "M_D_CPU0_SB_DQ<16>")
	)
	(gr_poly
		(pts
			(xy 330.04125 -283.604208) (xy 330.04125 -283.559758) (xy 329.841098 -283.559758) (xy 329.841098 -283.604208)
			(xy 329.941174 -283.704284)
		)
		(stroke
			(width 0)
			(type solid)
		)
		(fill yes)
		(layer "In4.Cu")
		(net "M_D_CPU0_SB_DQ<15>")
	)
	(gr_poly
		(pts
			(xy 330.04125 -282.388056) (xy 329.941174 -282.28798) (xy 329.841098 -282.388056) (xy 329.841098 -282.432506)
			(xy 330.04125 -282.432506)
		)
		(stroke
			(width 0)
			(type solid)
		)
		(fill yes)
		(layer "In4.Cu")
		(net "M_D_CPU0_SB_DQ<12>")
	)
	(gr_poly
		(pts
			(xy 330.04125 -281.98445) (xy 330.04125 -281.936698) (xy 329.841098 -281.936698) (xy 329.841098 -281.98445)
			(xy 329.941174 -282.084272)
		)
		(stroke
			(width 0)
			(type solid)
		)
		(fill yes)
		(layer "In4.Cu")
		(net "M_D_CPU0_SB_DQS_DP<6>")
	)
	(gr_poly
		(pts
			(xy 330.04125 -280.76779) (xy 329.941174 -280.667968) (xy 329.841098 -280.76779) (xy 329.841098 -280.815542)
			(xy 330.04125 -280.815542)
		)
		(stroke
			(width 0)
			(type solid)
		)
		(fill yes)
		(layer "In4.Cu")
		(net "M_D_CPU0_SB_DQS_DP<1>")
	)
	(gr_poly
		(pts
			(xy 330.04125 -280.364184) (xy 330.04125 -280.319734) (xy 329.841098 -280.319734) (xy 329.841098 -280.364184)
			(xy 329.941174 -280.46426)
		)
		(stroke
			(width 0)
			(type solid)
		)
		(fill yes)
		(layer "In4.Cu")
		(net "M_D_CPU0_SB_DQ<11>")
	)
	(gr_poly
		(pts
			(xy 330.04125 -279.148032) (xy 329.941174 -279.047956) (xy 329.841098 -279.148032) (xy 329.841098 -279.192482)
			(xy 330.04125 -279.192482)
		)
		(stroke
			(width 0)
			(type solid)
		)
		(fill yes)
		(layer "In4.Cu")
		(net "M_D_CPU0_SB_DQ<8>")
	)
	(gr_poly
		(pts
			(xy 330.04125 -278.744172) (xy 330.04125 -278.699722) (xy 329.841098 -278.699722) (xy 329.841098 -278.744172)
			(xy 329.941174 -278.844248)
		)
		(stroke
			(width 0)
			(type solid)
		)
		(fill yes)
		(layer "In4.Cu")
		(net "M_D_CPU0_SB_DQ<7>")
	)
	(gr_poly
		(pts
			(xy 330.04125 -277.52802) (xy 329.941174 -277.427944) (xy 329.841098 -277.52802) (xy 329.841098 -277.57247)
			(xy 330.04125 -277.57247)
		)
		(stroke
			(width 0)
			(type solid)
		)
		(fill yes)
		(layer "In4.Cu")
		(net "M_D_CPU0_SB_DQ<4>")
	)
	(gr_poly
		(pts
			(xy 330.04125 -277.12416) (xy 330.04125 -277.076662) (xy 329.841098 -277.076662) (xy 329.841098 -277.12416)
			(xy 329.941174 -277.224236)
		)
		(stroke
			(width 0)
			(type solid)
		)
		(fill yes)
		(layer "In4.Cu")
		(net "M_D_CPU0_SB_DQS_DP<5>")
	)
	(gr_poly
		(pts
			(xy 330.04125 -275.908008) (xy 329.941174 -275.807932) (xy 329.841098 -275.908008) (xy 329.841098 -275.955506)
			(xy 330.04125 -275.955506)
		)
		(stroke
			(width 0)
			(type solid)
		)
		(fill yes)
		(layer "In4.Cu")
		(net "M_D_CPU0_SB_DQS_DP<0>")
	)
	(gr_poly
		(pts
			(xy 330.04125 -275.504148) (xy 330.04125 -275.459698) (xy 329.841098 -275.459698) (xy 329.841098 -275.504148)
			(xy 329.941174 -275.604224)
		)
		(stroke
			(width 0)
			(type solid)
		)
		(fill yes)
		(layer "In4.Cu")
		(net "M_D_CPU0_SB_DQ<3>")
	)
	(gr_poly
		(pts
			(xy 330.04125 -274.287996) (xy 329.941174 -274.18792) (xy 329.841098 -274.287996) (xy 329.841098 -274.332446)
			(xy 330.04125 -274.332446)
		)
		(stroke
			(width 0)
			(type solid)
		)
		(fill yes)
		(layer "In4.Cu")
		(net "M_D_CPU0_SB_DQ<0>")
	)
	(gr_poly
		(pts
			(xy 330.04125 -273.884136) (xy 330.04125 -273.839686) (xy 329.841098 -273.839686) (xy 329.841098 -273.884136)
			(xy 329.941174 -273.984212)
		)
		(stroke
			(width 0)
			(type solid)
		)
		(fill yes)
		(layer "In4.Cu")
		(net "M_D_CPU0_SB_CB<3>")
	)
	(gr_poly
		(pts
			(xy 330.04125 -272.667984) (xy 329.941174 -272.567908) (xy 329.841098 -272.667984) (xy 329.841098 -272.712434)
			(xy 330.04125 -272.712434)
		)
		(stroke
			(width 0)
			(type solid)
		)
		(fill yes)
		(layer "In4.Cu")
		(net "M_D_CPU0_SB_CB<0>")
	)
	(gr_poly
		(pts
			(xy 330.04125 -272.264378) (xy 330.04125 -272.216626) (xy 329.841098 -272.216626) (xy 329.841098 -272.264378)
			(xy 329.941174 -272.3642)
		)
		(stroke
			(width 0)
			(type solid)
		)
		(fill yes)
		(layer "In4.Cu")
		(net "M_D_CPU0_SB_DQS_DP<4>")
	)
	(gr_poly
		(pts
			(xy 330.04125 -271.047718) (xy 329.941174 -270.947896) (xy 329.841098 -271.047718) (xy 329.841098 -271.09547)
			(xy 330.04125 -271.09547)
		)
		(stroke
			(width 0)
			(type solid)
		)
		(fill yes)
		(layer "In4.Cu")
		(net "M_D_CPU0_SB_DQS_DP<9>")
	)
	(gr_poly
		(pts
			(xy 330.04125 -270.644112) (xy 330.04125 -270.599662) (xy 329.841098 -270.599662) (xy 329.841098 -270.644112)
			(xy 329.941174 -270.744188)
		)
		(stroke
			(width 0)
			(type solid)
		)
		(fill yes)
		(layer "In4.Cu")
		(net "M_D_CPU0_SB_CB<7>")
	)
	(gr_poly
		(pts
			(xy 330.04125 -269.42796) (xy 329.941174 -269.327884) (xy 329.841098 -269.42796) (xy 329.841098 -269.47241)
			(xy 330.04125 -269.47241)
		)
		(stroke
			(width 0)
			(type solid)
		)
		(fill yes)
		(layer "In4.Cu")
		(net "M_D_CPU0_SB_CB<4>")
	)
	(gr_poly
		(pts
			(xy 330.04125 -265.784076) (xy 330.04125 -265.739626) (xy 329.841098 -265.739626) (xy 329.841098 -265.784076)
			(xy 329.941174 -265.884152)
		)
		(stroke
			(width 0)
			(type solid)
		)
		(fill yes)
		(layer "In4.Cu")
		(net "M_D_CPU0_SB_CS_N<0>")
	)
	(gr_poly
		(pts
			(xy 330.04125 -264.567924) (xy 329.941174 -264.467848) (xy 329.841098 -264.567924) (xy 329.841098 -264.612374)
			(xy 330.04125 -264.612374)
		)
		(stroke
			(width 0)
			(type solid)
		)
		(fill yes)
		(layer "In4.Cu")
		(net "M_D_CPU0_SB_CA<6>")
	)
	(gr_poly
		(pts
			(xy 330.04125 -264.164064) (xy 330.04125 -264.119614) (xy 329.841098 -264.119614) (xy 329.841098 -264.164064)
			(xy 329.941174 -264.26414)
		)
		(stroke
			(width 0)
			(type solid)
		)
		(fill yes)
		(layer "In4.Cu")
		(net "M_D_CPU0_SB_CA<5>")
	)
	(gr_poly
		(pts
			(xy 330.04125 -262.947912) (xy 329.941174 -262.847836) (xy 329.841098 -262.947912) (xy 329.841098 -262.992362)
			(xy 330.04125 -262.992362)
		)
		(stroke
			(width 0)
			(type solid)
		)
		(fill yes)
		(layer "In4.Cu")
		(net "M_D_CPU0_SB_CA<2>")
	)
	(gr_poly
		(pts
			(xy 330.04125 -262.544052) (xy 330.04125 -262.499602) (xy 329.841098 -262.499602) (xy 329.841098 -262.544052)
			(xy 329.941174 -262.644128)
		)
		(stroke
			(width 0)
			(type solid)
		)
		(fill yes)
		(layer "In4.Cu")
		(net "M_D_CPU0_SB_CA<1>")
	)
	(gr_poly
		(pts
			(xy 330.086462 -293.878508) (xy 330.049886 -293.741856) (xy 330.011278 -293.719504) (xy 329.911456 -293.892732)
			(xy 329.94981 -293.915084)
		)
		(stroke
			(width 0)
			(type solid)
		)
		(fill yes)
		(layer "In4.Cu")
		(net "M_D_CPU0_SB_DQ<31>")
	)
	(gr_poly
		(pts
			(xy 330.131166 -225.39452) (xy 330.03109 -225.221292) (xy 329.992482 -225.24339) (xy 329.955906 -225.380042)
			(xy 330.092558 -225.416618)
		)
		(stroke
			(width 0)
			(type solid)
		)
		(fill yes)
		(layer "In4.Cu")
		(net "M_D_CPU0_SA_DQ<3>")
	)
	(gr_poly
		(pts
			(xy 330.131166 -223.774508) (xy 330.03109 -223.60128) (xy 329.992482 -223.623378) (xy 329.955906 -223.76003)
			(xy 330.092558 -223.796606)
		)
		(stroke
			(width 0)
			(type solid)
		)
		(fill yes)
		(layer "In4.Cu")
		(net "M_D_CPU0_SA_DQ<2>")
	)
	(gr_poly
		(pts
			(xy 330.13396 -227.013516) (xy 330.034138 -226.840288) (xy 329.992736 -226.864164) (xy 329.95616 -227.000816)
			(xy 330.092812 -227.037392)
		)
		(stroke
			(width 0)
			(type solid)
		)
		(fill yes)
		(layer "In4.Cu")
		(net "M_D_CPU0_SA_DQS_DN<0>")
	)
	(gr_poly
		(pts
			(xy 330.211176 -256.025904) (xy 330.1111 -255.926082) (xy 330.011024 -256.025904) (xy 330.011024 -256.073656)
			(xy 330.211176 -256.073656)
		)
		(stroke
			(width 0)
			(type solid)
		)
		(fill yes)
		(layer "In4.Cu")
		(net "M_D_CPU0_CLK_DP<0>")
	)
	(gr_poly
		(pts
			(xy 330.211176 -255.622298) (xy 330.211176 -255.577848) (xy 330.011024 -255.577848) (xy 330.011024 -255.622298)
			(xy 330.1111 -255.722374)
		)
		(stroke
			(width 0)
			(type solid)
		)
		(fill yes)
		(layer "In4.Cu")
		(net "M_D_CPU0_SA_PAR")
	)
	(gr_poly
		(pts
			(xy 330.211176 -254.406146) (xy 330.1111 -254.30607) (xy 330.011024 -254.406146) (xy 330.011024 -254.450596)
			(xy 330.211176 -254.450596)
		)
		(stroke
			(width 0)
			(type solid)
		)
		(fill yes)
		(layer "In4.Cu")
		(net "M_D_CPU0_SA_CA<4>")
	)
	(gr_poly
		(pts
			(xy 330.211176 -254.002286) (xy 330.211176 -253.957836) (xy 330.011024 -253.957836) (xy 330.011024 -254.002286)
			(xy 330.1111 -254.102362)
		)
		(stroke
			(width 0)
			(type solid)
		)
		(fill yes)
		(layer "In4.Cu")
		(net "M_D_CPU0_SA_CA<3>")
	)
	(gr_poly
		(pts
			(xy 330.211176 -252.786134) (xy 330.1111 -252.686058) (xy 330.011024 -252.786134) (xy 330.011024 -252.830584)
			(xy 330.211176 -252.830584)
		)
		(stroke
			(width 0)
			(type solid)
		)
		(fill yes)
		(layer "In4.Cu")
		(net "M_D_CPU0_SA_CA<0>")
	)
	(gr_poly
		(pts
			(xy 330.211176 -252.382274) (xy 330.211176 -252.337824) (xy 330.011024 -252.337824) (xy 330.011024 -252.382274)
			(xy 330.1111 -252.48235)
		)
		(stroke
			(width 0)
			(type solid)
		)
		(fill yes)
		(layer "In4.Cu")
		(net "M_D_CPU0_SA_CS_N<1>")
	)
	(gr_poly
		(pts
			(xy 330.211176 -250.762262) (xy 330.211176 -250.717812) (xy 330.011024 -250.717812) (xy 330.011024 -250.762262)
			(xy 330.1111 -250.862338)
		)
		(stroke
			(width 0)
			(type solid)
		)
		(fill yes)
		(layer "In4.Cu")
		(net "M_D_CPU0_RESET_N")
	)
	(gr_poly
		(pts
			(xy 330.211176 -249.14225) (xy 330.211176 -249.0978) (xy 330.011024 -249.0978) (xy 330.011024 -249.14225)
			(xy 330.1111 -249.242326)
		)
		(stroke
			(width 0)
			(type solid)
		)
		(fill yes)
		(layer "In4.Cu")
		(net "M_D_CPU0_SA_CB<7>")
	)
	(gr_poly
		(pts
			(xy 330.211176 -247.926098) (xy 330.1111 -247.826022) (xy 330.011024 -247.926098) (xy 330.011024 -247.970548)
			(xy 330.211176 -247.970548)
		)
		(stroke
			(width 0)
			(type solid)
		)
		(fill yes)
		(layer "In4.Cu")
		(net "M_D_CPU0_SA_CB<4>")
	)
	(gr_poly
		(pts
			(xy 330.211176 -247.522492) (xy 330.211176 -247.47474) (xy 330.011024 -247.47474) (xy 330.011024 -247.522492)
			(xy 330.1111 -247.622314)
		)
		(stroke
			(width 0)
			(type solid)
		)
		(fill yes)
		(layer "In4.Cu")
		(net "M_D_CPU0_SA_DQS_DP<9>")
	)
	(gr_poly
		(pts
			(xy 330.211176 -246.305832) (xy 330.1111 -246.20601) (xy 330.011024 -246.305832) (xy 330.011024 -246.353584)
			(xy 330.211176 -246.353584)
		)
		(stroke
			(width 0)
			(type solid)
		)
		(fill yes)
		(layer "In4.Cu")
		(net "M_D_CPU0_SA_DQS_DP<4>")
	)
	(gr_poly
		(pts
			(xy 330.211176 -245.902226) (xy 330.211176 -245.857776) (xy 330.011024 -245.857776) (xy 330.011024 -245.902226)
			(xy 330.1111 -246.002302)
		)
		(stroke
			(width 0)
			(type solid)
		)
		(fill yes)
		(layer "In4.Cu")
		(net "M_D_CPU0_SA_CB<3>")
	)
	(gr_poly
		(pts
			(xy 330.211176 -244.686074) (xy 330.1111 -244.585998) (xy 330.011024 -244.686074) (xy 330.011024 -244.730524)
			(xy 330.211176 -244.730524)
		)
		(stroke
			(width 0)
			(type solid)
		)
		(fill yes)
		(layer "In4.Cu")
		(net "M_D_CPU0_SA_CB<0>")
	)
	(gr_poly
		(pts
			(xy 330.211176 -244.282214) (xy 330.211176 -244.237764) (xy 330.011024 -244.237764) (xy 330.011024 -244.282214)
			(xy 330.1111 -244.38229)
		)
		(stroke
			(width 0)
			(type solid)
		)
		(fill yes)
		(layer "In4.Cu")
		(net "M_D_CPU0_SA_DQ<31>")
	)
	(gr_poly
		(pts
			(xy 330.211176 -243.066062) (xy 330.1111 -242.965986) (xy 330.011024 -243.066062) (xy 330.011024 -243.110512)
			(xy 330.211176 -243.110512)
		)
		(stroke
			(width 0)
			(type solid)
		)
		(fill yes)
		(layer "In4.Cu")
		(net "M_D_CPU0_SA_DQ<28>")
	)
	(gr_poly
		(pts
			(xy 330.211176 -242.662456) (xy 330.211176 -242.614704) (xy 330.011024 -242.614704) (xy 330.011024 -242.662456)
			(xy 330.1111 -242.762278)
		)
		(stroke
			(width 0)
			(type solid)
		)
		(fill yes)
		(layer "In4.Cu")
		(net "M_D_CPU0_SA_DQS_DP<8>")
	)
	(gr_poly
		(pts
			(xy 330.211176 -241.445796) (xy 330.1111 -241.345974) (xy 330.011024 -241.445796) (xy 330.011024 -241.493548)
			(xy 330.211176 -241.493548)
		)
		(stroke
			(width 0)
			(type solid)
		)
		(fill yes)
		(layer "In4.Cu")
		(net "M_D_CPU0_SA_DQS_DP<3>")
	)
	(gr_poly
		(pts
			(xy 330.211176 -241.04219) (xy 330.211176 -240.99774) (xy 330.011024 -240.99774) (xy 330.011024 -241.04219)
			(xy 330.1111 -241.142266)
		)
		(stroke
			(width 0)
			(type solid)
		)
		(fill yes)
		(layer "In4.Cu")
		(net "M_D_CPU0_SA_DQ<27>")
	)
	(gr_poly
		(pts
			(xy 330.211176 -239.826038) (xy 330.1111 -239.725962) (xy 330.011024 -239.826038) (xy 330.011024 -239.870488)
			(xy 330.211176 -239.870488)
		)
		(stroke
			(width 0)
			(type solid)
		)
		(fill yes)
		(layer "In4.Cu")
		(net "M_D_CPU0_SA_DQ<24>")
	)
	(gr_poly
		(pts
			(xy 330.211176 -239.422178) (xy 330.211176 -239.377728) (xy 330.011024 -239.377728) (xy 330.011024 -239.422178)
			(xy 330.1111 -239.522254)
		)
		(stroke
			(width 0)
			(type solid)
		)
		(fill yes)
		(layer "In4.Cu")
		(net "M_D_CPU0_SA_DQ<23>")
	)
	(gr_poly
		(pts
			(xy 330.211176 -238.206026) (xy 330.1111 -238.10595) (xy 330.011024 -238.206026) (xy 330.011024 -238.250476)
			(xy 330.211176 -238.250476)
		)
		(stroke
			(width 0)
			(type solid)
		)
		(fill yes)
		(layer "In4.Cu")
		(net "M_D_CPU0_SA_DQ<20>")
	)
	(gr_poly
		(pts
			(xy 330.211176 -237.80242) (xy 330.211176 -237.754668) (xy 330.011024 -237.754668) (xy 330.011024 -237.80242)
			(xy 330.1111 -237.902242)
		)
		(stroke
			(width 0)
			(type solid)
		)
		(fill yes)
		(layer "In4.Cu")
		(net "M_D_CPU0_SA_DQS_DP<7>")
	)
	(gr_poly
		(pts
			(xy 330.211176 -236.58576) (xy 330.1111 -236.485938) (xy 330.011024 -236.58576) (xy 330.011024 -236.633512)
			(xy 330.211176 -236.633512)
		)
		(stroke
			(width 0)
			(type solid)
		)
		(fill yes)
		(layer "In4.Cu")
		(net "M_D_CPU0_SA_DQS_DP<2>")
	)
	(gr_poly
		(pts
			(xy 330.211176 -236.182154) (xy 330.211176 -236.137704) (xy 330.011024 -236.137704) (xy 330.011024 -236.182154)
			(xy 330.1111 -236.28223)
		)
		(stroke
			(width 0)
			(type solid)
		)
		(fill yes)
		(layer "In4.Cu")
		(net "M_D_CPU0_SA_DQ<19>")
	)
	(gr_poly
		(pts
			(xy 330.211176 -234.966002) (xy 330.1111 -234.865926) (xy 330.011024 -234.966002) (xy 330.011024 -235.010452)
			(xy 330.211176 -235.010452)
		)
		(stroke
			(width 0)
			(type solid)
		)
		(fill yes)
		(layer "In4.Cu")
		(net "M_D_CPU0_SA_DQ<16>")
	)
	(gr_poly
		(pts
			(xy 330.211176 -234.562142) (xy 330.211176 -234.517692) (xy 330.011024 -234.517692) (xy 330.011024 -234.562142)
			(xy 330.1111 -234.662218)
		)
		(stroke
			(width 0)
			(type solid)
		)
		(fill yes)
		(layer "In4.Cu")
		(net "M_D_CPU0_SA_DQ<15>")
	)
	(gr_poly
		(pts
			(xy 330.211176 -233.34599) (xy 330.1111 -233.245914) (xy 330.011024 -233.34599) (xy 330.011024 -233.39044)
			(xy 330.211176 -233.39044)
		)
		(stroke
			(width 0)
			(type solid)
		)
		(fill yes)
		(layer "In4.Cu")
		(net "M_D_CPU0_SA_DQ<12>")
	)
	(gr_poly
		(pts
			(xy 330.211176 -232.942384) (xy 330.211176 -232.894632) (xy 330.011024 -232.894632) (xy 330.011024 -232.942384)
			(xy 330.1111 -233.042206)
		)
		(stroke
			(width 0)
			(type solid)
		)
		(fill yes)
		(layer "In4.Cu")
		(net "M_D_CPU0_SA_DQS_DP<6>")
	)
	(gr_poly
		(pts
			(xy 330.211176 -231.725724) (xy 330.1111 -231.625902) (xy 330.011024 -231.725724) (xy 330.011024 -231.773476)
			(xy 330.211176 -231.773476)
		)
		(stroke
			(width 0)
			(type solid)
		)
		(fill yes)
		(layer "In4.Cu")
		(net "M_D_CPU0_SA_DQS_DP<1>")
	)
	(gr_poly
		(pts
			(xy 330.211176 -231.322372) (xy 330.211176 -231.277922) (xy 330.011024 -231.277922) (xy 330.011024 -231.322372)
			(xy 330.1111 -231.422448)
		)
		(stroke
			(width 0)
			(type solid)
		)
		(fill yes)
		(layer "In4.Cu")
		(net "M_D_CPU0_SA_DQ<11>")
	)
	(gr_poly
		(pts
			(xy 330.211176 -230.105966) (xy 330.1111 -230.006144) (xy 330.011024 -230.105966) (xy 330.011024 -230.150416)
			(xy 330.211176 -230.150416)
		)
		(stroke
			(width 0)
			(type solid)
		)
		(fill yes)
		(layer "In4.Cu")
		(net "M_D_CPU0_SA_DQ<8>")
	)
	(gr_poly
		(pts
			(xy 330.211176 -229.70236) (xy 330.211176 -229.65791) (xy 330.011024 -229.65791) (xy 330.011024 -229.70236)
			(xy 330.1111 -229.802436)
		)
		(stroke
			(width 0)
			(type solid)
		)
		(fill yes)
		(layer "In4.Cu")
		(net "M_D_CPU0_SA_DQ<7>")
	)
	(gr_poly
		(pts
			(xy 330.211176 -228.486208) (xy 330.1111 -228.386132) (xy 330.011024 -228.486208) (xy 330.011024 -228.530658)
			(xy 330.211176 -228.530658)
		)
		(stroke
			(width 0)
			(type solid)
		)
		(fill yes)
		(layer "In4.Cu")
		(net "M_D_CPU0_SA_DQ<4>")
	)
	(gr_poly
		(pts
			(xy 330.211176 -228.082602) (xy 330.211176 -228.03485) (xy 330.011024 -228.03485) (xy 330.011024 -228.082602)
			(xy 330.1111 -228.182424)
		)
		(stroke
			(width 0)
			(type solid)
		)
		(fill yes)
		(layer "In4.Cu")
		(net "M_D_CPU0_SA_DQS_DP<5>")
	)
	(gr_poly
		(pts
			(xy 330.229464 -226.464368) (xy 330.26604 -226.327716) (xy 330.129388 -226.29114) (xy 330.08824 -226.315016)
			(xy 330.188062 -226.488244)
		)
		(stroke
			(width 0)
			(type solid)
		)
		(fill yes)
		(layer "In4.Cu")
		(net "M_D_CPU0_SA_DQS_DP<0>")
	)
	(gr_poly
		(pts
			(xy 330.229718 -224.845118) (xy 330.266294 -224.708466) (xy 330.129642 -224.67189) (xy 330.091034 -224.693988)
			(xy 330.19111 -224.867216)
		)
		(stroke
			(width 0)
			(type solid)
		)
		(fill yes)
		(layer "In4.Cu")
		(net "M_D_CPU0_SA_DQ<1>")
	)
	(gr_poly
		(pts
			(xy 330.229718 -223.225106) (xy 330.266294 -223.088454) (xy 330.129642 -223.051878) (xy 330.091034 -223.073976)
			(xy 330.19111 -223.247204)
		)
		(stroke
			(width 0)
			(type solid)
		)
		(fill yes)
		(layer "In4.Cu")
		(net "M_D_CPU0_SA_DQ<0>")
	)
	(gr_poly
		(pts
			(xy 330.51115 -292.91788) (xy 330.411074 -292.817804) (xy 330.310998 -292.91788) (xy 330.310998 -292.96233)
			(xy 330.51115 -292.96233)
		)
		(stroke
			(width 0)
			(type solid)
		)
		(fill yes)
		(layer "In4.Cu")
		(net "M_D_CPU0_SB_DQ<29>")
	)
	(gr_poly
		(pts
			(xy 330.51115 -292.51402) (xy 330.51115 -292.46957) (xy 330.310998 -292.46957) (xy 330.310998 -292.51402)
			(xy 330.411074 -292.614096)
		)
		(stroke
			(width 0)
			(type solid)
		)
		(fill yes)
		(layer "In4.Cu")
		(net "M_D_CPU0_SB_DQ<30>")
	)
	(gr_poly
		(pts
			(xy 330.51115 -291.297614) (xy 330.411074 -291.197792) (xy 330.310998 -291.297614) (xy 330.310998 -291.345366)
			(xy 330.51115 -291.345366)
		)
		(stroke
			(width 0)
			(type solid)
		)
		(fill yes)
		(layer "In4.Cu")
		(net "M_D_CPU0_SB_DQS_DN<8>")
	)
	(gr_poly
		(pts
			(xy 330.51115 -290.894262) (xy 330.51115 -290.84651) (xy 330.310998 -290.84651) (xy 330.310998 -290.894262)
			(xy 330.411074 -290.994084)
		)
		(stroke
			(width 0)
			(type solid)
		)
		(fill yes)
		(layer "In4.Cu")
		(net "M_D_CPU0_SB_DQS_DN<3>")
	)
	(gr_poly
		(pts
			(xy 330.51115 -289.677856) (xy 330.411074 -289.57778) (xy 330.310998 -289.677856) (xy 330.310998 -289.722306)
			(xy 330.51115 -289.722306)
		)
		(stroke
			(width 0)
			(type solid)
		)
		(fill yes)
		(layer "In4.Cu")
		(net "M_D_CPU0_SB_DQ<25>")
	)
	(gr_poly
		(pts
			(xy 330.51115 -289.273996) (xy 330.51115 -289.229546) (xy 330.310998 -289.229546) (xy 330.310998 -289.273996)
			(xy 330.411074 -289.374072)
		)
		(stroke
			(width 0)
			(type solid)
		)
		(fill yes)
		(layer "In4.Cu")
		(net "M_D_CPU0_SB_DQ<26>")
	)
	(gr_poly
		(pts
			(xy 330.51115 -288.057844) (xy 330.411074 -287.957768) (xy 330.310998 -288.057844) (xy 330.310998 -288.102294)
			(xy 330.51115 -288.102294)
		)
		(stroke
			(width 0)
			(type solid)
		)
		(fill yes)
		(layer "In4.Cu")
		(net "M_D_CPU0_SB_DQ<21>")
	)
	(gr_poly
		(pts
			(xy 330.51115 -287.654238) (xy 330.51115 -287.609788) (xy 330.310998 -287.609788) (xy 330.310998 -287.654238)
			(xy 330.411074 -287.75406)
		)
		(stroke
			(width 0)
			(type solid)
		)
		(fill yes)
		(layer "In4.Cu")
		(net "M_D_CPU0_SB_DQ<22>")
	)
	(gr_poly
		(pts
			(xy 330.51115 -286.437832) (xy 330.411074 -286.337756) (xy 330.310998 -286.437832) (xy 330.310998 -286.485584)
			(xy 330.51115 -286.485584)
		)
		(stroke
			(width 0)
			(type solid)
		)
		(fill yes)
		(layer "In4.Cu")
		(net "M_D_CPU0_SB_DQS_DN<7>")
	)
	(gr_poly
		(pts
			(xy 330.51115 -286.03448) (xy 330.51115 -285.986728) (xy 330.310998 -285.986728) (xy 330.310998 -286.03448)
			(xy 330.411074 -286.134302)
		)
		(stroke
			(width 0)
			(type solid)
		)
		(fill yes)
		(layer "In4.Cu")
		(net "M_D_CPU0_SB_DQS_DN<2>")
	)
	(gr_poly
		(pts
			(xy 330.51115 -284.818074) (xy 330.411074 -284.717998) (xy 330.310998 -284.818074) (xy 330.310998 -284.862524)
			(xy 330.51115 -284.862524)
		)
		(stroke
			(width 0)
			(type solid)
		)
		(fill yes)
		(layer "In4.Cu")
		(net "M_D_CPU0_SB_DQ<17>")
	)
	(gr_poly
		(pts
			(xy 330.51115 -284.414214) (xy 330.51115 -284.369764) (xy 330.310998 -284.369764) (xy 330.310998 -284.414214)
			(xy 330.411074 -284.51429)
		)
		(stroke
			(width 0)
			(type solid)
		)
		(fill yes)
		(layer "In4.Cu")
		(net "M_D_CPU0_SB_DQ<18>")
	)
	(gr_poly
		(pts
			(xy 330.51115 -283.198062) (xy 330.411074 -283.097986) (xy 330.310998 -283.198062) (xy 330.310998 -283.242512)
			(xy 330.51115 -283.242512)
		)
		(stroke
			(width 0)
			(type solid)
		)
		(fill yes)
		(layer "In4.Cu")
		(net "M_D_CPU0_SB_DQ<13>")
	)
	(gr_poly
		(pts
			(xy 330.51115 -282.794202) (xy 330.51115 -282.749752) (xy 330.310998 -282.749752) (xy 330.310998 -282.794202)
			(xy 330.411074 -282.894278)
		)
		(stroke
			(width 0)
			(type solid)
		)
		(fill yes)
		(layer "In4.Cu")
		(net "M_D_CPU0_SB_DQ<14>")
	)
	(gr_poly
		(pts
			(xy 330.51115 -281.577796) (xy 330.411074 -281.477974) (xy 330.310998 -281.577796) (xy 330.310998 -281.625548)
			(xy 330.51115 -281.625548)
		)
		(stroke
			(width 0)
			(type solid)
		)
		(fill yes)
		(layer "In4.Cu")
		(net "M_D_CPU0_SB_DQS_DN<6>")
	)
	(gr_poly
		(pts
			(xy 330.51115 -281.174444) (xy 330.51115 -281.126692) (xy 330.310998 -281.126692) (xy 330.310998 -281.174444)
			(xy 330.411074 -281.274266)
		)
		(stroke
			(width 0)
			(type solid)
		)
		(fill yes)
		(layer "In4.Cu")
		(net "M_D_CPU0_SB_DQS_DN<1>")
	)
	(gr_poly
		(pts
			(xy 330.51115 -279.958038) (xy 330.411074 -279.857962) (xy 330.310998 -279.958038) (xy 330.310998 -280.002488)
			(xy 330.51115 -280.002488)
		)
		(stroke
			(width 0)
			(type solid)
		)
		(fill yes)
		(layer "In4.Cu")
		(net "M_D_CPU0_SB_DQ<9>")
	)
	(gr_poly
		(pts
			(xy 330.51115 -279.554178) (xy 330.51115 -279.509728) (xy 330.310998 -279.509728) (xy 330.310998 -279.554178)
			(xy 330.411074 -279.654254)
		)
		(stroke
			(width 0)
			(type solid)
		)
		(fill yes)
		(layer "In4.Cu")
		(net "M_D_CPU0_SB_DQ<10>")
	)
	(gr_poly
		(pts
			(xy 330.51115 -278.338026) (xy 330.411074 -278.23795) (xy 330.310998 -278.338026) (xy 330.310998 -278.382476)
			(xy 330.51115 -278.382476)
		)
		(stroke
			(width 0)
			(type solid)
		)
		(fill yes)
		(layer "In4.Cu")
		(net "M_D_CPU0_SB_DQ<5>")
	)
	(gr_poly
		(pts
			(xy 330.51115 -277.934166) (xy 330.51115 -277.889716) (xy 330.310998 -277.889716) (xy 330.310998 -277.934166)
			(xy 330.411074 -278.034242)
		)
		(stroke
			(width 0)
			(type solid)
		)
		(fill yes)
		(layer "In4.Cu")
		(net "M_D_CPU0_SB_DQ<6>")
	)
	(gr_poly
		(pts
			(xy 330.51115 -276.71776) (xy 330.411074 -276.617938) (xy 330.310998 -276.71776) (xy 330.310998 -276.765512)
			(xy 330.51115 -276.765512)
		)
		(stroke
			(width 0)
			(type solid)
		)
		(fill yes)
		(layer "In4.Cu")
		(net "M_D_CPU0_SB_DQS_DN<5>")
	)
	(gr_poly
		(pts
			(xy 330.51115 -276.314408) (xy 330.51115 -276.266656) (xy 330.310998 -276.266656) (xy 330.310998 -276.314408)
			(xy 330.411074 -276.41423)
		)
		(stroke
			(width 0)
			(type solid)
		)
		(fill yes)
		(layer "In4.Cu")
		(net "M_D_CPU0_SB_DQS_DN<0>")
	)
	(gr_poly
		(pts
			(xy 330.51115 -275.098002) (xy 330.411074 -274.997926) (xy 330.310998 -275.098002) (xy 330.310998 -275.142452)
			(xy 330.51115 -275.142452)
		)
		(stroke
			(width 0)
			(type solid)
		)
		(fill yes)
		(layer "In4.Cu")
		(net "M_D_CPU0_SB_DQ<1>")
	)
	(gr_poly
		(pts
			(xy 330.51115 -274.694142) (xy 330.51115 -274.649692) (xy 330.310998 -274.649692) (xy 330.310998 -274.694142)
			(xy 330.411074 -274.794218)
		)
		(stroke
			(width 0)
			(type solid)
		)
		(fill yes)
		(layer "In4.Cu")
		(net "M_D_CPU0_SB_DQ<2>")
	)
	(gr_poly
		(pts
			(xy 330.51115 -273.47799) (xy 330.411074 -273.377914) (xy 330.310998 -273.47799) (xy 330.310998 -273.52244)
			(xy 330.51115 -273.52244)
		)
		(stroke
			(width 0)
			(type solid)
		)
		(fill yes)
		(layer "In4.Cu")
		(net "M_D_CPU0_SB_CB<1>")
	)
	(gr_poly
		(pts
			(xy 330.51115 -273.07413) (xy 330.51115 -273.02968) (xy 330.310998 -273.02968) (xy 330.310998 -273.07413)
			(xy 330.411074 -273.174206)
		)
		(stroke
			(width 0)
			(type solid)
		)
		(fill yes)
		(layer "In4.Cu")
		(net "M_D_CPU0_SB_CB<2>")
	)
	(gr_poly
		(pts
			(xy 330.51115 -271.857724) (xy 330.411074 -271.757902) (xy 330.310998 -271.857724) (xy 330.310998 -271.905476)
			(xy 330.51115 -271.905476)
		)
		(stroke
			(width 0)
			(type solid)
		)
		(fill yes)
		(layer "In4.Cu")
		(net "M_D_CPU0_SB_DQS_DN<4>")
	)
	(gr_poly
		(pts
			(xy 330.51115 -271.454372) (xy 330.51115 -271.40662) (xy 330.310998 -271.40662) (xy 330.310998 -271.454372)
			(xy 330.411074 -271.554194)
		)
		(stroke
			(width 0)
			(type solid)
		)
		(fill yes)
		(layer "In4.Cu")
		(net "M_D_CPU0_SB_DQS_DN<9>")
	)
	(gr_poly
		(pts
			(xy 330.51115 -270.237966) (xy 330.411074 -270.13789) (xy 330.310998 -270.237966) (xy 330.310998 -270.282416)
			(xy 330.51115 -270.282416)
		)
		(stroke
			(width 0)
			(type solid)
		)
		(fill yes)
		(layer "In4.Cu")
		(net "M_D_CPU0_SB_CB<5>")
	)
	(gr_poly
		(pts
			(xy 330.51115 -269.834106) (xy 330.51115 -269.789656) (xy 330.310998 -269.789656) (xy 330.310998 -269.834106)
			(xy 330.411074 -269.934182)
		)
		(stroke
			(width 0)
			(type solid)
		)
		(fill yes)
		(layer "In4.Cu")
		(net "M_D_CPU0_SB_CB<6>")
	)
	(gr_poly
		(pts
			(xy 330.51115 -266.991592) (xy 330.411074 -266.891516) (xy 330.310998 -266.991592) (xy 330.310998 -267.036042)
			(xy 330.51115 -267.036042)
		)
		(stroke
			(width 0)
			(type solid)
		)
		(fill yes)
		(layer "In4.Cu")
		(net "M_D_CPU0_SA_RSP<0>")
	)
	(gr_poly
		(pts
			(xy 330.51115 -266.594082) (xy 330.51115 -266.549632) (xy 330.310998 -266.549632) (xy 330.310998 -266.594082)
			(xy 330.411074 -266.694158)
		)
		(stroke
			(width 0)
			(type solid)
		)
		(fill yes)
		(layer "In4.Cu")
		(net "M_D_CPU0_SB_CS_N<1>")
	)
	(gr_poly
		(pts
			(xy 330.51115 -264.97407) (xy 330.51115 -264.92962) (xy 330.310998 -264.92962) (xy 330.310998 -264.97407)
			(xy 330.411074 -265.074146)
		)
		(stroke
			(width 0)
			(type solid)
		)
		(fill yes)
		(layer "In4.Cu")
		(net "M_D_CPU0_SB_PAR")
	)
	(gr_poly
		(pts
			(xy 330.51115 -263.757918) (xy 330.411074 -263.657842) (xy 330.310998 -263.757918) (xy 330.310998 -263.802368)
			(xy 330.51115 -263.802368)
		)
		(stroke
			(width 0)
			(type solid)
		)
		(fill yes)
		(layer "In4.Cu")
		(net "M_D_CPU0_SB_CA<4>")
	)
	(gr_poly
		(pts
			(xy 330.51115 -263.354058) (xy 330.51115 -263.309608) (xy 330.310998 -263.309608) (xy 330.310998 -263.354058)
			(xy 330.411074 -263.454134)
		)
		(stroke
			(width 0)
			(type solid)
		)
		(fill yes)
		(layer "In4.Cu")
		(net "M_D_CPU0_SB_CA<3>")
	)
	(gr_poly
		(pts
			(xy 330.51115 -262.137906) (xy 330.411074 -262.03783) (xy 330.310998 -262.137906) (xy 330.310998 -262.182356)
			(xy 330.51115 -262.182356)
		)
		(stroke
			(width 0)
			(type solid)
		)
		(fill yes)
		(layer "In4.Cu")
		(net "M_D_CPU0_SB_CA<0>")
	)
	(gr_poly
		(pts
			(xy 330.600304 -226.203002) (xy 330.500228 -226.029774) (xy 330.461874 -226.052126) (xy 330.425298 -226.188778)
			(xy 330.561696 -226.225354)
		)
		(stroke
			(width 0)
			(type solid)
		)
		(fill yes)
		(layer "In4.Cu")
		(net "M_D_CPU0_SA_DQ<3>")
	)
	(gr_poly
		(pts
			(xy 330.600304 -224.58299) (xy 330.500228 -224.409762) (xy 330.461874 -224.432114) (xy 330.425298 -224.568766)
			(xy 330.561696 -224.605342)
		)
		(stroke
			(width 0)
			(type solid)
		)
		(fill yes)
		(layer "In4.Cu")
		(net "M_D_CPU0_SA_DQ<2>")
	)
	(gr_poly
		(pts
			(xy 330.681076 -256.432558) (xy 330.681076 -256.384806) (xy 330.480924 -256.384806) (xy 330.480924 -256.432558)
			(xy 330.581 -256.53238)
		)
		(stroke
			(width 0)
			(type solid)
		)
		(fill yes)
		(layer "In4.Cu")
		(net "M_D_CPU0_CLK_DN<0>")
	)
	(gr_poly
		(pts
			(xy 330.681076 -255.216152) (xy 330.581 -255.116076) (xy 330.480924 -255.216152) (xy 330.480924 -255.260602)
			(xy 330.681076 -255.260602)
		)
		(stroke
			(width 0)
			(type solid)
		)
		(fill yes)
		(layer "In4.Cu")
		(net "M_D_CPU0_SA_CA<6>")
	)
	(gr_poly
		(pts
			(xy 330.681076 -254.812292) (xy 330.681076 -254.767842) (xy 330.480924 -254.767842) (xy 330.480924 -254.812292)
			(xy 330.581 -254.912368)
		)
		(stroke
			(width 0)
			(type solid)
		)
		(fill yes)
		(layer "In4.Cu")
		(net "M_D_CPU0_SA_CA<5>")
	)
	(gr_poly
		(pts
			(xy 330.681076 -253.59614) (xy 330.581 -253.496064) (xy 330.480924 -253.59614) (xy 330.480924 -253.64059)
			(xy 330.681076 -253.64059)
		)
		(stroke
			(width 0)
			(type solid)
		)
		(fill yes)
		(layer "In4.Cu")
		(net "M_D_CPU0_SA_CA<2>")
	)
	(gr_poly
		(pts
			(xy 330.681076 -253.19228) (xy 330.681076 -253.14783) (xy 330.480924 -253.14783) (xy 330.480924 -253.19228)
			(xy 330.581 -253.292356)
		)
		(stroke
			(width 0)
			(type solid)
		)
		(fill yes)
		(layer "In4.Cu")
		(net "M_D_CPU0_SA_CA<1>")
	)
	(gr_poly
		(pts
			(xy 330.681076 -251.572268) (xy 330.681076 -251.527818) (xy 330.480924 -251.527818) (xy 330.480924 -251.572268)
			(xy 330.581 -251.672344)
		)
		(stroke
			(width 0)
			(type solid)
		)
		(fill yes)
		(layer "In4.Cu")
		(net "M_D_CPU0_SA_CS_N<0>")
	)
	(gr_poly
		(pts
			(xy 330.681076 -250.356116) (xy 330.581 -250.25604) (xy 330.480924 -250.356116) (xy 330.480924 -250.400566)
			(xy 330.681076 -250.400566)
		)
		(stroke
			(width 0)
			(type solid)
		)
		(fill yes)
		(layer "In4.Cu")
		(net "M_D_CPU0_ALERT_R_N")
	)
	(gr_poly
		(pts
			(xy 330.681076 -248.736104) (xy 330.581 -248.636028) (xy 330.480924 -248.736104) (xy 330.480924 -248.780554)
			(xy 330.681076 -248.780554)
		)
		(stroke
			(width 0)
			(type solid)
		)
		(fill yes)
		(layer "In4.Cu")
		(net "M_D_CPU0_SA_CB<5>")
	)
	(gr_poly
		(pts
			(xy 330.681076 -248.332244) (xy 330.681076 -248.287794) (xy 330.480924 -248.287794) (xy 330.480924 -248.332244)
			(xy 330.581 -248.43232)
		)
		(stroke
			(width 0)
			(type solid)
		)
		(fill yes)
		(layer "In4.Cu")
		(net "M_D_CPU0_SA_CB<6>")
	)
	(gr_poly
		(pts
			(xy 330.681076 -247.115838) (xy 330.581 -247.016016) (xy 330.480924 -247.115838) (xy 330.480924 -247.16359)
			(xy 330.681076 -247.16359)
		)
		(stroke
			(width 0)
			(type solid)
		)
		(fill yes)
		(layer "In4.Cu")
		(net "M_D_CPU0_SA_DQS_DN<9>")
	)
	(gr_poly
		(pts
			(xy 330.681076 -246.712486) (xy 330.681076 -246.664734) (xy 330.480924 -246.664734) (xy 330.480924 -246.712486)
			(xy 330.581 -246.812308)
		)
		(stroke
			(width 0)
			(type solid)
		)
		(fill yes)
		(layer "In4.Cu")
		(net "M_D_CPU0_SA_DQS_DN<4>")
	)
	(gr_poly
		(pts
			(xy 330.681076 -245.49608) (xy 330.581 -245.396004) (xy 330.480924 -245.49608) (xy 330.480924 -245.54053)
			(xy 330.681076 -245.54053)
		)
		(stroke
			(width 0)
			(type solid)
		)
		(fill yes)
		(layer "In4.Cu")
		(net "M_D_CPU0_SA_CB<1>")
	)
	(gr_poly
		(pts
			(xy 330.681076 -245.09222) (xy 330.681076 -245.04777) (xy 330.480924 -245.04777) (xy 330.480924 -245.09222)
			(xy 330.581 -245.192296)
		)
		(stroke
			(width 0)
			(type solid)
		)
		(fill yes)
		(layer "In4.Cu")
		(net "M_D_CPU0_SA_CB<2>")
	)
	(gr_poly
		(pts
			(xy 330.681076 -243.876068) (xy 330.581 -243.775992) (xy 330.480924 -243.876068) (xy 330.480924 -243.920518)
			(xy 330.681076 -243.920518)
		)
		(stroke
			(width 0)
			(type solid)
		)
		(fill yes)
		(layer "In4.Cu")
		(net "M_D_CPU0_SA_DQ<29>")
	)
	(gr_poly
		(pts
			(xy 330.681076 -243.472208) (xy 330.681076 -243.427758) (xy 330.480924 -243.427758) (xy 330.480924 -243.472208)
			(xy 330.581 -243.572284)
		)
		(stroke
			(width 0)
			(type solid)
		)
		(fill yes)
		(layer "In4.Cu")
		(net "M_D_CPU0_SA_DQ<30>")
	)
	(gr_poly
		(pts
			(xy 330.681076 -242.255802) (xy 330.581 -242.15598) (xy 330.480924 -242.255802) (xy 330.480924 -242.303554)
			(xy 330.681076 -242.303554)
		)
		(stroke
			(width 0)
			(type solid)
		)
		(fill yes)
		(layer "In4.Cu")
		(net "M_D_CPU0_SA_DQS_DN<8>")
	)
	(gr_poly
		(pts
			(xy 330.681076 -241.85245) (xy 330.681076 -241.804698) (xy 330.480924 -241.804698) (xy 330.480924 -241.85245)
			(xy 330.581 -241.952272)
		)
		(stroke
			(width 0)
			(type solid)
		)
		(fill yes)
		(layer "In4.Cu")
		(net "M_D_CPU0_SA_DQS_DN<3>")
	)
	(gr_poly
		(pts
			(xy 330.681076 -240.636044) (xy 330.581 -240.535968) (xy 330.480924 -240.636044) (xy 330.480924 -240.680494)
			(xy 330.681076 -240.680494)
		)
		(stroke
			(width 0)
			(type solid)
		)
		(fill yes)
		(layer "In4.Cu")
		(net "M_D_CPU0_SA_DQ<25>")
	)
	(gr_poly
		(pts
			(xy 330.681076 -240.232184) (xy 330.681076 -240.187734) (xy 330.480924 -240.187734) (xy 330.480924 -240.232184)
			(xy 330.581 -240.33226)
		)
		(stroke
			(width 0)
			(type solid)
		)
		(fill yes)
		(layer "In4.Cu")
		(net "M_D_CPU0_SA_DQ<26>")
	)
	(gr_poly
		(pts
			(xy 330.681076 -239.016032) (xy 330.581 -238.915956) (xy 330.480924 -239.016032) (xy 330.480924 -239.060482)
			(xy 330.681076 -239.060482)
		)
		(stroke
			(width 0)
			(type solid)
		)
		(fill yes)
		(layer "In4.Cu")
		(net "M_D_CPU0_SA_DQ<21>")
	)
	(gr_poly
		(pts
			(xy 330.681076 -238.612172) (xy 330.681076 -238.567722) (xy 330.480924 -238.567722) (xy 330.480924 -238.612172)
			(xy 330.581 -238.712248)
		)
		(stroke
			(width 0)
			(type solid)
		)
		(fill yes)
		(layer "In4.Cu")
		(net "M_D_CPU0_SA_DQ<22>")
	)
	(gr_poly
		(pts
			(xy 330.681076 -237.395766) (xy 330.581 -237.295944) (xy 330.480924 -237.395766) (xy 330.480924 -237.443518)
			(xy 330.681076 -237.443518)
		)
		(stroke
			(width 0)
			(type solid)
		)
		(fill yes)
		(layer "In4.Cu")
		(net "M_D_CPU0_SA_DQS_DN<7>")
	)
	(gr_poly
		(pts
			(xy 330.681076 -236.992414) (xy 330.681076 -236.944662) (xy 330.480924 -236.944662) (xy 330.480924 -236.992414)
			(xy 330.581 -237.092236)
		)
		(stroke
			(width 0)
			(type solid)
		)
		(fill yes)
		(layer "In4.Cu")
		(net "M_D_CPU0_SA_DQS_DN<2>")
	)
	(gr_poly
		(pts
			(xy 330.681076 -235.776008) (xy 330.581 -235.675932) (xy 330.480924 -235.776008) (xy 330.480924 -235.820458)
			(xy 330.681076 -235.820458)
		)
		(stroke
			(width 0)
			(type solid)
		)
		(fill yes)
		(layer "In4.Cu")
		(net "M_D_CPU0_SA_DQ<17>")
	)
	(gr_poly
		(pts
			(xy 330.681076 -235.372148) (xy 330.681076 -235.327698) (xy 330.480924 -235.327698) (xy 330.480924 -235.372148)
			(xy 330.581 -235.472224)
		)
		(stroke
			(width 0)
			(type solid)
		)
		(fill yes)
		(layer "In4.Cu")
		(net "M_D_CPU0_SA_DQ<18>")
	)
	(gr_poly
		(pts
			(xy 330.681076 -234.155996) (xy 330.581 -234.05592) (xy 330.480924 -234.155996) (xy 330.480924 -234.200446)
			(xy 330.681076 -234.200446)
		)
		(stroke
			(width 0)
			(type solid)
		)
		(fill yes)
		(layer "In4.Cu")
		(net "M_D_CPU0_SA_DQ<13>")
	)
	(gr_poly
		(pts
			(xy 330.681076 -233.752136) (xy 330.681076 -233.707686) (xy 330.480924 -233.707686) (xy 330.480924 -233.752136)
			(xy 330.581 -233.852212)
		)
		(stroke
			(width 0)
			(type solid)
		)
		(fill yes)
		(layer "In4.Cu")
		(net "M_D_CPU0_SA_DQ<14>")
	)
	(gr_poly
		(pts
			(xy 330.681076 -232.53573) (xy 330.581 -232.435908) (xy 330.480924 -232.53573) (xy 330.480924 -232.583482)
			(xy 330.681076 -232.583482)
		)
		(stroke
			(width 0)
			(type solid)
		)
		(fill yes)
		(layer "In4.Cu")
		(net "M_D_CPU0_SA_DQS_DN<6>")
	)
	(gr_poly
		(pts
			(xy 330.681076 -232.132378) (xy 330.681076 -232.084626) (xy 330.480924 -232.084626) (xy 330.480924 -232.132378)
			(xy 330.581 -232.2322)
		)
		(stroke
			(width 0)
			(type solid)
		)
		(fill yes)
		(layer "In4.Cu")
		(net "M_D_CPU0_SA_DQS_DN<1>")
	)
	(gr_poly
		(pts
			(xy 330.681076 -230.915972) (xy 330.581 -230.815896) (xy 330.480924 -230.915972) (xy 330.480924 -230.960422)
			(xy 330.681076 -230.960422)
		)
		(stroke
			(width 0)
			(type solid)
		)
		(fill yes)
		(layer "In4.Cu")
		(net "M_D_CPU0_SA_DQ<9>")
	)
	(gr_poly
		(pts
			(xy 330.681076 -230.512366) (xy 330.681076 -230.467916) (xy 330.480924 -230.467916) (xy 330.480924 -230.512366)
			(xy 330.581 -230.612188)
		)
		(stroke
			(width 0)
			(type solid)
		)
		(fill yes)
		(layer "In4.Cu")
		(net "M_D_CPU0_SA_DQ<10>")
	)
	(gr_poly
		(pts
			(xy 330.681076 -229.29596) (xy 330.581 -229.195884) (xy 330.480924 -229.29596) (xy 330.480924 -229.34041)
			(xy 330.681076 -229.34041)
		)
		(stroke
			(width 0)
			(type solid)
		)
		(fill yes)
		(layer "In4.Cu")
		(net "M_D_CPU0_SA_DQ<5>")
	)
	(gr_poly
		(pts
			(xy 330.681076 -228.892354) (xy 330.681076 -228.847904) (xy 330.480924 -228.847904) (xy 330.480924 -228.892354)
			(xy 330.581 -228.99243)
		)
		(stroke
			(width 0)
			(type solid)
		)
		(fill yes)
		(layer "In4.Cu")
		(net "M_D_CPU0_SA_DQ<6>")
	)
	(gr_poly
		(pts
			(xy 330.681076 -227.272596) (xy 330.681076 -227.224844) (xy 330.480924 -227.224844) (xy 330.480924 -227.272596)
			(xy 330.581 -227.372418)
		)
		(stroke
			(width 0)
			(type solid)
		)
		(fill yes)
		(layer "In4.Cu")
		(net "M_D_CPU0_SA_DQS_DN<0>")
	)
	(gr_poly
		(pts
			(xy 330.687172 -227.676456) (xy 330.587096 -227.57638) (xy 330.487274 -227.676456) (xy 330.487274 -227.723954)
			(xy 330.687172 -227.723954)
		)
		(stroke
			(width 0)
			(type solid)
		)
		(fill yes)
		(layer "In4.Cu")
		(net "M_D_CPU0_SA_DQS_DN<5>")
	)
	(gr_poly
		(pts
			(xy 330.70038 -225.656394) (xy 330.73721 -225.519742) (xy 330.600558 -225.483166) (xy 330.56195 -225.505518)
			(xy 330.662026 -225.678746)
		)
		(stroke
			(width 0)
			(type solid)
		)
		(fill yes)
		(layer "In4.Cu")
		(net "M_D_CPU0_SA_DQ<1>")
	)
	(gr_poly
		(pts
			(xy 330.70038 -224.036382) (xy 330.73721 -223.89973) (xy 330.600558 -223.863154) (xy 330.56195 -223.885506)
			(xy 330.662026 -224.058734)
		)
		(stroke
			(width 0)
			(type solid)
		)
		(fill yes)
		(layer "In4.Cu")
		(net "M_D_CPU0_SA_DQ<0>")
	)
	(gr_poly
		(pts
			(xy 330.98105 -293.324026) (xy 330.98105 -293.279576) (xy 330.780898 -293.279576) (xy 330.780898 -293.324026)
			(xy 330.880974 -293.424102)
		)
		(stroke
			(width 0)
			(type solid)
		)
		(fill yes)
		(layer "In4.Cu")
		(net "M_D_CPU0_SB_DQ<31>")
	)
	(gr_poly
		(pts
			(xy 330.98105 -292.107874) (xy 330.880974 -292.007798) (xy 330.780898 -292.107874) (xy 330.780898 -292.152324)
			(xy 330.98105 -292.152324)
		)
		(stroke
			(width 0)
			(type solid)
		)
		(fill yes)
		(layer "In4.Cu")
		(net "M_D_CPU0_SB_DQ<28>")
	)
	(gr_poly
		(pts
			(xy 330.98105 -291.704268) (xy 330.98105 -291.656516) (xy 330.780898 -291.656516) (xy 330.780898 -291.704268)
			(xy 330.880974 -291.80409)
		)
		(stroke
			(width 0)
			(type solid)
		)
		(fill yes)
		(layer "In4.Cu")
		(net "M_D_CPU0_SB_DQS_DP<8>")
	)
	(gr_poly
		(pts
			(xy 330.98105 -290.487608) (xy 330.880974 -290.387786) (xy 330.780898 -290.487608) (xy 330.780898 -290.53536)
			(xy 330.98105 -290.53536)
		)
		(stroke
			(width 0)
			(type solid)
		)
		(fill yes)
		(layer "In4.Cu")
		(net "M_D_CPU0_SB_DQS_DP<3>")
	)
	(gr_poly
		(pts
			(xy 330.98105 -290.084002) (xy 330.98105 -290.039552) (xy 330.780898 -290.039552) (xy 330.780898 -290.084002)
			(xy 330.880974 -290.184078)
		)
		(stroke
			(width 0)
			(type solid)
		)
		(fill yes)
		(layer "In4.Cu")
		(net "M_D_CPU0_SB_DQ<27>")
	)
	(gr_poly
		(pts
			(xy 330.98105 -288.86785) (xy 330.880974 -288.767774) (xy 330.780898 -288.86785) (xy 330.780898 -288.9123)
			(xy 330.98105 -288.9123)
		)
		(stroke
			(width 0)
			(type solid)
		)
		(fill yes)
		(layer "In4.Cu")
		(net "M_D_CPU0_SB_DQ<24>")
	)
	(gr_poly
		(pts
			(xy 330.98105 -288.464244) (xy 330.98105 -288.419794) (xy 330.780898 -288.419794) (xy 330.780898 -288.464244)
			(xy 330.880974 -288.56432)
		)
		(stroke
			(width 0)
			(type solid)
		)
		(fill yes)
		(layer "In4.Cu")
		(net "M_D_CPU0_SB_DQ<23>")
	)
	(gr_poly
		(pts
			(xy 330.98105 -287.247838) (xy 330.880974 -287.148016) (xy 330.780898 -287.247838) (xy 330.780898 -287.292288)
			(xy 330.98105 -287.292288)
		)
		(stroke
			(width 0)
			(type solid)
		)
		(fill yes)
		(layer "In4.Cu")
		(net "M_D_CPU0_SB_DQ<20>")
	)
	(gr_poly
		(pts
			(xy 330.98105 -286.844232) (xy 330.98105 -286.79648) (xy 330.780898 -286.79648) (xy 330.780898 -286.844232)
			(xy 330.880974 -286.944308)
		)
		(stroke
			(width 0)
			(type solid)
		)
		(fill yes)
		(layer "In4.Cu")
		(net "M_D_CPU0_SB_DQS_DP<7>")
	)
	(gr_poly
		(pts
			(xy 330.98105 -285.627826) (xy 330.880974 -285.528004) (xy 330.780898 -285.627826) (xy 330.780898 -285.675578)
			(xy 330.98105 -285.675578)
		)
		(stroke
			(width 0)
			(type solid)
		)
		(fill yes)
		(layer "In4.Cu")
		(net "M_D_CPU0_SB_DQS_DP<2>")
	)
	(gr_poly
		(pts
			(xy 330.98105 -285.22422) (xy 330.98105 -285.17977) (xy 330.780898 -285.17977) (xy 330.780898 -285.22422)
			(xy 330.880974 -285.324296)
		)
		(stroke
			(width 0)
			(type solid)
		)
		(fill yes)
		(layer "In4.Cu")
		(net "M_D_CPU0_SB_DQ<19>")
	)
	(gr_poly
		(pts
			(xy 330.98105 -284.008068) (xy 330.880974 -283.907992) (xy 330.780898 -284.008068) (xy 330.780898 -284.052518)
			(xy 330.98105 -284.052518)
		)
		(stroke
			(width 0)
			(type solid)
		)
		(fill yes)
		(layer "In4.Cu")
		(net "M_D_CPU0_SB_DQ<16>")
	)
	(gr_poly
		(pts
			(xy 330.98105 -283.604208) (xy 330.98105 -283.559758) (xy 330.780898 -283.559758) (xy 330.780898 -283.604208)
			(xy 330.880974 -283.704284)
		)
		(stroke
			(width 0)
			(type solid)
		)
		(fill yes)
		(layer "In4.Cu")
		(net "M_D_CPU0_SB_DQ<15>")
	)
	(gr_poly
		(pts
			(xy 330.98105 -282.388056) (xy 330.880974 -282.28798) (xy 330.780898 -282.388056) (xy 330.780898 -282.432506)
			(xy 330.98105 -282.432506)
		)
		(stroke
			(width 0)
			(type solid)
		)
		(fill yes)
		(layer "In4.Cu")
		(net "M_D_CPU0_SB_DQ<12>")
	)
	(gr_poly
		(pts
			(xy 330.98105 -281.98445) (xy 330.98105 -281.936698) (xy 330.780898 -281.936698) (xy 330.780898 -281.98445)
			(xy 330.880974 -282.084272)
		)
		(stroke
			(width 0)
			(type solid)
		)
		(fill yes)
		(layer "In4.Cu")
		(net "M_D_CPU0_SB_DQS_DP<6>")
	)
	(gr_poly
		(pts
			(xy 330.98105 -280.76779) (xy 330.880974 -280.667968) (xy 330.780898 -280.76779) (xy 330.780898 -280.815542)
			(xy 330.98105 -280.815542)
		)
		(stroke
			(width 0)
			(type solid)
		)
		(fill yes)
		(layer "In4.Cu")
		(net "M_D_CPU0_SB_DQS_DP<1>")
	)
	(gr_poly
		(pts
			(xy 330.98105 -280.364184) (xy 330.98105 -280.319734) (xy 330.780898 -280.319734) (xy 330.780898 -280.364184)
			(xy 330.880974 -280.46426)
		)
		(stroke
			(width 0)
			(type solid)
		)
		(fill yes)
		(layer "In4.Cu")
		(net "M_D_CPU0_SB_DQ<11>")
	)
	(gr_poly
		(pts
			(xy 330.98105 -279.148032) (xy 330.880974 -279.047956) (xy 330.780898 -279.148032) (xy 330.780898 -279.192482)
			(xy 330.98105 -279.192482)
		)
		(stroke
			(width 0)
			(type solid)
		)
		(fill yes)
		(layer "In4.Cu")
		(net "M_D_CPU0_SB_DQ<8>")
	)
	(gr_poly
		(pts
			(xy 330.98105 -278.744172) (xy 330.98105 -278.699722) (xy 330.780898 -278.699722) (xy 330.780898 -278.744172)
			(xy 330.880974 -278.844248)
		)
		(stroke
			(width 0)
			(type solid)
		)
		(fill yes)
		(layer "In4.Cu")
		(net "M_D_CPU0_SB_DQ<7>")
	)
	(gr_poly
		(pts
			(xy 330.98105 -277.52802) (xy 330.880974 -277.427944) (xy 330.780898 -277.52802) (xy 330.780898 -277.57247)
			(xy 330.98105 -277.57247)
		)
		(stroke
			(width 0)
			(type solid)
		)
		(fill yes)
		(layer "In4.Cu")
		(net "M_D_CPU0_SB_DQ<4>")
	)
	(gr_poly
		(pts
			(xy 330.98105 -275.504148) (xy 330.98105 -275.459698) (xy 330.780898 -275.459698) (xy 330.780898 -275.504148)
			(xy 330.880974 -275.604224)
		)
		(stroke
			(width 0)
			(type solid)
		)
		(fill yes)
		(layer "In4.Cu")
		(net "M_D_CPU0_SB_DQ<3>")
	)
	(gr_poly
		(pts
			(xy 330.98105 -274.287996) (xy 330.880974 -274.18792) (xy 330.780898 -274.287996) (xy 330.780898 -274.332446)
			(xy 330.98105 -274.332446)
		)
		(stroke
			(width 0)
			(type solid)
		)
		(fill yes)
		(layer "In4.Cu")
		(net "M_D_CPU0_SB_DQ<0>")
	)
	(gr_poly
		(pts
			(xy 330.98105 -273.884136) (xy 330.98105 -273.839686) (xy 330.780898 -273.839686) (xy 330.780898 -273.884136)
			(xy 330.880974 -273.984212)
		)
		(stroke
			(width 0)
			(type solid)
		)
		(fill yes)
		(layer "In4.Cu")
		(net "M_D_CPU0_SB_CB<3>")
	)
	(gr_poly
		(pts
			(xy 330.98105 -272.667984) (xy 330.880974 -272.567908) (xy 330.780898 -272.667984) (xy 330.780898 -272.712434)
			(xy 330.98105 -272.712434)
		)
		(stroke
			(width 0)
			(type solid)
		)
		(fill yes)
		(layer "In4.Cu")
		(net "M_D_CPU0_SB_CB<0>")
	)
	(gr_poly
		(pts
			(xy 330.98105 -272.264378) (xy 330.98105 -272.216626) (xy 330.780898 -272.216626) (xy 330.780898 -272.264378)
			(xy 330.880974 -272.3642)
		)
		(stroke
			(width 0)
			(type solid)
		)
		(fill yes)
		(layer "In4.Cu")
		(net "M_D_CPU0_SB_DQS_DP<4>")
	)
	(gr_poly
		(pts
			(xy 330.98105 -271.047718) (xy 330.880974 -270.947896) (xy 330.780898 -271.047718) (xy 330.780898 -271.09547)
			(xy 330.98105 -271.09547)
		)
		(stroke
			(width 0)
			(type solid)
		)
		(fill yes)
		(layer "In4.Cu")
		(net "M_D_CPU0_SB_DQS_DP<9>")
	)
	(gr_poly
		(pts
			(xy 330.98105 -270.644112) (xy 330.98105 -270.599662) (xy 330.780898 -270.599662) (xy 330.780898 -270.644112)
			(xy 330.880974 -270.744188)
		)
		(stroke
			(width 0)
			(type solid)
		)
		(fill yes)
		(layer "In4.Cu")
		(net "M_D_CPU0_SB_CB<7>")
	)
	(gr_poly
		(pts
			(xy 330.98105 -269.42796) (xy 330.880974 -269.327884) (xy 330.780898 -269.42796) (xy 330.780898 -269.47241)
			(xy 330.98105 -269.47241)
		)
		(stroke
			(width 0)
			(type solid)
		)
		(fill yes)
		(layer "In4.Cu")
		(net "M_D_CPU0_SB_CB<4>")
	)
	(gr_poly
		(pts
			(xy 330.98105 -264.164064) (xy 330.98105 -264.119614) (xy 330.780898 -264.119614) (xy 330.780898 -264.164064)
			(xy 330.880974 -264.26414)
		)
		(stroke
			(width 0)
			(type solid)
		)
		(fill yes)
		(layer "In4.Cu")
		(net "M_D_CPU0_SB_CA<5>")
	)
	(gr_poly
		(pts
			(xy 330.98105 -262.947912) (xy 330.880974 -262.847836) (xy 330.780898 -262.947912) (xy 330.780898 -262.992362)
			(xy 330.98105 -262.992362)
		)
		(stroke
			(width 0)
			(type solid)
		)
		(fill yes)
		(layer "In4.Cu")
		(net "M_D_CPU0_SB_CA<2>")
	)
	(gr_poly
		(pts
			(xy 330.98105 -262.544052) (xy 330.98105 -262.499602) (xy 330.780898 -262.499602) (xy 330.780898 -262.544052)
			(xy 330.880974 -262.644128)
		)
		(stroke
			(width 0)
			(type solid)
		)
		(fill yes)
		(layer "In4.Cu")
		(net "M_D_CPU0_SB_CA<1>")
	)
	(gr_poly
		(pts
			(xy 330.981304 -265.784076) (xy 330.981304 -265.739626) (xy 330.781152 -265.739626) (xy 330.781152 -265.784076)
			(xy 330.881228 -265.884152)
		)
		(stroke
			(width 0)
			(type solid)
		)
		(fill yes)
		(layer "In4.Cu")
		(net "M_D_CPU0_SB_CS_N<0>")
	)
	(gr_poly
		(pts
			(xy 330.981304 -264.567924) (xy 330.881228 -264.467848) (xy 330.781152 -264.567924) (xy 330.781152 -264.612374)
			(xy 330.981304 -264.612374)
		)
		(stroke
			(width 0)
			(type solid)
		)
		(fill yes)
		(layer "In4.Cu")
		(net "M_D_CPU0_SB_CA<6>")
	)
	(gr_poly
		(pts
			(xy 330.987146 -267.801598) (xy 330.887324 -267.701522) (xy 330.787248 -267.801598) (xy 330.787248 -267.846048)
			(xy 330.987146 -267.846048)
		)
		(stroke
			(width 0)
			(type solid)
		)
		(fill yes)
		(layer "In4.Cu")
		(net "M_D_CPU0_SB_RSP<0>")
	)
	(gr_poly
		(pts
			(xy 330.988416 -277.12416) (xy 330.988416 -277.076662) (xy 330.788264 -277.076662) (xy 330.788264 -277.12416)
			(xy 330.88834 -277.224236)
		)
		(stroke
			(width 0)
			(type solid)
		)
		(fill yes)
		(layer "In4.Cu")
		(net "M_D_CPU0_SB_DQS_DP<5>")
	)
	(gr_poly
		(pts
			(xy 330.988416 -275.908008) (xy 330.88834 -275.807932) (xy 330.788264 -275.908008) (xy 330.788264 -275.955506)
			(xy 330.988416 -275.955506)
		)
		(stroke
			(width 0)
			(type solid)
		)
		(fill yes)
		(layer "In4.Cu")
		(net "M_D_CPU0_SB_DQS_DP<0>")
	)
	(gr_poly
		(pts
			(xy 331.070204 -225.392996) (xy 330.970128 -225.219768) (xy 330.931774 -225.24212) (xy 330.895198 -225.378772)
			(xy 331.031596 -225.415348)
		)
		(stroke
			(width 0)
			(type solid)
		)
		(fill yes)
		(layer "In4.Cu")
		(net "M_D_CPU0_SA_DQ<2>")
	)
	(gr_poly
		(pts
			(xy 331.15123 -256.025904) (xy 331.051154 -255.926082) (xy 330.951078 -256.025904) (xy 330.951078 -256.073656)
			(xy 331.15123 -256.073656)
		)
		(stroke
			(width 0)
			(type solid)
		)
		(fill yes)
		(layer "In4.Cu")
		(net "M_D_CPU0_CLK_DP<0>")
	)
	(gr_poly
		(pts
			(xy 331.15123 -255.622298) (xy 331.15123 -255.577848) (xy 330.951078 -255.577848) (xy 330.951078 -255.622298)
			(xy 331.051154 -255.722374)
		)
		(stroke
			(width 0)
			(type solid)
		)
		(fill yes)
		(layer "In4.Cu")
		(net "M_D_CPU0_SA_PAR")
	)
	(gr_poly
		(pts
			(xy 331.15123 -254.406146) (xy 331.051154 -254.30607) (xy 330.951078 -254.406146) (xy 330.951078 -254.450596)
			(xy 331.15123 -254.450596)
		)
		(stroke
			(width 0)
			(type solid)
		)
		(fill yes)
		(layer "In4.Cu")
		(net "M_D_CPU0_SA_CA<4>")
	)
	(gr_poly
		(pts
			(xy 331.15123 -254.002286) (xy 331.15123 -253.957836) (xy 330.951078 -253.957836) (xy 330.951078 -254.002286)
			(xy 331.051154 -254.102362)
		)
		(stroke
			(width 0)
			(type solid)
		)
		(fill yes)
		(layer "In4.Cu")
		(net "M_D_CPU0_SA_CA<3>")
	)
	(gr_poly
		(pts
			(xy 331.15123 -252.786134) (xy 331.051154 -252.686058) (xy 330.951078 -252.786134) (xy 330.951078 -252.830584)
			(xy 331.15123 -252.830584)
		)
		(stroke
			(width 0)
			(type solid)
		)
		(fill yes)
		(layer "In4.Cu")
		(net "M_D_CPU0_SA_CA<0>")
	)
	(gr_poly
		(pts
			(xy 331.15123 -252.382274) (xy 331.15123 -252.337824) (xy 330.951078 -252.337824) (xy 330.951078 -252.382274)
			(xy 331.051154 -252.48235)
		)
		(stroke
			(width 0)
			(type solid)
		)
		(fill yes)
		(layer "In4.Cu")
		(net "M_D_CPU0_SA_CS_N<1>")
	)
	(gr_poly
		(pts
			(xy 331.15123 -250.762262) (xy 331.15123 -250.717812) (xy 330.951078 -250.717812) (xy 330.951078 -250.762262)
			(xy 331.051154 -250.862338)
		)
		(stroke
			(width 0)
			(type solid)
		)
		(fill yes)
		(layer "In4.Cu")
		(net "M_D_CPU0_RESET_N")
	)
	(gr_poly
		(pts
			(xy 331.15123 -249.14225) (xy 331.15123 -249.0978) (xy 330.951078 -249.0978) (xy 330.951078 -249.14225)
			(xy 331.051154 -249.242326)
		)
		(stroke
			(width 0)
			(type solid)
		)
		(fill yes)
		(layer "In4.Cu")
		(net "M_D_CPU0_SA_CB<7>")
	)
	(gr_poly
		(pts
			(xy 331.15123 -247.926098) (xy 331.051154 -247.826022) (xy 330.951078 -247.926098) (xy 330.951078 -247.970548)
			(xy 331.15123 -247.970548)
		)
		(stroke
			(width 0)
			(type solid)
		)
		(fill yes)
		(layer "In4.Cu")
		(net "M_D_CPU0_SA_CB<4>")
	)
	(gr_poly
		(pts
			(xy 331.15123 -247.522492) (xy 331.15123 -247.47474) (xy 330.951078 -247.47474) (xy 330.951078 -247.522492)
			(xy 331.051154 -247.622314)
		)
		(stroke
			(width 0)
			(type solid)
		)
		(fill yes)
		(layer "In4.Cu")
		(net "M_D_CPU0_SA_DQS_DP<9>")
	)
	(gr_poly
		(pts
			(xy 331.15123 -246.305832) (xy 331.051154 -246.20601) (xy 330.951078 -246.305832) (xy 330.951078 -246.353584)
			(xy 331.15123 -246.353584)
		)
		(stroke
			(width 0)
			(type solid)
		)
		(fill yes)
		(layer "In4.Cu")
		(net "M_D_CPU0_SA_DQS_DP<4>")
	)
	(gr_poly
		(pts
			(xy 331.15123 -245.902226) (xy 331.15123 -245.857776) (xy 330.951078 -245.857776) (xy 330.951078 -245.902226)
			(xy 331.051154 -246.002302)
		)
		(stroke
			(width 0)
			(type solid)
		)
		(fill yes)
		(layer "In4.Cu")
		(net "M_D_CPU0_SA_CB<3>")
	)
	(gr_poly
		(pts
			(xy 331.15123 -244.686074) (xy 331.051154 -244.585998) (xy 330.951078 -244.686074) (xy 330.951078 -244.730524)
			(xy 331.15123 -244.730524)
		)
		(stroke
			(width 0)
			(type solid)
		)
		(fill yes)
		(layer "In4.Cu")
		(net "M_D_CPU0_SA_CB<0>")
	)
	(gr_poly
		(pts
			(xy 331.15123 -244.282214) (xy 331.15123 -244.237764) (xy 330.951078 -244.237764) (xy 330.951078 -244.282214)
			(xy 331.051154 -244.38229)
		)
		(stroke
			(width 0)
			(type solid)
		)
		(fill yes)
		(layer "In4.Cu")
		(net "M_D_CPU0_SA_DQ<31>")
	)
	(gr_poly
		(pts
			(xy 331.15123 -243.066062) (xy 331.051154 -242.965986) (xy 330.951078 -243.066062) (xy 330.951078 -243.110512)
			(xy 331.15123 -243.110512)
		)
		(stroke
			(width 0)
			(type solid)
		)
		(fill yes)
		(layer "In4.Cu")
		(net "M_D_CPU0_SA_DQ<28>")
	)
	(gr_poly
		(pts
			(xy 331.15123 -242.662456) (xy 331.15123 -242.614704) (xy 330.951078 -242.614704) (xy 330.951078 -242.662456)
			(xy 331.051154 -242.762278)
		)
		(stroke
			(width 0)
			(type solid)
		)
		(fill yes)
		(layer "In4.Cu")
		(net "M_D_CPU0_SA_DQS_DP<8>")
	)
	(gr_poly
		(pts
			(xy 331.15123 -241.445796) (xy 331.051154 -241.345974) (xy 330.951078 -241.445796) (xy 330.951078 -241.493548)
			(xy 331.15123 -241.493548)
		)
		(stroke
			(width 0)
			(type solid)
		)
		(fill yes)
		(layer "In4.Cu")
		(net "M_D_CPU0_SA_DQS_DP<3>")
	)
	(gr_poly
		(pts
			(xy 331.15123 -241.04219) (xy 331.15123 -240.99774) (xy 330.951078 -240.99774) (xy 330.951078 -241.04219)
			(xy 331.051154 -241.142266)
		)
		(stroke
			(width 0)
			(type solid)
		)
		(fill yes)
		(layer "In4.Cu")
		(net "M_D_CPU0_SA_DQ<27>")
	)
	(gr_poly
		(pts
			(xy 331.15123 -239.826038) (xy 331.051154 -239.725962) (xy 330.951078 -239.826038) (xy 330.951078 -239.870488)
			(xy 331.15123 -239.870488)
		)
		(stroke
			(width 0)
			(type solid)
		)
		(fill yes)
		(layer "In4.Cu")
		(net "M_D_CPU0_SA_DQ<24>")
	)
	(gr_poly
		(pts
			(xy 331.15123 -239.422178) (xy 331.15123 -239.377728) (xy 330.951078 -239.377728) (xy 330.951078 -239.422178)
			(xy 331.051154 -239.522254)
		)
		(stroke
			(width 0)
			(type solid)
		)
		(fill yes)
		(layer "In4.Cu")
		(net "M_D_CPU0_SA_DQ<23>")
	)
	(gr_poly
		(pts
			(xy 331.15123 -238.206026) (xy 331.051154 -238.10595) (xy 330.951078 -238.206026) (xy 330.951078 -238.250476)
			(xy 331.15123 -238.250476)
		)
		(stroke
			(width 0)
			(type solid)
		)
		(fill yes)
		(layer "In4.Cu")
		(net "M_D_CPU0_SA_DQ<20>")
	)
	(gr_poly
		(pts
			(xy 331.15123 -237.80242) (xy 331.15123 -237.754668) (xy 330.951078 -237.754668) (xy 330.951078 -237.80242)
			(xy 331.051154 -237.902242)
		)
		(stroke
			(width 0)
			(type solid)
		)
		(fill yes)
		(layer "In4.Cu")
		(net "M_D_CPU0_SA_DQS_DP<7>")
	)
	(gr_poly
		(pts
			(xy 331.15123 -236.58576) (xy 331.051154 -236.485938) (xy 330.951078 -236.58576) (xy 330.951078 -236.633512)
			(xy 331.15123 -236.633512)
		)
		(stroke
			(width 0)
			(type solid)
		)
		(fill yes)
		(layer "In4.Cu")
		(net "M_D_CPU0_SA_DQS_DP<2>")
	)
	(gr_poly
		(pts
			(xy 331.15123 -236.182154) (xy 331.15123 -236.137704) (xy 330.951078 -236.137704) (xy 330.951078 -236.182154)
			(xy 331.051154 -236.28223)
		)
		(stroke
			(width 0)
			(type solid)
		)
		(fill yes)
		(layer "In4.Cu")
		(net "M_D_CPU0_SA_DQ<19>")
	)
	(gr_poly
		(pts
			(xy 331.15123 -234.966002) (xy 331.051154 -234.865926) (xy 330.951078 -234.966002) (xy 330.951078 -235.010452)
			(xy 331.15123 -235.010452)
		)
		(stroke
			(width 0)
			(type solid)
		)
		(fill yes)
		(layer "In4.Cu")
		(net "M_D_CPU0_SA_DQ<16>")
	)
	(gr_poly
		(pts
			(xy 331.15123 -234.562142) (xy 331.15123 -234.517692) (xy 330.951078 -234.517692) (xy 330.951078 -234.562142)
			(xy 331.051154 -234.662218)
		)
		(stroke
			(width 0)
			(type solid)
		)
		(fill yes)
		(layer "In4.Cu")
		(net "M_D_CPU0_SA_DQ<15>")
	)
	(gr_poly
		(pts
			(xy 331.15123 -233.34599) (xy 331.051154 -233.245914) (xy 330.951078 -233.34599) (xy 330.951078 -233.39044)
			(xy 331.15123 -233.39044)
		)
		(stroke
			(width 0)
			(type solid)
		)
		(fill yes)
		(layer "In4.Cu")
		(net "M_D_CPU0_SA_DQ<12>")
	)
	(gr_poly
		(pts
			(xy 331.15123 -232.942384) (xy 331.15123 -232.894632) (xy 330.951078 -232.894632) (xy 330.951078 -232.942384)
			(xy 331.051154 -233.042206)
		)
		(stroke
			(width 0)
			(type solid)
		)
		(fill yes)
		(layer "In4.Cu")
		(net "M_D_CPU0_SA_DQS_DP<6>")
	)
	(gr_poly
		(pts
			(xy 331.15123 -231.725724) (xy 331.051154 -231.625902) (xy 330.951078 -231.725724) (xy 330.951078 -231.773476)
			(xy 331.15123 -231.773476)
		)
		(stroke
			(width 0)
			(type solid)
		)
		(fill yes)
		(layer "In4.Cu")
		(net "M_D_CPU0_SA_DQS_DP<1>")
	)
	(gr_poly
		(pts
			(xy 331.15123 -231.322372) (xy 331.15123 -231.277922) (xy 330.951078 -231.277922) (xy 330.951078 -231.322372)
			(xy 331.051154 -231.422448)
		)
		(stroke
			(width 0)
			(type solid)
		)
		(fill yes)
		(layer "In4.Cu")
		(net "M_D_CPU0_SA_DQ<11>")
	)
	(gr_poly
		(pts
			(xy 331.15123 -230.105966) (xy 331.051154 -230.006144) (xy 330.951078 -230.105966) (xy 330.951078 -230.150416)
			(xy 331.15123 -230.150416)
		)
		(stroke
			(width 0)
			(type solid)
		)
		(fill yes)
		(layer "In4.Cu")
		(net "M_D_CPU0_SA_DQ<8>")
	)
	(gr_poly
		(pts
			(xy 331.15123 -229.70236) (xy 331.15123 -229.65791) (xy 330.951078 -229.65791) (xy 330.951078 -229.70236)
			(xy 331.051154 -229.802436)
		)
		(stroke
			(width 0)
			(type solid)
		)
		(fill yes)
		(layer "In4.Cu")
		(net "M_D_CPU0_SA_DQ<7>")
	)
	(gr_poly
		(pts
			(xy 331.15123 -228.486208) (xy 331.051154 -228.386132) (xy 330.951078 -228.486208) (xy 330.951078 -228.530658)
			(xy 331.15123 -228.530658)
		)
		(stroke
			(width 0)
			(type solid)
		)
		(fill yes)
		(layer "In4.Cu")
		(net "M_D_CPU0_SA_DQ<4>")
	)
	(gr_poly
		(pts
			(xy 331.15123 -228.082602) (xy 331.15123 -228.03485) (xy 330.951078 -228.03485) (xy 330.951078 -228.082602)
			(xy 331.051154 -228.182424)
		)
		(stroke
			(width 0)
			(type solid)
		)
		(fill yes)
		(layer "In4.Cu")
		(net "M_D_CPU0_SA_DQS_DP<5>")
	)
	(gr_poly
		(pts
			(xy 331.15123 -226.865942) (xy 331.051154 -226.76612) (xy 330.951078 -226.865942) (xy 330.951078 -226.913694)
			(xy 331.15123 -226.913694)
		)
		(stroke
			(width 0)
			(type solid)
		)
		(fill yes)
		(layer "In4.Cu")
		(net "M_D_CPU0_SA_DQS_DP<0>")
	)
	(gr_poly
		(pts
			(xy 331.15123 -226.462336) (xy 331.15123 -226.417886) (xy 330.951078 -226.417886) (xy 330.951078 -226.462336)
			(xy 331.051154 -226.562412)
		)
		(stroke
			(width 0)
			(type solid)
		)
		(fill yes)
		(layer "In4.Cu")
		(net "M_D_CPU0_SA_DQ<3>")
	)
	(gr_poly
		(pts
			(xy 331.17028 -224.846388) (xy 331.20711 -224.709736) (xy 331.070458 -224.67316) (xy 331.03185 -224.695512)
			(xy 331.131926 -224.86874)
		)
		(stroke
			(width 0)
			(type solid)
		)
		(fill yes)
		(layer "In4.Cu")
		(net "M_D_CPU0_SA_DQ<0>")
	)
	(gr_poly
		(pts
			(xy 331.444854 -266.991592) (xy 331.344778 -266.891516) (xy 331.244956 -266.991592) (xy 331.244956 -267.036042)
			(xy 331.444854 -267.036042)
		)
		(stroke
			(width 0)
			(type solid)
		)
		(fill yes)
		(layer "In4.Cu")
		(net "M_D_CPU0_SA_RSP<0>")
	)
	(gr_poly
		(pts
			(xy 331.451204 -292.91788) (xy 331.351128 -292.817804) (xy 331.251052 -292.91788) (xy 331.251052 -292.96233)
			(xy 331.451204 -292.96233)
		)
		(stroke
			(width 0)
			(type solid)
		)
		(fill yes)
		(layer "In4.Cu")
		(net "M_D_CPU0_SB_DQ<29>")
	)
	(gr_poly
		(pts
			(xy 331.451204 -292.51402) (xy 331.451204 -292.46957) (xy 331.251052 -292.46957) (xy 331.251052 -292.51402)
			(xy 331.351128 -292.614096)
		)
		(stroke
			(width 0)
			(type solid)
		)
		(fill yes)
		(layer "In4.Cu")
		(net "M_D_CPU0_SB_DQ<30>")
	)
	(gr_poly
		(pts
			(xy 331.451204 -291.297614) (xy 331.351128 -291.197792) (xy 331.251052 -291.297614) (xy 331.251052 -291.345366)
			(xy 331.451204 -291.345366)
		)
		(stroke
			(width 0)
			(type solid)
		)
		(fill yes)
		(layer "In4.Cu")
		(net "M_D_CPU0_SB_DQS_DN<8>")
	)
	(gr_poly
		(pts
			(xy 331.451204 -290.894262) (xy 331.451204 -290.84651) (xy 331.251052 -290.84651) (xy 331.251052 -290.894262)
			(xy 331.351128 -290.994084)
		)
		(stroke
			(width 0)
			(type solid)
		)
		(fill yes)
		(layer "In4.Cu")
		(net "M_D_CPU0_SB_DQS_DN<3>")
	)
	(gr_poly
		(pts
			(xy 331.451204 -289.677856) (xy 331.351128 -289.57778) (xy 331.251052 -289.677856) (xy 331.251052 -289.722306)
			(xy 331.451204 -289.722306)
		)
		(stroke
			(width 0)
			(type solid)
		)
		(fill yes)
		(layer "In4.Cu")
		(net "M_D_CPU0_SB_DQ<25>")
	)
	(gr_poly
		(pts
			(xy 331.451204 -289.273996) (xy 331.451204 -289.229546) (xy 331.251052 -289.229546) (xy 331.251052 -289.273996)
			(xy 331.351128 -289.374072)
		)
		(stroke
			(width 0)
			(type solid)
		)
		(fill yes)
		(layer "In4.Cu")
		(net "M_D_CPU0_SB_DQ<26>")
	)
	(gr_poly
		(pts
			(xy 331.451204 -288.057844) (xy 331.351128 -287.957768) (xy 331.251052 -288.057844) (xy 331.251052 -288.102294)
			(xy 331.451204 -288.102294)
		)
		(stroke
			(width 0)
			(type solid)
		)
		(fill yes)
		(layer "In4.Cu")
		(net "M_D_CPU0_SB_DQ<21>")
	)
	(gr_poly
		(pts
			(xy 331.451204 -287.654238) (xy 331.451204 -287.609788) (xy 331.251052 -287.609788) (xy 331.251052 -287.654238)
			(xy 331.351128 -287.75406)
		)
		(stroke
			(width 0)
			(type solid)
		)
		(fill yes)
		(layer "In4.Cu")
		(net "M_D_CPU0_SB_DQ<22>")
	)
	(gr_poly
		(pts
			(xy 331.451204 -286.437832) (xy 331.351128 -286.337756) (xy 331.251052 -286.437832) (xy 331.251052 -286.485584)
			(xy 331.451204 -286.485584)
		)
		(stroke
			(width 0)
			(type solid)
		)
		(fill yes)
		(layer "In4.Cu")
		(net "M_D_CPU0_SB_DQS_DN<7>")
	)
	(gr_poly
		(pts
			(xy 331.451204 -286.03448) (xy 331.451204 -285.986728) (xy 331.251052 -285.986728) (xy 331.251052 -286.03448)
			(xy 331.351128 -286.134302)
		)
		(stroke
			(width 0)
			(type solid)
		)
		(fill yes)
		(layer "In4.Cu")
		(net "M_D_CPU0_SB_DQS_DN<2>")
	)
	(gr_poly
		(pts
			(xy 331.451204 -284.818074) (xy 331.351128 -284.717998) (xy 331.251052 -284.818074) (xy 331.251052 -284.862524)
			(xy 331.451204 -284.862524)
		)
		(stroke
			(width 0)
			(type solid)
		)
		(fill yes)
		(layer "In4.Cu")
		(net "M_D_CPU0_SB_DQ<17>")
	)
	(gr_poly
		(pts
			(xy 331.451204 -284.414214) (xy 331.451204 -284.369764) (xy 331.251052 -284.369764) (xy 331.251052 -284.414214)
			(xy 331.351128 -284.51429)
		)
		(stroke
			(width 0)
			(type solid)
		)
		(fill yes)
		(layer "In4.Cu")
		(net "M_D_CPU0_SB_DQ<18>")
	)
	(gr_poly
		(pts
			(xy 331.451204 -283.198062) (xy 331.351128 -283.097986) (xy 331.251052 -283.198062) (xy 331.251052 -283.242512)
			(xy 331.451204 -283.242512)
		)
		(stroke
			(width 0)
			(type solid)
		)
		(fill yes)
		(layer "In4.Cu")
		(net "M_D_CPU0_SB_DQ<13>")
	)
	(gr_poly
		(pts
			(xy 331.451204 -282.794202) (xy 331.451204 -282.749752) (xy 331.251052 -282.749752) (xy 331.251052 -282.794202)
			(xy 331.351128 -282.894278)
		)
		(stroke
			(width 0)
			(type solid)
		)
		(fill yes)
		(layer "In4.Cu")
		(net "M_D_CPU0_SB_DQ<14>")
	)
	(gr_poly
		(pts
			(xy 331.451204 -281.577796) (xy 331.351128 -281.477974) (xy 331.251052 -281.577796) (xy 331.251052 -281.625548)
			(xy 331.451204 -281.625548)
		)
		(stroke
			(width 0)
			(type solid)
		)
		(fill yes)
		(layer "In4.Cu")
		(net "M_D_CPU0_SB_DQS_DN<6>")
	)
	(gr_poly
		(pts
			(xy 331.451204 -281.174444) (xy 331.451204 -281.126692) (xy 331.251052 -281.126692) (xy 331.251052 -281.174444)
			(xy 331.351128 -281.274266)
		)
		(stroke
			(width 0)
			(type solid)
		)
		(fill yes)
		(layer "In4.Cu")
		(net "M_D_CPU0_SB_DQS_DN<1>")
	)
	(gr_poly
		(pts
			(xy 331.451204 -279.958038) (xy 331.351128 -279.857962) (xy 331.251052 -279.958038) (xy 331.251052 -280.002488)
			(xy 331.451204 -280.002488)
		)
		(stroke
			(width 0)
			(type solid)
		)
		(fill yes)
		(layer "In4.Cu")
		(net "M_D_CPU0_SB_DQ<9>")
	)
	(gr_poly
		(pts
			(xy 331.451204 -279.554178) (xy 331.451204 -279.509728) (xy 331.251052 -279.509728) (xy 331.251052 -279.554178)
			(xy 331.351128 -279.654254)
		)
		(stroke
			(width 0)
			(type solid)
		)
		(fill yes)
		(layer "In4.Cu")
		(net "M_D_CPU0_SB_DQ<10>")
	)
	(gr_poly
		(pts
			(xy 331.451204 -278.338026) (xy 331.351128 -278.23795) (xy 331.251052 -278.338026) (xy 331.251052 -278.382476)
			(xy 331.451204 -278.382476)
		)
		(stroke
			(width 0)
			(type solid)
		)
		(fill yes)
		(layer "In4.Cu")
		(net "M_D_CPU0_SB_DQ<5>")
	)
	(gr_poly
		(pts
			(xy 331.451204 -277.934166) (xy 331.451204 -277.889716) (xy 331.251052 -277.889716) (xy 331.251052 -277.934166)
			(xy 331.351128 -278.034242)
		)
		(stroke
			(width 0)
			(type solid)
		)
		(fill yes)
		(layer "In4.Cu")
		(net "M_D_CPU0_SB_DQ<6>")
	)
	(gr_poly
		(pts
			(xy 331.451204 -276.71776) (xy 331.351128 -276.617938) (xy 331.251052 -276.71776) (xy 331.251052 -276.765512)
			(xy 331.451204 -276.765512)
		)
		(stroke
			(width 0)
			(type solid)
		)
		(fill yes)
		(layer "In4.Cu")
		(net "M_D_CPU0_SB_DQS_DN<5>")
	)
	(gr_poly
		(pts
			(xy 331.451204 -276.314408) (xy 331.451204 -276.266656) (xy 331.251052 -276.266656) (xy 331.251052 -276.314408)
			(xy 331.351128 -276.41423)
		)
		(stroke
			(width 0)
			(type solid)
		)
		(fill yes)
		(layer "In4.Cu")
		(net "M_D_CPU0_SB_DQS_DN<0>")
	)
	(gr_poly
		(pts
			(xy 331.451204 -275.098002) (xy 331.351128 -274.997926) (xy 331.251052 -275.098002) (xy 331.251052 -275.142452)
			(xy 331.451204 -275.142452)
		)
		(stroke
			(width 0)
			(type solid)
		)
		(fill yes)
		(layer "In4.Cu")
		(net "M_D_CPU0_SB_DQ<1>")
	)
	(gr_poly
		(pts
			(xy 331.451204 -274.694142) (xy 331.451204 -274.649692) (xy 331.251052 -274.649692) (xy 331.251052 -274.694142)
			(xy 331.351128 -274.794218)
		)
		(stroke
			(width 0)
			(type solid)
		)
		(fill yes)
		(layer "In4.Cu")
		(net "M_D_CPU0_SB_DQ<2>")
	)
	(gr_poly
		(pts
			(xy 331.451204 -273.47799) (xy 331.351128 -273.377914) (xy 331.251052 -273.47799) (xy 331.251052 -273.52244)
			(xy 331.451204 -273.52244)
		)
		(stroke
			(width 0)
			(type solid)
		)
		(fill yes)
		(layer "In4.Cu")
		(net "M_D_CPU0_SB_CB<1>")
	)
	(gr_poly
		(pts
			(xy 331.451204 -273.07413) (xy 331.451204 -273.02968) (xy 331.251052 -273.02968) (xy 331.251052 -273.07413)
			(xy 331.351128 -273.174206)
		)
		(stroke
			(width 0)
			(type solid)
		)
		(fill yes)
		(layer "In4.Cu")
		(net "M_D_CPU0_SB_CB<2>")
	)
	(gr_poly
		(pts
			(xy 331.451204 -271.857724) (xy 331.351128 -271.757902) (xy 331.251052 -271.857724) (xy 331.251052 -271.905476)
			(xy 331.451204 -271.905476)
		)
		(stroke
			(width 0)
			(type solid)
		)
		(fill yes)
		(layer "In4.Cu")
		(net "M_D_CPU0_SB_DQS_DN<4>")
	)
	(gr_poly
		(pts
			(xy 331.451204 -271.454372) (xy 331.451204 -271.40662) (xy 331.251052 -271.40662) (xy 331.251052 -271.454372)
			(xy 331.351128 -271.554194)
		)
		(stroke
			(width 0)
			(type solid)
		)
		(fill yes)
		(layer "In4.Cu")
		(net "M_D_CPU0_SB_DQS_DN<9>")
	)
	(gr_poly
		(pts
			(xy 331.451204 -270.237966) (xy 331.351128 -270.13789) (xy 331.251052 -270.237966) (xy 331.251052 -270.282416)
			(xy 331.451204 -270.282416)
		)
		(stroke
			(width 0)
			(type solid)
		)
		(fill yes)
		(layer "In4.Cu")
		(net "M_D_CPU0_SB_CB<5>")
	)
	(gr_poly
		(pts
			(xy 331.451204 -269.834106) (xy 331.451204 -269.789656) (xy 331.251052 -269.789656) (xy 331.251052 -269.834106)
			(xy 331.351128 -269.934182)
		)
		(stroke
			(width 0)
			(type solid)
		)
		(fill yes)
		(layer "In4.Cu")
		(net "M_D_CPU0_SB_CB<6>")
	)
	(gr_poly
		(pts
			(xy 331.451204 -266.594082) (xy 331.451204 -266.549632) (xy 331.251052 -266.549632) (xy 331.251052 -266.594082)
			(xy 331.351128 -266.694158)
		)
		(stroke
			(width 0)
			(type solid)
		)
		(fill yes)
		(layer "In4.Cu")
		(net "M_D_CPU0_SB_CS_N<1>")
	)
	(gr_poly
		(pts
			(xy 331.451204 -264.97407) (xy 331.451204 -264.92962) (xy 331.251052 -264.92962) (xy 331.251052 -264.97407)
			(xy 331.351128 -265.074146)
		)
		(stroke
			(width 0)
			(type solid)
		)
		(fill yes)
		(layer "In4.Cu")
		(net "M_D_CPU0_SB_PAR")
	)
	(gr_poly
		(pts
			(xy 331.451204 -263.757918) (xy 331.351128 -263.657842) (xy 331.251052 -263.757918) (xy 331.251052 -263.802368)
			(xy 331.451204 -263.802368)
		)
		(stroke
			(width 0)
			(type solid)
		)
		(fill yes)
		(layer "In4.Cu")
		(net "M_D_CPU0_SB_CA<4>")
	)
	(gr_poly
		(pts
			(xy 331.451204 -263.354058) (xy 331.451204 -263.309608) (xy 331.251052 -263.309608) (xy 331.251052 -263.354058)
			(xy 331.351128 -263.454134)
		)
		(stroke
			(width 0)
			(type solid)
		)
		(fill yes)
		(layer "In4.Cu")
		(net "M_D_CPU0_SB_CA<3>")
	)
	(gr_poly
		(pts
			(xy 331.451204 -262.137906) (xy 331.351128 -262.03783) (xy 331.251052 -262.137906) (xy 331.251052 -262.182356)
			(xy 331.451204 -262.182356)
		)
		(stroke
			(width 0)
			(type solid)
		)
		(fill yes)
		(layer "In4.Cu")
		(net "M_D_CPU0_SB_CA<0>")
	)
	(gr_poly
		(pts
			(xy 331.62113 -256.432558) (xy 331.62113 -256.384806) (xy 331.420978 -256.384806) (xy 331.420978 -256.432558)
			(xy 331.521054 -256.53238)
		)
		(stroke
			(width 0)
			(type solid)
		)
		(fill yes)
		(layer "In4.Cu")
		(net "M_D_CPU0_CLK_DN<0>")
	)
	(gr_poly
		(pts
			(xy 331.62113 -255.216152) (xy 331.521054 -255.116076) (xy 331.420978 -255.216152) (xy 331.420978 -255.260602)
			(xy 331.62113 -255.260602)
		)
		(stroke
			(width 0)
			(type solid)
		)
		(fill yes)
		(layer "In4.Cu")
		(net "M_D_CPU0_SA_CA<6>")
	)
	(gr_poly
		(pts
			(xy 331.62113 -254.812292) (xy 331.62113 -254.767842) (xy 331.420978 -254.767842) (xy 331.420978 -254.812292)
			(xy 331.521054 -254.912368)
		)
		(stroke
			(width 0)
			(type solid)
		)
		(fill yes)
		(layer "In4.Cu")
		(net "M_D_CPU0_SA_CA<5>")
	)
	(gr_poly
		(pts
			(xy 331.62113 -253.59614) (xy 331.521054 -253.496064) (xy 331.420978 -253.59614) (xy 331.420978 -253.64059)
			(xy 331.62113 -253.64059)
		)
		(stroke
			(width 0)
			(type solid)
		)
		(fill yes)
		(layer "In4.Cu")
		(net "M_D_CPU0_SA_CA<2>")
	)
	(gr_poly
		(pts
			(xy 331.62113 -253.19228) (xy 331.62113 -253.14783) (xy 331.420978 -253.14783) (xy 331.420978 -253.19228)
			(xy 331.521054 -253.292356)
		)
		(stroke
			(width 0)
			(type solid)
		)
		(fill yes)
		(layer "In4.Cu")
		(net "M_D_CPU0_SA_CA<1>")
	)
	(gr_poly
		(pts
			(xy 331.62113 -251.572268) (xy 331.62113 -251.527818) (xy 331.420978 -251.527818) (xy 331.420978 -251.572268)
			(xy 331.521054 -251.672344)
		)
		(stroke
			(width 0)
			(type solid)
		)
		(fill yes)
		(layer "In4.Cu")
		(net "M_D_CPU0_SA_CS_N<0>")
	)
	(gr_poly
		(pts
			(xy 331.62113 -250.356116) (xy 331.521054 -250.25604) (xy 331.420978 -250.356116) (xy 331.420978 -250.400566)
			(xy 331.62113 -250.400566)
		)
		(stroke
			(width 0)
			(type solid)
		)
		(fill yes)
		(layer "In4.Cu")
		(net "M_D_CPU0_ALERT_R_N")
	)
	(gr_poly
		(pts
			(xy 331.62113 -248.736104) (xy 331.521054 -248.636028) (xy 331.420978 -248.736104) (xy 331.420978 -248.780554)
			(xy 331.62113 -248.780554)
		)
		(stroke
			(width 0)
			(type solid)
		)
		(fill yes)
		(layer "In4.Cu")
		(net "M_D_CPU0_SA_CB<5>")
	)
	(gr_poly
		(pts
			(xy 331.62113 -248.332244) (xy 331.62113 -248.287794) (xy 331.420978 -248.287794) (xy 331.420978 -248.332244)
			(xy 331.521054 -248.43232)
		)
		(stroke
			(width 0)
			(type solid)
		)
		(fill yes)
		(layer "In4.Cu")
		(net "M_D_CPU0_SA_CB<6>")
	)
	(gr_poly
		(pts
			(xy 331.62113 -247.115838) (xy 331.521054 -247.016016) (xy 331.420978 -247.115838) (xy 331.420978 -247.16359)
			(xy 331.62113 -247.16359)
		)
		(stroke
			(width 0)
			(type solid)
		)
		(fill yes)
		(layer "In4.Cu")
		(net "M_D_CPU0_SA_DQS_DN<9>")
	)
	(gr_poly
		(pts
			(xy 331.62113 -246.712486) (xy 331.62113 -246.664734) (xy 331.420978 -246.664734) (xy 331.420978 -246.712486)
			(xy 331.521054 -246.812308)
		)
		(stroke
			(width 0)
			(type solid)
		)
		(fill yes)
		(layer "In4.Cu")
		(net "M_D_CPU0_SA_DQS_DN<4>")
	)
	(gr_poly
		(pts
			(xy 331.62113 -245.49608) (xy 331.521054 -245.396004) (xy 331.420978 -245.49608) (xy 331.420978 -245.54053)
			(xy 331.62113 -245.54053)
		)
		(stroke
			(width 0)
			(type solid)
		)
		(fill yes)
		(layer "In4.Cu")
		(net "M_D_CPU0_SA_CB<1>")
	)
	(gr_poly
		(pts
			(xy 331.62113 -245.09222) (xy 331.62113 -245.04777) (xy 331.420978 -245.04777) (xy 331.420978 -245.09222)
			(xy 331.521054 -245.192296)
		)
		(stroke
			(width 0)
			(type solid)
		)
		(fill yes)
		(layer "In4.Cu")
		(net "M_D_CPU0_SA_CB<2>")
	)
	(gr_poly
		(pts
			(xy 331.62113 -243.876068) (xy 331.521054 -243.775992) (xy 331.420978 -243.876068) (xy 331.420978 -243.920518)
			(xy 331.62113 -243.920518)
		)
		(stroke
			(width 0)
			(type solid)
		)
		(fill yes)
		(layer "In4.Cu")
		(net "M_D_CPU0_SA_DQ<29>")
	)
	(gr_poly
		(pts
			(xy 331.62113 -243.472208) (xy 331.62113 -243.427758) (xy 331.420978 -243.427758) (xy 331.420978 -243.472208)
			(xy 331.521054 -243.572284)
		)
		(stroke
			(width 0)
			(type solid)
		)
		(fill yes)
		(layer "In4.Cu")
		(net "M_D_CPU0_SA_DQ<30>")
	)
	(gr_poly
		(pts
			(xy 331.62113 -242.255802) (xy 331.521054 -242.15598) (xy 331.420978 -242.255802) (xy 331.420978 -242.303554)
			(xy 331.62113 -242.303554)
		)
		(stroke
			(width 0)
			(type solid)
		)
		(fill yes)
		(layer "In4.Cu")
		(net "M_D_CPU0_SA_DQS_DN<8>")
	)
	(gr_poly
		(pts
			(xy 331.62113 -241.85245) (xy 331.62113 -241.804698) (xy 331.420978 -241.804698) (xy 331.420978 -241.85245)
			(xy 331.521054 -241.952272)
		)
		(stroke
			(width 0)
			(type solid)
		)
		(fill yes)
		(layer "In4.Cu")
		(net "M_D_CPU0_SA_DQS_DN<3>")
	)
	(gr_poly
		(pts
			(xy 331.62113 -240.636044) (xy 331.521054 -240.535968) (xy 331.420978 -240.636044) (xy 331.420978 -240.680494)
			(xy 331.62113 -240.680494)
		)
		(stroke
			(width 0)
			(type solid)
		)
		(fill yes)
		(layer "In4.Cu")
		(net "M_D_CPU0_SA_DQ<25>")
	)
	(gr_poly
		(pts
			(xy 331.62113 -240.232184) (xy 331.62113 -240.187734) (xy 331.420978 -240.187734) (xy 331.420978 -240.232184)
			(xy 331.521054 -240.33226)
		)
		(stroke
			(width 0)
			(type solid)
		)
		(fill yes)
		(layer "In4.Cu")
		(net "M_D_CPU0_SA_DQ<26>")
	)
	(gr_poly
		(pts
			(xy 331.62113 -239.016032) (xy 331.521054 -238.915956) (xy 331.420978 -239.016032) (xy 331.420978 -239.060482)
			(xy 331.62113 -239.060482)
		)
		(stroke
			(width 0)
			(type solid)
		)
		(fill yes)
		(layer "In4.Cu")
		(net "M_D_CPU0_SA_DQ<21>")
	)
	(gr_poly
		(pts
			(xy 331.62113 -238.612172) (xy 331.62113 -238.567722) (xy 331.420978 -238.567722) (xy 331.420978 -238.612172)
			(xy 331.521054 -238.712248)
		)
		(stroke
			(width 0)
			(type solid)
		)
		(fill yes)
		(layer "In4.Cu")
		(net "M_D_CPU0_SA_DQ<22>")
	)
	(gr_poly
		(pts
			(xy 331.62113 -237.395766) (xy 331.521054 -237.295944) (xy 331.420978 -237.395766) (xy 331.420978 -237.443518)
			(xy 331.62113 -237.443518)
		)
		(stroke
			(width 0)
			(type solid)
		)
		(fill yes)
		(layer "In4.Cu")
		(net "M_D_CPU0_SA_DQS_DN<7>")
	)
	(gr_poly
		(pts
			(xy 331.62113 -236.992414) (xy 331.62113 -236.944662) (xy 331.420978 -236.944662) (xy 331.420978 -236.992414)
			(xy 331.521054 -237.092236)
		)
		(stroke
			(width 0)
			(type solid)
		)
		(fill yes)
		(layer "In4.Cu")
		(net "M_D_CPU0_SA_DQS_DN<2>")
	)
	(gr_poly
		(pts
			(xy 331.62113 -235.776008) (xy 331.521054 -235.675932) (xy 331.420978 -235.776008) (xy 331.420978 -235.820458)
			(xy 331.62113 -235.820458)
		)
		(stroke
			(width 0)
			(type solid)
		)
		(fill yes)
		(layer "In4.Cu")
		(net "M_D_CPU0_SA_DQ<17>")
	)
	(gr_poly
		(pts
			(xy 331.62113 -235.372148) (xy 331.62113 -235.327698) (xy 331.420978 -235.327698) (xy 331.420978 -235.372148)
			(xy 331.521054 -235.472224)
		)
		(stroke
			(width 0)
			(type solid)
		)
		(fill yes)
		(layer "In4.Cu")
		(net "M_D_CPU0_SA_DQ<18>")
	)
	(gr_poly
		(pts
			(xy 331.62113 -234.155996) (xy 331.521054 -234.05592) (xy 331.420978 -234.155996) (xy 331.420978 -234.200446)
			(xy 331.62113 -234.200446)
		)
		(stroke
			(width 0)
			(type solid)
		)
		(fill yes)
		(layer "In4.Cu")
		(net "M_D_CPU0_SA_DQ<13>")
	)
	(gr_poly
		(pts
			(xy 331.62113 -233.752136) (xy 331.62113 -233.707686) (xy 331.420978 -233.707686) (xy 331.420978 -233.752136)
			(xy 331.521054 -233.852212)
		)
		(stroke
			(width 0)
			(type solid)
		)
		(fill yes)
		(layer "In4.Cu")
		(net "M_D_CPU0_SA_DQ<14>")
	)
	(gr_poly
		(pts
			(xy 331.62113 -232.53573) (xy 331.521054 -232.435908) (xy 331.420978 -232.53573) (xy 331.420978 -232.583482)
			(xy 331.62113 -232.583482)
		)
		(stroke
			(width 0)
			(type solid)
		)
		(fill yes)
		(layer "In4.Cu")
		(net "M_D_CPU0_SA_DQS_DN<6>")
	)
	(gr_poly
		(pts
			(xy 331.62113 -232.132378) (xy 331.62113 -232.084626) (xy 331.420978 -232.084626) (xy 331.420978 -232.132378)
			(xy 331.521054 -232.2322)
		)
		(stroke
			(width 0)
			(type solid)
		)
		(fill yes)
		(layer "In4.Cu")
		(net "M_D_CPU0_SA_DQS_DN<1>")
	)
	(gr_poly
		(pts
			(xy 331.62113 -230.915972) (xy 331.521054 -230.815896) (xy 331.420978 -230.915972) (xy 331.420978 -230.960422)
			(xy 331.62113 -230.960422)
		)
		(stroke
			(width 0)
			(type solid)
		)
		(fill yes)
		(layer "In4.Cu")
		(net "M_D_CPU0_SA_DQ<9>")
	)
	(gr_poly
		(pts
			(xy 331.62113 -230.512366) (xy 331.62113 -230.467916) (xy 331.420978 -230.467916) (xy 331.420978 -230.512366)
			(xy 331.521054 -230.612188)
		)
		(stroke
			(width 0)
			(type solid)
		)
		(fill yes)
		(layer "In4.Cu")
		(net "M_D_CPU0_SA_DQ<10>")
	)
	(gr_poly
		(pts
			(xy 331.62113 -229.29596) (xy 331.521054 -229.195884) (xy 331.420978 -229.29596) (xy 331.420978 -229.34041)
			(xy 331.62113 -229.34041)
		)
		(stroke
			(width 0)
			(type solid)
		)
		(fill yes)
		(layer "In4.Cu")
		(net "M_D_CPU0_SA_DQ<5>")
	)
	(gr_poly
		(pts
			(xy 331.62113 -228.892354) (xy 331.62113 -228.847904) (xy 331.420978 -228.847904) (xy 331.420978 -228.892354)
			(xy 331.521054 -228.99243)
		)
		(stroke
			(width 0)
			(type solid)
		)
		(fill yes)
		(layer "In4.Cu")
		(net "M_D_CPU0_SA_DQ<6>")
	)
	(gr_poly
		(pts
			(xy 331.62113 -227.272596) (xy 331.62113 -227.224844) (xy 331.420978 -227.224844) (xy 331.420978 -227.272596)
			(xy 331.521054 -227.372418)
		)
		(stroke
			(width 0)
			(type solid)
		)
		(fill yes)
		(layer "In4.Cu")
		(net "M_D_CPU0_SA_DQS_DN<0>")
	)
	(gr_poly
		(pts
			(xy 331.62113 -226.05619) (xy 331.521054 -225.956114) (xy 331.420978 -226.05619) (xy 331.420978 -226.10064)
			(xy 331.62113 -226.10064)
		)
		(stroke
			(width 0)
			(type solid)
		)
		(fill yes)
		(layer "In4.Cu")
		(net "M_D_CPU0_SA_DQ<1>")
	)
	(gr_poly
		(pts
			(xy 331.62113 -225.65233) (xy 331.62113 -225.60788) (xy 331.420978 -225.60788) (xy 331.420978 -225.65233)
			(xy 331.521054 -225.752406)
		)
		(stroke
			(width 0)
			(type solid)
		)
		(fill yes)
		(layer "In4.Cu")
		(net "M_D_CPU0_SA_DQ<2>")
	)
	(gr_poly
		(pts
			(xy 331.627226 -227.676456) (xy 331.52715 -227.57638) (xy 331.427074 -227.676456) (xy 331.427074 -227.723954)
			(xy 331.627226 -227.723954)
		)
		(stroke
			(width 0)
			(type solid)
		)
		(fill yes)
		(layer "In4.Cu")
		(net "M_D_CPU0_SA_DQS_DN<5>")
	)
	(gr_poly
		(pts
			(xy 331.921104 -293.324026) (xy 331.921104 -293.279576) (xy 331.720952 -293.279576) (xy 331.720952 -293.324026)
			(xy 331.821028 -293.424102)
		)
		(stroke
			(width 0)
			(type solid)
		)
		(fill yes)
		(layer "In4.Cu")
		(net "M_D_CPU0_SB_DQ<31>")
	)
	(gr_poly
		(pts
			(xy 331.921104 -292.107874) (xy 331.821028 -292.007798) (xy 331.720952 -292.107874) (xy 331.720952 -292.152324)
			(xy 331.921104 -292.152324)
		)
		(stroke
			(width 0)
			(type solid)
		)
		(fill yes)
		(layer "In4.Cu")
		(net "M_D_CPU0_SB_DQ<28>")
	)
	(gr_poly
		(pts
			(xy 331.921104 -291.704268) (xy 331.921104 -291.656516) (xy 331.720952 -291.656516) (xy 331.720952 -291.704268)
			(xy 331.821028 -291.80409)
		)
		(stroke
			(width 0)
			(type solid)
		)
		(fill yes)
		(layer "In4.Cu")
		(net "M_D_CPU0_SB_DQS_DP<8>")
	)
	(gr_poly
		(pts
			(xy 331.921104 -290.487608) (xy 331.821028 -290.387786) (xy 331.720952 -290.487608) (xy 331.720952 -290.53536)
			(xy 331.921104 -290.53536)
		)
		(stroke
			(width 0)
			(type solid)
		)
		(fill yes)
		(layer "In4.Cu")
		(net "M_D_CPU0_SB_DQS_DP<3>")
	)
	(gr_poly
		(pts
			(xy 331.921104 -290.084002) (xy 331.921104 -290.039552) (xy 331.720952 -290.039552) (xy 331.720952 -290.084002)
			(xy 331.821028 -290.184078)
		)
		(stroke
			(width 0)
			(type solid)
		)
		(fill yes)
		(layer "In4.Cu")
		(net "M_D_CPU0_SB_DQ<27>")
	)
	(gr_poly
		(pts
			(xy 331.921104 -288.86785) (xy 331.821028 -288.767774) (xy 331.720952 -288.86785) (xy 331.720952 -288.9123)
			(xy 331.921104 -288.9123)
		)
		(stroke
			(width 0)
			(type solid)
		)
		(fill yes)
		(layer "In4.Cu")
		(net "M_D_CPU0_SB_DQ<24>")
	)
	(gr_poly
		(pts
			(xy 331.921104 -288.464244) (xy 331.921104 -288.419794) (xy 331.720952 -288.419794) (xy 331.720952 -288.464244)
			(xy 331.821028 -288.56432)
		)
		(stroke
			(width 0)
			(type solid)
		)
		(fill yes)
		(layer "In4.Cu")
		(net "M_D_CPU0_SB_DQ<23>")
	)
	(gr_poly
		(pts
			(xy 331.921104 -287.247838) (xy 331.821028 -287.148016) (xy 331.720952 -287.247838) (xy 331.720952 -287.292288)
			(xy 331.921104 -287.292288)
		)
		(stroke
			(width 0)
			(type solid)
		)
		(fill yes)
		(layer "In4.Cu")
		(net "M_D_CPU0_SB_DQ<20>")
	)
	(gr_poly
		(pts
			(xy 331.921104 -286.844232) (xy 331.921104 -286.79648) (xy 331.720952 -286.79648) (xy 331.720952 -286.844232)
			(xy 331.821028 -286.944308)
		)
		(stroke
			(width 0)
			(type solid)
		)
		(fill yes)
		(layer "In4.Cu")
		(net "M_D_CPU0_SB_DQS_DP<7>")
	)
	(gr_poly
		(pts
			(xy 331.921104 -285.627826) (xy 331.821028 -285.528004) (xy 331.720952 -285.627826) (xy 331.720952 -285.675578)
			(xy 331.921104 -285.675578)
		)
		(stroke
			(width 0)
			(type solid)
		)
		(fill yes)
		(layer "In4.Cu")
		(net "M_D_CPU0_SB_DQS_DP<2>")
	)
	(gr_poly
		(pts
			(xy 331.921104 -285.22422) (xy 331.921104 -285.17977) (xy 331.720952 -285.17977) (xy 331.720952 -285.22422)
			(xy 331.821028 -285.324296)
		)
		(stroke
			(width 0)
			(type solid)
		)
		(fill yes)
		(layer "In4.Cu")
		(net "M_D_CPU0_SB_DQ<19>")
	)
	(gr_poly
		(pts
			(xy 331.921104 -284.008068) (xy 331.821028 -283.907992) (xy 331.720952 -284.008068) (xy 331.720952 -284.052518)
			(xy 331.921104 -284.052518)
		)
		(stroke
			(width 0)
			(type solid)
		)
		(fill yes)
		(layer "In4.Cu")
		(net "M_D_CPU0_SB_DQ<16>")
	)
	(gr_poly
		(pts
			(xy 331.921104 -283.604208) (xy 331.921104 -283.559758) (xy 331.720952 -283.559758) (xy 331.720952 -283.604208)
			(xy 331.821028 -283.704284)
		)
		(stroke
			(width 0)
			(type solid)
		)
		(fill yes)
		(layer "In4.Cu")
		(net "M_D_CPU0_SB_DQ<15>")
	)
	(gr_poly
		(pts
			(xy 331.921104 -282.388056) (xy 331.821028 -282.28798) (xy 331.720952 -282.388056) (xy 331.720952 -282.432506)
			(xy 331.921104 -282.432506)
		)
		(stroke
			(width 0)
			(type solid)
		)
		(fill yes)
		(layer "In4.Cu")
		(net "M_D_CPU0_SB_DQ<12>")
	)
	(gr_poly
		(pts
			(xy 331.921104 -281.98445) (xy 331.921104 -281.936698) (xy 331.720952 -281.936698) (xy 331.720952 -281.98445)
			(xy 331.821028 -282.084272)
		)
		(stroke
			(width 0)
			(type solid)
		)
		(fill yes)
		(layer "In4.Cu")
		(net "M_D_CPU0_SB_DQS_DP<6>")
	)
	(gr_poly
		(pts
			(xy 331.921104 -280.76779) (xy 331.821028 -280.667968) (xy 331.720952 -280.76779) (xy 331.720952 -280.815542)
			(xy 331.921104 -280.815542)
		)
		(stroke
			(width 0)
			(type solid)
		)
		(fill yes)
		(layer "In4.Cu")
		(net "M_D_CPU0_SB_DQS_DP<1>")
	)
	(gr_poly
		(pts
			(xy 331.921104 -280.364184) (xy 331.921104 -280.319734) (xy 331.720952 -280.319734) (xy 331.720952 -280.364184)
			(xy 331.821028 -280.46426)
		)
		(stroke
			(width 0)
			(type solid)
		)
		(fill yes)
		(layer "In4.Cu")
		(net "M_D_CPU0_SB_DQ<11>")
	)
	(gr_poly
		(pts
			(xy 331.921104 -279.148032) (xy 331.821028 -279.047956) (xy 331.720952 -279.148032) (xy 331.720952 -279.192482)
			(xy 331.921104 -279.192482)
		)
		(stroke
			(width 0)
			(type solid)
		)
		(fill yes)
		(layer "In4.Cu")
		(net "M_D_CPU0_SB_DQ<8>")
	)
	(gr_poly
		(pts
			(xy 331.921104 -278.744172) (xy 331.921104 -278.699722) (xy 331.720952 -278.699722) (xy 331.720952 -278.744172)
			(xy 331.821028 -278.844248)
		)
		(stroke
			(width 0)
			(type solid)
		)
		(fill yes)
		(layer "In4.Cu")
		(net "M_D_CPU0_SB_DQ<7>")
	)
	(gr_poly
		(pts
			(xy 331.921104 -277.52802) (xy 331.821028 -277.427944) (xy 331.720952 -277.52802) (xy 331.720952 -277.57247)
			(xy 331.921104 -277.57247)
		)
		(stroke
			(width 0)
			(type solid)
		)
		(fill yes)
		(layer "In4.Cu")
		(net "M_D_CPU0_SB_DQ<4>")
	)
	(gr_poly
		(pts
			(xy 331.921104 -275.504148) (xy 331.921104 -275.459698) (xy 331.720952 -275.459698) (xy 331.720952 -275.504148)
			(xy 331.821028 -275.604224)
		)
		(stroke
			(width 0)
			(type solid)
		)
		(fill yes)
		(layer "In4.Cu")
		(net "M_D_CPU0_SB_DQ<3>")
	)
	(gr_poly
		(pts
			(xy 331.921104 -274.287996) (xy 331.821028 -274.18792) (xy 331.720952 -274.287996) (xy 331.720952 -274.332446)
			(xy 331.921104 -274.332446)
		)
		(stroke
			(width 0)
			(type solid)
		)
		(fill yes)
		(layer "In4.Cu")
		(net "M_D_CPU0_SB_DQ<0>")
	)
	(gr_poly
		(pts
			(xy 331.921104 -273.884136) (xy 331.921104 -273.839686) (xy 331.720952 -273.839686) (xy 331.720952 -273.884136)
			(xy 331.821028 -273.984212)
		)
		(stroke
			(width 0)
			(type solid)
		)
		(fill yes)
		(layer "In4.Cu")
		(net "M_D_CPU0_SB_CB<3>")
	)
	(gr_poly
		(pts
			(xy 331.921104 -272.667984) (xy 331.821028 -272.567908) (xy 331.720952 -272.667984) (xy 331.720952 -272.712434)
			(xy 331.921104 -272.712434)
		)
		(stroke
			(width 0)
			(type solid)
		)
		(fill yes)
		(layer "In4.Cu")
		(net "M_D_CPU0_SB_CB<0>")
	)
	(gr_poly
		(pts
			(xy 331.921104 -272.264378) (xy 331.921104 -272.216626) (xy 331.720952 -272.216626) (xy 331.720952 -272.264378)
			(xy 331.821028 -272.3642)
		)
		(stroke
			(width 0)
			(type solid)
		)
		(fill yes)
		(layer "In4.Cu")
		(net "M_D_CPU0_SB_DQS_DP<4>")
	)
	(gr_poly
		(pts
			(xy 331.921104 -271.047718) (xy 331.821028 -270.947896) (xy 331.720952 -271.047718) (xy 331.720952 -271.09547)
			(xy 331.921104 -271.09547)
		)
		(stroke
			(width 0)
			(type solid)
		)
		(fill yes)
		(layer "In4.Cu")
		(net "M_D_CPU0_SB_DQS_DP<9>")
	)
	(gr_poly
		(pts
			(xy 331.921104 -270.644112) (xy 331.921104 -270.599662) (xy 331.720952 -270.599662) (xy 331.720952 -270.644112)
			(xy 331.821028 -270.744188)
		)
		(stroke
			(width 0)
			(type solid)
		)
		(fill yes)
		(layer "In4.Cu")
		(net "M_D_CPU0_SB_CB<7>")
	)
	(gr_poly
		(pts
			(xy 331.921104 -269.42796) (xy 331.821028 -269.327884) (xy 331.720952 -269.42796) (xy 331.720952 -269.47241)
			(xy 331.921104 -269.47241)
		)
		(stroke
			(width 0)
			(type solid)
		)
		(fill yes)
		(layer "In4.Cu")
		(net "M_D_CPU0_SB_CB<4>")
	)
	(gr_poly
		(pts
			(xy 331.921104 -265.784076) (xy 331.921104 -265.739626) (xy 331.720952 -265.739626) (xy 331.720952 -265.784076)
			(xy 331.821028 -265.884152)
		)
		(stroke
			(width 0)
			(type solid)
		)
		(fill yes)
		(layer "In4.Cu")
		(net "M_D_CPU0_SB_CS_N<0>")
	)
	(gr_poly
		(pts
			(xy 331.921104 -264.567924) (xy 331.821028 -264.467848) (xy 331.720952 -264.567924) (xy 331.720952 -264.612374)
			(xy 331.921104 -264.612374)
		)
		(stroke
			(width 0)
			(type solid)
		)
		(fill yes)
		(layer "In4.Cu")
		(net "M_D_CPU0_SB_CA<6>")
	)
	(gr_poly
		(pts
			(xy 331.921104 -264.164064) (xy 331.921104 -264.119614) (xy 331.720952 -264.119614) (xy 331.720952 -264.164064)
			(xy 331.821028 -264.26414)
		)
		(stroke
			(width 0)
			(type solid)
		)
		(fill yes)
		(layer "In4.Cu")
		(net "M_D_CPU0_SB_CA<5>")
	)
	(gr_poly
		(pts
			(xy 331.921104 -262.947912) (xy 331.821028 -262.847836) (xy 331.720952 -262.947912) (xy 331.720952 -262.992362)
			(xy 331.921104 -262.992362)
		)
		(stroke
			(width 0)
			(type solid)
		)
		(fill yes)
		(layer "In4.Cu")
		(net "M_D_CPU0_SB_CA<2>")
	)
	(gr_poly
		(pts
			(xy 331.921104 -262.544052) (xy 331.921104 -262.499602) (xy 331.720952 -262.499602) (xy 331.720952 -262.544052)
			(xy 331.821028 -262.644128)
		)
		(stroke
			(width 0)
			(type solid)
		)
		(fill yes)
		(layer "In4.Cu")
		(net "M_D_CPU0_SB_CA<1>")
	)
	(gr_poly
		(pts
			(xy 331.9272 -267.801598) (xy 331.827378 -267.701522) (xy 331.727302 -267.801598) (xy 331.727302 -267.846048)
			(xy 331.9272 -267.846048)
		)
		(stroke
			(width 0)
			(type solid)
		)
		(fill yes)
		(layer "In4.Cu")
		(net "M_D_CPU0_SB_RSP<0>")
	)
	(gr_poly
		(pts
			(xy 331.92847 -277.12416) (xy 331.92847 -277.076662) (xy 331.728318 -277.076662) (xy 331.728318 -277.12416)
			(xy 331.828394 -277.224236)
		)
		(stroke
			(width 0)
			(type solid)
		)
		(fill yes)
		(layer "In4.Cu")
		(net "M_D_CPU0_SB_DQS_DP<5>")
	)
	(gr_poly
		(pts
			(xy 331.92847 -275.908008) (xy 331.828394 -275.807932) (xy 331.728318 -275.908008) (xy 331.728318 -275.955506)
			(xy 331.92847 -275.955506)
		)
		(stroke
			(width 0)
			(type solid)
		)
		(fill yes)
		(layer "In4.Cu")
		(net "M_D_CPU0_SB_DQS_DP<0>")
	)
	(gr_poly
		(pts
			(xy 332.091284 -256.025904) (xy 331.991208 -255.926082) (xy 331.891132 -256.025904) (xy 331.891132 -256.073656)
			(xy 332.091284 -256.073656)
		)
		(stroke
			(width 0)
			(type solid)
		)
		(fill yes)
		(layer "In4.Cu")
		(net "M_D_CPU0_CLK_DP<0>")
	)
	(gr_poly
		(pts
			(xy 332.091284 -255.622298) (xy 332.091284 -255.577848) (xy 331.891132 -255.577848) (xy 331.891132 -255.622298)
			(xy 331.991208 -255.722374)
		)
		(stroke
			(width 0)
			(type solid)
		)
		(fill yes)
		(layer "In4.Cu")
		(net "M_D_CPU0_SA_PAR")
	)
	(gr_poly
		(pts
			(xy 332.091284 -254.406146) (xy 331.991208 -254.30607) (xy 331.891132 -254.406146) (xy 331.891132 -254.450596)
			(xy 332.091284 -254.450596)
		)
		(stroke
			(width 0)
			(type solid)
		)
		(fill yes)
		(layer "In4.Cu")
		(net "M_D_CPU0_SA_CA<4>")
	)
	(gr_poly
		(pts
			(xy 332.091284 -254.002286) (xy 332.091284 -253.957836) (xy 331.891132 -253.957836) (xy 331.891132 -254.002286)
			(xy 331.991208 -254.102362)
		)
		(stroke
			(width 0)
			(type solid)
		)
		(fill yes)
		(layer "In4.Cu")
		(net "M_D_CPU0_SA_CA<3>")
	)
	(gr_poly
		(pts
			(xy 332.091284 -252.786134) (xy 331.991208 -252.686058) (xy 331.891132 -252.786134) (xy 331.891132 -252.830584)
			(xy 332.091284 -252.830584)
		)
		(stroke
			(width 0)
			(type solid)
		)
		(fill yes)
		(layer "In4.Cu")
		(net "M_D_CPU0_SA_CA<0>")
	)
	(gr_poly
		(pts
			(xy 332.091284 -252.382274) (xy 332.091284 -252.337824) (xy 331.891132 -252.337824) (xy 331.891132 -252.382274)
			(xy 331.991208 -252.48235)
		)
		(stroke
			(width 0)
			(type solid)
		)
		(fill yes)
		(layer "In4.Cu")
		(net "M_D_CPU0_SA_CS_N<1>")
	)
	(gr_poly
		(pts
			(xy 332.091284 -250.762262) (xy 332.091284 -250.717812) (xy 331.891132 -250.717812) (xy 331.891132 -250.762262)
			(xy 331.991208 -250.862338)
		)
		(stroke
			(width 0)
			(type solid)
		)
		(fill yes)
		(layer "In4.Cu")
		(net "M_D_CPU0_RESET_N")
	)
	(gr_poly
		(pts
			(xy 332.091284 -249.14225) (xy 332.091284 -249.0978) (xy 331.891132 -249.0978) (xy 331.891132 -249.14225)
			(xy 331.991208 -249.242326)
		)
		(stroke
			(width 0)
			(type solid)
		)
		(fill yes)
		(layer "In4.Cu")
		(net "M_D_CPU0_SA_CB<7>")
	)
	(gr_poly
		(pts
			(xy 332.091284 -247.926098) (xy 331.991208 -247.826022) (xy 331.891132 -247.926098) (xy 331.891132 -247.970548)
			(xy 332.091284 -247.970548)
		)
		(stroke
			(width 0)
			(type solid)
		)
		(fill yes)
		(layer "In4.Cu")
		(net "M_D_CPU0_SA_CB<4>")
	)
	(gr_poly
		(pts
			(xy 332.091284 -247.522492) (xy 332.091284 -247.47474) (xy 331.891132 -247.47474) (xy 331.891132 -247.522492)
			(xy 331.991208 -247.622314)
		)
		(stroke
			(width 0)
			(type solid)
		)
		(fill yes)
		(layer "In4.Cu")
		(net "M_D_CPU0_SA_DQS_DP<9>")
	)
	(gr_poly
		(pts
			(xy 332.091284 -246.305832) (xy 331.991208 -246.20601) (xy 331.891132 -246.305832) (xy 331.891132 -246.353584)
			(xy 332.091284 -246.353584)
		)
		(stroke
			(width 0)
			(type solid)
		)
		(fill yes)
		(layer "In4.Cu")
		(net "M_D_CPU0_SA_DQS_DP<4>")
	)
	(gr_poly
		(pts
			(xy 332.091284 -245.902226) (xy 332.091284 -245.857776) (xy 331.891132 -245.857776) (xy 331.891132 -245.902226)
			(xy 331.991208 -246.002302)
		)
		(stroke
			(width 0)
			(type solid)
		)
		(fill yes)
		(layer "In4.Cu")
		(net "M_D_CPU0_SA_CB<3>")
	)
	(gr_poly
		(pts
			(xy 332.091284 -244.686074) (xy 331.991208 -244.585998) (xy 331.891132 -244.686074) (xy 331.891132 -244.730524)
			(xy 332.091284 -244.730524)
		)
		(stroke
			(width 0)
			(type solid)
		)
		(fill yes)
		(layer "In4.Cu")
		(net "M_D_CPU0_SA_CB<0>")
	)
	(gr_poly
		(pts
			(xy 332.091284 -244.282214) (xy 332.091284 -244.237764) (xy 331.891132 -244.237764) (xy 331.891132 -244.282214)
			(xy 331.991208 -244.38229)
		)
		(stroke
			(width 0)
			(type solid)
		)
		(fill yes)
		(layer "In4.Cu")
		(net "M_D_CPU0_SA_DQ<31>")
	)
	(gr_poly
		(pts
			(xy 332.091284 -243.066062) (xy 331.991208 -242.965986) (xy 331.891132 -243.066062) (xy 331.891132 -243.110512)
			(xy 332.091284 -243.110512)
		)
		(stroke
			(width 0)
			(type solid)
		)
		(fill yes)
		(layer "In4.Cu")
		(net "M_D_CPU0_SA_DQ<28>")
	)
	(gr_poly
		(pts
			(xy 332.091284 -242.662456) (xy 332.091284 -242.614704) (xy 331.891132 -242.614704) (xy 331.891132 -242.662456)
			(xy 331.991208 -242.762278)
		)
		(stroke
			(width 0)
			(type solid)
		)
		(fill yes)
		(layer "In4.Cu")
		(net "M_D_CPU0_SA_DQS_DP<8>")
	)
	(gr_poly
		(pts
			(xy 332.091284 -241.445796) (xy 331.991208 -241.345974) (xy 331.891132 -241.445796) (xy 331.891132 -241.493548)
			(xy 332.091284 -241.493548)
		)
		(stroke
			(width 0)
			(type solid)
		)
		(fill yes)
		(layer "In4.Cu")
		(net "M_D_CPU0_SA_DQS_DP<3>")
	)
	(gr_poly
		(pts
			(xy 332.091284 -241.04219) (xy 332.091284 -240.99774) (xy 331.891132 -240.99774) (xy 331.891132 -241.04219)
			(xy 331.991208 -241.142266)
		)
		(stroke
			(width 0)
			(type solid)
		)
		(fill yes)
		(layer "In4.Cu")
		(net "M_D_CPU0_SA_DQ<27>")
	)
	(gr_poly
		(pts
			(xy 332.091284 -239.826038) (xy 331.991208 -239.725962) (xy 331.891132 -239.826038) (xy 331.891132 -239.870488)
			(xy 332.091284 -239.870488)
		)
		(stroke
			(width 0)
			(type solid)
		)
		(fill yes)
		(layer "In4.Cu")
		(net "M_D_CPU0_SA_DQ<24>")
	)
	(gr_poly
		(pts
			(xy 332.091284 -239.422178) (xy 332.091284 -239.377728) (xy 331.891132 -239.377728) (xy 331.891132 -239.422178)
			(xy 331.991208 -239.522254)
		)
		(stroke
			(width 0)
			(type solid)
		)
		(fill yes)
		(layer "In4.Cu")
		(net "M_D_CPU0_SA_DQ<23>")
	)
	(gr_poly
		(pts
			(xy 332.091284 -238.206026) (xy 331.991208 -238.10595) (xy 331.891132 -238.206026) (xy 331.891132 -238.250476)
			(xy 332.091284 -238.250476)
		)
		(stroke
			(width 0)
			(type solid)
		)
		(fill yes)
		(layer "In4.Cu")
		(net "M_D_CPU0_SA_DQ<20>")
	)
	(gr_poly
		(pts
			(xy 332.091284 -237.80242) (xy 332.091284 -237.754668) (xy 331.891132 -237.754668) (xy 331.891132 -237.80242)
			(xy 331.991208 -237.902242)
		)
		(stroke
			(width 0)
			(type solid)
		)
		(fill yes)
		(layer "In4.Cu")
		(net "M_D_CPU0_SA_DQS_DP<7>")
	)
	(gr_poly
		(pts
			(xy 332.091284 -236.58576) (xy 331.991208 -236.485938) (xy 331.891132 -236.58576) (xy 331.891132 -236.633512)
			(xy 332.091284 -236.633512)
		)
		(stroke
			(width 0)
			(type solid)
		)
		(fill yes)
		(layer "In4.Cu")
		(net "M_D_CPU0_SA_DQS_DP<2>")
	)
	(gr_poly
		(pts
			(xy 332.091284 -236.182154) (xy 332.091284 -236.137704) (xy 331.891132 -236.137704) (xy 331.891132 -236.182154)
			(xy 331.991208 -236.28223)
		)
		(stroke
			(width 0)
			(type solid)
		)
		(fill yes)
		(layer "In4.Cu")
		(net "M_D_CPU0_SA_DQ<19>")
	)
	(gr_poly
		(pts
			(xy 332.091284 -234.966002) (xy 331.991208 -234.865926) (xy 331.891132 -234.966002) (xy 331.891132 -235.010452)
			(xy 332.091284 -235.010452)
		)
		(stroke
			(width 0)
			(type solid)
		)
		(fill yes)
		(layer "In4.Cu")
		(net "M_D_CPU0_SA_DQ<16>")
	)
	(gr_poly
		(pts
			(xy 332.091284 -234.562142) (xy 332.091284 -234.517692) (xy 331.891132 -234.517692) (xy 331.891132 -234.562142)
			(xy 331.991208 -234.662218)
		)
		(stroke
			(width 0)
			(type solid)
		)
		(fill yes)
		(layer "In4.Cu")
		(net "M_D_CPU0_SA_DQ<15>")
	)
	(gr_poly
		(pts
			(xy 332.091284 -233.34599) (xy 331.991208 -233.245914) (xy 331.891132 -233.34599) (xy 331.891132 -233.39044)
			(xy 332.091284 -233.39044)
		)
		(stroke
			(width 0)
			(type solid)
		)
		(fill yes)
		(layer "In4.Cu")
		(net "M_D_CPU0_SA_DQ<12>")
	)
	(gr_poly
		(pts
			(xy 332.091284 -232.942384) (xy 332.091284 -232.894632) (xy 331.891132 -232.894632) (xy 331.891132 -232.942384)
			(xy 331.991208 -233.042206)
		)
		(stroke
			(width 0)
			(type solid)
		)
		(fill yes)
		(layer "In4.Cu")
		(net "M_D_CPU0_SA_DQS_DP<6>")
	)
	(gr_poly
		(pts
			(xy 332.091284 -231.725724) (xy 331.991208 -231.625902) (xy 331.891132 -231.725724) (xy 331.891132 -231.773476)
			(xy 332.091284 -231.773476)
		)
		(stroke
			(width 0)
			(type solid)
		)
		(fill yes)
		(layer "In4.Cu")
		(net "M_D_CPU0_SA_DQS_DP<1>")
	)
	(gr_poly
		(pts
			(xy 332.091284 -231.322372) (xy 332.091284 -231.277922) (xy 331.891132 -231.277922) (xy 331.891132 -231.322372)
			(xy 331.991208 -231.422448)
		)
		(stroke
			(width 0)
			(type solid)
		)
		(fill yes)
		(layer "In4.Cu")
		(net "M_D_CPU0_SA_DQ<11>")
	)
	(gr_poly
		(pts
			(xy 332.091284 -230.105966) (xy 331.991208 -230.006144) (xy 331.891132 -230.105966) (xy 331.891132 -230.150416)
			(xy 332.091284 -230.150416)
		)
		(stroke
			(width 0)
			(type solid)
		)
		(fill yes)
		(layer "In4.Cu")
		(net "M_D_CPU0_SA_DQ<8>")
	)
	(gr_poly
		(pts
			(xy 332.091284 -229.70236) (xy 332.091284 -229.65791) (xy 331.891132 -229.65791) (xy 331.891132 -229.70236)
			(xy 331.991208 -229.802436)
		)
		(stroke
			(width 0)
			(type solid)
		)
		(fill yes)
		(layer "In4.Cu")
		(net "M_D_CPU0_SA_DQ<7>")
	)
	(gr_poly
		(pts
			(xy 332.091284 -228.486208) (xy 331.991208 -228.386132) (xy 331.891132 -228.486208) (xy 331.891132 -228.530658)
			(xy 332.091284 -228.530658)
		)
		(stroke
			(width 0)
			(type solid)
		)
		(fill yes)
		(layer "In4.Cu")
		(net "M_D_CPU0_SA_DQ<4>")
	)
	(gr_poly
		(pts
			(xy 332.091284 -228.082602) (xy 332.091284 -228.03485) (xy 331.891132 -228.03485) (xy 331.891132 -228.082602)
			(xy 331.991208 -228.182424)
		)
		(stroke
			(width 0)
			(type solid)
		)
		(fill yes)
		(layer "In4.Cu")
		(net "M_D_CPU0_SA_DQS_DP<5>")
	)
	(gr_poly
		(pts
			(xy 332.091284 -226.865942) (xy 331.991208 -226.76612) (xy 331.891132 -226.865942) (xy 331.891132 -226.913694)
			(xy 332.091284 -226.913694)
		)
		(stroke
			(width 0)
			(type solid)
		)
		(fill yes)
		(layer "In4.Cu")
		(net "M_D_CPU0_SA_DQS_DP<0>")
	)
	(gr_poly
		(pts
			(xy 332.091284 -226.462336) (xy 332.091284 -226.417886) (xy 331.891132 -226.417886) (xy 331.891132 -226.462336)
			(xy 331.991208 -226.562412)
		)
		(stroke
			(width 0)
			(type solid)
		)
		(fill yes)
		(layer "In4.Cu")
		(net "M_D_CPU0_SA_DQ<3>")
	)
	(gr_poly
		(pts
			(xy 332.091284 -225.246184) (xy 331.991208 -225.146108) (xy 331.891132 -225.246184) (xy 331.891132 -225.290634)
			(xy 332.091284 -225.290634)
		)
		(stroke
			(width 0)
			(type solid)
		)
		(fill yes)
		(layer "In4.Cu")
		(net "M_D_CPU0_SA_DQ<0>")
	)
	(gr_poly
		(pts
			(xy 332.384908 -266.991592) (xy 332.284832 -266.891516) (xy 332.18501 -266.991592) (xy 332.18501 -267.036042)
			(xy 332.384908 -267.036042)
		)
		(stroke
			(width 0)
			(type solid)
		)
		(fill yes)
		(layer "In4.Cu")
		(net "M_D_CPU0_SA_RSP<0>")
	)
	(gr_poly
		(pts
			(xy 332.391258 -292.91788) (xy 332.291182 -292.817804) (xy 332.191106 -292.91788) (xy 332.191106 -292.96233)
			(xy 332.391258 -292.96233)
		)
		(stroke
			(width 0)
			(type solid)
		)
		(fill yes)
		(layer "In4.Cu")
		(net "M_D_CPU0_SB_DQ<29>")
	)
	(gr_poly
		(pts
			(xy 332.391258 -292.51402) (xy 332.391258 -292.46957) (xy 332.191106 -292.46957) (xy 332.191106 -292.51402)
			(xy 332.291182 -292.614096)
		)
		(stroke
			(width 0)
			(type solid)
		)
		(fill yes)
		(layer "In4.Cu")
		(net "M_D_CPU0_SB_DQ<30>")
	)
	(gr_poly
		(pts
			(xy 332.391258 -291.297614) (xy 332.291182 -291.197792) (xy 332.191106 -291.297614) (xy 332.191106 -291.345366)
			(xy 332.391258 -291.345366)
		)
		(stroke
			(width 0)
			(type solid)
		)
		(fill yes)
		(layer "In4.Cu")
		(net "M_D_CPU0_SB_DQS_DN<8>")
	)
	(gr_poly
		(pts
			(xy 332.391258 -290.894262) (xy 332.391258 -290.84651) (xy 332.191106 -290.84651) (xy 332.191106 -290.894262)
			(xy 332.291182 -290.994084)
		)
		(stroke
			(width 0)
			(type solid)
		)
		(fill yes)
		(layer "In4.Cu")
		(net "M_D_CPU0_SB_DQS_DN<3>")
	)
	(gr_poly
		(pts
			(xy 332.391258 -289.677856) (xy 332.291182 -289.57778) (xy 332.191106 -289.677856) (xy 332.191106 -289.722306)
			(xy 332.391258 -289.722306)
		)
		(stroke
			(width 0)
			(type solid)
		)
		(fill yes)
		(layer "In4.Cu")
		(net "M_D_CPU0_SB_DQ<25>")
	)
	(gr_poly
		(pts
			(xy 332.391258 -289.273996) (xy 332.391258 -289.229546) (xy 332.191106 -289.229546) (xy 332.191106 -289.273996)
			(xy 332.291182 -289.374072)
		)
		(stroke
			(width 0)
			(type solid)
		)
		(fill yes)
		(layer "In4.Cu")
		(net "M_D_CPU0_SB_DQ<26>")
	)
	(gr_poly
		(pts
			(xy 332.391258 -288.057844) (xy 332.291182 -287.957768) (xy 332.191106 -288.057844) (xy 332.191106 -288.102294)
			(xy 332.391258 -288.102294)
		)
		(stroke
			(width 0)
			(type solid)
		)
		(fill yes)
		(layer "In4.Cu")
		(net "M_D_CPU0_SB_DQ<21>")
	)
	(gr_poly
		(pts
			(xy 332.391258 -287.654238) (xy 332.391258 -287.609788) (xy 332.191106 -287.609788) (xy 332.191106 -287.654238)
			(xy 332.291182 -287.75406)
		)
		(stroke
			(width 0)
			(type solid)
		)
		(fill yes)
		(layer "In4.Cu")
		(net "M_D_CPU0_SB_DQ<22>")
	)
	(gr_poly
		(pts
			(xy 332.391258 -286.437832) (xy 332.291182 -286.337756) (xy 332.191106 -286.437832) (xy 332.191106 -286.485584)
			(xy 332.391258 -286.485584)
		)
		(stroke
			(width 0)
			(type solid)
		)
		(fill yes)
		(layer "In4.Cu")
		(net "M_D_CPU0_SB_DQS_DN<7>")
	)
	(gr_poly
		(pts
			(xy 332.391258 -286.03448) (xy 332.391258 -285.986728) (xy 332.191106 -285.986728) (xy 332.191106 -286.03448)
			(xy 332.291182 -286.134302)
		)
		(stroke
			(width 0)
			(type solid)
		)
		(fill yes)
		(layer "In4.Cu")
		(net "M_D_CPU0_SB_DQS_DN<2>")
	)
	(gr_poly
		(pts
			(xy 332.391258 -284.818074) (xy 332.291182 -284.717998) (xy 332.191106 -284.818074) (xy 332.191106 -284.862524)
			(xy 332.391258 -284.862524)
		)
		(stroke
			(width 0)
			(type solid)
		)
		(fill yes)
		(layer "In4.Cu")
		(net "M_D_CPU0_SB_DQ<17>")
	)
	(gr_poly
		(pts
			(xy 332.391258 -284.414214) (xy 332.391258 -284.369764) (xy 332.191106 -284.369764) (xy 332.191106 -284.414214)
			(xy 332.291182 -284.51429)
		)
		(stroke
			(width 0)
			(type solid)
		)
		(fill yes)
		(layer "In4.Cu")
		(net "M_D_CPU0_SB_DQ<18>")
	)
	(gr_poly
		(pts
			(xy 332.391258 -283.198062) (xy 332.291182 -283.097986) (xy 332.191106 -283.198062) (xy 332.191106 -283.242512)
			(xy 332.391258 -283.242512)
		)
		(stroke
			(width 0)
			(type solid)
		)
		(fill yes)
		(layer "In4.Cu")
		(net "M_D_CPU0_SB_DQ<13>")
	)
	(gr_poly
		(pts
			(xy 332.391258 -282.794202) (xy 332.391258 -282.749752) (xy 332.191106 -282.749752) (xy 332.191106 -282.794202)
			(xy 332.291182 -282.894278)
		)
		(stroke
			(width 0)
			(type solid)
		)
		(fill yes)
		(layer "In4.Cu")
		(net "M_D_CPU0_SB_DQ<14>")
	)
	(gr_poly
		(pts
			(xy 332.391258 -281.577796) (xy 332.291182 -281.477974) (xy 332.191106 -281.577796) (xy 332.191106 -281.625548)
			(xy 332.391258 -281.625548)
		)
		(stroke
			(width 0)
			(type solid)
		)
		(fill yes)
		(layer "In4.Cu")
		(net "M_D_CPU0_SB_DQS_DN<6>")
	)
	(gr_poly
		(pts
			(xy 332.391258 -281.174444) (xy 332.391258 -281.126692) (xy 332.191106 -281.126692) (xy 332.191106 -281.174444)
			(xy 332.291182 -281.274266)
		)
		(stroke
			(width 0)
			(type solid)
		)
		(fill yes)
		(layer "In4.Cu")
		(net "M_D_CPU0_SB_DQS_DN<1>")
	)
	(gr_poly
		(pts
			(xy 332.391258 -279.958038) (xy 332.291182 -279.857962) (xy 332.191106 -279.958038) (xy 332.191106 -280.002488)
			(xy 332.391258 -280.002488)
		)
		(stroke
			(width 0)
			(type solid)
		)
		(fill yes)
		(layer "In4.Cu")
		(net "M_D_CPU0_SB_DQ<9>")
	)
	(gr_poly
		(pts
			(xy 332.391258 -279.554178) (xy 332.391258 -279.509728) (xy 332.191106 -279.509728) (xy 332.191106 -279.554178)
			(xy 332.291182 -279.654254)
		)
		(stroke
			(width 0)
			(type solid)
		)
		(fill yes)
		(layer "In4.Cu")
		(net "M_D_CPU0_SB_DQ<10>")
	)
	(gr_poly
		(pts
			(xy 332.391258 -278.338026) (xy 332.291182 -278.23795) (xy 332.191106 -278.338026) (xy 332.191106 -278.382476)
			(xy 332.391258 -278.382476)
		)
		(stroke
			(width 0)
			(type solid)
		)
		(fill yes)
		(layer "In4.Cu")
		(net "M_D_CPU0_SB_DQ<5>")
	)
	(gr_poly
		(pts
			(xy 332.391258 -277.934166) (xy 332.391258 -277.889716) (xy 332.191106 -277.889716) (xy 332.191106 -277.934166)
			(xy 332.291182 -278.034242)
		)
		(stroke
			(width 0)
			(type solid)
		)
		(fill yes)
		(layer "In4.Cu")
		(net "M_D_CPU0_SB_DQ<6>")
	)
	(gr_poly
		(pts
			(xy 332.391258 -276.71776) (xy 332.291182 -276.617938) (xy 332.191106 -276.71776) (xy 332.191106 -276.765512)
			(xy 332.391258 -276.765512)
		)
		(stroke
			(width 0)
			(type solid)
		)
		(fill yes)
		(layer "In4.Cu")
		(net "M_D_CPU0_SB_DQS_DN<5>")
	)
	(gr_poly
		(pts
			(xy 332.391258 -276.314408) (xy 332.391258 -276.266656) (xy 332.191106 -276.266656) (xy 332.191106 -276.314408)
			(xy 332.291182 -276.41423)
		)
		(stroke
			(width 0)
			(type solid)
		)
		(fill yes)
		(layer "In4.Cu")
		(net "M_D_CPU0_SB_DQS_DN<0>")
	)
	(gr_poly
		(pts
			(xy 332.391258 -275.098002) (xy 332.291182 -274.997926) (xy 332.191106 -275.098002) (xy 332.191106 -275.142452)
			(xy 332.391258 -275.142452)
		)
		(stroke
			(width 0)
			(type solid)
		)
		(fill yes)
		(layer "In4.Cu")
		(net "M_D_CPU0_SB_DQ<1>")
	)
	(gr_poly
		(pts
			(xy 332.391258 -274.694142) (xy 332.391258 -274.649692) (xy 332.191106 -274.649692) (xy 332.191106 -274.694142)
			(xy 332.291182 -274.794218)
		)
		(stroke
			(width 0)
			(type solid)
		)
		(fill yes)
		(layer "In4.Cu")
		(net "M_D_CPU0_SB_DQ<2>")
	)
	(gr_poly
		(pts
			(xy 332.391258 -273.47799) (xy 332.291182 -273.377914) (xy 332.191106 -273.47799) (xy 332.191106 -273.52244)
			(xy 332.391258 -273.52244)
		)
		(stroke
			(width 0)
			(type solid)
		)
		(fill yes)
		(layer "In4.Cu")
		(net "M_D_CPU0_SB_CB<1>")
	)
	(gr_poly
		(pts
			(xy 332.391258 -273.07413) (xy 332.391258 -273.02968) (xy 332.191106 -273.02968) (xy 332.191106 -273.07413)
			(xy 332.291182 -273.174206)
		)
		(stroke
			(width 0)
			(type solid)
		)
		(fill yes)
		(layer "In4.Cu")
		(net "M_D_CPU0_SB_CB<2>")
	)
	(gr_poly
		(pts
			(xy 332.391258 -271.857724) (xy 332.291182 -271.757902) (xy 332.191106 -271.857724) (xy 332.191106 -271.905476)
			(xy 332.391258 -271.905476)
		)
		(stroke
			(width 0)
			(type solid)
		)
		(fill yes)
		(layer "In4.Cu")
		(net "M_D_CPU0_SB_DQS_DN<4>")
	)
	(gr_poly
		(pts
			(xy 332.391258 -271.454372) (xy 332.391258 -271.40662) (xy 332.191106 -271.40662) (xy 332.191106 -271.454372)
			(xy 332.291182 -271.554194)
		)
		(stroke
			(width 0)
			(type solid)
		)
		(fill yes)
		(layer "In4.Cu")
		(net "M_D_CPU0_SB_DQS_DN<9>")
	)
	(gr_poly
		(pts
			(xy 332.391258 -270.237966) (xy 332.291182 -270.13789) (xy 332.191106 -270.237966) (xy 332.191106 -270.282416)
			(xy 332.391258 -270.282416)
		)
		(stroke
			(width 0)
			(type solid)
		)
		(fill yes)
		(layer "In4.Cu")
		(net "M_D_CPU0_SB_CB<5>")
	)
	(gr_poly
		(pts
			(xy 332.391258 -269.834106) (xy 332.391258 -269.789656) (xy 332.191106 -269.789656) (xy 332.191106 -269.834106)
			(xy 332.291182 -269.934182)
		)
		(stroke
			(width 0)
			(type solid)
		)
		(fill yes)
		(layer "In4.Cu")
		(net "M_D_CPU0_SB_CB<6>")
	)
	(gr_poly
		(pts
			(xy 332.391258 -266.594082) (xy 332.391258 -266.549632) (xy 332.191106 -266.549632) (xy 332.191106 -266.594082)
			(xy 332.291182 -266.694158)
		)
		(stroke
			(width 0)
			(type solid)
		)
		(fill yes)
		(layer "In4.Cu")
		(net "M_D_CPU0_SB_CS_N<1>")
	)
	(gr_poly
		(pts
			(xy 332.391258 -264.97407) (xy 332.391258 -264.92962) (xy 332.191106 -264.92962) (xy 332.191106 -264.97407)
			(xy 332.291182 -265.074146)
		)
		(stroke
			(width 0)
			(type solid)
		)
		(fill yes)
		(layer "In4.Cu")
		(net "M_D_CPU0_SB_PAR")
	)
	(gr_poly
		(pts
			(xy 332.391258 -263.757918) (xy 332.291182 -263.657842) (xy 332.191106 -263.757918) (xy 332.191106 -263.802368)
			(xy 332.391258 -263.802368)
		)
		(stroke
			(width 0)
			(type solid)
		)
		(fill yes)
		(layer "In4.Cu")
		(net "M_D_CPU0_SB_CA<4>")
	)
	(gr_poly
		(pts
			(xy 332.391258 -263.354058) (xy 332.391258 -263.309608) (xy 332.191106 -263.309608) (xy 332.191106 -263.354058)
			(xy 332.291182 -263.454134)
		)
		(stroke
			(width 0)
			(type solid)
		)
		(fill yes)
		(layer "In4.Cu")
		(net "M_D_CPU0_SB_CA<3>")
	)
	(gr_poly
		(pts
			(xy 332.391258 -262.137906) (xy 332.291182 -262.03783) (xy 332.191106 -262.137906) (xy 332.191106 -262.182356)
			(xy 332.391258 -262.182356)
		)
		(stroke
			(width 0)
			(type solid)
		)
		(fill yes)
		(layer "In4.Cu")
		(net "M_D_CPU0_SB_CA<0>")
	)
	(gr_poly
		(pts
			(xy 332.561184 -256.432558) (xy 332.561184 -256.384806) (xy 332.361032 -256.384806) (xy 332.361032 -256.432558)
			(xy 332.461108 -256.53238)
		)
		(stroke
			(width 0)
			(type solid)
		)
		(fill yes)
		(layer "In4.Cu")
		(net "M_D_CPU0_CLK_DN<0>")
	)
	(gr_poly
		(pts
			(xy 332.561184 -255.216152) (xy 332.461108 -255.116076) (xy 332.361032 -255.216152) (xy 332.361032 -255.260602)
			(xy 332.561184 -255.260602)
		)
		(stroke
			(width 0)
			(type solid)
		)
		(fill yes)
		(layer "In4.Cu")
		(net "M_D_CPU0_SA_CA<6>")
	)
	(gr_poly
		(pts
			(xy 332.561184 -254.812292) (xy 332.561184 -254.767842) (xy 332.361032 -254.767842) (xy 332.361032 -254.812292)
			(xy 332.461108 -254.912368)
		)
		(stroke
			(width 0)
			(type solid)
		)
		(fill yes)
		(layer "In4.Cu")
		(net "M_D_CPU0_SA_CA<5>")
	)
	(gr_poly
		(pts
			(xy 332.561184 -253.59614) (xy 332.461108 -253.496064) (xy 332.361032 -253.59614) (xy 332.361032 -253.64059)
			(xy 332.561184 -253.64059)
		)
		(stroke
			(width 0)
			(type solid)
		)
		(fill yes)
		(layer "In4.Cu")
		(net "M_D_CPU0_SA_CA<2>")
	)
	(gr_poly
		(pts
			(xy 332.561184 -253.19228) (xy 332.561184 -253.14783) (xy 332.361032 -253.14783) (xy 332.361032 -253.19228)
			(xy 332.461108 -253.292356)
		)
		(stroke
			(width 0)
			(type solid)
		)
		(fill yes)
		(layer "In4.Cu")
		(net "M_D_CPU0_SA_CA<1>")
	)
	(gr_poly
		(pts
			(xy 332.561184 -251.572268) (xy 332.561184 -251.527818) (xy 332.361032 -251.527818) (xy 332.361032 -251.572268)
			(xy 332.461108 -251.672344)
		)
		(stroke
			(width 0)
			(type solid)
		)
		(fill yes)
		(layer "In4.Cu")
		(net "M_D_CPU0_SA_CS_N<0>")
	)
	(gr_poly
		(pts
			(xy 332.561184 -250.356116) (xy 332.461108 -250.25604) (xy 332.361032 -250.356116) (xy 332.361032 -250.400566)
			(xy 332.561184 -250.400566)
		)
		(stroke
			(width 0)
			(type solid)
		)
		(fill yes)
		(layer "In4.Cu")
		(net "M_D_CPU0_ALERT_R_N")
	)
	(gr_poly
		(pts
			(xy 332.561184 -248.736104) (xy 332.461108 -248.636028) (xy 332.361032 -248.736104) (xy 332.361032 -248.780554)
			(xy 332.561184 -248.780554)
		)
		(stroke
			(width 0)
			(type solid)
		)
		(fill yes)
		(layer "In4.Cu")
		(net "M_D_CPU0_SA_CB<5>")
	)
	(gr_poly
		(pts
			(xy 332.561184 -248.332244) (xy 332.561184 -248.287794) (xy 332.361032 -248.287794) (xy 332.361032 -248.332244)
			(xy 332.461108 -248.43232)
		)
		(stroke
			(width 0)
			(type solid)
		)
		(fill yes)
		(layer "In4.Cu")
		(net "M_D_CPU0_SA_CB<6>")
	)
	(gr_poly
		(pts
			(xy 332.561184 -247.115838) (xy 332.461108 -247.016016) (xy 332.361032 -247.115838) (xy 332.361032 -247.16359)
			(xy 332.561184 -247.16359)
		)
		(stroke
			(width 0)
			(type solid)
		)
		(fill yes)
		(layer "In4.Cu")
		(net "M_D_CPU0_SA_DQS_DN<9>")
	)
	(gr_poly
		(pts
			(xy 332.561184 -246.712486) (xy 332.561184 -246.664734) (xy 332.361032 -246.664734) (xy 332.361032 -246.712486)
			(xy 332.461108 -246.812308)
		)
		(stroke
			(width 0)
			(type solid)
		)
		(fill yes)
		(layer "In4.Cu")
		(net "M_D_CPU0_SA_DQS_DN<4>")
	)
	(gr_poly
		(pts
			(xy 332.561184 -245.49608) (xy 332.461108 -245.396004) (xy 332.361032 -245.49608) (xy 332.361032 -245.54053)
			(xy 332.561184 -245.54053)
		)
		(stroke
			(width 0)
			(type solid)
		)
		(fill yes)
		(layer "In4.Cu")
		(net "M_D_CPU0_SA_CB<1>")
	)
	(gr_poly
		(pts
			(xy 332.561184 -245.09222) (xy 332.561184 -245.04777) (xy 332.361032 -245.04777) (xy 332.361032 -245.09222)
			(xy 332.461108 -245.192296)
		)
		(stroke
			(width 0)
			(type solid)
		)
		(fill yes)
		(layer "In4.Cu")
		(net "M_D_CPU0_SA_CB<2>")
	)
	(gr_poly
		(pts
			(xy 332.561184 -243.876068) (xy 332.461108 -243.775992) (xy 332.361032 -243.876068) (xy 332.361032 -243.920518)
			(xy 332.561184 -243.920518)
		)
		(stroke
			(width 0)
			(type solid)
		)
		(fill yes)
		(layer "In4.Cu")
		(net "M_D_CPU0_SA_DQ<29>")
	)
	(gr_poly
		(pts
			(xy 332.561184 -243.472208) (xy 332.561184 -243.427758) (xy 332.361032 -243.427758) (xy 332.361032 -243.472208)
			(xy 332.461108 -243.572284)
		)
		(stroke
			(width 0)
			(type solid)
		)
		(fill yes)
		(layer "In4.Cu")
		(net "M_D_CPU0_SA_DQ<30>")
	)
	(gr_poly
		(pts
			(xy 332.561184 -242.255802) (xy 332.461108 -242.15598) (xy 332.361032 -242.255802) (xy 332.361032 -242.303554)
			(xy 332.561184 -242.303554)
		)
		(stroke
			(width 0)
			(type solid)
		)
		(fill yes)
		(layer "In4.Cu")
		(net "M_D_CPU0_SA_DQS_DN<8>")
	)
	(gr_poly
		(pts
			(xy 332.561184 -241.85245) (xy 332.561184 -241.804698) (xy 332.361032 -241.804698) (xy 332.361032 -241.85245)
			(xy 332.461108 -241.952272)
		)
		(stroke
			(width 0)
			(type solid)
		)
		(fill yes)
		(layer "In4.Cu")
		(net "M_D_CPU0_SA_DQS_DN<3>")
	)
	(gr_poly
		(pts
			(xy 332.561184 -240.636044) (xy 332.461108 -240.535968) (xy 332.361032 -240.636044) (xy 332.361032 -240.680494)
			(xy 332.561184 -240.680494)
		)
		(stroke
			(width 0)
			(type solid)
		)
		(fill yes)
		(layer "In4.Cu")
		(net "M_D_CPU0_SA_DQ<25>")
	)
	(gr_poly
		(pts
			(xy 332.561184 -240.232184) (xy 332.561184 -240.187734) (xy 332.361032 -240.187734) (xy 332.361032 -240.232184)
			(xy 332.461108 -240.33226)
		)
		(stroke
			(width 0)
			(type solid)
		)
		(fill yes)
		(layer "In4.Cu")
		(net "M_D_CPU0_SA_DQ<26>")
	)
	(gr_poly
		(pts
			(xy 332.561184 -239.016032) (xy 332.461108 -238.915956) (xy 332.361032 -239.016032) (xy 332.361032 -239.060482)
			(xy 332.561184 -239.060482)
		)
		(stroke
			(width 0)
			(type solid)
		)
		(fill yes)
		(layer "In4.Cu")
		(net "M_D_CPU0_SA_DQ<21>")
	)
	(gr_poly
		(pts
			(xy 332.561184 -238.612172) (xy 332.561184 -238.567722) (xy 332.361032 -238.567722) (xy 332.361032 -238.612172)
			(xy 332.461108 -238.712248)
		)
		(stroke
			(width 0)
			(type solid)
		)
		(fill yes)
		(layer "In4.Cu")
		(net "M_D_CPU0_SA_DQ<22>")
	)
	(gr_poly
		(pts
			(xy 332.561184 -237.395766) (xy 332.461108 -237.295944) (xy 332.361032 -237.395766) (xy 332.361032 -237.443518)
			(xy 332.561184 -237.443518)
		)
		(stroke
			(width 0)
			(type solid)
		)
		(fill yes)
		(layer "In4.Cu")
		(net "M_D_CPU0_SA_DQS_DN<7>")
	)
	(gr_poly
		(pts
			(xy 332.561184 -236.992414) (xy 332.561184 -236.944662) (xy 332.361032 -236.944662) (xy 332.361032 -236.992414)
			(xy 332.461108 -237.092236)
		)
		(stroke
			(width 0)
			(type solid)
		)
		(fill yes)
		(layer "In4.Cu")
		(net "M_D_CPU0_SA_DQS_DN<2>")
	)
	(gr_poly
		(pts
			(xy 332.561184 -235.776008) (xy 332.461108 -235.675932) (xy 332.361032 -235.776008) (xy 332.361032 -235.820458)
			(xy 332.561184 -235.820458)
		)
		(stroke
			(width 0)
			(type solid)
		)
		(fill yes)
		(layer "In4.Cu")
		(net "M_D_CPU0_SA_DQ<17>")
	)
	(gr_poly
		(pts
			(xy 332.561184 -235.372148) (xy 332.561184 -235.327698) (xy 332.361032 -235.327698) (xy 332.361032 -235.372148)
			(xy 332.461108 -235.472224)
		)
		(stroke
			(width 0)
			(type solid)
		)
		(fill yes)
		(layer "In4.Cu")
		(net "M_D_CPU0_SA_DQ<18>")
	)
	(gr_poly
		(pts
			(xy 332.561184 -234.155996) (xy 332.461108 -234.05592) (xy 332.361032 -234.155996) (xy 332.361032 -234.200446)
			(xy 332.561184 -234.200446)
		)
		(stroke
			(width 0)
			(type solid)
		)
		(fill yes)
		(layer "In4.Cu")
		(net "M_D_CPU0_SA_DQ<13>")
	)
	(gr_poly
		(pts
			(xy 332.561184 -233.752136) (xy 332.561184 -233.707686) (xy 332.361032 -233.707686) (xy 332.361032 -233.752136)
			(xy 332.461108 -233.852212)
		)
		(stroke
			(width 0)
			(type solid)
		)
		(fill yes)
		(layer "In4.Cu")
		(net "M_D_CPU0_SA_DQ<14>")
	)
	(gr_poly
		(pts
			(xy 332.561184 -232.53573) (xy 332.461108 -232.435908) (xy 332.361032 -232.53573) (xy 332.361032 -232.583482)
			(xy 332.561184 -232.583482)
		)
		(stroke
			(width 0)
			(type solid)
		)
		(fill yes)
		(layer "In4.Cu")
		(net "M_D_CPU0_SA_DQS_DN<6>")
	)
	(gr_poly
		(pts
			(xy 332.561184 -232.132378) (xy 332.561184 -232.084626) (xy 332.361032 -232.084626) (xy 332.361032 -232.132378)
			(xy 332.461108 -232.2322)
		)
		(stroke
			(width 0)
			(type solid)
		)
		(fill yes)
		(layer "In4.Cu")
		(net "M_D_CPU0_SA_DQS_DN<1>")
	)
	(gr_poly
		(pts
			(xy 332.561184 -230.915972) (xy 332.461108 -230.815896) (xy 332.361032 -230.915972) (xy 332.361032 -230.960422)
			(xy 332.561184 -230.960422)
		)
		(stroke
			(width 0)
			(type solid)
		)
		(fill yes)
		(layer "In4.Cu")
		(net "M_D_CPU0_SA_DQ<9>")
	)
	(gr_poly
		(pts
			(xy 332.561184 -230.512366) (xy 332.561184 -230.467916) (xy 332.361032 -230.467916) (xy 332.361032 -230.512366)
			(xy 332.461108 -230.612188)
		)
		(stroke
			(width 0)
			(type solid)
		)
		(fill yes)
		(layer "In4.Cu")
		(net "M_D_CPU0_SA_DQ<10>")
	)
	(gr_poly
		(pts
			(xy 332.561184 -229.29596) (xy 332.461108 -229.195884) (xy 332.361032 -229.29596) (xy 332.361032 -229.34041)
			(xy 332.561184 -229.34041)
		)
		(stroke
			(width 0)
			(type solid)
		)
		(fill yes)
		(layer "In4.Cu")
		(net "M_D_CPU0_SA_DQ<5>")
	)
	(gr_poly
		(pts
			(xy 332.561184 -228.892354) (xy 332.561184 -228.847904) (xy 332.361032 -228.847904) (xy 332.361032 -228.892354)
			(xy 332.461108 -228.99243)
		)
		(stroke
			(width 0)
			(type solid)
		)
		(fill yes)
		(layer "In4.Cu")
		(net "M_D_CPU0_SA_DQ<6>")
	)
	(gr_poly
		(pts
			(xy 332.561184 -227.676456) (xy 332.461108 -227.57638) (xy 332.361032 -227.676456) (xy 332.361032 -227.724208)
			(xy 332.561184 -227.724208)
		)
		(stroke
			(width 0)
			(type solid)
		)
		(fill yes)
		(layer "In4.Cu")
		(net "M_D_CPU0_SA_DQS_DN<5>")
	)
	(gr_poly
		(pts
			(xy 332.561184 -227.272596) (xy 332.561184 -227.224844) (xy 332.361032 -227.224844) (xy 332.361032 -227.272596)
			(xy 332.461108 -227.372418)
		)
		(stroke
			(width 0)
			(type solid)
		)
		(fill yes)
		(layer "In4.Cu")
		(net "M_D_CPU0_SA_DQS_DN<0>")
	)
	(gr_poly
		(pts
			(xy 332.561184 -226.05619) (xy 332.461108 -225.956114) (xy 332.361032 -226.05619) (xy 332.361032 -226.10064)
			(xy 332.561184 -226.10064)
		)
		(stroke
			(width 0)
			(type solid)
		)
		(fill yes)
		(layer "In4.Cu")
		(net "M_D_CPU0_SA_DQ<1>")
	)
	(gr_poly
		(pts
			(xy 332.561184 -225.65233) (xy 332.561184 -225.60788) (xy 332.361032 -225.60788) (xy 332.361032 -225.65233)
			(xy 332.461108 -225.752406)
		)
		(stroke
			(width 0)
			(type solid)
		)
		(fill yes)
		(layer "In4.Cu")
		(net "M_D_CPU0_SA_DQ<2>")
	)
	(gr_poly
		(pts
			(xy 332.861158 -293.324026) (xy 332.861158 -293.279576) (xy 332.661006 -293.279576) (xy 332.661006 -293.324026)
			(xy 332.761082 -293.424102)
		)
		(stroke
			(width 0)
			(type solid)
		)
		(fill yes)
		(layer "In4.Cu")
		(net "M_D_CPU0_SB_DQ<31>")
	)
	(gr_poly
		(pts
			(xy 332.861158 -292.107874) (xy 332.761082 -292.007798) (xy 332.661006 -292.107874) (xy 332.661006 -292.152324)
			(xy 332.861158 -292.152324)
		)
		(stroke
			(width 0)
			(type solid)
		)
		(fill yes)
		(layer "In4.Cu")
		(net "M_D_CPU0_SB_DQ<28>")
	)
	(gr_poly
		(pts
			(xy 332.861158 -291.704268) (xy 332.861158 -291.656516) (xy 332.661006 -291.656516) (xy 332.661006 -291.704268)
			(xy 332.761082 -291.80409)
		)
		(stroke
			(width 0)
			(type solid)
		)
		(fill yes)
		(layer "In4.Cu")
		(net "M_D_CPU0_SB_DQS_DP<8>")
	)
	(gr_poly
		(pts
			(xy 332.861158 -290.487608) (xy 332.761082 -290.387786) (xy 332.661006 -290.487608) (xy 332.661006 -290.53536)
			(xy 332.861158 -290.53536)
		)
		(stroke
			(width 0)
			(type solid)
		)
		(fill yes)
		(layer "In4.Cu")
		(net "M_D_CPU0_SB_DQS_DP<3>")
	)
	(gr_poly
		(pts
			(xy 332.861158 -290.084002) (xy 332.861158 -290.039552) (xy 332.661006 -290.039552) (xy 332.661006 -290.084002)
			(xy 332.761082 -290.184078)
		)
		(stroke
			(width 0)
			(type solid)
		)
		(fill yes)
		(layer "In4.Cu")
		(net "M_D_CPU0_SB_DQ<27>")
	)
	(gr_poly
		(pts
			(xy 332.861158 -288.86785) (xy 332.761082 -288.767774) (xy 332.661006 -288.86785) (xy 332.661006 -288.9123)
			(xy 332.861158 -288.9123)
		)
		(stroke
			(width 0)
			(type solid)
		)
		(fill yes)
		(layer "In4.Cu")
		(net "M_D_CPU0_SB_DQ<24>")
	)
	(gr_poly
		(pts
			(xy 332.861158 -288.464244) (xy 332.861158 -288.419794) (xy 332.661006 -288.419794) (xy 332.661006 -288.464244)
			(xy 332.761082 -288.56432)
		)
		(stroke
			(width 0)
			(type solid)
		)
		(fill yes)
		(layer "In4.Cu")
		(net "M_D_CPU0_SB_DQ<23>")
	)
	(gr_poly
		(pts
			(xy 332.861158 -287.247838) (xy 332.761082 -287.148016) (xy 332.661006 -287.247838) (xy 332.661006 -287.292288)
			(xy 332.861158 -287.292288)
		)
		(stroke
			(width 0)
			(type solid)
		)
		(fill yes)
		(layer "In4.Cu")
		(net "M_D_CPU0_SB_DQ<20>")
	)
	(gr_poly
		(pts
			(xy 332.861158 -286.844232) (xy 332.861158 -286.79648) (xy 332.661006 -286.79648) (xy 332.661006 -286.844232)
			(xy 332.761082 -286.944308)
		)
		(stroke
			(width 0)
			(type solid)
		)
		(fill yes)
		(layer "In4.Cu")
		(net "M_D_CPU0_SB_DQS_DP<7>")
	)
	(gr_poly
		(pts
			(xy 332.861158 -285.627826) (xy 332.761082 -285.528004) (xy 332.661006 -285.627826) (xy 332.661006 -285.675578)
			(xy 332.861158 -285.675578)
		)
		(stroke
			(width 0)
			(type solid)
		)
		(fill yes)
		(layer "In4.Cu")
		(net "M_D_CPU0_SB_DQS_DP<2>")
	)
	(gr_poly
		(pts
			(xy 332.861158 -285.22422) (xy 332.861158 -285.17977) (xy 332.661006 -285.17977) (xy 332.661006 -285.22422)
			(xy 332.761082 -285.324296)
		)
		(stroke
			(width 0)
			(type solid)
		)
		(fill yes)
		(layer "In4.Cu")
		(net "M_D_CPU0_SB_DQ<19>")
	)
	(gr_poly
		(pts
			(xy 332.861158 -284.008068) (xy 332.761082 -283.907992) (xy 332.661006 -284.008068) (xy 332.661006 -284.052518)
			(xy 332.861158 -284.052518)
		)
		(stroke
			(width 0)
			(type solid)
		)
		(fill yes)
		(layer "In4.Cu")
		(net "M_D_CPU0_SB_DQ<16>")
	)
	(gr_poly
		(pts
			(xy 332.861158 -283.604208) (xy 332.861158 -283.559758) (xy 332.661006 -283.559758) (xy 332.661006 -283.604208)
			(xy 332.761082 -283.704284)
		)
		(stroke
			(width 0)
			(type solid)
		)
		(fill yes)
		(layer "In4.Cu")
		(net "M_D_CPU0_SB_DQ<15>")
	)
	(gr_poly
		(pts
			(xy 332.861158 -282.388056) (xy 332.761082 -282.28798) (xy 332.661006 -282.388056) (xy 332.661006 -282.432506)
			(xy 332.861158 -282.432506)
		)
		(stroke
			(width 0)
			(type solid)
		)
		(fill yes)
		(layer "In4.Cu")
		(net "M_D_CPU0_SB_DQ<12>")
	)
	(gr_poly
		(pts
			(xy 332.861158 -281.98445) (xy 332.861158 -281.936698) (xy 332.661006 -281.936698) (xy 332.661006 -281.98445)
			(xy 332.761082 -282.084272)
		)
		(stroke
			(width 0)
			(type solid)
		)
		(fill yes)
		(layer "In4.Cu")
		(net "M_D_CPU0_SB_DQS_DP<6>")
	)
	(gr_poly
		(pts
			(xy 332.861158 -280.76779) (xy 332.761082 -280.667968) (xy 332.661006 -280.76779) (xy 332.661006 -280.815542)
			(xy 332.861158 -280.815542)
		)
		(stroke
			(width 0)
			(type solid)
		)
		(fill yes)
		(layer "In4.Cu")
		(net "M_D_CPU0_SB_DQS_DP<1>")
	)
	(gr_poly
		(pts
			(xy 332.861158 -280.364184) (xy 332.861158 -280.319734) (xy 332.661006 -280.319734) (xy 332.661006 -280.364184)
			(xy 332.761082 -280.46426)
		)
		(stroke
			(width 0)
			(type solid)
		)
		(fill yes)
		(layer "In4.Cu")
		(net "M_D_CPU0_SB_DQ<11>")
	)
	(gr_poly
		(pts
			(xy 332.861158 -279.148032) (xy 332.761082 -279.047956) (xy 332.661006 -279.148032) (xy 332.661006 -279.192482)
			(xy 332.861158 -279.192482)
		)
		(stroke
			(width 0)
			(type solid)
		)
		(fill yes)
		(layer "In4.Cu")
		(net "M_D_CPU0_SB_DQ<8>")
	)
	(gr_poly
		(pts
			(xy 332.861158 -278.744172) (xy 332.861158 -278.699722) (xy 332.661006 -278.699722) (xy 332.661006 -278.744172)
			(xy 332.761082 -278.844248)
		)
		(stroke
			(width 0)
			(type solid)
		)
		(fill yes)
		(layer "In4.Cu")
		(net "M_D_CPU0_SB_DQ<7>")
	)
	(gr_poly
		(pts
			(xy 332.861158 -277.52802) (xy 332.761082 -277.427944) (xy 332.661006 -277.52802) (xy 332.661006 -277.57247)
			(xy 332.861158 -277.57247)
		)
		(stroke
			(width 0)
			(type solid)
		)
		(fill yes)
		(layer "In4.Cu")
		(net "M_D_CPU0_SB_DQ<4>")
	)
	(gr_poly
		(pts
			(xy 332.861158 -277.124414) (xy 332.861158 -277.076662) (xy 332.661006 -277.076662) (xy 332.661006 -277.124414)
			(xy 332.761082 -277.224236)
		)
		(stroke
			(width 0)
			(type solid)
		)
		(fill yes)
		(layer "In4.Cu")
		(net "M_D_CPU0_SB_DQS_DP<5>")
	)
	(gr_poly
		(pts
			(xy 332.861158 -275.907754) (xy 332.761082 -275.807932) (xy 332.661006 -275.907754) (xy 332.661006 -275.955506)
			(xy 332.861158 -275.955506)
		)
		(stroke
			(width 0)
			(type solid)
		)
		(fill yes)
		(layer "In4.Cu")
		(net "M_D_CPU0_SB_DQS_DP<0>")
	)
	(gr_poly
		(pts
			(xy 332.861158 -275.504148) (xy 332.861158 -275.459698) (xy 332.661006 -275.459698) (xy 332.661006 -275.504148)
			(xy 332.761082 -275.604224)
		)
		(stroke
			(width 0)
			(type solid)
		)
		(fill yes)
		(layer "In4.Cu")
		(net "M_D_CPU0_SB_DQ<3>")
	)
	(gr_poly
		(pts
			(xy 332.861158 -274.287996) (xy 332.761082 -274.18792) (xy 332.661006 -274.287996) (xy 332.661006 -274.332446)
			(xy 332.861158 -274.332446)
		)
		(stroke
			(width 0)
			(type solid)
		)
		(fill yes)
		(layer "In4.Cu")
		(net "M_D_CPU0_SB_DQ<0>")
	)
	(gr_poly
		(pts
			(xy 332.861158 -273.884136) (xy 332.861158 -273.839686) (xy 332.661006 -273.839686) (xy 332.661006 -273.884136)
			(xy 332.761082 -273.984212)
		)
		(stroke
			(width 0)
			(type solid)
		)
		(fill yes)
		(layer "In4.Cu")
		(net "M_D_CPU0_SB_CB<3>")
	)
	(gr_poly
		(pts
			(xy 332.861158 -272.667984) (xy 332.761082 -272.567908) (xy 332.661006 -272.667984) (xy 332.661006 -272.712434)
			(xy 332.861158 -272.712434)
		)
		(stroke
			(width 0)
			(type solid)
		)
		(fill yes)
		(layer "In4.Cu")
		(net "M_D_CPU0_SB_CB<0>")
	)
	(gr_poly
		(pts
			(xy 332.861158 -272.264378) (xy 332.861158 -272.216626) (xy 332.661006 -272.216626) (xy 332.661006 -272.264378)
			(xy 332.761082 -272.3642)
		)
		(stroke
			(width 0)
			(type solid)
		)
		(fill yes)
		(layer "In4.Cu")
		(net "M_D_CPU0_SB_DQS_DP<4>")
	)
	(gr_poly
		(pts
			(xy 332.861158 -271.047718) (xy 332.761082 -270.947896) (xy 332.661006 -271.047718) (xy 332.661006 -271.09547)
			(xy 332.861158 -271.09547)
		)
		(stroke
			(width 0)
			(type solid)
		)
		(fill yes)
		(layer "In4.Cu")
		(net "M_D_CPU0_SB_DQS_DP<9>")
	)
	(gr_poly
		(pts
			(xy 332.861158 -270.644112) (xy 332.861158 -270.599662) (xy 332.661006 -270.599662) (xy 332.661006 -270.644112)
			(xy 332.761082 -270.744188)
		)
		(stroke
			(width 0)
			(type solid)
		)
		(fill yes)
		(layer "In4.Cu")
		(net "M_D_CPU0_SB_CB<7>")
	)
	(gr_poly
		(pts
			(xy 332.861158 -269.42796) (xy 332.761082 -269.327884) (xy 332.661006 -269.42796) (xy 332.661006 -269.47241)
			(xy 332.861158 -269.47241)
		)
		(stroke
			(width 0)
			(type solid)
		)
		(fill yes)
		(layer "In4.Cu")
		(net "M_D_CPU0_SB_CB<4>")
	)
	(gr_poly
		(pts
			(xy 332.861158 -267.801598) (xy 332.761082 -267.701522) (xy 332.661006 -267.801598) (xy 332.661006 -267.846048)
			(xy 332.861158 -267.846048)
		)
		(stroke
			(width 0)
			(type solid)
		)
		(fill yes)
		(layer "In4.Cu")
		(net "M_D_CPU0_SB_RSP<0>")
	)
	(gr_poly
		(pts
			(xy 332.861158 -265.784076) (xy 332.861158 -265.739626) (xy 332.661006 -265.739626) (xy 332.661006 -265.784076)
			(xy 332.761082 -265.884152)
		)
		(stroke
			(width 0)
			(type solid)
		)
		(fill yes)
		(layer "In4.Cu")
		(net "M_D_CPU0_SB_CS_N<0>")
	)
	(gr_poly
		(pts
			(xy 332.861158 -264.567924) (xy 332.761082 -264.467848) (xy 332.661006 -264.567924) (xy 332.661006 -264.612374)
			(xy 332.861158 -264.612374)
		)
		(stroke
			(width 0)
			(type solid)
		)
		(fill yes)
		(layer "In4.Cu")
		(net "M_D_CPU0_SB_CA<6>")
	)
	(gr_poly
		(pts
			(xy 332.861158 -264.164064) (xy 332.861158 -264.119614) (xy 332.661006 -264.119614) (xy 332.661006 -264.164064)
			(xy 332.761082 -264.26414)
		)
		(stroke
			(width 0)
			(type solid)
		)
		(fill yes)
		(layer "In4.Cu")
		(net "M_D_CPU0_SB_CA<5>")
	)
	(gr_poly
		(pts
			(xy 332.861158 -262.947912) (xy 332.761082 -262.847836) (xy 332.661006 -262.947912) (xy 332.661006 -262.992362)
			(xy 332.861158 -262.992362)
		)
		(stroke
			(width 0)
			(type solid)
		)
		(fill yes)
		(layer "In4.Cu")
		(net "M_D_CPU0_SB_CA<2>")
	)
	(gr_poly
		(pts
			(xy 332.861158 -262.544052) (xy 332.861158 -262.499602) (xy 332.661006 -262.499602) (xy 332.661006 -262.544052)
			(xy 332.761082 -262.644128)
		)
		(stroke
			(width 0)
			(type solid)
		)
		(fill yes)
		(layer "In4.Cu")
		(net "M_D_CPU0_SB_CA<1>")
	)
	(gr_poly
		(pts
			(xy 333.031084 -256.025904) (xy 332.931008 -255.926082) (xy 332.830932 -256.025904) (xy 332.830932 -256.073656)
			(xy 333.031084 -256.073656)
		)
		(stroke
			(width 0)
			(type solid)
		)
		(fill yes)
		(layer "In4.Cu")
		(net "M_D_CPU0_CLK_DP<0>")
	)
	(gr_poly
		(pts
			(xy 333.031084 -255.622298) (xy 333.031084 -255.577848) (xy 332.830932 -255.577848) (xy 332.830932 -255.622298)
			(xy 332.931008 -255.722374)
		)
		(stroke
			(width 0)
			(type solid)
		)
		(fill yes)
		(layer "In4.Cu")
		(net "M_D_CPU0_SA_PAR")
	)
	(gr_poly
		(pts
			(xy 333.031084 -254.406146) (xy 332.931008 -254.30607) (xy 332.830932 -254.406146) (xy 332.830932 -254.450596)
			(xy 333.031084 -254.450596)
		)
		(stroke
			(width 0)
			(type solid)
		)
		(fill yes)
		(layer "In4.Cu")
		(net "M_D_CPU0_SA_CA<4>")
	)
	(gr_poly
		(pts
			(xy 333.031084 -254.002286) (xy 333.031084 -253.957836) (xy 332.830932 -253.957836) (xy 332.830932 -254.002286)
			(xy 332.931008 -254.102362)
		)
		(stroke
			(width 0)
			(type solid)
		)
		(fill yes)
		(layer "In4.Cu")
		(net "M_D_CPU0_SA_CA<3>")
	)
	(gr_poly
		(pts
			(xy 333.031084 -252.786134) (xy 332.931008 -252.686058) (xy 332.830932 -252.786134) (xy 332.830932 -252.830584)
			(xy 333.031084 -252.830584)
		)
		(stroke
			(width 0)
			(type solid)
		)
		(fill yes)
		(layer "In4.Cu")
		(net "M_D_CPU0_SA_CA<0>")
	)
	(gr_poly
		(pts
			(xy 333.031084 -252.382274) (xy 333.031084 -252.337824) (xy 332.830932 -252.337824) (xy 332.830932 -252.382274)
			(xy 332.931008 -252.48235)
		)
		(stroke
			(width 0)
			(type solid)
		)
		(fill yes)
		(layer "In4.Cu")
		(net "M_D_CPU0_SA_CS_N<1>")
	)
	(gr_poly
		(pts
			(xy 333.031084 -250.762262) (xy 333.031084 -250.717812) (xy 332.830932 -250.717812) (xy 332.830932 -250.762262)
			(xy 332.931008 -250.862338)
		)
		(stroke
			(width 0)
			(type solid)
		)
		(fill yes)
		(layer "In4.Cu")
		(net "M_D_CPU0_RESET_N")
	)
	(gr_poly
		(pts
			(xy 333.031084 -249.14225) (xy 333.031084 -249.0978) (xy 332.830932 -249.0978) (xy 332.830932 -249.14225)
			(xy 332.931008 -249.242326)
		)
		(stroke
			(width 0)
			(type solid)
		)
		(fill yes)
		(layer "In4.Cu")
		(net "M_D_CPU0_SA_CB<7>")
	)
	(gr_poly
		(pts
			(xy 333.031084 -247.926098) (xy 332.931008 -247.826022) (xy 332.830932 -247.926098) (xy 332.830932 -247.970548)
			(xy 333.031084 -247.970548)
		)
		(stroke
			(width 0)
			(type solid)
		)
		(fill yes)
		(layer "In4.Cu")
		(net "M_D_CPU0_SA_CB<4>")
	)
	(gr_poly
		(pts
			(xy 333.031084 -247.522492) (xy 333.031084 -247.47474) (xy 332.830932 -247.47474) (xy 332.830932 -247.522492)
			(xy 332.931008 -247.622314)
		)
		(stroke
			(width 0)
			(type solid)
		)
		(fill yes)
		(layer "In4.Cu")
		(net "M_D_CPU0_SA_DQS_DP<9>")
	)
	(gr_poly
		(pts
			(xy 333.031084 -246.305832) (xy 332.931008 -246.20601) (xy 332.830932 -246.305832) (xy 332.830932 -246.353584)
			(xy 333.031084 -246.353584)
		)
		(stroke
			(width 0)
			(type solid)
		)
		(fill yes)
		(layer "In4.Cu")
		(net "M_D_CPU0_SA_DQS_DP<4>")
	)
	(gr_poly
		(pts
			(xy 333.031084 -245.902226) (xy 333.031084 -245.857776) (xy 332.830932 -245.857776) (xy 332.830932 -245.902226)
			(xy 332.931008 -246.002302)
		)
		(stroke
			(width 0)
			(type solid)
		)
		(fill yes)
		(layer "In4.Cu")
		(net "M_D_CPU0_SA_CB<3>")
	)
	(gr_poly
		(pts
			(xy 333.031084 -244.686074) (xy 332.931008 -244.585998) (xy 332.830932 -244.686074) (xy 332.830932 -244.730524)
			(xy 333.031084 -244.730524)
		)
		(stroke
			(width 0)
			(type solid)
		)
		(fill yes)
		(layer "In4.Cu")
		(net "M_D_CPU0_SA_CB<0>")
	)
	(gr_poly
		(pts
			(xy 333.031084 -244.282214) (xy 333.031084 -244.237764) (xy 332.830932 -244.237764) (xy 332.830932 -244.282214)
			(xy 332.931008 -244.38229)
		)
		(stroke
			(width 0)
			(type solid)
		)
		(fill yes)
		(layer "In4.Cu")
		(net "M_D_CPU0_SA_DQ<31>")
	)
	(gr_poly
		(pts
			(xy 333.031084 -243.066062) (xy 332.931008 -242.965986) (xy 332.830932 -243.066062) (xy 332.830932 -243.110512)
			(xy 333.031084 -243.110512)
		)
		(stroke
			(width 0)
			(type solid)
		)
		(fill yes)
		(layer "In4.Cu")
		(net "M_D_CPU0_SA_DQ<28>")
	)
	(gr_poly
		(pts
			(xy 333.031084 -242.662456) (xy 333.031084 -242.614704) (xy 332.830932 -242.614704) (xy 332.830932 -242.662456)
			(xy 332.931008 -242.762278)
		)
		(stroke
			(width 0)
			(type solid)
		)
		(fill yes)
		(layer "In4.Cu")
		(net "M_D_CPU0_SA_DQS_DP<8>")
	)
	(gr_poly
		(pts
			(xy 333.031084 -241.445796) (xy 332.931008 -241.345974) (xy 332.830932 -241.445796) (xy 332.830932 -241.493548)
			(xy 333.031084 -241.493548)
		)
		(stroke
			(width 0)
			(type solid)
		)
		(fill yes)
		(layer "In4.Cu")
		(net "M_D_CPU0_SA_DQS_DP<3>")
	)
	(gr_poly
		(pts
			(xy 333.031084 -241.04219) (xy 333.031084 -240.99774) (xy 332.830932 -240.99774) (xy 332.830932 -241.04219)
			(xy 332.931008 -241.142266)
		)
		(stroke
			(width 0)
			(type solid)
		)
		(fill yes)
		(layer "In4.Cu")
		(net "M_D_CPU0_SA_DQ<27>")
	)
	(gr_poly
		(pts
			(xy 333.031084 -239.826038) (xy 332.931008 -239.725962) (xy 332.830932 -239.826038) (xy 332.830932 -239.870488)
			(xy 333.031084 -239.870488)
		)
		(stroke
			(width 0)
			(type solid)
		)
		(fill yes)
		(layer "In4.Cu")
		(net "M_D_CPU0_SA_DQ<24>")
	)
	(gr_poly
		(pts
			(xy 333.031084 -239.422178) (xy 333.031084 -239.377728) (xy 332.830932 -239.377728) (xy 332.830932 -239.422178)
			(xy 332.931008 -239.522254)
		)
		(stroke
			(width 0)
			(type solid)
		)
		(fill yes)
		(layer "In4.Cu")
		(net "M_D_CPU0_SA_DQ<23>")
	)
	(gr_poly
		(pts
			(xy 333.031084 -238.206026) (xy 332.931008 -238.10595) (xy 332.830932 -238.206026) (xy 332.830932 -238.250476)
			(xy 333.031084 -238.250476)
		)
		(stroke
			(width 0)
			(type solid)
		)
		(fill yes)
		(layer "In4.Cu")
		(net "M_D_CPU0_SA_DQ<20>")
	)
	(gr_poly
		(pts
			(xy 333.031084 -237.80242) (xy 333.031084 -237.754668) (xy 332.830932 -237.754668) (xy 332.830932 -237.80242)
			(xy 332.931008 -237.902242)
		)
		(stroke
			(width 0)
			(type solid)
		)
		(fill yes)
		(layer "In4.Cu")
		(net "M_D_CPU0_SA_DQS_DP<7>")
	)
	(gr_poly
		(pts
			(xy 333.031084 -236.58576) (xy 332.931008 -236.485938) (xy 332.830932 -236.58576) (xy 332.830932 -236.633512)
			(xy 333.031084 -236.633512)
		)
		(stroke
			(width 0)
			(type solid)
		)
		(fill yes)
		(layer "In4.Cu")
		(net "M_D_CPU0_SA_DQS_DP<2>")
	)
	(gr_poly
		(pts
			(xy 333.031084 -236.182154) (xy 333.031084 -236.137704) (xy 332.830932 -236.137704) (xy 332.830932 -236.182154)
			(xy 332.931008 -236.28223)
		)
		(stroke
			(width 0)
			(type solid)
		)
		(fill yes)
		(layer "In4.Cu")
		(net "M_D_CPU0_SA_DQ<19>")
	)
	(gr_poly
		(pts
			(xy 333.031084 -234.966002) (xy 332.931008 -234.865926) (xy 332.830932 -234.966002) (xy 332.830932 -235.010452)
			(xy 333.031084 -235.010452)
		)
		(stroke
			(width 0)
			(type solid)
		)
		(fill yes)
		(layer "In4.Cu")
		(net "M_D_CPU0_SA_DQ<16>")
	)
	(gr_poly
		(pts
			(xy 333.031084 -234.562142) (xy 333.031084 -234.517692) (xy 332.830932 -234.517692) (xy 332.830932 -234.562142)
			(xy 332.931008 -234.662218)
		)
		(stroke
			(width 0)
			(type solid)
		)
		(fill yes)
		(layer "In4.Cu")
		(net "M_D_CPU0_SA_DQ<15>")
	)
	(gr_poly
		(pts
			(xy 333.031084 -233.34599) (xy 332.931008 -233.245914) (xy 332.830932 -233.34599) (xy 332.830932 -233.39044)
			(xy 333.031084 -233.39044)
		)
		(stroke
			(width 0)
			(type solid)
		)
		(fill yes)
		(layer "In4.Cu")
		(net "M_D_CPU0_SA_DQ<12>")
	)
	(gr_poly
		(pts
			(xy 333.031084 -232.942384) (xy 333.031084 -232.894632) (xy 332.830932 -232.894632) (xy 332.830932 -232.942384)
			(xy 332.931008 -233.042206)
		)
		(stroke
			(width 0)
			(type solid)
		)
		(fill yes)
		(layer "In4.Cu")
		(net "M_D_CPU0_SA_DQS_DP<6>")
	)
	(gr_poly
		(pts
			(xy 333.031084 -231.725724) (xy 332.931008 -231.625902) (xy 332.830932 -231.725724) (xy 332.830932 -231.773476)
			(xy 333.031084 -231.773476)
		)
		(stroke
			(width 0)
			(type solid)
		)
		(fill yes)
		(layer "In4.Cu")
		(net "M_D_CPU0_SA_DQS_DP<1>")
	)
	(gr_poly
		(pts
			(xy 333.031084 -231.322372) (xy 333.031084 -231.277922) (xy 332.830932 -231.277922) (xy 332.830932 -231.322372)
			(xy 332.931008 -231.422448)
		)
		(stroke
			(width 0)
			(type solid)
		)
		(fill yes)
		(layer "In4.Cu")
		(net "M_D_CPU0_SA_DQ<11>")
	)
	(gr_poly
		(pts
			(xy 333.031084 -230.105966) (xy 332.931008 -230.006144) (xy 332.830932 -230.105966) (xy 332.830932 -230.150416)
			(xy 333.031084 -230.150416)
		)
		(stroke
			(width 0)
			(type solid)
		)
		(fill yes)
		(layer "In4.Cu")
		(net "M_D_CPU0_SA_DQ<8>")
	)
	(gr_poly
		(pts
			(xy 333.031084 -229.70236) (xy 333.031084 -229.65791) (xy 332.830932 -229.65791) (xy 332.830932 -229.70236)
			(xy 332.931008 -229.802436)
		)
		(stroke
			(width 0)
			(type solid)
		)
		(fill yes)
		(layer "In4.Cu")
		(net "M_D_CPU0_SA_DQ<7>")
	)
	(gr_poly
		(pts
			(xy 333.031084 -228.486208) (xy 332.931008 -228.386132) (xy 332.830932 -228.486208) (xy 332.830932 -228.530658)
			(xy 333.031084 -228.530658)
		)
		(stroke
			(width 0)
			(type solid)
		)
		(fill yes)
		(layer "In4.Cu")
		(net "M_D_CPU0_SA_DQ<4>")
	)
	(gr_poly
		(pts
			(xy 333.031084 -228.082602) (xy 333.031084 -228.03485) (xy 332.830932 -228.03485) (xy 332.830932 -228.082602)
			(xy 332.931008 -228.182424)
		)
		(stroke
			(width 0)
			(type solid)
		)
		(fill yes)
		(layer "In4.Cu")
		(net "M_D_CPU0_SA_DQS_DP<5>")
	)
	(gr_poly
		(pts
			(xy 333.031084 -226.865942) (xy 332.931008 -226.76612) (xy 332.830932 -226.865942) (xy 332.830932 -226.913694)
			(xy 333.031084 -226.913694)
		)
		(stroke
			(width 0)
			(type solid)
		)
		(fill yes)
		(layer "In4.Cu")
		(net "M_D_CPU0_SA_DQS_DP<0>")
	)
	(gr_poly
		(pts
			(xy 333.031084 -226.462336) (xy 333.031084 -226.417886) (xy 332.830932 -226.417886) (xy 332.830932 -226.462336)
			(xy 332.931008 -226.562412)
		)
		(stroke
			(width 0)
			(type solid)
		)
		(fill yes)
		(layer "In4.Cu")
		(net "M_D_CPU0_SA_DQ<3>")
	)
	(gr_poly
		(pts
			(xy 333.031084 -225.246184) (xy 332.931008 -225.146108) (xy 332.830932 -225.246184) (xy 332.830932 -225.290634)
			(xy 333.031084 -225.290634)
		)
		(stroke
			(width 0)
			(type solid)
		)
		(fill yes)
		(layer "In4.Cu")
		(net "M_D_CPU0_SA_DQ<0>")
	)
	(gr_poly
		(pts
			(xy 333.331058 -292.91788) (xy 333.230982 -292.817804) (xy 333.130906 -292.91788) (xy 333.130906 -292.96233)
			(xy 333.331058 -292.96233)
		)
		(stroke
			(width 0)
			(type solid)
		)
		(fill yes)
		(layer "In4.Cu")
		(net "M_D_CPU0_SB_DQ<29>")
	)
	(gr_poly
		(pts
			(xy 333.331058 -292.51402) (xy 333.331058 -292.46957) (xy 333.130906 -292.46957) (xy 333.130906 -292.51402)
			(xy 333.230982 -292.614096)
		)
		(stroke
			(width 0)
			(type solid)
		)
		(fill yes)
		(layer "In4.Cu")
		(net "M_D_CPU0_SB_DQ<30>")
	)
	(gr_poly
		(pts
			(xy 333.331058 -291.297614) (xy 333.230982 -291.197792) (xy 333.130906 -291.297614) (xy 333.130906 -291.345366)
			(xy 333.331058 -291.345366)
		)
		(stroke
			(width 0)
			(type solid)
		)
		(fill yes)
		(layer "In4.Cu")
		(net "M_D_CPU0_SB_DQS_DN<8>")
	)
	(gr_poly
		(pts
			(xy 333.331058 -290.894262) (xy 333.331058 -290.84651) (xy 333.130906 -290.84651) (xy 333.130906 -290.894262)
			(xy 333.230982 -290.994084)
		)
		(stroke
			(width 0)
			(type solid)
		)
		(fill yes)
		(layer "In4.Cu")
		(net "M_D_CPU0_SB_DQS_DN<3>")
	)
	(gr_poly
		(pts
			(xy 333.331058 -289.677856) (xy 333.230982 -289.57778) (xy 333.130906 -289.677856) (xy 333.130906 -289.722306)
			(xy 333.331058 -289.722306)
		)
		(stroke
			(width 0)
			(type solid)
		)
		(fill yes)
		(layer "In4.Cu")
		(net "M_D_CPU0_SB_DQ<25>")
	)
	(gr_poly
		(pts
			(xy 333.331058 -289.273996) (xy 333.331058 -289.229546) (xy 333.130906 -289.229546) (xy 333.130906 -289.273996)
			(xy 333.230982 -289.374072)
		)
		(stroke
			(width 0)
			(type solid)
		)
		(fill yes)
		(layer "In4.Cu")
		(net "M_D_CPU0_SB_DQ<26>")
	)
	(gr_poly
		(pts
			(xy 333.331058 -288.057844) (xy 333.230982 -287.957768) (xy 333.130906 -288.057844) (xy 333.130906 -288.102294)
			(xy 333.331058 -288.102294)
		)
		(stroke
			(width 0)
			(type solid)
		)
		(fill yes)
		(layer "In4.Cu")
		(net "M_D_CPU0_SB_DQ<21>")
	)
	(gr_poly
		(pts
			(xy 333.331058 -287.654238) (xy 333.331058 -287.609788) (xy 333.130906 -287.609788) (xy 333.130906 -287.654238)
			(xy 333.230982 -287.75406)
		)
		(stroke
			(width 0)
			(type solid)
		)
		(fill yes)
		(layer "In4.Cu")
		(net "M_D_CPU0_SB_DQ<22>")
	)
	(gr_poly
		(pts
			(xy 333.331058 -286.437832) (xy 333.230982 -286.337756) (xy 333.130906 -286.437832) (xy 333.130906 -286.485584)
			(xy 333.331058 -286.485584)
		)
		(stroke
			(width 0)
			(type solid)
		)
		(fill yes)
		(layer "In4.Cu")
		(net "M_D_CPU0_SB_DQS_DN<7>")
	)
	(gr_poly
		(pts
			(xy 333.331058 -286.03448) (xy 333.331058 -285.986728) (xy 333.130906 -285.986728) (xy 333.130906 -286.03448)
			(xy 333.230982 -286.134302)
		)
		(stroke
			(width 0)
			(type solid)
		)
		(fill yes)
		(layer "In4.Cu")
		(net "M_D_CPU0_SB_DQS_DN<2>")
	)
	(gr_poly
		(pts
			(xy 333.331058 -284.818074) (xy 333.230982 -284.717998) (xy 333.130906 -284.818074) (xy 333.130906 -284.862524)
			(xy 333.331058 -284.862524)
		)
		(stroke
			(width 0)
			(type solid)
		)
		(fill yes)
		(layer "In4.Cu")
		(net "M_D_CPU0_SB_DQ<17>")
	)
	(gr_poly
		(pts
			(xy 333.331058 -284.414214) (xy 333.331058 -284.369764) (xy 333.130906 -284.369764) (xy 333.130906 -284.414214)
			(xy 333.230982 -284.51429)
		)
		(stroke
			(width 0)
			(type solid)
		)
		(fill yes)
		(layer "In4.Cu")
		(net "M_D_CPU0_SB_DQ<18>")
	)
	(gr_poly
		(pts
			(xy 333.331058 -283.198062) (xy 333.230982 -283.097986) (xy 333.130906 -283.198062) (xy 333.130906 -283.242512)
			(xy 333.331058 -283.242512)
		)
		(stroke
			(width 0)
			(type solid)
		)
		(fill yes)
		(layer "In4.Cu")
		(net "M_D_CPU0_SB_DQ<13>")
	)
	(gr_poly
		(pts
			(xy 333.331058 -282.794202) (xy 333.331058 -282.749752) (xy 333.130906 -282.749752) (xy 333.130906 -282.794202)
			(xy 333.230982 -282.894278)
		)
		(stroke
			(width 0)
			(type solid)
		)
		(fill yes)
		(layer "In4.Cu")
		(net "M_D_CPU0_SB_DQ<14>")
	)
	(gr_poly
		(pts
			(xy 333.331058 -281.577796) (xy 333.230982 -281.477974) (xy 333.130906 -281.577796) (xy 333.130906 -281.625548)
			(xy 333.331058 -281.625548)
		)
		(stroke
			(width 0)
			(type solid)
		)
		(fill yes)
		(layer "In4.Cu")
		(net "M_D_CPU0_SB_DQS_DN<6>")
	)
	(gr_poly
		(pts
			(xy 333.331058 -281.174444) (xy 333.331058 -281.126692) (xy 333.130906 -281.126692) (xy 333.130906 -281.174444)
			(xy 333.230982 -281.274266)
		)
		(stroke
			(width 0)
			(type solid)
		)
		(fill yes)
		(layer "In4.Cu")
		(net "M_D_CPU0_SB_DQS_DN<1>")
	)
	(gr_poly
		(pts
			(xy 333.331058 -279.958038) (xy 333.230982 -279.857962) (xy 333.130906 -279.958038) (xy 333.130906 -280.002488)
			(xy 333.331058 -280.002488)
		)
		(stroke
			(width 0)
			(type solid)
		)
		(fill yes)
		(layer "In4.Cu")
		(net "M_D_CPU0_SB_DQ<9>")
	)
	(gr_poly
		(pts
			(xy 333.331058 -279.554178) (xy 333.331058 -279.509728) (xy 333.130906 -279.509728) (xy 333.130906 -279.554178)
			(xy 333.230982 -279.654254)
		)
		(stroke
			(width 0)
			(type solid)
		)
		(fill yes)
		(layer "In4.Cu")
		(net "M_D_CPU0_SB_DQ<10>")
	)
	(gr_poly
		(pts
			(xy 333.331058 -278.338026) (xy 333.230982 -278.23795) (xy 333.130906 -278.338026) (xy 333.130906 -278.382476)
			(xy 333.331058 -278.382476)
		)
		(stroke
			(width 0)
			(type solid)
		)
		(fill yes)
		(layer "In4.Cu")
		(net "M_D_CPU0_SB_DQ<5>")
	)
	(gr_poly
		(pts
			(xy 333.331058 -277.934166) (xy 333.331058 -277.889716) (xy 333.130906 -277.889716) (xy 333.130906 -277.934166)
			(xy 333.230982 -278.034242)
		)
		(stroke
			(width 0)
			(type solid)
		)
		(fill yes)
		(layer "In4.Cu")
		(net "M_D_CPU0_SB_DQ<6>")
	)
	(gr_poly
		(pts
			(xy 333.331058 -276.71776) (xy 333.230982 -276.617938) (xy 333.130906 -276.71776) (xy 333.130906 -276.765512)
			(xy 333.331058 -276.765512)
		)
		(stroke
			(width 0)
			(type solid)
		)
		(fill yes)
		(layer "In4.Cu")
		(net "M_D_CPU0_SB_DQS_DN<5>")
	)
	(gr_poly
		(pts
			(xy 333.331058 -276.314408) (xy 333.331058 -276.266656) (xy 333.130906 -276.266656) (xy 333.130906 -276.314408)
			(xy 333.230982 -276.41423)
		)
		(stroke
			(width 0)
			(type solid)
		)
		(fill yes)
		(layer "In4.Cu")
		(net "M_D_CPU0_SB_DQS_DN<0>")
	)
	(gr_poly
		(pts
			(xy 333.331058 -275.098002) (xy 333.230982 -274.997926) (xy 333.130906 -275.098002) (xy 333.130906 -275.142452)
			(xy 333.331058 -275.142452)
		)
		(stroke
			(width 0)
			(type solid)
		)
		(fill yes)
		(layer "In4.Cu")
		(net "M_D_CPU0_SB_DQ<1>")
	)
	(gr_poly
		(pts
			(xy 333.331058 -274.694142) (xy 333.331058 -274.649692) (xy 333.130906 -274.649692) (xy 333.130906 -274.694142)
			(xy 333.230982 -274.794218)
		)
		(stroke
			(width 0)
			(type solid)
		)
		(fill yes)
		(layer "In4.Cu")
		(net "M_D_CPU0_SB_DQ<2>")
	)
	(gr_poly
		(pts
			(xy 333.331058 -273.47799) (xy 333.230982 -273.377914) (xy 333.130906 -273.47799) (xy 333.130906 -273.52244)
			(xy 333.331058 -273.52244)
		)
		(stroke
			(width 0)
			(type solid)
		)
		(fill yes)
		(layer "In4.Cu")
		(net "M_D_CPU0_SB_CB<1>")
	)
	(gr_poly
		(pts
			(xy 333.331058 -273.07413) (xy 333.331058 -273.02968) (xy 333.130906 -273.02968) (xy 333.130906 -273.07413)
			(xy 333.230982 -273.174206)
		)
		(stroke
			(width 0)
			(type solid)
		)
		(fill yes)
		(layer "In4.Cu")
		(net "M_D_CPU0_SB_CB<2>")
	)
	(gr_poly
		(pts
			(xy 333.331058 -271.857724) (xy 333.230982 -271.757902) (xy 333.130906 -271.857724) (xy 333.130906 -271.905476)
			(xy 333.331058 -271.905476)
		)
		(stroke
			(width 0)
			(type solid)
		)
		(fill yes)
		(layer "In4.Cu")
		(net "M_D_CPU0_SB_DQS_DN<4>")
	)
	(gr_poly
		(pts
			(xy 333.331058 -271.454372) (xy 333.331058 -271.40662) (xy 333.130906 -271.40662) (xy 333.130906 -271.454372)
			(xy 333.230982 -271.554194)
		)
		(stroke
			(width 0)
			(type solid)
		)
		(fill yes)
		(layer "In4.Cu")
		(net "M_D_CPU0_SB_DQS_DN<9>")
	)
	(gr_poly
		(pts
			(xy 333.331058 -270.237966) (xy 333.230982 -270.13789) (xy 333.130906 -270.237966) (xy 333.130906 -270.282416)
			(xy 333.331058 -270.282416)
		)
		(stroke
			(width 0)
			(type solid)
		)
		(fill yes)
		(layer "In4.Cu")
		(net "M_D_CPU0_SB_CB<5>")
	)
	(gr_poly
		(pts
			(xy 333.331058 -269.834106) (xy 333.331058 -269.789656) (xy 333.130906 -269.789656) (xy 333.130906 -269.834106)
			(xy 333.230982 -269.934182)
		)
		(stroke
			(width 0)
			(type solid)
		)
		(fill yes)
		(layer "In4.Cu")
		(net "M_D_CPU0_SB_CB<6>")
	)
	(gr_poly
		(pts
			(xy 333.331058 -266.594082) (xy 333.331058 -266.549632) (xy 333.130906 -266.549632) (xy 333.130906 -266.594082)
			(xy 333.230982 -266.694158)
		)
		(stroke
			(width 0)
			(type solid)
		)
		(fill yes)
		(layer "In4.Cu")
		(net "M_D_CPU0_SB_CS_N<1>")
	)
	(gr_poly
		(pts
			(xy 333.331058 -264.97407) (xy 333.331058 -264.92962) (xy 333.130906 -264.92962) (xy 333.130906 -264.97407)
			(xy 333.230982 -265.074146)
		)
		(stroke
			(width 0)
			(type solid)
		)
		(fill yes)
		(layer "In4.Cu")
		(net "M_D_CPU0_SB_PAR")
	)
	(gr_poly
		(pts
			(xy 333.331058 -263.757918) (xy 333.230982 -263.657842) (xy 333.130906 -263.757918) (xy 333.130906 -263.802368)
			(xy 333.331058 -263.802368)
		)
		(stroke
			(width 0)
			(type solid)
		)
		(fill yes)
		(layer "In4.Cu")
		(net "M_D_CPU0_SB_CA<4>")
	)
	(gr_poly
		(pts
			(xy 333.331058 -263.354058) (xy 333.331058 -263.309608) (xy 333.130906 -263.309608) (xy 333.130906 -263.354058)
			(xy 333.230982 -263.454134)
		)
		(stroke
			(width 0)
			(type solid)
		)
		(fill yes)
		(layer "In4.Cu")
		(net "M_D_CPU0_SB_CA<3>")
	)
	(gr_poly
		(pts
			(xy 333.331058 -262.137906) (xy 333.230982 -262.03783) (xy 333.130906 -262.137906) (xy 333.130906 -262.182356)
			(xy 333.331058 -262.182356)
		)
		(stroke
			(width 0)
			(type solid)
		)
		(fill yes)
		(layer "In4.Cu")
		(net "M_D_CPU0_SB_CA<0>")
	)
	(gr_poly
		(pts
			(xy 333.337154 -266.991592) (xy 333.237332 -266.891516) (xy 333.137256 -266.991592) (xy 333.137256 -267.036042)
			(xy 333.337154 -267.036042)
		)
		(stroke
			(width 0)
			(type solid)
		)
		(fill yes)
		(layer "In4.Cu")
		(net "M_D_CPU0_SA_RSP<0>")
	)
	(gr_poly
		(pts
			(xy 333.495142 -227.676456) (xy 333.395066 -227.57638) (xy 333.29499 -227.676456) (xy 333.29499 -227.723954)
			(xy 333.495142 -227.723954)
		)
		(stroke
			(width 0)
			(type solid)
		)
		(fill yes)
		(layer "In4.Cu")
		(net "M_D_CPU0_SA_DQS_DN<5>")
	)
	(gr_poly
		(pts
			(xy 333.501238 -256.432558) (xy 333.501238 -256.384806) (xy 333.301086 -256.384806) (xy 333.301086 -256.432558)
			(xy 333.401162 -256.53238)
		)
		(stroke
			(width 0)
			(type solid)
		)
		(fill yes)
		(layer "In4.Cu")
		(net "M_D_CPU0_CLK_DN<0>")
	)
	(gr_poly
		(pts
			(xy 333.501238 -255.216152) (xy 333.401162 -255.116076) (xy 333.301086 -255.216152) (xy 333.301086 -255.260602)
			(xy 333.501238 -255.260602)
		)
		(stroke
			(width 0)
			(type solid)
		)
		(fill yes)
		(layer "In4.Cu")
		(net "M_D_CPU0_SA_CA<6>")
	)
	(gr_poly
		(pts
			(xy 333.501238 -254.812292) (xy 333.501238 -254.767842) (xy 333.301086 -254.767842) (xy 333.301086 -254.812292)
			(xy 333.401162 -254.912368)
		)
		(stroke
			(width 0)
			(type solid)
		)
		(fill yes)
		(layer "In4.Cu")
		(net "M_D_CPU0_SA_CA<5>")
	)
	(gr_poly
		(pts
			(xy 333.501238 -253.59614) (xy 333.401162 -253.496064) (xy 333.301086 -253.59614) (xy 333.301086 -253.64059)
			(xy 333.501238 -253.64059)
		)
		(stroke
			(width 0)
			(type solid)
		)
		(fill yes)
		(layer "In4.Cu")
		(net "M_D_CPU0_SA_CA<2>")
	)
	(gr_poly
		(pts
			(xy 333.501238 -253.19228) (xy 333.501238 -253.14783) (xy 333.301086 -253.14783) (xy 333.301086 -253.19228)
			(xy 333.401162 -253.292356)
		)
		(stroke
			(width 0)
			(type solid)
		)
		(fill yes)
		(layer "In4.Cu")
		(net "M_D_CPU0_SA_CA<1>")
	)
	(gr_poly
		(pts
			(xy 333.501238 -251.572268) (xy 333.501238 -251.527818) (xy 333.301086 -251.527818) (xy 333.301086 -251.572268)
			(xy 333.401162 -251.672344)
		)
		(stroke
			(width 0)
			(type solid)
		)
		(fill yes)
		(layer "In4.Cu")
		(net "M_D_CPU0_SA_CS_N<0>")
	)
	(gr_poly
		(pts
			(xy 333.501238 -250.356116) (xy 333.401162 -250.25604) (xy 333.301086 -250.356116) (xy 333.301086 -250.400566)
			(xy 333.501238 -250.400566)
		)
		(stroke
			(width 0)
			(type solid)
		)
		(fill yes)
		(layer "In4.Cu")
		(net "M_D_CPU0_ALERT_R_N")
	)
	(gr_poly
		(pts
			(xy 333.501238 -248.736104) (xy 333.401162 -248.636028) (xy 333.301086 -248.736104) (xy 333.301086 -248.780554)
			(xy 333.501238 -248.780554)
		)
		(stroke
			(width 0)
			(type solid)
		)
		(fill yes)
		(layer "In4.Cu")
		(net "M_D_CPU0_SA_CB<5>")
	)
	(gr_poly
		(pts
			(xy 333.501238 -248.332244) (xy 333.501238 -248.287794) (xy 333.301086 -248.287794) (xy 333.301086 -248.332244)
			(xy 333.401162 -248.43232)
		)
		(stroke
			(width 0)
			(type solid)
		)
		(fill yes)
		(layer "In4.Cu")
		(net "M_D_CPU0_SA_CB<6>")
	)
	(gr_poly
		(pts
			(xy 333.501238 -247.115838) (xy 333.401162 -247.016016) (xy 333.301086 -247.115838) (xy 333.301086 -247.16359)
			(xy 333.501238 -247.16359)
		)
		(stroke
			(width 0)
			(type solid)
		)
		(fill yes)
		(layer "In4.Cu")
		(net "M_D_CPU0_SA_DQS_DN<9>")
	)
	(gr_poly
		(pts
			(xy 333.501238 -246.712486) (xy 333.501238 -246.664734) (xy 333.301086 -246.664734) (xy 333.301086 -246.712486)
			(xy 333.401162 -246.812308)
		)
		(stroke
			(width 0)
			(type solid)
		)
		(fill yes)
		(layer "In4.Cu")
		(net "M_D_CPU0_SA_DQS_DN<4>")
	)
	(gr_poly
		(pts
			(xy 333.501238 -245.49608) (xy 333.401162 -245.396004) (xy 333.301086 -245.49608) (xy 333.301086 -245.54053)
			(xy 333.501238 -245.54053)
		)
		(stroke
			(width 0)
			(type solid)
		)
		(fill yes)
		(layer "In4.Cu")
		(net "M_D_CPU0_SA_CB<1>")
	)
	(gr_poly
		(pts
			(xy 333.501238 -245.09222) (xy 333.501238 -245.04777) (xy 333.301086 -245.04777) (xy 333.301086 -245.09222)
			(xy 333.401162 -245.192296)
		)
		(stroke
			(width 0)
			(type solid)
		)
		(fill yes)
		(layer "In4.Cu")
		(net "M_D_CPU0_SA_CB<2>")
	)
	(gr_poly
		(pts
			(xy 333.501238 -243.876068) (xy 333.401162 -243.775992) (xy 333.301086 -243.876068) (xy 333.301086 -243.920518)
			(xy 333.501238 -243.920518)
		)
		(stroke
			(width 0)
			(type solid)
		)
		(fill yes)
		(layer "In4.Cu")
		(net "M_D_CPU0_SA_DQ<29>")
	)
	(gr_poly
		(pts
			(xy 333.501238 -243.472208) (xy 333.501238 -243.427758) (xy 333.301086 -243.427758) (xy 333.301086 -243.472208)
			(xy 333.401162 -243.572284)
		)
		(stroke
			(width 0)
			(type solid)
		)
		(fill yes)
		(layer "In4.Cu")
		(net "M_D_CPU0_SA_DQ<30>")
	)
	(gr_poly
		(pts
			(xy 333.501238 -242.255802) (xy 333.401162 -242.15598) (xy 333.301086 -242.255802) (xy 333.301086 -242.303554)
			(xy 333.501238 -242.303554)
		)
		(stroke
			(width 0)
			(type solid)
		)
		(fill yes)
		(layer "In4.Cu")
		(net "M_D_CPU0_SA_DQS_DN<8>")
	)
	(gr_poly
		(pts
			(xy 333.501238 -241.85245) (xy 333.501238 -241.804698) (xy 333.301086 -241.804698) (xy 333.301086 -241.85245)
			(xy 333.401162 -241.952272)
		)
		(stroke
			(width 0)
			(type solid)
		)
		(fill yes)
		(layer "In4.Cu")
		(net "M_D_CPU0_SA_DQS_DN<3>")
	)
	(gr_poly
		(pts
			(xy 333.501238 -240.636044) (xy 333.401162 -240.535968) (xy 333.301086 -240.636044) (xy 333.301086 -240.680494)
			(xy 333.501238 -240.680494)
		)
		(stroke
			(width 0)
			(type solid)
		)
		(fill yes)
		(layer "In4.Cu")
		(net "M_D_CPU0_SA_DQ<25>")
	)
	(gr_poly
		(pts
			(xy 333.501238 -240.232184) (xy 333.501238 -240.187734) (xy 333.301086 -240.187734) (xy 333.301086 -240.232184)
			(xy 333.401162 -240.33226)
		)
		(stroke
			(width 0)
			(type solid)
		)
		(fill yes)
		(layer "In4.Cu")
		(net "M_D_CPU0_SA_DQ<26>")
	)
	(gr_poly
		(pts
			(xy 333.501238 -239.016032) (xy 333.401162 -238.915956) (xy 333.301086 -239.016032) (xy 333.301086 -239.060482)
			(xy 333.501238 -239.060482)
		)
		(stroke
			(width 0)
			(type solid)
		)
		(fill yes)
		(layer "In4.Cu")
		(net "M_D_CPU0_SA_DQ<21>")
	)
	(gr_poly
		(pts
			(xy 333.501238 -238.612172) (xy 333.501238 -238.567722) (xy 333.301086 -238.567722) (xy 333.301086 -238.612172)
			(xy 333.401162 -238.712248)
		)
		(stroke
			(width 0)
			(type solid)
		)
		(fill yes)
		(layer "In4.Cu")
		(net "M_D_CPU0_SA_DQ<22>")
	)
	(gr_poly
		(pts
			(xy 333.501238 -237.395766) (xy 333.401162 -237.295944) (xy 333.301086 -237.395766) (xy 333.301086 -237.443518)
			(xy 333.501238 -237.443518)
		)
		(stroke
			(width 0)
			(type solid)
		)
		(fill yes)
		(layer "In4.Cu")
		(net "M_D_CPU0_SA_DQS_DN<7>")
	)
	(gr_poly
		(pts
			(xy 333.501238 -236.992414) (xy 333.501238 -236.944662) (xy 333.301086 -236.944662) (xy 333.301086 -236.992414)
			(xy 333.401162 -237.092236)
		)
		(stroke
			(width 0)
			(type solid)
		)
		(fill yes)
		(layer "In4.Cu")
		(net "M_D_CPU0_SA_DQS_DN<2>")
	)
	(gr_poly
		(pts
			(xy 333.501238 -235.776008) (xy 333.401162 -235.675932) (xy 333.301086 -235.776008) (xy 333.301086 -235.820458)
			(xy 333.501238 -235.820458)
		)
		(stroke
			(width 0)
			(type solid)
		)
		(fill yes)
		(layer "In4.Cu")
		(net "M_D_CPU0_SA_DQ<17>")
	)
	(gr_poly
		(pts
			(xy 333.501238 -235.372148) (xy 333.501238 -235.327698) (xy 333.301086 -235.327698) (xy 333.301086 -235.372148)
			(xy 333.401162 -235.472224)
		)
		(stroke
			(width 0)
			(type solid)
		)
		(fill yes)
		(layer "In4.Cu")
		(net "M_D_CPU0_SA_DQ<18>")
	)
	(gr_poly
		(pts
			(xy 333.501238 -234.155996) (xy 333.401162 -234.05592) (xy 333.301086 -234.155996) (xy 333.301086 -234.200446)
			(xy 333.501238 -234.200446)
		)
		(stroke
			(width 0)
			(type solid)
		)
		(fill yes)
		(layer "In4.Cu")
		(net "M_D_CPU0_SA_DQ<13>")
	)
	(gr_poly
		(pts
			(xy 333.501238 -233.752136) (xy 333.501238 -233.707686) (xy 333.301086 -233.707686) (xy 333.301086 -233.752136)
			(xy 333.401162 -233.852212)
		)
		(stroke
			(width 0)
			(type solid)
		)
		(fill yes)
		(layer "In4.Cu")
		(net "M_D_CPU0_SA_DQ<14>")
	)
	(gr_poly
		(pts
			(xy 333.501238 -232.53573) (xy 333.401162 -232.435908) (xy 333.301086 -232.53573) (xy 333.301086 -232.583482)
			(xy 333.501238 -232.583482)
		)
		(stroke
			(width 0)
			(type solid)
		)
		(fill yes)
		(layer "In4.Cu")
		(net "M_D_CPU0_SA_DQS_DN<6>")
	)
	(gr_poly
		(pts
			(xy 333.501238 -232.132378) (xy 333.501238 -232.084626) (xy 333.301086 -232.084626) (xy 333.301086 -232.132378)
			(xy 333.401162 -232.2322)
		)
		(stroke
			(width 0)
			(type solid)
		)
		(fill yes)
		(layer "In4.Cu")
		(net "M_D_CPU0_SA_DQS_DN<1>")
	)
	(gr_poly
		(pts
			(xy 333.501238 -230.915972) (xy 333.401162 -230.815896) (xy 333.301086 -230.915972) (xy 333.301086 -230.960422)
			(xy 333.501238 -230.960422)
		)
		(stroke
			(width 0)
			(type solid)
		)
		(fill yes)
		(layer "In4.Cu")
		(net "M_D_CPU0_SA_DQ<9>")
	)
	(gr_poly
		(pts
			(xy 333.501238 -230.512366) (xy 333.501238 -230.467916) (xy 333.301086 -230.467916) (xy 333.301086 -230.512366)
			(xy 333.401162 -230.612188)
		)
		(stroke
			(width 0)
			(type solid)
		)
		(fill yes)
		(layer "In4.Cu")
		(net "M_D_CPU0_SA_DQ<10>")
	)
	(gr_poly
		(pts
			(xy 333.501238 -229.29596) (xy 333.401162 -229.195884) (xy 333.301086 -229.29596) (xy 333.301086 -229.34041)
			(xy 333.501238 -229.34041)
		)
		(stroke
			(width 0)
			(type solid)
		)
		(fill yes)
		(layer "In4.Cu")
		(net "M_D_CPU0_SA_DQ<5>")
	)
	(gr_poly
		(pts
			(xy 333.501238 -228.892354) (xy 333.501238 -228.847904) (xy 333.301086 -228.847904) (xy 333.301086 -228.892354)
			(xy 333.401162 -228.99243)
		)
		(stroke
			(width 0)
			(type solid)
		)
		(fill yes)
		(layer "In4.Cu")
		(net "M_D_CPU0_SA_DQ<6>")
	)
	(gr_poly
		(pts
			(xy 333.501238 -227.272596) (xy 333.501238 -227.224844) (xy 333.301086 -227.224844) (xy 333.301086 -227.272596)
			(xy 333.401162 -227.372418)
		)
		(stroke
			(width 0)
			(type solid)
		)
		(fill yes)
		(layer "In4.Cu")
		(net "M_D_CPU0_SA_DQS_DN<0>")
	)
	(gr_poly
		(pts
			(xy 333.501238 -226.05619) (xy 333.401162 -225.956114) (xy 333.301086 -226.05619) (xy 333.301086 -226.10064)
			(xy 333.501238 -226.10064)
		)
		(stroke
			(width 0)
			(type solid)
		)
		(fill yes)
		(layer "In4.Cu")
		(net "M_D_CPU0_SA_DQ<1>")
	)
	(gr_poly
		(pts
			(xy 333.501238 -225.65233) (xy 333.501238 -225.60788) (xy 333.301086 -225.60788) (xy 333.301086 -225.65233)
			(xy 333.401162 -225.752406)
		)
		(stroke
			(width 0)
			(type solid)
		)
		(fill yes)
		(layer "In4.Cu")
		(net "M_D_CPU0_SA_DQ<2>")
	)
	(gr_poly
		(pts
			(xy 333.794862 -267.801598) (xy 333.694786 -267.701522) (xy 333.594964 -267.801598) (xy 333.594964 -267.846048)
			(xy 333.794862 -267.846048)
		)
		(stroke
			(width 0)
			(type solid)
		)
		(fill yes)
		(layer "In4.Cu")
		(net "M_D_CPU0_SB_RSP<0>")
	)
	(gr_poly
		(pts
			(xy 333.801212 -293.324026) (xy 333.801212 -293.279576) (xy 333.60106 -293.279576) (xy 333.60106 -293.324026)
			(xy 333.701136 -293.424102)
		)
		(stroke
			(width 0)
			(type solid)
		)
		(fill yes)
		(layer "In4.Cu")
		(net "M_D_CPU0_SB_DQ<31>")
	)
	(gr_poly
		(pts
			(xy 333.801212 -292.107874) (xy 333.701136 -292.007798) (xy 333.60106 -292.107874) (xy 333.60106 -292.152324)
			(xy 333.801212 -292.152324)
		)
		(stroke
			(width 0)
			(type solid)
		)
		(fill yes)
		(layer "In4.Cu")
		(net "M_D_CPU0_SB_DQ<28>")
	)
	(gr_poly
		(pts
			(xy 333.801212 -291.704268) (xy 333.801212 -291.656516) (xy 333.60106 -291.656516) (xy 333.60106 -291.704268)
			(xy 333.701136 -291.80409)
		)
		(stroke
			(width 0)
			(type solid)
		)
		(fill yes)
		(layer "In4.Cu")
		(net "M_D_CPU0_SB_DQS_DP<8>")
	)
	(gr_poly
		(pts
			(xy 333.801212 -290.487608) (xy 333.701136 -290.387786) (xy 333.60106 -290.487608) (xy 333.60106 -290.53536)
			(xy 333.801212 -290.53536)
		)
		(stroke
			(width 0)
			(type solid)
		)
		(fill yes)
		(layer "In4.Cu")
		(net "M_D_CPU0_SB_DQS_DP<3>")
	)
	(gr_poly
		(pts
			(xy 333.801212 -290.084002) (xy 333.801212 -290.039552) (xy 333.60106 -290.039552) (xy 333.60106 -290.084002)
			(xy 333.701136 -290.184078)
		)
		(stroke
			(width 0)
			(type solid)
		)
		(fill yes)
		(layer "In4.Cu")
		(net "M_D_CPU0_SB_DQ<27>")
	)
	(gr_poly
		(pts
			(xy 333.801212 -288.86785) (xy 333.701136 -288.767774) (xy 333.60106 -288.86785) (xy 333.60106 -288.9123)
			(xy 333.801212 -288.9123)
		)
		(stroke
			(width 0)
			(type solid)
		)
		(fill yes)
		(layer "In4.Cu")
		(net "M_D_CPU0_SB_DQ<24>")
	)
	(gr_poly
		(pts
			(xy 333.801212 -288.464244) (xy 333.801212 -288.419794) (xy 333.60106 -288.419794) (xy 333.60106 -288.464244)
			(xy 333.701136 -288.56432)
		)
		(stroke
			(width 0)
			(type solid)
		)
		(fill yes)
		(layer "In4.Cu")
		(net "M_D_CPU0_SB_DQ<23>")
	)
	(gr_poly
		(pts
			(xy 333.801212 -287.247838) (xy 333.701136 -287.148016) (xy 333.60106 -287.247838) (xy 333.60106 -287.292288)
			(xy 333.801212 -287.292288)
		)
		(stroke
			(width 0)
			(type solid)
		)
		(fill yes)
		(layer "In4.Cu")
		(net "M_D_CPU0_SB_DQ<20>")
	)
	(gr_poly
		(pts
			(xy 333.801212 -286.844232) (xy 333.801212 -286.79648) (xy 333.60106 -286.79648) (xy 333.60106 -286.844232)
			(xy 333.701136 -286.944308)
		)
		(stroke
			(width 0)
			(type solid)
		)
		(fill yes)
		(layer "In4.Cu")
		(net "M_D_CPU0_SB_DQS_DP<7>")
	)
	(gr_poly
		(pts
			(xy 333.801212 -285.627826) (xy 333.701136 -285.528004) (xy 333.60106 -285.627826) (xy 333.60106 -285.675578)
			(xy 333.801212 -285.675578)
		)
		(stroke
			(width 0)
			(type solid)
		)
		(fill yes)
		(layer "In4.Cu")
		(net "M_D_CPU0_SB_DQS_DP<2>")
	)
	(gr_poly
		(pts
			(xy 333.801212 -285.22422) (xy 333.801212 -285.17977) (xy 333.60106 -285.17977) (xy 333.60106 -285.22422)
			(xy 333.701136 -285.324296)
		)
		(stroke
			(width 0)
			(type solid)
		)
		(fill yes)
		(layer "In4.Cu")
		(net "M_D_CPU0_SB_DQ<19>")
	)
	(gr_poly
		(pts
			(xy 333.801212 -284.008068) (xy 333.701136 -283.907992) (xy 333.60106 -284.008068) (xy 333.60106 -284.052518)
			(xy 333.801212 -284.052518)
		)
		(stroke
			(width 0)
			(type solid)
		)
		(fill yes)
		(layer "In4.Cu")
		(net "M_D_CPU0_SB_DQ<16>")
	)
	(gr_poly
		(pts
			(xy 333.801212 -283.604208) (xy 333.801212 -283.559758) (xy 333.60106 -283.559758) (xy 333.60106 -283.604208)
			(xy 333.701136 -283.704284)
		)
		(stroke
			(width 0)
			(type solid)
		)
		(fill yes)
		(layer "In4.Cu")
		(net "M_D_CPU0_SB_DQ<15>")
	)
	(gr_poly
		(pts
			(xy 333.801212 -282.388056) (xy 333.701136 -282.28798) (xy 333.60106 -282.388056) (xy 333.60106 -282.432506)
			(xy 333.801212 -282.432506)
		)
		(stroke
			(width 0)
			(type solid)
		)
		(fill yes)
		(layer "In4.Cu")
		(net "M_D_CPU0_SB_DQ<12>")
	)
	(gr_poly
		(pts
			(xy 333.801212 -281.98445) (xy 333.801212 -281.936698) (xy 333.60106 -281.936698) (xy 333.60106 -281.98445)
			(xy 333.701136 -282.084272)
		)
		(stroke
			(width 0)
			(type solid)
		)
		(fill yes)
		(layer "In4.Cu")
		(net "M_D_CPU0_SB_DQS_DP<6>")
	)
	(gr_poly
		(pts
			(xy 333.801212 -280.76779) (xy 333.701136 -280.667968) (xy 333.60106 -280.76779) (xy 333.60106 -280.815542)
			(xy 333.801212 -280.815542)
		)
		(stroke
			(width 0)
			(type solid)
		)
		(fill yes)
		(layer "In4.Cu")
		(net "M_D_CPU0_SB_DQS_DP<1>")
	)
	(gr_poly
		(pts
			(xy 333.801212 -280.364184) (xy 333.801212 -280.319734) (xy 333.60106 -280.319734) (xy 333.60106 -280.364184)
			(xy 333.701136 -280.46426)
		)
		(stroke
			(width 0)
			(type solid)
		)
		(fill yes)
		(layer "In4.Cu")
		(net "M_D_CPU0_SB_DQ<11>")
	)
	(gr_poly
		(pts
			(xy 333.801212 -279.148032) (xy 333.701136 -279.047956) (xy 333.60106 -279.148032) (xy 333.60106 -279.192482)
			(xy 333.801212 -279.192482)
		)
		(stroke
			(width 0)
			(type solid)
		)
		(fill yes)
		(layer "In4.Cu")
		(net "M_D_CPU0_SB_DQ<8>")
	)
	(gr_poly
		(pts
			(xy 333.801212 -278.744172) (xy 333.801212 -278.699722) (xy 333.60106 -278.699722) (xy 333.60106 -278.744172)
			(xy 333.701136 -278.844248)
		)
		(stroke
			(width 0)
			(type solid)
		)
		(fill yes)
		(layer "In4.Cu")
		(net "M_D_CPU0_SB_DQ<7>")
	)
	(gr_poly
		(pts
			(xy 333.801212 -277.52802) (xy 333.701136 -277.427944) (xy 333.60106 -277.52802) (xy 333.60106 -277.57247)
			(xy 333.801212 -277.57247)
		)
		(stroke
			(width 0)
			(type solid)
		)
		(fill yes)
		(layer "In4.Cu")
		(net "M_D_CPU0_SB_DQ<4>")
	)
	(gr_poly
		(pts
			(xy 333.801212 -277.12416) (xy 333.801212 -277.076662) (xy 333.60106 -277.076662) (xy 333.60106 -277.12416)
			(xy 333.701136 -277.224236)
		)
		(stroke
			(width 0)
			(type solid)
		)
		(fill yes)
		(layer "In4.Cu")
		(net "M_D_CPU0_SB_DQS_DP<5>")
	)
	(gr_poly
		(pts
			(xy 333.801212 -275.908008) (xy 333.701136 -275.807932) (xy 333.60106 -275.908008) (xy 333.60106 -275.955506)
			(xy 333.801212 -275.955506)
		)
		(stroke
			(width 0)
			(type solid)
		)
		(fill yes)
		(layer "In4.Cu")
		(net "M_D_CPU0_SB_DQS_DP<0>")
	)
	(gr_poly
		(pts
			(xy 333.801212 -275.504148) (xy 333.801212 -275.459698) (xy 333.60106 -275.459698) (xy 333.60106 -275.504148)
			(xy 333.701136 -275.604224)
		)
		(stroke
			(width 0)
			(type solid)
		)
		(fill yes)
		(layer "In4.Cu")
		(net "M_D_CPU0_SB_DQ<3>")
	)
	(gr_poly
		(pts
			(xy 333.801212 -274.287996) (xy 333.701136 -274.18792) (xy 333.60106 -274.287996) (xy 333.60106 -274.332446)
			(xy 333.801212 -274.332446)
		)
		(stroke
			(width 0)
			(type solid)
		)
		(fill yes)
		(layer "In4.Cu")
		(net "M_D_CPU0_SB_DQ<0>")
	)
	(gr_poly
		(pts
			(xy 333.801212 -273.884136) (xy 333.801212 -273.839686) (xy 333.60106 -273.839686) (xy 333.60106 -273.884136)
			(xy 333.701136 -273.984212)
		)
		(stroke
			(width 0)
			(type solid)
		)
		(fill yes)
		(layer "In4.Cu")
		(net "M_D_CPU0_SB_CB<3>")
	)
	(gr_poly
		(pts
			(xy 333.801212 -272.667984) (xy 333.701136 -272.567908) (xy 333.60106 -272.667984) (xy 333.60106 -272.712434)
			(xy 333.801212 -272.712434)
		)
		(stroke
			(width 0)
			(type solid)
		)
		(fill yes)
		(layer "In4.Cu")
		(net "M_D_CPU0_SB_CB<0>")
	)
	(gr_poly
		(pts
			(xy 333.801212 -272.264378) (xy 333.801212 -272.216626) (xy 333.60106 -272.216626) (xy 333.60106 -272.264378)
			(xy 333.701136 -272.3642)
		)
		(stroke
			(width 0)
			(type solid)
		)
		(fill yes)
		(layer "In4.Cu")
		(net "M_D_CPU0_SB_DQS_DP<4>")
	)
	(gr_poly
		(pts
			(xy 333.801212 -271.047718) (xy 333.701136 -270.947896) (xy 333.60106 -271.047718) (xy 333.60106 -271.09547)
			(xy 333.801212 -271.09547)
		)
		(stroke
			(width 0)
			(type solid)
		)
		(fill yes)
		(layer "In4.Cu")
		(net "M_D_CPU0_SB_DQS_DP<9>")
	)
	(gr_poly
		(pts
			(xy 333.801212 -270.644112) (xy 333.801212 -270.599662) (xy 333.60106 -270.599662) (xy 333.60106 -270.644112)
			(xy 333.701136 -270.744188)
		)
		(stroke
			(width 0)
			(type solid)
		)
		(fill yes)
		(layer "In4.Cu")
		(net "M_D_CPU0_SB_CB<7>")
	)
	(gr_poly
		(pts
			(xy 333.801212 -269.42796) (xy 333.701136 -269.327884) (xy 333.60106 -269.42796) (xy 333.60106 -269.47241)
			(xy 333.801212 -269.47241)
		)
		(stroke
			(width 0)
			(type solid)
		)
		(fill yes)
		(layer "In4.Cu")
		(net "M_D_CPU0_SB_CB<4>")
	)
	(gr_poly
		(pts
			(xy 333.801212 -265.784076) (xy 333.801212 -265.739626) (xy 333.60106 -265.739626) (xy 333.60106 -265.784076)
			(xy 333.701136 -265.884152)
		)
		(stroke
			(width 0)
			(type solid)
		)
		(fill yes)
		(layer "In4.Cu")
		(net "M_D_CPU0_SB_CS_N<0>")
	)
	(gr_poly
		(pts
			(xy 333.801212 -264.567924) (xy 333.701136 -264.467848) (xy 333.60106 -264.567924) (xy 333.60106 -264.612374)
			(xy 333.801212 -264.612374)
		)
		(stroke
			(width 0)
			(type solid)
		)
		(fill yes)
		(layer "In4.Cu")
		(net "M_D_CPU0_SB_CA<6>")
	)
	(gr_poly
		(pts
			(xy 333.801212 -264.164064) (xy 333.801212 -264.119614) (xy 333.60106 -264.119614) (xy 333.60106 -264.164064)
			(xy 333.701136 -264.26414)
		)
		(stroke
			(width 0)
			(type solid)
		)
		(fill yes)
		(layer "In4.Cu")
		(net "M_D_CPU0_SB_CA<5>")
	)
	(gr_poly
		(pts
			(xy 333.801212 -262.947912) (xy 333.701136 -262.847836) (xy 333.60106 -262.947912) (xy 333.60106 -262.992362)
			(xy 333.801212 -262.992362)
		)
		(stroke
			(width 0)
			(type solid)
		)
		(fill yes)
		(layer "In4.Cu")
		(net "M_D_CPU0_SB_CA<2>")
	)
	(gr_poly
		(pts
			(xy 333.801212 -262.544052) (xy 333.801212 -262.499602) (xy 333.60106 -262.499602) (xy 333.60106 -262.544052)
			(xy 333.701136 -262.644128)
		)
		(stroke
			(width 0)
			(type solid)
		)
		(fill yes)
		(layer "In4.Cu")
		(net "M_D_CPU0_SB_CA<1>")
	)
	(gr_poly
		(pts
			(xy 333.971138 -256.025904) (xy 333.871062 -255.926082) (xy 333.770986 -256.025904) (xy 333.770986 -256.073656)
			(xy 333.971138 -256.073656)
		)
		(stroke
			(width 0)
			(type solid)
		)
		(fill yes)
		(layer "In4.Cu")
		(net "M_D_CPU0_CLK_DP<0>")
	)
	(gr_poly
		(pts
			(xy 333.971138 -255.622298) (xy 333.971138 -255.577848) (xy 333.770986 -255.577848) (xy 333.770986 -255.622298)
			(xy 333.871062 -255.722374)
		)
		(stroke
			(width 0)
			(type solid)
		)
		(fill yes)
		(layer "In4.Cu")
		(net "M_D_CPU0_SA_PAR")
	)
	(gr_poly
		(pts
			(xy 333.971138 -254.406146) (xy 333.871062 -254.30607) (xy 333.770986 -254.406146) (xy 333.770986 -254.450596)
			(xy 333.971138 -254.450596)
		)
		(stroke
			(width 0)
			(type solid)
		)
		(fill yes)
		(layer "In4.Cu")
		(net "M_D_CPU0_SA_CA<4>")
	)
	(gr_poly
		(pts
			(xy 333.971138 -254.002286) (xy 333.971138 -253.957836) (xy 333.770986 -253.957836) (xy 333.770986 -254.002286)
			(xy 333.871062 -254.102362)
		)
		(stroke
			(width 0)
			(type solid)
		)
		(fill yes)
		(layer "In4.Cu")
		(net "M_D_CPU0_SA_CA<3>")
	)
	(gr_poly
		(pts
			(xy 333.971138 -252.786134) (xy 333.871062 -252.686058) (xy 333.770986 -252.786134) (xy 333.770986 -252.830584)
			(xy 333.971138 -252.830584)
		)
		(stroke
			(width 0)
			(type solid)
		)
		(fill yes)
		(layer "In4.Cu")
		(net "M_D_CPU0_SA_CA<0>")
	)
	(gr_poly
		(pts
			(xy 333.971138 -252.382274) (xy 333.971138 -252.337824) (xy 333.770986 -252.337824) (xy 333.770986 -252.382274)
			(xy 333.871062 -252.48235)
		)
		(stroke
			(width 0)
			(type solid)
		)
		(fill yes)
		(layer "In4.Cu")
		(net "M_D_CPU0_SA_CS_N<1>")
	)
	(gr_poly
		(pts
			(xy 333.971138 -250.762262) (xy 333.971138 -250.717812) (xy 333.770986 -250.717812) (xy 333.770986 -250.762262)
			(xy 333.871062 -250.862338)
		)
		(stroke
			(width 0)
			(type solid)
		)
		(fill yes)
		(layer "In4.Cu")
		(net "M_D_CPU0_RESET_N")
	)
	(gr_poly
		(pts
			(xy 333.971138 -249.14225) (xy 333.971138 -249.0978) (xy 333.770986 -249.0978) (xy 333.770986 -249.14225)
			(xy 333.871062 -249.242326)
		)
		(stroke
			(width 0)
			(type solid)
		)
		(fill yes)
		(layer "In4.Cu")
		(net "M_D_CPU0_SA_CB<7>")
	)
	(gr_poly
		(pts
			(xy 333.971138 -247.926098) (xy 333.871062 -247.826022) (xy 333.770986 -247.926098) (xy 333.770986 -247.970548)
			(xy 333.971138 -247.970548)
		)
		(stroke
			(width 0)
			(type solid)
		)
		(fill yes)
		(layer "In4.Cu")
		(net "M_D_CPU0_SA_CB<4>")
	)
	(gr_poly
		(pts
			(xy 333.971138 -247.522492) (xy 333.971138 -247.47474) (xy 333.770986 -247.47474) (xy 333.770986 -247.522492)
			(xy 333.871062 -247.622314)
		)
		(stroke
			(width 0)
			(type solid)
		)
		(fill yes)
		(layer "In4.Cu")
		(net "M_D_CPU0_SA_DQS_DP<9>")
	)
	(gr_poly
		(pts
			(xy 333.971138 -246.305832) (xy 333.871062 -246.20601) (xy 333.770986 -246.305832) (xy 333.770986 -246.353584)
			(xy 333.971138 -246.353584)
		)
		(stroke
			(width 0)
			(type solid)
		)
		(fill yes)
		(layer "In4.Cu")
		(net "M_D_CPU0_SA_DQS_DP<4>")
	)
	(gr_poly
		(pts
			(xy 333.971138 -245.902226) (xy 333.971138 -245.857776) (xy 333.770986 -245.857776) (xy 333.770986 -245.902226)
			(xy 333.871062 -246.002302)
		)
		(stroke
			(width 0)
			(type solid)
		)
		(fill yes)
		(layer "In4.Cu")
		(net "M_D_CPU0_SA_CB<3>")
	)
	(gr_poly
		(pts
			(xy 333.971138 -244.686074) (xy 333.871062 -244.585998) (xy 333.770986 -244.686074) (xy 333.770986 -244.730524)
			(xy 333.971138 -244.730524)
		)
		(stroke
			(width 0)
			(type solid)
		)
		(fill yes)
		(layer "In4.Cu")
		(net "M_D_CPU0_SA_CB<0>")
	)
	(gr_poly
		(pts
			(xy 333.971138 -244.282214) (xy 333.971138 -244.237764) (xy 333.770986 -244.237764) (xy 333.770986 -244.282214)
			(xy 333.871062 -244.38229)
		)
		(stroke
			(width 0)
			(type solid)
		)
		(fill yes)
		(layer "In4.Cu")
		(net "M_D_CPU0_SA_DQ<31>")
	)
	(gr_poly
		(pts
			(xy 333.971138 -243.066062) (xy 333.871062 -242.965986) (xy 333.770986 -243.066062) (xy 333.770986 -243.110512)
			(xy 333.971138 -243.110512)
		)
		(stroke
			(width 0)
			(type solid)
		)
		(fill yes)
		(layer "In4.Cu")
		(net "M_D_CPU0_SA_DQ<28>")
	)
	(gr_poly
		(pts
			(xy 333.971138 -242.662456) (xy 333.971138 -242.614704) (xy 333.770986 -242.614704) (xy 333.770986 -242.662456)
			(xy 333.871062 -242.762278)
		)
		(stroke
			(width 0)
			(type solid)
		)
		(fill yes)
		(layer "In4.Cu")
		(net "M_D_CPU0_SA_DQS_DP<8>")
	)
	(gr_poly
		(pts
			(xy 333.971138 -241.445796) (xy 333.871062 -241.345974) (xy 333.770986 -241.445796) (xy 333.770986 -241.493548)
			(xy 333.971138 -241.493548)
		)
		(stroke
			(width 0)
			(type solid)
		)
		(fill yes)
		(layer "In4.Cu")
		(net "M_D_CPU0_SA_DQS_DP<3>")
	)
	(gr_poly
		(pts
			(xy 333.971138 -241.04219) (xy 333.971138 -240.99774) (xy 333.770986 -240.99774) (xy 333.770986 -241.04219)
			(xy 333.871062 -241.142266)
		)
		(stroke
			(width 0)
			(type solid)
		)
		(fill yes)
		(layer "In4.Cu")
		(net "M_D_CPU0_SA_DQ<27>")
	)
	(gr_poly
		(pts
			(xy 333.971138 -239.826038) (xy 333.871062 -239.725962) (xy 333.770986 -239.826038) (xy 333.770986 -239.870488)
			(xy 333.971138 -239.870488)
		)
		(stroke
			(width 0)
			(type solid)
		)
		(fill yes)
		(layer "In4.Cu")
		(net "M_D_CPU0_SA_DQ<24>")
	)
	(gr_poly
		(pts
			(xy 333.971138 -239.422178) (xy 333.971138 -239.377728) (xy 333.770986 -239.377728) (xy 333.770986 -239.422178)
			(xy 333.871062 -239.522254)
		)
		(stroke
			(width 0)
			(type solid)
		)
		(fill yes)
		(layer "In4.Cu")
		(net "M_D_CPU0_SA_DQ<23>")
	)
	(gr_poly
		(pts
			(xy 333.971138 -238.206026) (xy 333.871062 -238.10595) (xy 333.770986 -238.206026) (xy 333.770986 -238.250476)
			(xy 333.971138 -238.250476)
		)
		(stroke
			(width 0)
			(type solid)
		)
		(fill yes)
		(layer "In4.Cu")
		(net "M_D_CPU0_SA_DQ<20>")
	)
	(gr_poly
		(pts
			(xy 333.971138 -237.80242) (xy 333.971138 -237.754668) (xy 333.770986 -237.754668) (xy 333.770986 -237.80242)
			(xy 333.871062 -237.902242)
		)
		(stroke
			(width 0)
			(type solid)
		)
		(fill yes)
		(layer "In4.Cu")
		(net "M_D_CPU0_SA_DQS_DP<7>")
	)
	(gr_poly
		(pts
			(xy 333.971138 -236.58576) (xy 333.871062 -236.485938) (xy 333.770986 -236.58576) (xy 333.770986 -236.633512)
			(xy 333.971138 -236.633512)
		)
		(stroke
			(width 0)
			(type solid)
		)
		(fill yes)
		(layer "In4.Cu")
		(net "M_D_CPU0_SA_DQS_DP<2>")
	)
	(gr_poly
		(pts
			(xy 333.971138 -236.182154) (xy 333.971138 -236.137704) (xy 333.770986 -236.137704) (xy 333.770986 -236.182154)
			(xy 333.871062 -236.28223)
		)
		(stroke
			(width 0)
			(type solid)
		)
		(fill yes)
		(layer "In4.Cu")
		(net "M_D_CPU0_SA_DQ<19>")
	)
	(gr_poly
		(pts
			(xy 333.971138 -234.966002) (xy 333.871062 -234.865926) (xy 333.770986 -234.966002) (xy 333.770986 -235.010452)
			(xy 333.971138 -235.010452)
		)
		(stroke
			(width 0)
			(type solid)
		)
		(fill yes)
		(layer "In4.Cu")
		(net "M_D_CPU0_SA_DQ<16>")
	)
	(gr_poly
		(pts
			(xy 333.971138 -234.562142) (xy 333.971138 -234.517692) (xy 333.770986 -234.517692) (xy 333.770986 -234.562142)
			(xy 333.871062 -234.662218)
		)
		(stroke
			(width 0)
			(type solid)
		)
		(fill yes)
		(layer "In4.Cu")
		(net "M_D_CPU0_SA_DQ<15>")
	)
	(gr_poly
		(pts
			(xy 333.971138 -233.34599) (xy 333.871062 -233.245914) (xy 333.770986 -233.34599) (xy 333.770986 -233.39044)
			(xy 333.971138 -233.39044)
		)
		(stroke
			(width 0)
			(type solid)
		)
		(fill yes)
		(layer "In4.Cu")
		(net "M_D_CPU0_SA_DQ<12>")
	)
	(gr_poly
		(pts
			(xy 333.971138 -232.942384) (xy 333.971138 -232.894632) (xy 333.770986 -232.894632) (xy 333.770986 -232.942384)
			(xy 333.871062 -233.042206)
		)
		(stroke
			(width 0)
			(type solid)
		)
		(fill yes)
		(layer "In4.Cu")
		(net "M_D_CPU0_SA_DQS_DP<6>")
	)
	(gr_poly
		(pts
			(xy 333.971138 -231.725724) (xy 333.871062 -231.625902) (xy 333.770986 -231.725724) (xy 333.770986 -231.773476)
			(xy 333.971138 -231.773476)
		)
		(stroke
			(width 0)
			(type solid)
		)
		(fill yes)
		(layer "In4.Cu")
		(net "M_D_CPU0_SA_DQS_DP<1>")
	)
	(gr_poly
		(pts
			(xy 333.971138 -231.322372) (xy 333.971138 -231.277922) (xy 333.770986 -231.277922) (xy 333.770986 -231.322372)
			(xy 333.871062 -231.422448)
		)
		(stroke
			(width 0)
			(type solid)
		)
		(fill yes)
		(layer "In4.Cu")
		(net "M_D_CPU0_SA_DQ<11>")
	)
	(gr_poly
		(pts
			(xy 333.971138 -230.105966) (xy 333.871062 -230.006144) (xy 333.770986 -230.105966) (xy 333.770986 -230.150416)
			(xy 333.971138 -230.150416)
		)
		(stroke
			(width 0)
			(type solid)
		)
		(fill yes)
		(layer "In4.Cu")
		(net "M_D_CPU0_SA_DQ<8>")
	)
	(gr_poly
		(pts
			(xy 333.971138 -229.70236) (xy 333.971138 -229.65791) (xy 333.770986 -229.65791) (xy 333.770986 -229.70236)
			(xy 333.871062 -229.802436)
		)
		(stroke
			(width 0)
			(type solid)
		)
		(fill yes)
		(layer "In4.Cu")
		(net "M_D_CPU0_SA_DQ<7>")
	)
	(gr_poly
		(pts
			(xy 333.971138 -228.486208) (xy 333.871062 -228.386132) (xy 333.770986 -228.486208) (xy 333.770986 -228.530658)
			(xy 333.971138 -228.530658)
		)
		(stroke
			(width 0)
			(type solid)
		)
		(fill yes)
		(layer "In4.Cu")
		(net "M_D_CPU0_SA_DQ<4>")
	)
	(gr_poly
		(pts
			(xy 333.971138 -228.082602) (xy 333.971138 -228.03485) (xy 333.770986 -228.03485) (xy 333.770986 -228.082602)
			(xy 333.871062 -228.182424)
		)
		(stroke
			(width 0)
			(type solid)
		)
		(fill yes)
		(layer "In4.Cu")
		(net "M_D_CPU0_SA_DQS_DP<5>")
	)
	(gr_poly
		(pts
			(xy 333.971138 -226.865942) (xy 333.871062 -226.76612) (xy 333.770986 -226.865942) (xy 333.770986 -226.913694)
			(xy 333.971138 -226.913694)
		)
		(stroke
			(width 0)
			(type solid)
		)
		(fill yes)
		(layer "In4.Cu")
		(net "M_D_CPU0_SA_DQS_DP<0>")
	)
	(gr_poly
		(pts
			(xy 333.971138 -226.462336) (xy 333.971138 -226.417886) (xy 333.770986 -226.417886) (xy 333.770986 -226.462336)
			(xy 333.871062 -226.562412)
		)
		(stroke
			(width 0)
			(type solid)
		)
		(fill yes)
		(layer "In4.Cu")
		(net "M_D_CPU0_SA_DQ<3>")
	)
	(gr_poly
		(pts
			(xy 333.971138 -225.246184) (xy 333.871062 -225.146108) (xy 333.770986 -225.246184) (xy 333.770986 -225.290634)
			(xy 333.971138 -225.290634)
		)
		(stroke
			(width 0)
			(type solid)
		)
		(fill yes)
		(layer "In4.Cu")
		(net "M_D_CPU0_SA_DQ<0>")
	)
	(gr_poly
		(pts
			(xy 334.271112 -292.91788) (xy 334.171036 -292.817804) (xy 334.07096 -292.91788) (xy 334.07096 -292.96233)
			(xy 334.271112 -292.96233)
		)
		(stroke
			(width 0)
			(type solid)
		)
		(fill yes)
		(layer "In4.Cu")
		(net "M_D_CPU0_SB_DQ<29>")
	)
	(gr_poly
		(pts
			(xy 334.271112 -292.51402) (xy 334.271112 -292.46957) (xy 334.07096 -292.46957) (xy 334.07096 -292.51402)
			(xy 334.171036 -292.614096)
		)
		(stroke
			(width 0)
			(type solid)
		)
		(fill yes)
		(layer "In4.Cu")
		(net "M_D_CPU0_SB_DQ<30>")
	)
	(gr_poly
		(pts
			(xy 334.271112 -291.297614) (xy 334.171036 -291.197792) (xy 334.07096 -291.297614) (xy 334.07096 -291.345366)
			(xy 334.271112 -291.345366)
		)
		(stroke
			(width 0)
			(type solid)
		)
		(fill yes)
		(layer "In4.Cu")
		(net "M_D_CPU0_SB_DQS_DN<8>")
	)
	(gr_poly
		(pts
			(xy 334.271112 -290.894262) (xy 334.271112 -290.84651) (xy 334.07096 -290.84651) (xy 334.07096 -290.894262)
			(xy 334.171036 -290.994084)
		)
		(stroke
			(width 0)
			(type solid)
		)
		(fill yes)
		(layer "In4.Cu")
		(net "M_D_CPU0_SB_DQS_DN<3>")
	)
	(gr_poly
		(pts
			(xy 334.271112 -289.677856) (xy 334.171036 -289.57778) (xy 334.07096 -289.677856) (xy 334.07096 -289.722306)
			(xy 334.271112 -289.722306)
		)
		(stroke
			(width 0)
			(type solid)
		)
		(fill yes)
		(layer "In4.Cu")
		(net "M_D_CPU0_SB_DQ<25>")
	)
	(gr_poly
		(pts
			(xy 334.271112 -289.273996) (xy 334.271112 -289.229546) (xy 334.07096 -289.229546) (xy 334.07096 -289.273996)
			(xy 334.171036 -289.374072)
		)
		(stroke
			(width 0)
			(type solid)
		)
		(fill yes)
		(layer "In4.Cu")
		(net "M_D_CPU0_SB_DQ<26>")
	)
	(gr_poly
		(pts
			(xy 334.271112 -288.057844) (xy 334.171036 -287.957768) (xy 334.07096 -288.057844) (xy 334.07096 -288.102294)
			(xy 334.271112 -288.102294)
		)
		(stroke
			(width 0)
			(type solid)
		)
		(fill yes)
		(layer "In4.Cu")
		(net "M_D_CPU0_SB_DQ<21>")
	)
	(gr_poly
		(pts
			(xy 334.271112 -287.654238) (xy 334.271112 -287.609788) (xy 334.07096 -287.609788) (xy 334.07096 -287.654238)
			(xy 334.171036 -287.75406)
		)
		(stroke
			(width 0)
			(type solid)
		)
		(fill yes)
		(layer "In4.Cu")
		(net "M_D_CPU0_SB_DQ<22>")
	)
	(gr_poly
		(pts
			(xy 334.271112 -286.437832) (xy 334.171036 -286.337756) (xy 334.07096 -286.437832) (xy 334.07096 -286.485584)
			(xy 334.271112 -286.485584)
		)
		(stroke
			(width 0)
			(type solid)
		)
		(fill yes)
		(layer "In4.Cu")
		(net "M_D_CPU0_SB_DQS_DN<7>")
	)
	(gr_poly
		(pts
			(xy 334.271112 -286.03448) (xy 334.271112 -285.986728) (xy 334.07096 -285.986728) (xy 334.07096 -286.03448)
			(xy 334.171036 -286.134302)
		)
		(stroke
			(width 0)
			(type solid)
		)
		(fill yes)
		(layer "In4.Cu")
		(net "M_D_CPU0_SB_DQS_DN<2>")
	)
	(gr_poly
		(pts
			(xy 334.271112 -284.818074) (xy 334.171036 -284.717998) (xy 334.07096 -284.818074) (xy 334.07096 -284.862524)
			(xy 334.271112 -284.862524)
		)
		(stroke
			(width 0)
			(type solid)
		)
		(fill yes)
		(layer "In4.Cu")
		(net "M_D_CPU0_SB_DQ<17>")
	)
	(gr_poly
		(pts
			(xy 334.271112 -284.414214) (xy 334.271112 -284.369764) (xy 334.07096 -284.369764) (xy 334.07096 -284.414214)
			(xy 334.171036 -284.51429)
		)
		(stroke
			(width 0)
			(type solid)
		)
		(fill yes)
		(layer "In4.Cu")
		(net "M_D_CPU0_SB_DQ<18>")
	)
	(gr_poly
		(pts
			(xy 334.271112 -283.198062) (xy 334.171036 -283.097986) (xy 334.07096 -283.198062) (xy 334.07096 -283.242512)
			(xy 334.271112 -283.242512)
		)
		(stroke
			(width 0)
			(type solid)
		)
		(fill yes)
		(layer "In4.Cu")
		(net "M_D_CPU0_SB_DQ<13>")
	)
	(gr_poly
		(pts
			(xy 334.271112 -282.794202) (xy 334.271112 -282.749752) (xy 334.07096 -282.749752) (xy 334.07096 -282.794202)
			(xy 334.171036 -282.894278)
		)
		(stroke
			(width 0)
			(type solid)
		)
		(fill yes)
		(layer "In4.Cu")
		(net "M_D_CPU0_SB_DQ<14>")
	)
	(gr_poly
		(pts
			(xy 334.271112 -281.577796) (xy 334.171036 -281.477974) (xy 334.07096 -281.577796) (xy 334.07096 -281.625548)
			(xy 334.271112 -281.625548)
		)
		(stroke
			(width 0)
			(type solid)
		)
		(fill yes)
		(layer "In4.Cu")
		(net "M_D_CPU0_SB_DQS_DN<6>")
	)
	(gr_poly
		(pts
			(xy 334.271112 -281.174444) (xy 334.271112 -281.126692) (xy 334.07096 -281.126692) (xy 334.07096 -281.174444)
			(xy 334.171036 -281.274266)
		)
		(stroke
			(width 0)
			(type solid)
		)
		(fill yes)
		(layer "In4.Cu")
		(net "M_D_CPU0_SB_DQS_DN<1>")
	)
	(gr_poly
		(pts
			(xy 334.271112 -279.958038) (xy 334.171036 -279.857962) (xy 334.07096 -279.958038) (xy 334.07096 -280.002488)
			(xy 334.271112 -280.002488)
		)
		(stroke
			(width 0)
			(type solid)
		)
		(fill yes)
		(layer "In4.Cu")
		(net "M_D_CPU0_SB_DQ<9>")
	)
	(gr_poly
		(pts
			(xy 334.271112 -279.554178) (xy 334.271112 -279.509728) (xy 334.07096 -279.509728) (xy 334.07096 -279.554178)
			(xy 334.171036 -279.654254)
		)
		(stroke
			(width 0)
			(type solid)
		)
		(fill yes)
		(layer "In4.Cu")
		(net "M_D_CPU0_SB_DQ<10>")
	)
	(gr_poly
		(pts
			(xy 334.271112 -278.338026) (xy 334.171036 -278.23795) (xy 334.07096 -278.338026) (xy 334.07096 -278.382476)
			(xy 334.271112 -278.382476)
		)
		(stroke
			(width 0)
			(type solid)
		)
		(fill yes)
		(layer "In4.Cu")
		(net "M_D_CPU0_SB_DQ<5>")
	)
	(gr_poly
		(pts
			(xy 334.271112 -277.934166) (xy 334.271112 -277.889716) (xy 334.07096 -277.889716) (xy 334.07096 -277.934166)
			(xy 334.171036 -278.034242)
		)
		(stroke
			(width 0)
			(type solid)
		)
		(fill yes)
		(layer "In4.Cu")
		(net "M_D_CPU0_SB_DQ<6>")
	)
	(gr_poly
		(pts
			(xy 334.271112 -275.098002) (xy 334.171036 -274.997926) (xy 334.07096 -275.098002) (xy 334.07096 -275.142452)
			(xy 334.271112 -275.142452)
		)
		(stroke
			(width 0)
			(type solid)
		)
		(fill yes)
		(layer "In4.Cu")
		(net "M_D_CPU0_SB_DQ<1>")
	)
	(gr_poly
		(pts
			(xy 334.271112 -274.694142) (xy 334.271112 -274.649692) (xy 334.07096 -274.649692) (xy 334.07096 -274.694142)
			(xy 334.171036 -274.794218)
		)
		(stroke
			(width 0)
			(type solid)
		)
		(fill yes)
		(layer "In4.Cu")
		(net "M_D_CPU0_SB_DQ<2>")
	)
	(gr_poly
		(pts
			(xy 334.271112 -273.47799) (xy 334.171036 -273.377914) (xy 334.07096 -273.47799) (xy 334.07096 -273.52244)
			(xy 334.271112 -273.52244)
		)
		(stroke
			(width 0)
			(type solid)
		)
		(fill yes)
		(layer "In4.Cu")
		(net "M_D_CPU0_SB_CB<1>")
	)
	(gr_poly
		(pts
			(xy 334.271112 -273.07413) (xy 334.271112 -273.02968) (xy 334.07096 -273.02968) (xy 334.07096 -273.07413)
			(xy 334.171036 -273.174206)
		)
		(stroke
			(width 0)
			(type solid)
		)
		(fill yes)
		(layer "In4.Cu")
		(net "M_D_CPU0_SB_CB<2>")
	)
	(gr_poly
		(pts
			(xy 334.271112 -271.857724) (xy 334.171036 -271.757902) (xy 334.07096 -271.857724) (xy 334.07096 -271.905476)
			(xy 334.271112 -271.905476)
		)
		(stroke
			(width 0)
			(type solid)
		)
		(fill yes)
		(layer "In4.Cu")
		(net "M_D_CPU0_SB_DQS_DN<4>")
	)
	(gr_poly
		(pts
			(xy 334.271112 -271.454372) (xy 334.271112 -271.40662) (xy 334.07096 -271.40662) (xy 334.07096 -271.454372)
			(xy 334.171036 -271.554194)
		)
		(stroke
			(width 0)
			(type solid)
		)
		(fill yes)
		(layer "In4.Cu")
		(net "M_D_CPU0_SB_DQS_DN<9>")
	)
	(gr_poly
		(pts
			(xy 334.271112 -270.237966) (xy 334.171036 -270.13789) (xy 334.07096 -270.237966) (xy 334.07096 -270.282416)
			(xy 334.271112 -270.282416)
		)
		(stroke
			(width 0)
			(type solid)
		)
		(fill yes)
		(layer "In4.Cu")
		(net "M_D_CPU0_SB_CB<5>")
	)
	(gr_poly
		(pts
			(xy 334.271112 -269.834106) (xy 334.271112 -269.789656) (xy 334.07096 -269.789656) (xy 334.07096 -269.834106)
			(xy 334.171036 -269.934182)
		)
		(stroke
			(width 0)
			(type solid)
		)
		(fill yes)
		(layer "In4.Cu")
		(net "M_D_CPU0_SB_CB<6>")
	)
	(gr_poly
		(pts
			(xy 334.271112 -266.594082) (xy 334.271112 -266.549632) (xy 334.07096 -266.549632) (xy 334.07096 -266.594082)
			(xy 334.171036 -266.694158)
		)
		(stroke
			(width 0)
			(type solid)
		)
		(fill yes)
		(layer "In4.Cu")
		(net "M_D_CPU0_SB_CS_N<1>")
	)
	(gr_poly
		(pts
			(xy 334.271112 -264.97407) (xy 334.271112 -264.92962) (xy 334.07096 -264.92962) (xy 334.07096 -264.97407)
			(xy 334.171036 -265.074146)
		)
		(stroke
			(width 0)
			(type solid)
		)
		(fill yes)
		(layer "In4.Cu")
		(net "M_D_CPU0_SB_PAR")
	)
	(gr_poly
		(pts
			(xy 334.271112 -263.757918) (xy 334.171036 -263.657842) (xy 334.07096 -263.757918) (xy 334.07096 -263.802368)
			(xy 334.271112 -263.802368)
		)
		(stroke
			(width 0)
			(type solid)
		)
		(fill yes)
		(layer "In4.Cu")
		(net "M_D_CPU0_SB_CA<4>")
	)
	(gr_poly
		(pts
			(xy 334.271112 -263.354058) (xy 334.271112 -263.309608) (xy 334.07096 -263.309608) (xy 334.07096 -263.354058)
			(xy 334.171036 -263.454134)
		)
		(stroke
			(width 0)
			(type solid)
		)
		(fill yes)
		(layer "In4.Cu")
		(net "M_D_CPU0_SB_CA<3>")
	)
	(gr_poly
		(pts
			(xy 334.271112 -262.137906) (xy 334.171036 -262.03783) (xy 334.07096 -262.137906) (xy 334.07096 -262.182356)
			(xy 334.271112 -262.182356)
		)
		(stroke
			(width 0)
			(type solid)
		)
		(fill yes)
		(layer "In4.Cu")
		(net "M_D_CPU0_SB_CA<0>")
	)
	(gr_poly
		(pts
			(xy 334.277208 -266.991592) (xy 334.177386 -266.891516) (xy 334.07731 -266.991592) (xy 334.07731 -267.036042)
			(xy 334.277208 -267.036042)
		)
		(stroke
			(width 0)
			(type solid)
		)
		(fill yes)
		(layer "In4.Cu")
		(net "M_D_CPU0_SA_RSP<0>")
	)
	(gr_poly
		(pts
			(xy 334.278478 -276.71776) (xy 334.178402 -276.617938) (xy 334.078326 -276.71776) (xy 334.078326 -276.765512)
			(xy 334.278478 -276.765512)
		)
		(stroke
			(width 0)
			(type solid)
		)
		(fill yes)
		(layer "In4.Cu")
		(net "M_D_CPU0_SB_DQS_DN<5>")
	)
	(gr_poly
		(pts
			(xy 334.278478 -276.314408) (xy 334.278478 -276.266656) (xy 334.078326 -276.266656) (xy 334.078326 -276.314408)
			(xy 334.178402 -276.41423)
		)
		(stroke
			(width 0)
			(type solid)
		)
		(fill yes)
		(layer "In4.Cu")
		(net "M_D_CPU0_SB_DQS_DN<0>")
	)
	(gr_poly
		(pts
			(xy 334.434942 -227.676456) (xy 334.33512 -227.57638) (xy 334.235044 -227.676456) (xy 334.235044 -227.723954)
			(xy 334.434942 -227.723954)
		)
		(stroke
			(width 0)
			(type solid)
		)
		(fill yes)
		(layer "In4.Cu")
		(net "M_D_CPU0_SA_DQS_DN<5>")
	)
	(gr_poly
		(pts
			(xy 334.441292 -256.432558) (xy 334.441292 -256.384806) (xy 334.24114 -256.384806) (xy 334.24114 -256.432558)
			(xy 334.341216 -256.53238)
		)
		(stroke
			(width 0)
			(type solid)
		)
		(fill yes)
		(layer "In4.Cu")
		(net "M_D_CPU0_CLK_DN<0>")
	)
	(gr_poly
		(pts
			(xy 334.441292 -255.216152) (xy 334.341216 -255.116076) (xy 334.24114 -255.216152) (xy 334.24114 -255.260602)
			(xy 334.441292 -255.260602)
		)
		(stroke
			(width 0)
			(type solid)
		)
		(fill yes)
		(layer "In4.Cu")
		(net "M_D_CPU0_SA_CA<6>")
	)
	(gr_poly
		(pts
			(xy 334.441292 -254.812292) (xy 334.441292 -254.767842) (xy 334.24114 -254.767842) (xy 334.24114 -254.812292)
			(xy 334.341216 -254.912368)
		)
		(stroke
			(width 0)
			(type solid)
		)
		(fill yes)
		(layer "In4.Cu")
		(net "M_D_CPU0_SA_CA<5>")
	)
	(gr_poly
		(pts
			(xy 334.441292 -253.59614) (xy 334.341216 -253.496064) (xy 334.24114 -253.59614) (xy 334.24114 -253.64059)
			(xy 334.441292 -253.64059)
		)
		(stroke
			(width 0)
			(type solid)
		)
		(fill yes)
		(layer "In4.Cu")
		(net "M_D_CPU0_SA_CA<2>")
	)
	(gr_poly
		(pts
			(xy 334.441292 -253.19228) (xy 334.441292 -253.14783) (xy 334.24114 -253.14783) (xy 334.24114 -253.19228)
			(xy 334.341216 -253.292356)
		)
		(stroke
			(width 0)
			(type solid)
		)
		(fill yes)
		(layer "In4.Cu")
		(net "M_D_CPU0_SA_CA<1>")
	)
	(gr_poly
		(pts
			(xy 334.441292 -251.572268) (xy 334.441292 -251.527818) (xy 334.24114 -251.527818) (xy 334.24114 -251.572268)
			(xy 334.341216 -251.672344)
		)
		(stroke
			(width 0)
			(type solid)
		)
		(fill yes)
		(layer "In4.Cu")
		(net "M_D_CPU0_SA_CS_N<0>")
	)
	(gr_poly
		(pts
			(xy 334.441292 -250.356116) (xy 334.341216 -250.25604) (xy 334.24114 -250.356116) (xy 334.24114 -250.400566)
			(xy 334.441292 -250.400566)
		)
		(stroke
			(width 0)
			(type solid)
		)
		(fill yes)
		(layer "In4.Cu")
		(net "M_D_CPU0_ALERT_R_N")
	)
	(gr_poly
		(pts
			(xy 334.441292 -248.736104) (xy 334.341216 -248.636028) (xy 334.24114 -248.736104) (xy 334.24114 -248.780554)
			(xy 334.441292 -248.780554)
		)
		(stroke
			(width 0)
			(type solid)
		)
		(fill yes)
		(layer "In4.Cu")
		(net "M_D_CPU0_SA_CB<5>")
	)
	(gr_poly
		(pts
			(xy 334.441292 -248.332244) (xy 334.441292 -248.287794) (xy 334.24114 -248.287794) (xy 334.24114 -248.332244)
			(xy 334.341216 -248.43232)
		)
		(stroke
			(width 0)
			(type solid)
		)
		(fill yes)
		(layer "In4.Cu")
		(net "M_D_CPU0_SA_CB<6>")
	)
	(gr_poly
		(pts
			(xy 334.441292 -247.115838) (xy 334.341216 -247.016016) (xy 334.24114 -247.115838) (xy 334.24114 -247.16359)
			(xy 334.441292 -247.16359)
		)
		(stroke
			(width 0)
			(type solid)
		)
		(fill yes)
		(layer "In4.Cu")
		(net "M_D_CPU0_SA_DQS_DN<9>")
	)
	(gr_poly
		(pts
			(xy 334.441292 -246.712486) (xy 334.441292 -246.664734) (xy 334.24114 -246.664734) (xy 334.24114 -246.712486)
			(xy 334.341216 -246.812308)
		)
		(stroke
			(width 0)
			(type solid)
		)
		(fill yes)
		(layer "In4.Cu")
		(net "M_D_CPU0_SA_DQS_DN<4>")
	)
	(gr_poly
		(pts
			(xy 334.441292 -245.49608) (xy 334.341216 -245.396004) (xy 334.24114 -245.49608) (xy 334.24114 -245.54053)
			(xy 334.441292 -245.54053)
		)
		(stroke
			(width 0)
			(type solid)
		)
		(fill yes)
		(layer "In4.Cu")
		(net "M_D_CPU0_SA_CB<1>")
	)
	(gr_poly
		(pts
			(xy 334.441292 -245.09222) (xy 334.441292 -245.04777) (xy 334.24114 -245.04777) (xy 334.24114 -245.09222)
			(xy 334.341216 -245.192296)
		)
		(stroke
			(width 0)
			(type solid)
		)
		(fill yes)
		(layer "In4.Cu")
		(net "M_D_CPU0_SA_CB<2>")
	)
	(gr_poly
		(pts
			(xy 334.441292 -243.876068) (xy 334.341216 -243.775992) (xy 334.24114 -243.876068) (xy 334.24114 -243.920518)
			(xy 334.441292 -243.920518)
		)
		(stroke
			(width 0)
			(type solid)
		)
		(fill yes)
		(layer "In4.Cu")
		(net "M_D_CPU0_SA_DQ<29>")
	)
	(gr_poly
		(pts
			(xy 334.441292 -243.472208) (xy 334.441292 -243.427758) (xy 334.24114 -243.427758) (xy 334.24114 -243.472208)
			(xy 334.341216 -243.572284)
		)
		(stroke
			(width 0)
			(type solid)
		)
		(fill yes)
		(layer "In4.Cu")
		(net "M_D_CPU0_SA_DQ<30>")
	)
	(gr_poly
		(pts
			(xy 334.441292 -242.255802) (xy 334.341216 -242.15598) (xy 334.24114 -242.255802) (xy 334.24114 -242.303554)
			(xy 334.441292 -242.303554)
		)
		(stroke
			(width 0)
			(type solid)
		)
		(fill yes)
		(layer "In4.Cu")
		(net "M_D_CPU0_SA_DQS_DN<8>")
	)
	(gr_poly
		(pts
			(xy 334.441292 -241.85245) (xy 334.441292 -241.804698) (xy 334.24114 -241.804698) (xy 334.24114 -241.85245)
			(xy 334.341216 -241.952272)
		)
		(stroke
			(width 0)
			(type solid)
		)
		(fill yes)
		(layer "In4.Cu")
		(net "M_D_CPU0_SA_DQS_DN<3>")
	)
	(gr_poly
		(pts
			(xy 334.441292 -240.636044) (xy 334.341216 -240.535968) (xy 334.24114 -240.636044) (xy 334.24114 -240.680494)
			(xy 334.441292 -240.680494)
		)
		(stroke
			(width 0)
			(type solid)
		)
		(fill yes)
		(layer "In4.Cu")
		(net "M_D_CPU0_SA_DQ<25>")
	)
	(gr_poly
		(pts
			(xy 334.441292 -240.232184) (xy 334.441292 -240.187734) (xy 334.24114 -240.187734) (xy 334.24114 -240.232184)
			(xy 334.341216 -240.33226)
		)
		(stroke
			(width 0)
			(type solid)
		)
		(fill yes)
		(layer "In4.Cu")
		(net "M_D_CPU0_SA_DQ<26>")
	)
	(gr_poly
		(pts
			(xy 334.441292 -239.016032) (xy 334.341216 -238.915956) (xy 334.24114 -239.016032) (xy 334.24114 -239.060482)
			(xy 334.441292 -239.060482)
		)
		(stroke
			(width 0)
			(type solid)
		)
		(fill yes)
		(layer "In4.Cu")
		(net "M_D_CPU0_SA_DQ<21>")
	)
	(gr_poly
		(pts
			(xy 334.441292 -238.612172) (xy 334.441292 -238.567722) (xy 334.24114 -238.567722) (xy 334.24114 -238.612172)
			(xy 334.341216 -238.712248)
		)
		(stroke
			(width 0)
			(type solid)
		)
		(fill yes)
		(layer "In4.Cu")
		(net "M_D_CPU0_SA_DQ<22>")
	)
	(gr_poly
		(pts
			(xy 334.441292 -237.395766) (xy 334.341216 -237.295944) (xy 334.24114 -237.395766) (xy 334.24114 -237.443518)
			(xy 334.441292 -237.443518)
		)
		(stroke
			(width 0)
			(type solid)
		)
		(fill yes)
		(layer "In4.Cu")
		(net "M_D_CPU0_SA_DQS_DN<7>")
	)
	(gr_poly
		(pts
			(xy 334.441292 -236.992414) (xy 334.441292 -236.944662) (xy 334.24114 -236.944662) (xy 334.24114 -236.992414)
			(xy 334.341216 -237.092236)
		)
		(stroke
			(width 0)
			(type solid)
		)
		(fill yes)
		(layer "In4.Cu")
		(net "M_D_CPU0_SA_DQS_DN<2>")
	)
	(gr_poly
		(pts
			(xy 334.441292 -235.776008) (xy 334.341216 -235.675932) (xy 334.24114 -235.776008) (xy 334.24114 -235.820458)
			(xy 334.441292 -235.820458)
		)
		(stroke
			(width 0)
			(type solid)
		)
		(fill yes)
		(layer "In4.Cu")
		(net "M_D_CPU0_SA_DQ<17>")
	)
	(gr_poly
		(pts
			(xy 334.441292 -235.372148) (xy 334.441292 -235.327698) (xy 334.24114 -235.327698) (xy 334.24114 -235.372148)
			(xy 334.341216 -235.472224)
		)
		(stroke
			(width 0)
			(type solid)
		)
		(fill yes)
		(layer "In4.Cu")
		(net "M_D_CPU0_SA_DQ<18>")
	)
	(gr_poly
		(pts
			(xy 334.441292 -234.155996) (xy 334.341216 -234.05592) (xy 334.24114 -234.155996) (xy 334.24114 -234.200446)
			(xy 334.441292 -234.200446)
		)
		(stroke
			(width 0)
			(type solid)
		)
		(fill yes)
		(layer "In4.Cu")
		(net "M_D_CPU0_SA_DQ<13>")
	)
	(gr_poly
		(pts
			(xy 334.441292 -233.752136) (xy 334.441292 -233.707686) (xy 334.24114 -233.707686) (xy 334.24114 -233.752136)
			(xy 334.341216 -233.852212)
		)
		(stroke
			(width 0)
			(type solid)
		)
		(fill yes)
		(layer "In4.Cu")
		(net "M_D_CPU0_SA_DQ<14>")
	)
	(gr_poly
		(pts
			(xy 334.441292 -232.53573) (xy 334.341216 -232.435908) (xy 334.24114 -232.53573) (xy 334.24114 -232.583482)
			(xy 334.441292 -232.583482)
		)
		(stroke
			(width 0)
			(type solid)
		)
		(fill yes)
		(layer "In4.Cu")
		(net "M_D_CPU0_SA_DQS_DN<6>")
	)
	(gr_poly
		(pts
			(xy 334.441292 -232.132378) (xy 334.441292 -232.084626) (xy 334.24114 -232.084626) (xy 334.24114 -232.132378)
			(xy 334.341216 -232.2322)
		)
		(stroke
			(width 0)
			(type solid)
		)
		(fill yes)
		(layer "In4.Cu")
		(net "M_D_CPU0_SA_DQS_DN<1>")
	)
	(gr_poly
		(pts
			(xy 334.441292 -230.915972) (xy 334.341216 -230.815896) (xy 334.24114 -230.915972) (xy 334.24114 -230.960422)
			(xy 334.441292 -230.960422)
		)
		(stroke
			(width 0)
			(type solid)
		)
		(fill yes)
		(layer "In4.Cu")
		(net "M_D_CPU0_SA_DQ<9>")
	)
	(gr_poly
		(pts
			(xy 334.441292 -230.512366) (xy 334.441292 -230.467916) (xy 334.24114 -230.467916) (xy 334.24114 -230.512366)
			(xy 334.341216 -230.612188)
		)
		(stroke
			(width 0)
			(type solid)
		)
		(fill yes)
		(layer "In4.Cu")
		(net "M_D_CPU0_SA_DQ<10>")
	)
	(gr_poly
		(pts
			(xy 334.441292 -229.29596) (xy 334.341216 -229.195884) (xy 334.24114 -229.29596) (xy 334.24114 -229.34041)
			(xy 334.441292 -229.34041)
		)
		(stroke
			(width 0)
			(type solid)
		)
		(fill yes)
		(layer "In4.Cu")
		(net "M_D_CPU0_SA_DQ<5>")
	)
	(gr_poly
		(pts
			(xy 334.441292 -228.892354) (xy 334.441292 -228.847904) (xy 334.24114 -228.847904) (xy 334.24114 -228.892354)
			(xy 334.341216 -228.99243)
		)
		(stroke
			(width 0)
			(type solid)
		)
		(fill yes)
		(layer "In4.Cu")
		(net "M_D_CPU0_SA_DQ<6>")
	)
	(gr_poly
		(pts
			(xy 334.441292 -227.272596) (xy 334.441292 -227.224844) (xy 334.24114 -227.224844) (xy 334.24114 -227.272596)
			(xy 334.341216 -227.372418)
		)
		(stroke
			(width 0)
			(type solid)
		)
		(fill yes)
		(layer "In4.Cu")
		(net "M_D_CPU0_SA_DQS_DN<0>")
	)
	(gr_poly
		(pts
			(xy 334.441292 -226.05619) (xy 334.341216 -225.956114) (xy 334.24114 -226.05619) (xy 334.24114 -226.10064)
			(xy 334.441292 -226.10064)
		)
		(stroke
			(width 0)
			(type solid)
		)
		(fill yes)
		(layer "In4.Cu")
		(net "M_D_CPU0_SA_DQ<1>")
	)
	(gr_poly
		(pts
			(xy 334.441292 -225.65233) (xy 334.441292 -225.60788) (xy 334.24114 -225.60788) (xy 334.24114 -225.65233)
			(xy 334.341216 -225.752406)
		)
		(stroke
			(width 0)
			(type solid)
		)
		(fill yes)
		(layer "In4.Cu")
		(net "M_D_CPU0_SA_DQ<2>")
	)
	(gr_poly
		(pts
			(xy 334.734916 -267.801598) (xy 334.63484 -267.701522) (xy 334.535018 -267.801598) (xy 334.535018 -267.846048)
			(xy 334.734916 -267.846048)
		)
		(stroke
			(width 0)
			(type solid)
		)
		(fill yes)
		(layer "In4.Cu")
		(net "M_D_CPU0_SB_RSP<0>")
	)
	(gr_poly
		(pts
			(xy 334.741266 -293.324026) (xy 334.741266 -293.279576) (xy 334.541114 -293.279576) (xy 334.541114 -293.324026)
			(xy 334.64119 -293.424102)
		)
		(stroke
			(width 0)
			(type solid)
		)
		(fill yes)
		(layer "In4.Cu")
		(net "M_D_CPU0_SB_DQ<31>")
	)
	(gr_poly
		(pts
			(xy 334.741266 -292.107874) (xy 334.64119 -292.007798) (xy 334.541114 -292.107874) (xy 334.541114 -292.152324)
			(xy 334.741266 -292.152324)
		)
		(stroke
			(width 0)
			(type solid)
		)
		(fill yes)
		(layer "In4.Cu")
		(net "M_D_CPU0_SB_DQ<28>")
	)
	(gr_poly
		(pts
			(xy 334.741266 -291.704268) (xy 334.741266 -291.656516) (xy 334.541114 -291.656516) (xy 334.541114 -291.704268)
			(xy 334.64119 -291.80409)
		)
		(stroke
			(width 0)
			(type solid)
		)
		(fill yes)
		(layer "In4.Cu")
		(net "M_D_CPU0_SB_DQS_DP<8>")
	)
	(gr_poly
		(pts
			(xy 334.741266 -290.487608) (xy 334.64119 -290.387786) (xy 334.541114 -290.487608) (xy 334.541114 -290.53536)
			(xy 334.741266 -290.53536)
		)
		(stroke
			(width 0)
			(type solid)
		)
		(fill yes)
		(layer "In4.Cu")
		(net "M_D_CPU0_SB_DQS_DP<3>")
	)
	(gr_poly
		(pts
			(xy 334.741266 -290.084002) (xy 334.741266 -290.039552) (xy 334.541114 -290.039552) (xy 334.541114 -290.084002)
			(xy 334.64119 -290.184078)
		)
		(stroke
			(width 0)
			(type solid)
		)
		(fill yes)
		(layer "In4.Cu")
		(net "M_D_CPU0_SB_DQ<27>")
	)
	(gr_poly
		(pts
			(xy 334.741266 -288.86785) (xy 334.64119 -288.767774) (xy 334.541114 -288.86785) (xy 334.541114 -288.9123)
			(xy 334.741266 -288.9123)
		)
		(stroke
			(width 0)
			(type solid)
		)
		(fill yes)
		(layer "In4.Cu")
		(net "M_D_CPU0_SB_DQ<24>")
	)
	(gr_poly
		(pts
			(xy 334.741266 -288.464244) (xy 334.741266 -288.419794) (xy 334.541114 -288.419794) (xy 334.541114 -288.464244)
			(xy 334.64119 -288.56432)
		)
		(stroke
			(width 0)
			(type solid)
		)
		(fill yes)
		(layer "In4.Cu")
		(net "M_D_CPU0_SB_DQ<23>")
	)
	(gr_poly
		(pts
			(xy 334.741266 -287.247838) (xy 334.64119 -287.148016) (xy 334.541114 -287.247838) (xy 334.541114 -287.292288)
			(xy 334.741266 -287.292288)
		)
		(stroke
			(width 0)
			(type solid)
		)
		(fill yes)
		(layer "In4.Cu")
		(net "M_D_CPU0_SB_DQ<20>")
	)
	(gr_poly
		(pts
			(xy 334.741266 -286.844232) (xy 334.741266 -286.79648) (xy 334.541114 -286.79648) (xy 334.541114 -286.844232)
			(xy 334.64119 -286.944308)
		)
		(stroke
			(width 0)
			(type solid)
		)
		(fill yes)
		(layer "In4.Cu")
		(net "M_D_CPU0_SB_DQS_DP<7>")
	)
	(gr_poly
		(pts
			(xy 334.741266 -285.627826) (xy 334.64119 -285.528004) (xy 334.541114 -285.627826) (xy 334.541114 -285.675578)
			(xy 334.741266 -285.675578)
		)
		(stroke
			(width 0)
			(type solid)
		)
		(fill yes)
		(layer "In4.Cu")
		(net "M_D_CPU0_SB_DQS_DP<2>")
	)
	(gr_poly
		(pts
			(xy 334.741266 -285.22422) (xy 334.741266 -285.17977) (xy 334.541114 -285.17977) (xy 334.541114 -285.22422)
			(xy 334.64119 -285.324296)
		)
		(stroke
			(width 0)
			(type solid)
		)
		(fill yes)
		(layer "In4.Cu")
		(net "M_D_CPU0_SB_DQ<19>")
	)
	(gr_poly
		(pts
			(xy 334.741266 -284.008068) (xy 334.64119 -283.907992) (xy 334.541114 -284.008068) (xy 334.541114 -284.052518)
			(xy 334.741266 -284.052518)
		)
		(stroke
			(width 0)
			(type solid)
		)
		(fill yes)
		(layer "In4.Cu")
		(net "M_D_CPU0_SB_DQ<16>")
	)
	(gr_poly
		(pts
			(xy 334.741266 -283.604208) (xy 334.741266 -283.559758) (xy 334.541114 -283.559758) (xy 334.541114 -283.604208)
			(xy 334.64119 -283.704284)
		)
		(stroke
			(width 0)
			(type solid)
		)
		(fill yes)
		(layer "In4.Cu")
		(net "M_D_CPU0_SB_DQ<15>")
	)
	(gr_poly
		(pts
			(xy 334.741266 -282.388056) (xy 334.64119 -282.28798) (xy 334.541114 -282.388056) (xy 334.541114 -282.432506)
			(xy 334.741266 -282.432506)
		)
		(stroke
			(width 0)
			(type solid)
		)
		(fill yes)
		(layer "In4.Cu")
		(net "M_D_CPU0_SB_DQ<12>")
	)
	(gr_poly
		(pts
			(xy 334.741266 -281.98445) (xy 334.741266 -281.936698) (xy 334.541114 -281.936698) (xy 334.541114 -281.98445)
			(xy 334.64119 -282.084272)
		)
		(stroke
			(width 0)
			(type solid)
		)
		(fill yes)
		(layer "In4.Cu")
		(net "M_D_CPU0_SB_DQS_DP<6>")
	)
	(gr_poly
		(pts
			(xy 334.741266 -280.76779) (xy 334.64119 -280.667968) (xy 334.541114 -280.76779) (xy 334.541114 -280.815542)
			(xy 334.741266 -280.815542)
		)
		(stroke
			(width 0)
			(type solid)
		)
		(fill yes)
		(layer "In4.Cu")
		(net "M_D_CPU0_SB_DQS_DP<1>")
	)
	(gr_poly
		(pts
			(xy 334.741266 -280.364184) (xy 334.741266 -280.319734) (xy 334.541114 -280.319734) (xy 334.541114 -280.364184)
			(xy 334.64119 -280.46426)
		)
		(stroke
			(width 0)
			(type solid)
		)
		(fill yes)
		(layer "In4.Cu")
		(net "M_D_CPU0_SB_DQ<11>")
	)
	(gr_poly
		(pts
			(xy 334.741266 -279.148032) (xy 334.64119 -279.047956) (xy 334.541114 -279.148032) (xy 334.541114 -279.192482)
			(xy 334.741266 -279.192482)
		)
		(stroke
			(width 0)
			(type solid)
		)
		(fill yes)
		(layer "In4.Cu")
		(net "M_D_CPU0_SB_DQ<8>")
	)
	(gr_poly
		(pts
			(xy 334.741266 -278.744172) (xy 334.741266 -278.699722) (xy 334.541114 -278.699722) (xy 334.541114 -278.744172)
			(xy 334.64119 -278.844248)
		)
		(stroke
			(width 0)
			(type solid)
		)
		(fill yes)
		(layer "In4.Cu")
		(net "M_D_CPU0_SB_DQ<7>")
	)
	(gr_poly
		(pts
			(xy 334.741266 -277.52802) (xy 334.64119 -277.427944) (xy 334.541114 -277.52802) (xy 334.541114 -277.57247)
			(xy 334.741266 -277.57247)
		)
		(stroke
			(width 0)
			(type solid)
		)
		(fill yes)
		(layer "In4.Cu")
		(net "M_D_CPU0_SB_DQ<4>")
	)
	(gr_poly
		(pts
			(xy 334.741266 -277.12416) (xy 334.741266 -277.076662) (xy 334.541114 -277.076662) (xy 334.541114 -277.12416)
			(xy 334.64119 -277.224236)
		)
		(stroke
			(width 0)
			(type solid)
		)
		(fill yes)
		(layer "In4.Cu")
		(net "M_D_CPU0_SB_DQS_DP<5>")
	)
	(gr_poly
		(pts
			(xy 334.741266 -275.908008) (xy 334.64119 -275.807932) (xy 334.541114 -275.908008) (xy 334.541114 -275.955506)
			(xy 334.741266 -275.955506)
		)
		(stroke
			(width 0)
			(type solid)
		)
		(fill yes)
		(layer "In4.Cu")
		(net "M_D_CPU0_SB_DQS_DP<0>")
	)
	(gr_poly
		(pts
			(xy 334.741266 -275.504148) (xy 334.741266 -275.459698) (xy 334.541114 -275.459698) (xy 334.541114 -275.504148)
			(xy 334.64119 -275.604224)
		)
		(stroke
			(width 0)
			(type solid)
		)
		(fill yes)
		(layer "In4.Cu")
		(net "M_D_CPU0_SB_DQ<3>")
	)
	(gr_poly
		(pts
			(xy 334.741266 -274.287996) (xy 334.64119 -274.18792) (xy 334.541114 -274.287996) (xy 334.541114 -274.332446)
			(xy 334.741266 -274.332446)
		)
		(stroke
			(width 0)
			(type solid)
		)
		(fill yes)
		(layer "In4.Cu")
		(net "M_D_CPU0_SB_DQ<0>")
	)
	(gr_poly
		(pts
			(xy 334.741266 -273.884136) (xy 334.741266 -273.839686) (xy 334.541114 -273.839686) (xy 334.541114 -273.884136)
			(xy 334.64119 -273.984212)
		)
		(stroke
			(width 0)
			(type solid)
		)
		(fill yes)
		(layer "In4.Cu")
		(net "M_D_CPU0_SB_CB<3>")
	)
	(gr_poly
		(pts
			(xy 334.741266 -272.667984) (xy 334.64119 -272.567908) (xy 334.541114 -272.667984) (xy 334.541114 -272.712434)
			(xy 334.741266 -272.712434)
		)
		(stroke
			(width 0)
			(type solid)
		)
		(fill yes)
		(layer "In4.Cu")
		(net "M_D_CPU0_SB_CB<0>")
	)
	(gr_poly
		(pts
			(xy 334.741266 -272.264378) (xy 334.741266 -272.216626) (xy 334.541114 -272.216626) (xy 334.541114 -272.264378)
			(xy 334.64119 -272.3642)
		)
		(stroke
			(width 0)
			(type solid)
		)
		(fill yes)
		(layer "In4.Cu")
		(net "M_D_CPU0_SB_DQS_DP<4>")
	)
	(gr_poly
		(pts
			(xy 334.741266 -271.047718) (xy 334.64119 -270.947896) (xy 334.541114 -271.047718) (xy 334.541114 -271.09547)
			(xy 334.741266 -271.09547)
		)
		(stroke
			(width 0)
			(type solid)
		)
		(fill yes)
		(layer "In4.Cu")
		(net "M_D_CPU0_SB_DQS_DP<9>")
	)
	(gr_poly
		(pts
			(xy 334.741266 -270.644112) (xy 334.741266 -270.599662) (xy 334.541114 -270.599662) (xy 334.541114 -270.644112)
			(xy 334.64119 -270.744188)
		)
		(stroke
			(width 0)
			(type solid)
		)
		(fill yes)
		(layer "In4.Cu")
		(net "M_D_CPU0_SB_CB<7>")
	)
	(gr_poly
		(pts
			(xy 334.741266 -269.42796) (xy 334.64119 -269.327884) (xy 334.541114 -269.42796) (xy 334.541114 -269.47241)
			(xy 334.741266 -269.47241)
		)
		(stroke
			(width 0)
			(type solid)
		)
		(fill yes)
		(layer "In4.Cu")
		(net "M_D_CPU0_SB_CB<4>")
	)
	(gr_poly
		(pts
			(xy 334.741266 -265.784076) (xy 334.741266 -265.739626) (xy 334.541114 -265.739626) (xy 334.541114 -265.784076)
			(xy 334.64119 -265.884152)
		)
		(stroke
			(width 0)
			(type solid)
		)
		(fill yes)
		(layer "In4.Cu")
		(net "M_D_CPU0_SB_CS_N<0>")
	)
	(gr_poly
		(pts
			(xy 334.741266 -264.567924) (xy 334.64119 -264.467848) (xy 334.541114 -264.567924) (xy 334.541114 -264.612374)
			(xy 334.741266 -264.612374)
		)
		(stroke
			(width 0)
			(type solid)
		)
		(fill yes)
		(layer "In4.Cu")
		(net "M_D_CPU0_SB_CA<6>")
	)
	(gr_poly
		(pts
			(xy 334.741266 -264.164064) (xy 334.741266 -264.119614) (xy 334.541114 -264.119614) (xy 334.541114 -264.164064)
			(xy 334.64119 -264.26414)
		)
		(stroke
			(width 0)
			(type solid)
		)
		(fill yes)
		(layer "In4.Cu")
		(net "M_D_CPU0_SB_CA<5>")
	)
	(gr_poly
		(pts
			(xy 334.741266 -262.947912) (xy 334.64119 -262.847836) (xy 334.541114 -262.947912) (xy 334.541114 -262.992362)
			(xy 334.741266 -262.992362)
		)
		(stroke
			(width 0)
			(type solid)
		)
		(fill yes)
		(layer "In4.Cu")
		(net "M_D_CPU0_SB_CA<2>")
	)
	(gr_poly
		(pts
			(xy 334.741266 -262.544052) (xy 334.741266 -262.499602) (xy 334.541114 -262.499602) (xy 334.541114 -262.544052)
			(xy 334.64119 -262.644128)
		)
		(stroke
			(width 0)
			(type solid)
		)
		(fill yes)
		(layer "In4.Cu")
		(net "M_D_CPU0_SB_CA<1>")
	)
	(gr_poly
		(pts
			(xy 334.911192 -256.025904) (xy 334.811116 -255.926082) (xy 334.71104 -256.025904) (xy 334.71104 -256.073656)
			(xy 334.911192 -256.073656)
		)
		(stroke
			(width 0)
			(type solid)
		)
		(fill yes)
		(layer "In4.Cu")
		(net "M_D_CPU0_CLK_DP<0>")
	)
	(gr_poly
		(pts
			(xy 334.911192 -255.622298) (xy 334.911192 -255.577848) (xy 334.71104 -255.577848) (xy 334.71104 -255.622298)
			(xy 334.811116 -255.722374)
		)
		(stroke
			(width 0)
			(type solid)
		)
		(fill yes)
		(layer "In4.Cu")
		(net "M_D_CPU0_SA_PAR")
	)
	(gr_poly
		(pts
			(xy 334.911192 -254.406146) (xy 334.811116 -254.30607) (xy 334.71104 -254.406146) (xy 334.71104 -254.450596)
			(xy 334.911192 -254.450596)
		)
		(stroke
			(width 0)
			(type solid)
		)
		(fill yes)
		(layer "In4.Cu")
		(net "M_D_CPU0_SA_CA<4>")
	)
	(gr_poly
		(pts
			(xy 334.911192 -254.002286) (xy 334.911192 -253.957836) (xy 334.71104 -253.957836) (xy 334.71104 -254.002286)
			(xy 334.811116 -254.102362)
		)
		(stroke
			(width 0)
			(type solid)
		)
		(fill yes)
		(layer "In4.Cu")
		(net "M_D_CPU0_SA_CA<3>")
	)
	(gr_poly
		(pts
			(xy 334.911192 -252.786134) (xy 334.811116 -252.686058) (xy 334.71104 -252.786134) (xy 334.71104 -252.830584)
			(xy 334.911192 -252.830584)
		)
		(stroke
			(width 0)
			(type solid)
		)
		(fill yes)
		(layer "In4.Cu")
		(net "M_D_CPU0_SA_CA<0>")
	)
	(gr_poly
		(pts
			(xy 334.911192 -252.382274) (xy 334.911192 -252.337824) (xy 334.71104 -252.337824) (xy 334.71104 -252.382274)
			(xy 334.811116 -252.48235)
		)
		(stroke
			(width 0)
			(type solid)
		)
		(fill yes)
		(layer "In4.Cu")
		(net "M_D_CPU0_SA_CS_N<1>")
	)
	(gr_poly
		(pts
			(xy 334.911192 -250.762262) (xy 334.911192 -250.717812) (xy 334.71104 -250.717812) (xy 334.71104 -250.762262)
			(xy 334.811116 -250.862338)
		)
		(stroke
			(width 0)
			(type solid)
		)
		(fill yes)
		(layer "In4.Cu")
		(net "M_D_CPU0_RESET_N")
	)
	(gr_poly
		(pts
			(xy 334.911192 -249.14225) (xy 334.911192 -249.0978) (xy 334.71104 -249.0978) (xy 334.71104 -249.14225)
			(xy 334.811116 -249.242326)
		)
		(stroke
			(width 0)
			(type solid)
		)
		(fill yes)
		(layer "In4.Cu")
		(net "M_D_CPU0_SA_CB<7>")
	)
	(gr_poly
		(pts
			(xy 334.911192 -247.926098) (xy 334.811116 -247.826022) (xy 334.71104 -247.926098) (xy 334.71104 -247.970548)
			(xy 334.911192 -247.970548)
		)
		(stroke
			(width 0)
			(type solid)
		)
		(fill yes)
		(layer "In4.Cu")
		(net "M_D_CPU0_SA_CB<4>")
	)
	(gr_poly
		(pts
			(xy 334.911192 -247.522492) (xy 334.911192 -247.47474) (xy 334.71104 -247.47474) (xy 334.71104 -247.522492)
			(xy 334.811116 -247.622314)
		)
		(stroke
			(width 0)
			(type solid)
		)
		(fill yes)
		(layer "In4.Cu")
		(net "M_D_CPU0_SA_DQS_DP<9>")
	)
	(gr_poly
		(pts
			(xy 334.911192 -246.305832) (xy 334.811116 -246.20601) (xy 334.71104 -246.305832) (xy 334.71104 -246.353584)
			(xy 334.911192 -246.353584)
		)
		(stroke
			(width 0)
			(type solid)
		)
		(fill yes)
		(layer "In4.Cu")
		(net "M_D_CPU0_SA_DQS_DP<4>")
	)
	(gr_poly
		(pts
			(xy 334.911192 -245.902226) (xy 334.911192 -245.857776) (xy 334.71104 -245.857776) (xy 334.71104 -245.902226)
			(xy 334.811116 -246.002302)
		)
		(stroke
			(width 0)
			(type solid)
		)
		(fill yes)
		(layer "In4.Cu")
		(net "M_D_CPU0_SA_CB<3>")
	)
	(gr_poly
		(pts
			(xy 334.911192 -244.686074) (xy 334.811116 -244.585998) (xy 334.71104 -244.686074) (xy 334.71104 -244.730524)
			(xy 334.911192 -244.730524)
		)
		(stroke
			(width 0)
			(type solid)
		)
		(fill yes)
		(layer "In4.Cu")
		(net "M_D_CPU0_SA_CB<0>")
	)
	(gr_poly
		(pts
			(xy 334.911192 -244.282214) (xy 334.911192 -244.237764) (xy 334.71104 -244.237764) (xy 334.71104 -244.282214)
			(xy 334.811116 -244.38229)
		)
		(stroke
			(width 0)
			(type solid)
		)
		(fill yes)
		(layer "In4.Cu")
		(net "M_D_CPU0_SA_DQ<31>")
	)
	(gr_poly
		(pts
			(xy 334.911192 -243.066062) (xy 334.811116 -242.965986) (xy 334.71104 -243.066062) (xy 334.71104 -243.110512)
			(xy 334.911192 -243.110512)
		)
		(stroke
			(width 0)
			(type solid)
		)
		(fill yes)
		(layer "In4.Cu")
		(net "M_D_CPU0_SA_DQ<28>")
	)
	(gr_poly
		(pts
			(xy 334.911192 -242.662456) (xy 334.911192 -242.614704) (xy 334.71104 -242.614704) (xy 334.71104 -242.662456)
			(xy 334.811116 -242.762278)
		)
		(stroke
			(width 0)
			(type solid)
		)
		(fill yes)
		(layer "In4.Cu")
		(net "M_D_CPU0_SA_DQS_DP<8>")
	)
	(gr_poly
		(pts
			(xy 334.911192 -241.445796) (xy 334.811116 -241.345974) (xy 334.71104 -241.445796) (xy 334.71104 -241.493548)
			(xy 334.911192 -241.493548)
		)
		(stroke
			(width 0)
			(type solid)
		)
		(fill yes)
		(layer "In4.Cu")
		(net "M_D_CPU0_SA_DQS_DP<3>")
	)
	(gr_poly
		(pts
			(xy 334.911192 -241.04219) (xy 334.911192 -240.99774) (xy 334.71104 -240.99774) (xy 334.71104 -241.04219)
			(xy 334.811116 -241.142266)
		)
		(stroke
			(width 0)
			(type solid)
		)
		(fill yes)
		(layer "In4.Cu")
		(net "M_D_CPU0_SA_DQ<27>")
	)
	(gr_poly
		(pts
			(xy 334.911192 -239.826038) (xy 334.811116 -239.725962) (xy 334.71104 -239.826038) (xy 334.71104 -239.870488)
			(xy 334.911192 -239.870488)
		)
		(stroke
			(width 0)
			(type solid)
		)
		(fill yes)
		(layer "In4.Cu")
		(net "M_D_CPU0_SA_DQ<24>")
	)
	(gr_poly
		(pts
			(xy 334.911192 -239.422178) (xy 334.911192 -239.377728) (xy 334.71104 -239.377728) (xy 334.71104 -239.422178)
			(xy 334.811116 -239.522254)
		)
		(stroke
			(width 0)
			(type solid)
		)
		(fill yes)
		(layer "In4.Cu")
		(net "M_D_CPU0_SA_DQ<23>")
	)
	(gr_poly
		(pts
			(xy 334.911192 -238.206026) (xy 334.811116 -238.10595) (xy 334.71104 -238.206026) (xy 334.71104 -238.250476)
			(xy 334.911192 -238.250476)
		)
		(stroke
			(width 0)
			(type solid)
		)
		(fill yes)
		(layer "In4.Cu")
		(net "M_D_CPU0_SA_DQ<20>")
	)
	(gr_poly
		(pts
			(xy 334.911192 -237.80242) (xy 334.911192 -237.754668) (xy 334.71104 -237.754668) (xy 334.71104 -237.80242)
			(xy 334.811116 -237.902242)
		)
		(stroke
			(width 0)
			(type solid)
		)
		(fill yes)
		(layer "In4.Cu")
		(net "M_D_CPU0_SA_DQS_DP<7>")
	)
	(gr_poly
		(pts
			(xy 334.911192 -236.58576) (xy 334.811116 -236.485938) (xy 334.71104 -236.58576) (xy 334.71104 -236.633512)
			(xy 334.911192 -236.633512)
		)
		(stroke
			(width 0)
			(type solid)
		)
		(fill yes)
		(layer "In4.Cu")
		(net "M_D_CPU0_SA_DQS_DP<2>")
	)
	(gr_poly
		(pts
			(xy 334.911192 -236.182154) (xy 334.911192 -236.137704) (xy 334.71104 -236.137704) (xy 334.71104 -236.182154)
			(xy 334.811116 -236.28223)
		)
		(stroke
			(width 0)
			(type solid)
		)
		(fill yes)
		(layer "In4.Cu")
		(net "M_D_CPU0_SA_DQ<19>")
	)
	(gr_poly
		(pts
			(xy 334.911192 -234.966002) (xy 334.811116 -234.865926) (xy 334.71104 -234.966002) (xy 334.71104 -235.010452)
			(xy 334.911192 -235.010452)
		)
		(stroke
			(width 0)
			(type solid)
		)
		(fill yes)
		(layer "In4.Cu")
		(net "M_D_CPU0_SA_DQ<16>")
	)
	(gr_poly
		(pts
			(xy 334.911192 -234.562142) (xy 334.911192 -234.517692) (xy 334.71104 -234.517692) (xy 334.71104 -234.562142)
			(xy 334.811116 -234.662218)
		)
		(stroke
			(width 0)
			(type solid)
		)
		(fill yes)
		(layer "In4.Cu")
		(net "M_D_CPU0_SA_DQ<15>")
	)
	(gr_poly
		(pts
			(xy 334.911192 -233.34599) (xy 334.811116 -233.245914) (xy 334.71104 -233.34599) (xy 334.71104 -233.39044)
			(xy 334.911192 -233.39044)
		)
		(stroke
			(width 0)
			(type solid)
		)
		(fill yes)
		(layer "In4.Cu")
		(net "M_D_CPU0_SA_DQ<12>")
	)
	(gr_poly
		(pts
			(xy 334.911192 -232.942384) (xy 334.911192 -232.894632) (xy 334.71104 -232.894632) (xy 334.71104 -232.942384)
			(xy 334.811116 -233.042206)
		)
		(stroke
			(width 0)
			(type solid)
		)
		(fill yes)
		(layer "In4.Cu")
		(net "M_D_CPU0_SA_DQS_DP<6>")
	)
	(gr_poly
		(pts
			(xy 334.911192 -231.725724) (xy 334.811116 -231.625902) (xy 334.71104 -231.725724) (xy 334.71104 -231.773476)
			(xy 334.911192 -231.773476)
		)
		(stroke
			(width 0)
			(type solid)
		)
		(fill yes)
		(layer "In4.Cu")
		(net "M_D_CPU0_SA_DQS_DP<1>")
	)
	(gr_poly
		(pts
			(xy 334.911192 -231.322372) (xy 334.911192 -231.277922) (xy 334.71104 -231.277922) (xy 334.71104 -231.322372)
			(xy 334.811116 -231.422448)
		)
		(stroke
			(width 0)
			(type solid)
		)
		(fill yes)
		(layer "In4.Cu")
		(net "M_D_CPU0_SA_DQ<11>")
	)
	(gr_poly
		(pts
			(xy 334.911192 -230.105966) (xy 334.811116 -230.006144) (xy 334.71104 -230.105966) (xy 334.71104 -230.150416)
			(xy 334.911192 -230.150416)
		)
		(stroke
			(width 0)
			(type solid)
		)
		(fill yes)
		(layer "In4.Cu")
		(net "M_D_CPU0_SA_DQ<8>")
	)
	(gr_poly
		(pts
			(xy 334.911192 -229.70236) (xy 334.911192 -229.65791) (xy 334.71104 -229.65791) (xy 334.71104 -229.70236)
			(xy 334.811116 -229.802436)
		)
		(stroke
			(width 0)
			(type solid)
		)
		(fill yes)
		(layer "In4.Cu")
		(net "M_D_CPU0_SA_DQ<7>")
	)
	(gr_poly
		(pts
			(xy 334.911192 -228.486208) (xy 334.811116 -228.386132) (xy 334.71104 -228.486208) (xy 334.71104 -228.530658)
			(xy 334.911192 -228.530658)
		)
		(stroke
			(width 0)
			(type solid)
		)
		(fill yes)
		(layer "In4.Cu")
		(net "M_D_CPU0_SA_DQ<4>")
	)
	(gr_poly
		(pts
			(xy 334.911192 -228.082602) (xy 334.911192 -228.03485) (xy 334.71104 -228.03485) (xy 334.71104 -228.082602)
			(xy 334.811116 -228.182424)
		)
		(stroke
			(width 0)
			(type solid)
		)
		(fill yes)
		(layer "In4.Cu")
		(net "M_D_CPU0_SA_DQS_DP<5>")
	)
	(gr_poly
		(pts
			(xy 334.911192 -226.865942) (xy 334.811116 -226.76612) (xy 334.71104 -226.865942) (xy 334.71104 -226.913694)
			(xy 334.911192 -226.913694)
		)
		(stroke
			(width 0)
			(type solid)
		)
		(fill yes)
		(layer "In4.Cu")
		(net "M_D_CPU0_SA_DQS_DP<0>")
	)
	(gr_poly
		(pts
			(xy 334.911192 -226.462336) (xy 334.911192 -226.417886) (xy 334.71104 -226.417886) (xy 334.71104 -226.462336)
			(xy 334.811116 -226.562412)
		)
		(stroke
			(width 0)
			(type solid)
		)
		(fill yes)
		(layer "In4.Cu")
		(net "M_D_CPU0_SA_DQ<3>")
	)
	(gr_poly
		(pts
			(xy 334.911192 -225.246184) (xy 334.811116 -225.146108) (xy 334.71104 -225.246184) (xy 334.71104 -225.290634)
			(xy 334.911192 -225.290634)
		)
		(stroke
			(width 0)
			(type solid)
		)
		(fill yes)
		(layer "In4.Cu")
		(net "M_D_CPU0_SA_DQ<0>")
	)
	(gr_poly
		(pts
			(xy 335.211166 -292.91788) (xy 335.11109 -292.817804) (xy 335.011014 -292.91788) (xy 335.011014 -292.96233)
			(xy 335.211166 -292.96233)
		)
		(stroke
			(width 0)
			(type solid)
		)
		(fill yes)
		(layer "In4.Cu")
		(net "M_D_CPU0_SB_DQ<29>")
	)
	(gr_poly
		(pts
			(xy 335.211166 -292.51402) (xy 335.211166 -292.46957) (xy 335.011014 -292.46957) (xy 335.011014 -292.51402)
			(xy 335.11109 -292.614096)
		)
		(stroke
			(width 0)
			(type solid)
		)
		(fill yes)
		(layer "In4.Cu")
		(net "M_D_CPU0_SB_DQ<30>")
	)
	(gr_poly
		(pts
			(xy 335.211166 -291.297614) (xy 335.11109 -291.197792) (xy 335.011014 -291.297614) (xy 335.011014 -291.345366)
			(xy 335.211166 -291.345366)
		)
		(stroke
			(width 0)
			(type solid)
		)
		(fill yes)
		(layer "In4.Cu")
		(net "M_D_CPU0_SB_DQS_DN<8>")
	)
	(gr_poly
		(pts
			(xy 335.211166 -290.894262) (xy 335.211166 -290.84651) (xy 335.011014 -290.84651) (xy 335.011014 -290.894262)
			(xy 335.11109 -290.994084)
		)
		(stroke
			(width 0)
			(type solid)
		)
		(fill yes)
		(layer "In4.Cu")
		(net "M_D_CPU0_SB_DQS_DN<3>")
	)
	(gr_poly
		(pts
			(xy 335.211166 -289.677856) (xy 335.11109 -289.57778) (xy 335.011014 -289.677856) (xy 335.011014 -289.722306)
			(xy 335.211166 -289.722306)
		)
		(stroke
			(width 0)
			(type solid)
		)
		(fill yes)
		(layer "In4.Cu")
		(net "M_D_CPU0_SB_DQ<25>")
	)
	(gr_poly
		(pts
			(xy 335.211166 -289.273996) (xy 335.211166 -289.229546) (xy 335.011014 -289.229546) (xy 335.011014 -289.273996)
			(xy 335.11109 -289.374072)
		)
		(stroke
			(width 0)
			(type solid)
		)
		(fill yes)
		(layer "In4.Cu")
		(net "M_D_CPU0_SB_DQ<26>")
	)
	(gr_poly
		(pts
			(xy 335.211166 -288.057844) (xy 335.11109 -287.957768) (xy 335.011014 -288.057844) (xy 335.011014 -288.102294)
			(xy 335.211166 -288.102294)
		)
		(stroke
			(width 0)
			(type solid)
		)
		(fill yes)
		(layer "In4.Cu")
		(net "M_D_CPU0_SB_DQ<21>")
	)
	(gr_poly
		(pts
			(xy 335.211166 -287.654238) (xy 335.211166 -287.609788) (xy 335.011014 -287.609788) (xy 335.011014 -287.654238)
			(xy 335.11109 -287.75406)
		)
		(stroke
			(width 0)
			(type solid)
		)
		(fill yes)
		(layer "In4.Cu")
		(net "M_D_CPU0_SB_DQ<22>")
	)
	(gr_poly
		(pts
			(xy 335.211166 -286.437832) (xy 335.11109 -286.337756) (xy 335.011014 -286.437832) (xy 335.011014 -286.485584)
			(xy 335.211166 -286.485584)
		)
		(stroke
			(width 0)
			(type solid)
		)
		(fill yes)
		(layer "In4.Cu")
		(net "M_D_CPU0_SB_DQS_DN<7>")
	)
	(gr_poly
		(pts
			(xy 335.211166 -286.03448) (xy 335.211166 -285.986728) (xy 335.011014 -285.986728) (xy 335.011014 -286.03448)
			(xy 335.11109 -286.134302)
		)
		(stroke
			(width 0)
			(type solid)
		)
		(fill yes)
		(layer "In4.Cu")
		(net "M_D_CPU0_SB_DQS_DN<2>")
	)
	(gr_poly
		(pts
			(xy 335.211166 -284.818074) (xy 335.11109 -284.717998) (xy 335.011014 -284.818074) (xy 335.011014 -284.862524)
			(xy 335.211166 -284.862524)
		)
		(stroke
			(width 0)
			(type solid)
		)
		(fill yes)
		(layer "In4.Cu")
		(net "M_D_CPU0_SB_DQ<17>")
	)
	(gr_poly
		(pts
			(xy 335.211166 -284.414214) (xy 335.211166 -284.369764) (xy 335.011014 -284.369764) (xy 335.011014 -284.414214)
			(xy 335.11109 -284.51429)
		)
		(stroke
			(width 0)
			(type solid)
		)
		(fill yes)
		(layer "In4.Cu")
		(net "M_D_CPU0_SB_DQ<18>")
	)
	(gr_poly
		(pts
			(xy 335.211166 -283.198062) (xy 335.11109 -283.097986) (xy 335.011014 -283.198062) (xy 335.011014 -283.242512)
			(xy 335.211166 -283.242512)
		)
		(stroke
			(width 0)
			(type solid)
		)
		(fill yes)
		(layer "In4.Cu")
		(net "M_D_CPU0_SB_DQ<13>")
	)
	(gr_poly
		(pts
			(xy 335.211166 -282.794202) (xy 335.211166 -282.749752) (xy 335.011014 -282.749752) (xy 335.011014 -282.794202)
			(xy 335.11109 -282.894278)
		)
		(stroke
			(width 0)
			(type solid)
		)
		(fill yes)
		(layer "In4.Cu")
		(net "M_D_CPU0_SB_DQ<14>")
	)
	(gr_poly
		(pts
			(xy 335.211166 -281.577796) (xy 335.11109 -281.477974) (xy 335.011014 -281.577796) (xy 335.011014 -281.625548)
			(xy 335.211166 -281.625548)
		)
		(stroke
			(width 0)
			(type solid)
		)
		(fill yes)
		(layer "In4.Cu")
		(net "M_D_CPU0_SB_DQS_DN<6>")
	)
	(gr_poly
		(pts
			(xy 335.211166 -281.174444) (xy 335.211166 -281.126692) (xy 335.011014 -281.126692) (xy 335.011014 -281.174444)
			(xy 335.11109 -281.274266)
		)
		(stroke
			(width 0)
			(type solid)
		)
		(fill yes)
		(layer "In4.Cu")
		(net "M_D_CPU0_SB_DQS_DN<1>")
	)
	(gr_poly
		(pts
			(xy 335.211166 -279.958038) (xy 335.11109 -279.857962) (xy 335.011014 -279.958038) (xy 335.011014 -280.002488)
			(xy 335.211166 -280.002488)
		)
		(stroke
			(width 0)
			(type solid)
		)
		(fill yes)
		(layer "In4.Cu")
		(net "M_D_CPU0_SB_DQ<9>")
	)
	(gr_poly
		(pts
			(xy 335.211166 -279.554178) (xy 335.211166 -279.509728) (xy 335.011014 -279.509728) (xy 335.011014 -279.554178)
			(xy 335.11109 -279.654254)
		)
		(stroke
			(width 0)
			(type solid)
		)
		(fill yes)
		(layer "In4.Cu")
		(net "M_D_CPU0_SB_DQ<10>")
	)
	(gr_poly
		(pts
			(xy 335.211166 -278.338026) (xy 335.11109 -278.23795) (xy 335.011014 -278.338026) (xy 335.011014 -278.382476)
			(xy 335.211166 -278.382476)
		)
		(stroke
			(width 0)
			(type solid)
		)
		(fill yes)
		(layer "In4.Cu")
		(net "M_D_CPU0_SB_DQ<5>")
	)
	(gr_poly
		(pts
			(xy 335.211166 -277.934166) (xy 335.211166 -277.889716) (xy 335.011014 -277.889716) (xy 335.011014 -277.934166)
			(xy 335.11109 -278.034242)
		)
		(stroke
			(width 0)
			(type solid)
		)
		(fill yes)
		(layer "In4.Cu")
		(net "M_D_CPU0_SB_DQ<6>")
	)
	(gr_poly
		(pts
			(xy 335.211166 -276.71776) (xy 335.11109 -276.617938) (xy 335.011014 -276.71776) (xy 335.011014 -276.765512)
			(xy 335.211166 -276.765512)
		)
		(stroke
			(width 0)
			(type solid)
		)
		(fill yes)
		(layer "In4.Cu")
		(net "M_D_CPU0_SB_DQS_DN<5>")
	)
	(gr_poly
		(pts
			(xy 335.211166 -276.314408) (xy 335.211166 -276.266656) (xy 335.011014 -276.266656) (xy 335.011014 -276.314408)
			(xy 335.11109 -276.41423)
		)
		(stroke
			(width 0)
			(type solid)
		)
		(fill yes)
		(layer "In4.Cu")
		(net "M_D_CPU0_SB_DQS_DN<0>")
	)
	(gr_poly
		(pts
			(xy 335.211166 -275.098002) (xy 335.11109 -274.997926) (xy 335.011014 -275.098002) (xy 335.011014 -275.142452)
			(xy 335.211166 -275.142452)
		)
		(stroke
			(width 0)
			(type solid)
		)
		(fill yes)
		(layer "In4.Cu")
		(net "M_D_CPU0_SB_DQ<1>")
	)
	(gr_poly
		(pts
			(xy 335.211166 -274.694142) (xy 335.211166 -274.649692) (xy 335.011014 -274.649692) (xy 335.011014 -274.694142)
			(xy 335.11109 -274.794218)
		)
		(stroke
			(width 0)
			(type solid)
		)
		(fill yes)
		(layer "In4.Cu")
		(net "M_D_CPU0_SB_DQ<2>")
	)
	(gr_poly
		(pts
			(xy 335.211166 -273.47799) (xy 335.11109 -273.377914) (xy 335.011014 -273.47799) (xy 335.011014 -273.52244)
			(xy 335.211166 -273.52244)
		)
		(stroke
			(width 0)
			(type solid)
		)
		(fill yes)
		(layer "In4.Cu")
		(net "M_D_CPU0_SB_CB<1>")
	)
	(gr_poly
		(pts
			(xy 335.211166 -273.07413) (xy 335.211166 -273.02968) (xy 335.011014 -273.02968) (xy 335.011014 -273.07413)
			(xy 335.11109 -273.174206)
		)
		(stroke
			(width 0)
			(type solid)
		)
		(fill yes)
		(layer "In4.Cu")
		(net "M_D_CPU0_SB_CB<2>")
	)
	(gr_poly
		(pts
			(xy 335.211166 -271.857724) (xy 335.11109 -271.757902) (xy 335.011014 -271.857724) (xy 335.011014 -271.905476)
			(xy 335.211166 -271.905476)
		)
		(stroke
			(width 0)
			(type solid)
		)
		(fill yes)
		(layer "In4.Cu")
		(net "M_D_CPU0_SB_DQS_DN<4>")
	)
	(gr_poly
		(pts
			(xy 335.211166 -271.454372) (xy 335.211166 -271.40662) (xy 335.011014 -271.40662) (xy 335.011014 -271.454372)
			(xy 335.11109 -271.554194)
		)
		(stroke
			(width 0)
			(type solid)
		)
		(fill yes)
		(layer "In4.Cu")
		(net "M_D_CPU0_SB_DQS_DN<9>")
	)
	(gr_poly
		(pts
			(xy 335.211166 -270.237966) (xy 335.11109 -270.13789) (xy 335.011014 -270.237966) (xy 335.011014 -270.282416)
			(xy 335.211166 -270.282416)
		)
		(stroke
			(width 0)
			(type solid)
		)
		(fill yes)
		(layer "In4.Cu")
		(net "M_D_CPU0_SB_CB<5>")
	)
	(gr_poly
		(pts
			(xy 335.211166 -269.834106) (xy 335.211166 -269.789656) (xy 335.011014 -269.789656) (xy 335.011014 -269.834106)
			(xy 335.11109 -269.934182)
		)
		(stroke
			(width 0)
			(type solid)
		)
		(fill yes)
		(layer "In4.Cu")
		(net "M_D_CPU0_SB_CB<6>")
	)
	(gr_poly
		(pts
			(xy 335.211166 -266.991592) (xy 335.11109 -266.891516) (xy 335.011014 -266.991592) (xy 335.011014 -267.036042)
			(xy 335.211166 -267.036042)
		)
		(stroke
			(width 0)
			(type solid)
		)
		(fill yes)
		(layer "In4.Cu")
		(net "M_D_CPU0_SA_RSP<0>")
	)
	(gr_poly
		(pts
			(xy 335.211166 -266.594082) (xy 335.211166 -266.549632) (xy 335.011014 -266.549632) (xy 335.011014 -266.594082)
			(xy 335.11109 -266.694158)
		)
		(stroke
			(width 0)
			(type solid)
		)
		(fill yes)
		(layer "In4.Cu")
		(net "M_D_CPU0_SB_CS_N<1>")
	)
	(gr_poly
		(pts
			(xy 335.211166 -264.97407) (xy 335.211166 -264.92962) (xy 335.011014 -264.92962) (xy 335.011014 -264.97407)
			(xy 335.11109 -265.074146)
		)
		(stroke
			(width 0)
			(type solid)
		)
		(fill yes)
		(layer "In4.Cu")
		(net "M_D_CPU0_SB_PAR")
	)
	(gr_poly
		(pts
			(xy 335.211166 -263.757918) (xy 335.11109 -263.657842) (xy 335.011014 -263.757918) (xy 335.011014 -263.802368)
			(xy 335.211166 -263.802368)
		)
		(stroke
			(width 0)
			(type solid)
		)
		(fill yes)
		(layer "In4.Cu")
		(net "M_D_CPU0_SB_CA<4>")
	)
	(gr_poly
		(pts
			(xy 335.211166 -263.354058) (xy 335.211166 -263.309608) (xy 335.011014 -263.309608) (xy 335.011014 -263.354058)
			(xy 335.11109 -263.454134)
		)
		(stroke
			(width 0)
			(type solid)
		)
		(fill yes)
		(layer "In4.Cu")
		(net "M_D_CPU0_SB_CA<3>")
	)
	(gr_poly
		(pts
			(xy 335.211166 -262.137906) (xy 335.11109 -262.03783) (xy 335.011014 -262.137906) (xy 335.011014 -262.182356)
			(xy 335.211166 -262.182356)
		)
		(stroke
			(width 0)
			(type solid)
		)
		(fill yes)
		(layer "In4.Cu")
		(net "M_D_CPU0_SB_CA<0>")
	)
	(gr_poly
		(pts
			(xy 335.381092 -256.432558) (xy 335.381092 -256.384806) (xy 335.18094 -256.384806) (xy 335.18094 -256.432558)
			(xy 335.281016 -256.53238)
		)
		(stroke
			(width 0)
			(type solid)
		)
		(fill yes)
		(layer "In4.Cu")
		(net "M_D_CPU0_CLK_DN<0>")
	)
	(gr_poly
		(pts
			(xy 335.381092 -255.216152) (xy 335.281016 -255.116076) (xy 335.18094 -255.216152) (xy 335.18094 -255.260602)
			(xy 335.381092 -255.260602)
		)
		(stroke
			(width 0)
			(type solid)
		)
		(fill yes)
		(layer "In4.Cu")
		(net "M_D_CPU0_SA_CA<6>")
	)
	(gr_poly
		(pts
			(xy 335.381092 -254.812292) (xy 335.381092 -254.767842) (xy 335.18094 -254.767842) (xy 335.18094 -254.812292)
			(xy 335.281016 -254.912368)
		)
		(stroke
			(width 0)
			(type solid)
		)
		(fill yes)
		(layer "In4.Cu")
		(net "M_D_CPU0_SA_CA<5>")
	)
	(gr_poly
		(pts
			(xy 335.381092 -253.59614) (xy 335.281016 -253.496064) (xy 335.18094 -253.59614) (xy 335.18094 -253.64059)
			(xy 335.381092 -253.64059)
		)
		(stroke
			(width 0)
			(type solid)
		)
		(fill yes)
		(layer "In4.Cu")
		(net "M_D_CPU0_SA_CA<2>")
	)
	(gr_poly
		(pts
			(xy 335.381092 -253.19228) (xy 335.381092 -253.14783) (xy 335.18094 -253.14783) (xy 335.18094 -253.19228)
			(xy 335.281016 -253.292356)
		)
		(stroke
			(width 0)
			(type solid)
		)
		(fill yes)
		(layer "In4.Cu")
		(net "M_D_CPU0_SA_CA<1>")
	)
	(gr_poly
		(pts
			(xy 335.381092 -251.572268) (xy 335.381092 -251.527818) (xy 335.18094 -251.527818) (xy 335.18094 -251.572268)
			(xy 335.281016 -251.672344)
		)
		(stroke
			(width 0)
			(type solid)
		)
		(fill yes)
		(layer "In4.Cu")
		(net "M_D_CPU0_SA_CS_N<0>")
	)
	(gr_poly
		(pts
			(xy 335.381092 -250.356116) (xy 335.281016 -250.25604) (xy 335.18094 -250.356116) (xy 335.18094 -250.400566)
			(xy 335.381092 -250.400566)
		)
		(stroke
			(width 0)
			(type solid)
		)
		(fill yes)
		(layer "In4.Cu")
		(net "M_D_CPU0_ALERT_R_N")
	)
	(gr_poly
		(pts
			(xy 335.381092 -248.736104) (xy 335.281016 -248.636028) (xy 335.18094 -248.736104) (xy 335.18094 -248.780554)
			(xy 335.381092 -248.780554)
		)
		(stroke
			(width 0)
			(type solid)
		)
		(fill yes)
		(layer "In4.Cu")
		(net "M_D_CPU0_SA_CB<5>")
	)
	(gr_poly
		(pts
			(xy 335.381092 -248.332244) (xy 335.381092 -248.287794) (xy 335.18094 -248.287794) (xy 335.18094 -248.332244)
			(xy 335.281016 -248.43232)
		)
		(stroke
			(width 0)
			(type solid)
		)
		(fill yes)
		(layer "In4.Cu")
		(net "M_D_CPU0_SA_CB<6>")
	)
	(gr_poly
		(pts
			(xy 335.381092 -247.115838) (xy 335.281016 -247.016016) (xy 335.18094 -247.115838) (xy 335.18094 -247.16359)
			(xy 335.381092 -247.16359)
		)
		(stroke
			(width 0)
			(type solid)
		)
		(fill yes)
		(layer "In4.Cu")
		(net "M_D_CPU0_SA_DQS_DN<9>")
	)
	(gr_poly
		(pts
			(xy 335.381092 -246.712486) (xy 335.381092 -246.664734) (xy 335.18094 -246.664734) (xy 335.18094 -246.712486)
			(xy 335.281016 -246.812308)
		)
		(stroke
			(width 0)
			(type solid)
		)
		(fill yes)
		(layer "In4.Cu")
		(net "M_D_CPU0_SA_DQS_DN<4>")
	)
	(gr_poly
		(pts
			(xy 335.381092 -245.49608) (xy 335.281016 -245.396004) (xy 335.18094 -245.49608) (xy 335.18094 -245.54053)
			(xy 335.381092 -245.54053)
		)
		(stroke
			(width 0)
			(type solid)
		)
		(fill yes)
		(layer "In4.Cu")
		(net "M_D_CPU0_SA_CB<1>")
	)
	(gr_poly
		(pts
			(xy 335.381092 -245.09222) (xy 335.381092 -245.04777) (xy 335.18094 -245.04777) (xy 335.18094 -245.09222)
			(xy 335.281016 -245.192296)
		)
		(stroke
			(width 0)
			(type solid)
		)
		(fill yes)
		(layer "In4.Cu")
		(net "M_D_CPU0_SA_CB<2>")
	)
	(gr_poly
		(pts
			(xy 335.381092 -243.876068) (xy 335.281016 -243.775992) (xy 335.18094 -243.876068) (xy 335.18094 -243.920518)
			(xy 335.381092 -243.920518)
		)
		(stroke
			(width 0)
			(type solid)
		)
		(fill yes)
		(layer "In4.Cu")
		(net "M_D_CPU0_SA_DQ<29>")
	)
	(gr_poly
		(pts
			(xy 335.381092 -243.472208) (xy 335.381092 -243.427758) (xy 335.18094 -243.427758) (xy 335.18094 -243.472208)
			(xy 335.281016 -243.572284)
		)
		(stroke
			(width 0)
			(type solid)
		)
		(fill yes)
		(layer "In4.Cu")
		(net "M_D_CPU0_SA_DQ<30>")
	)
	(gr_poly
		(pts
			(xy 335.381092 -242.255802) (xy 335.281016 -242.15598) (xy 335.18094 -242.255802) (xy 335.18094 -242.303554)
			(xy 335.381092 -242.303554)
		)
		(stroke
			(width 0)
			(type solid)
		)
		(fill yes)
		(layer "In4.Cu")
		(net "M_D_CPU0_SA_DQS_DN<8>")
	)
	(gr_poly
		(pts
			(xy 335.381092 -241.85245) (xy 335.381092 -241.804698) (xy 335.18094 -241.804698) (xy 335.18094 -241.85245)
			(xy 335.281016 -241.952272)
		)
		(stroke
			(width 0)
			(type solid)
		)
		(fill yes)
		(layer "In4.Cu")
		(net "M_D_CPU0_SA_DQS_DN<3>")
	)
	(gr_poly
		(pts
			(xy 335.381092 -240.636044) (xy 335.281016 -240.535968) (xy 335.18094 -240.636044) (xy 335.18094 -240.680494)
			(xy 335.381092 -240.680494)
		)
		(stroke
			(width 0)
			(type solid)
		)
		(fill yes)
		(layer "In4.Cu")
		(net "M_D_CPU0_SA_DQ<25>")
	)
	(gr_poly
		(pts
			(xy 335.381092 -240.232184) (xy 335.381092 -240.187734) (xy 335.18094 -240.187734) (xy 335.18094 -240.232184)
			(xy 335.281016 -240.33226)
		)
		(stroke
			(width 0)
			(type solid)
		)
		(fill yes)
		(layer "In4.Cu")
		(net "M_D_CPU0_SA_DQ<26>")
	)
	(gr_poly
		(pts
			(xy 335.381092 -239.016032) (xy 335.281016 -238.915956) (xy 335.18094 -239.016032) (xy 335.18094 -239.060482)
			(xy 335.381092 -239.060482)
		)
		(stroke
			(width 0)
			(type solid)
		)
		(fill yes)
		(layer "In4.Cu")
		(net "M_D_CPU0_SA_DQ<21>")
	)
	(gr_poly
		(pts
			(xy 335.381092 -238.612172) (xy 335.381092 -238.567722) (xy 335.18094 -238.567722) (xy 335.18094 -238.612172)
			(xy 335.281016 -238.712248)
		)
		(stroke
			(width 0)
			(type solid)
		)
		(fill yes)
		(layer "In4.Cu")
		(net "M_D_CPU0_SA_DQ<22>")
	)
	(gr_poly
		(pts
			(xy 335.381092 -237.395766) (xy 335.281016 -237.295944) (xy 335.18094 -237.395766) (xy 335.18094 -237.443518)
			(xy 335.381092 -237.443518)
		)
		(stroke
			(width 0)
			(type solid)
		)
		(fill yes)
		(layer "In4.Cu")
		(net "M_D_CPU0_SA_DQS_DN<7>")
	)
	(gr_poly
		(pts
			(xy 335.381092 -236.992414) (xy 335.381092 -236.944662) (xy 335.18094 -236.944662) (xy 335.18094 -236.992414)
			(xy 335.281016 -237.092236)
		)
		(stroke
			(width 0)
			(type solid)
		)
		(fill yes)
		(layer "In4.Cu")
		(net "M_D_CPU0_SA_DQS_DN<2>")
	)
	(gr_poly
		(pts
			(xy 335.381092 -235.776008) (xy 335.281016 -235.675932) (xy 335.18094 -235.776008) (xy 335.18094 -235.820458)
			(xy 335.381092 -235.820458)
		)
		(stroke
			(width 0)
			(type solid)
		)
		(fill yes)
		(layer "In4.Cu")
		(net "M_D_CPU0_SA_DQ<17>")
	)
	(gr_poly
		(pts
			(xy 335.381092 -235.372148) (xy 335.381092 -235.327698) (xy 335.18094 -235.327698) (xy 335.18094 -235.372148)
			(xy 335.281016 -235.472224)
		)
		(stroke
			(width 0)
			(type solid)
		)
		(fill yes)
		(layer "In4.Cu")
		(net "M_D_CPU0_SA_DQ<18>")
	)
	(gr_poly
		(pts
			(xy 335.381092 -234.155996) (xy 335.281016 -234.05592) (xy 335.18094 -234.155996) (xy 335.18094 -234.200446)
			(xy 335.381092 -234.200446)
		)
		(stroke
			(width 0)
			(type solid)
		)
		(fill yes)
		(layer "In4.Cu")
		(net "M_D_CPU0_SA_DQ<13>")
	)
	(gr_poly
		(pts
			(xy 335.381092 -233.752136) (xy 335.381092 -233.707686) (xy 335.18094 -233.707686) (xy 335.18094 -233.752136)
			(xy 335.281016 -233.852212)
		)
		(stroke
			(width 0)
			(type solid)
		)
		(fill yes)
		(layer "In4.Cu")
		(net "M_D_CPU0_SA_DQ<14>")
	)
	(gr_poly
		(pts
			(xy 335.381092 -232.53573) (xy 335.281016 -232.435908) (xy 335.18094 -232.53573) (xy 335.18094 -232.583482)
			(xy 335.381092 -232.583482)
		)
		(stroke
			(width 0)
			(type solid)
		)
		(fill yes)
		(layer "In4.Cu")
		(net "M_D_CPU0_SA_DQS_DN<6>")
	)
	(gr_poly
		(pts
			(xy 335.381092 -232.132378) (xy 335.381092 -232.084626) (xy 335.18094 -232.084626) (xy 335.18094 -232.132378)
			(xy 335.281016 -232.2322)
		)
		(stroke
			(width 0)
			(type solid)
		)
		(fill yes)
		(layer "In4.Cu")
		(net "M_D_CPU0_SA_DQS_DN<1>")
	)
	(gr_poly
		(pts
			(xy 335.381092 -230.915972) (xy 335.281016 -230.815896) (xy 335.18094 -230.915972) (xy 335.18094 -230.960422)
			(xy 335.381092 -230.960422)
		)
		(stroke
			(width 0)
			(type solid)
		)
		(fill yes)
		(layer "In4.Cu")
		(net "M_D_CPU0_SA_DQ<9>")
	)
	(gr_poly
		(pts
			(xy 335.381092 -230.512366) (xy 335.381092 -230.467916) (xy 335.18094 -230.467916) (xy 335.18094 -230.512366)
			(xy 335.281016 -230.612188)
		)
		(stroke
			(width 0)
			(type solid)
		)
		(fill yes)
		(layer "In4.Cu")
		(net "M_D_CPU0_SA_DQ<10>")
	)
	(gr_poly
		(pts
			(xy 335.381092 -229.29596) (xy 335.281016 -229.195884) (xy 335.18094 -229.29596) (xy 335.18094 -229.34041)
			(xy 335.381092 -229.34041)
		)
		(stroke
			(width 0)
			(type solid)
		)
		(fill yes)
		(layer "In4.Cu")
		(net "M_D_CPU0_SA_DQ<5>")
	)
	(gr_poly
		(pts
			(xy 335.381092 -228.892354) (xy 335.381092 -228.847904) (xy 335.18094 -228.847904) (xy 335.18094 -228.892354)
			(xy 335.281016 -228.99243)
		)
		(stroke
			(width 0)
			(type solid)
		)
		(fill yes)
		(layer "In4.Cu")
		(net "M_D_CPU0_SA_DQ<6>")
	)
	(gr_poly
		(pts
			(xy 335.381092 -227.272596) (xy 335.381092 -227.224844) (xy 335.18094 -227.224844) (xy 335.18094 -227.272596)
			(xy 335.281016 -227.372418)
		)
		(stroke
			(width 0)
			(type solid)
		)
		(fill yes)
		(layer "In4.Cu")
		(net "M_D_CPU0_SA_DQS_DN<0>")
	)
	(gr_poly
		(pts
			(xy 335.381092 -226.05619) (xy 335.281016 -225.956114) (xy 335.18094 -226.05619) (xy 335.18094 -226.10064)
			(xy 335.381092 -226.10064)
		)
		(stroke
			(width 0)
			(type solid)
		)
		(fill yes)
		(layer "In4.Cu")
		(net "M_D_CPU0_SA_DQ<1>")
	)
	(gr_poly
		(pts
			(xy 335.381092 -225.65233) (xy 335.381092 -225.60788) (xy 335.18094 -225.60788) (xy 335.18094 -225.65233)
			(xy 335.281016 -225.752406)
		)
		(stroke
			(width 0)
			(type solid)
		)
		(fill yes)
		(layer "In4.Cu")
		(net "M_D_CPU0_SA_DQ<2>")
	)
	(gr_poly
		(pts
			(xy 335.387188 -227.676456) (xy 335.287112 -227.57638) (xy 335.18729 -227.676456) (xy 335.18729 -227.723954)
			(xy 335.387188 -227.723954)
		)
		(stroke
			(width 0)
			(type solid)
		)
		(fill yes)
		(layer "In4.Cu")
		(net "M_D_CPU0_SA_DQS_DN<5>")
	)
	(gr_poly
		(pts
			(xy 335.681066 -293.324026) (xy 335.681066 -293.279576) (xy 335.480914 -293.279576) (xy 335.480914 -293.324026)
			(xy 335.58099 -293.424102)
		)
		(stroke
			(width 0)
			(type solid)
		)
		(fill yes)
		(layer "In4.Cu")
		(net "M_D_CPU0_SB_DQ<31>")
	)
	(gr_poly
		(pts
			(xy 335.681066 -292.107874) (xy 335.58099 -292.007798) (xy 335.480914 -292.107874) (xy 335.480914 -292.152324)
			(xy 335.681066 -292.152324)
		)
		(stroke
			(width 0)
			(type solid)
		)
		(fill yes)
		(layer "In4.Cu")
		(net "M_D_CPU0_SB_DQ<28>")
	)
	(gr_poly
		(pts
			(xy 335.681066 -291.704268) (xy 335.681066 -291.656516) (xy 335.480914 -291.656516) (xy 335.480914 -291.704268)
			(xy 335.58099 -291.80409)
		)
		(stroke
			(width 0)
			(type solid)
		)
		(fill yes)
		(layer "In4.Cu")
		(net "M_D_CPU0_SB_DQS_DP<8>")
	)
	(gr_poly
		(pts
			(xy 335.681066 -290.487608) (xy 335.58099 -290.387786) (xy 335.480914 -290.487608) (xy 335.480914 -290.53536)
			(xy 335.681066 -290.53536)
		)
		(stroke
			(width 0)
			(type solid)
		)
		(fill yes)
		(layer "In4.Cu")
		(net "M_D_CPU0_SB_DQS_DP<3>")
	)
	(gr_poly
		(pts
			(xy 335.681066 -290.084002) (xy 335.681066 -290.039552) (xy 335.480914 -290.039552) (xy 335.480914 -290.084002)
			(xy 335.58099 -290.184078)
		)
		(stroke
			(width 0)
			(type solid)
		)
		(fill yes)
		(layer "In4.Cu")
		(net "M_D_CPU0_SB_DQ<27>")
	)
	(gr_poly
		(pts
			(xy 335.681066 -288.86785) (xy 335.58099 -288.767774) (xy 335.480914 -288.86785) (xy 335.480914 -288.9123)
			(xy 335.681066 -288.9123)
		)
		(stroke
			(width 0)
			(type solid)
		)
		(fill yes)
		(layer "In4.Cu")
		(net "M_D_CPU0_SB_DQ<24>")
	)
	(gr_poly
		(pts
			(xy 335.681066 -288.464244) (xy 335.681066 -288.419794) (xy 335.480914 -288.419794) (xy 335.480914 -288.464244)
			(xy 335.58099 -288.56432)
		)
		(stroke
			(width 0)
			(type solid)
		)
		(fill yes)
		(layer "In4.Cu")
		(net "M_D_CPU0_SB_DQ<23>")
	)
	(gr_poly
		(pts
			(xy 335.681066 -287.247838) (xy 335.58099 -287.148016) (xy 335.480914 -287.247838) (xy 335.480914 -287.292288)
			(xy 335.681066 -287.292288)
		)
		(stroke
			(width 0)
			(type solid)
		)
		(fill yes)
		(layer "In4.Cu")
		(net "M_D_CPU0_SB_DQ<20>")
	)
	(gr_poly
		(pts
			(xy 335.681066 -286.844232) (xy 335.681066 -286.79648) (xy 335.480914 -286.79648) (xy 335.480914 -286.844232)
			(xy 335.58099 -286.944308)
		)
		(stroke
			(width 0)
			(type solid)
		)
		(fill yes)
		(layer "In4.Cu")
		(net "M_D_CPU0_SB_DQS_DP<7>")
	)
	(gr_poly
		(pts
			(xy 335.681066 -285.627826) (xy 335.58099 -285.528004) (xy 335.480914 -285.627826) (xy 335.480914 -285.675578)
			(xy 335.681066 -285.675578)
		)
		(stroke
			(width 0)
			(type solid)
		)
		(fill yes)
		(layer "In4.Cu")
		(net "M_D_CPU0_SB_DQS_DP<2>")
	)
	(gr_poly
		(pts
			(xy 335.681066 -285.22422) (xy 335.681066 -285.17977) (xy 335.480914 -285.17977) (xy 335.480914 -285.22422)
			(xy 335.58099 -285.324296)
		)
		(stroke
			(width 0)
			(type solid)
		)
		(fill yes)
		(layer "In4.Cu")
		(net "M_D_CPU0_SB_DQ<19>")
	)
	(gr_poly
		(pts
			(xy 335.681066 -284.008068) (xy 335.58099 -283.907992) (xy 335.480914 -284.008068) (xy 335.480914 -284.052518)
			(xy 335.681066 -284.052518)
		)
		(stroke
			(width 0)
			(type solid)
		)
		(fill yes)
		(layer "In4.Cu")
		(net "M_D_CPU0_SB_DQ<16>")
	)
	(gr_poly
		(pts
			(xy 335.681066 -283.604208) (xy 335.681066 -283.559758) (xy 335.480914 -283.559758) (xy 335.480914 -283.604208)
			(xy 335.58099 -283.704284)
		)
		(stroke
			(width 0)
			(type solid)
		)
		(fill yes)
		(layer "In4.Cu")
		(net "M_D_CPU0_SB_DQ<15>")
	)
	(gr_poly
		(pts
			(xy 335.681066 -282.388056) (xy 335.58099 -282.28798) (xy 335.480914 -282.388056) (xy 335.480914 -282.432506)
			(xy 335.681066 -282.432506)
		)
		(stroke
			(width 0)
			(type solid)
		)
		(fill yes)
		(layer "In4.Cu")
		(net "M_D_CPU0_SB_DQ<12>")
	)
	(gr_poly
		(pts
			(xy 335.681066 -281.98445) (xy 335.681066 -281.936698) (xy 335.480914 -281.936698) (xy 335.480914 -281.98445)
			(xy 335.58099 -282.084272)
		)
		(stroke
			(width 0)
			(type solid)
		)
		(fill yes)
		(layer "In4.Cu")
		(net "M_D_CPU0_SB_DQS_DP<6>")
	)
	(gr_poly
		(pts
			(xy 335.681066 -280.76779) (xy 335.58099 -280.667968) (xy 335.480914 -280.76779) (xy 335.480914 -280.815542)
			(xy 335.681066 -280.815542)
		)
		(stroke
			(width 0)
			(type solid)
		)
		(fill yes)
		(layer "In4.Cu")
		(net "M_D_CPU0_SB_DQS_DP<1>")
	)
	(gr_poly
		(pts
			(xy 335.681066 -280.364184) (xy 335.681066 -280.319734) (xy 335.480914 -280.319734) (xy 335.480914 -280.364184)
			(xy 335.58099 -280.46426)
		)
		(stroke
			(width 0)
			(type solid)
		)
		(fill yes)
		(layer "In4.Cu")
		(net "M_D_CPU0_SB_DQ<11>")
	)
	(gr_poly
		(pts
			(xy 335.681066 -279.148032) (xy 335.58099 -279.047956) (xy 335.480914 -279.148032) (xy 335.480914 -279.192482)
			(xy 335.681066 -279.192482)
		)
		(stroke
			(width 0)
			(type solid)
		)
		(fill yes)
		(layer "In4.Cu")
		(net "M_D_CPU0_SB_DQ<8>")
	)
	(gr_poly
		(pts
			(xy 335.681066 -278.744172) (xy 335.681066 -278.699722) (xy 335.480914 -278.699722) (xy 335.480914 -278.744172)
			(xy 335.58099 -278.844248)
		)
		(stroke
			(width 0)
			(type solid)
		)
		(fill yes)
		(layer "In4.Cu")
		(net "M_D_CPU0_SB_DQ<7>")
	)
	(gr_poly
		(pts
			(xy 335.681066 -277.52802) (xy 335.58099 -277.427944) (xy 335.480914 -277.52802) (xy 335.480914 -277.57247)
			(xy 335.681066 -277.57247)
		)
		(stroke
			(width 0)
			(type solid)
		)
		(fill yes)
		(layer "In4.Cu")
		(net "M_D_CPU0_SB_DQ<4>")
	)
	(gr_poly
		(pts
			(xy 335.681066 -275.504148) (xy 335.681066 -275.459698) (xy 335.480914 -275.459698) (xy 335.480914 -275.504148)
			(xy 335.58099 -275.604224)
		)
		(stroke
			(width 0)
			(type solid)
		)
		(fill yes)
		(layer "In4.Cu")
		(net "M_D_CPU0_SB_DQ<3>")
	)
	(gr_poly
		(pts
			(xy 335.681066 -274.287996) (xy 335.58099 -274.18792) (xy 335.480914 -274.287996) (xy 335.480914 -274.332446)
			(xy 335.681066 -274.332446)
		)
		(stroke
			(width 0)
			(type solid)
		)
		(fill yes)
		(layer "In4.Cu")
		(net "M_D_CPU0_SB_DQ<0>")
	)
	(gr_poly
		(pts
			(xy 335.681066 -273.884136) (xy 335.681066 -273.839686) (xy 335.480914 -273.839686) (xy 335.480914 -273.884136)
			(xy 335.58099 -273.984212)
		)
		(stroke
			(width 0)
			(type solid)
		)
		(fill yes)
		(layer "In4.Cu")
		(net "M_D_CPU0_SB_CB<3>")
	)
	(gr_poly
		(pts
			(xy 335.681066 -272.667984) (xy 335.58099 -272.567908) (xy 335.480914 -272.667984) (xy 335.480914 -272.712434)
			(xy 335.681066 -272.712434)
		)
		(stroke
			(width 0)
			(type solid)
		)
		(fill yes)
		(layer "In4.Cu")
		(net "M_D_CPU0_SB_CB<0>")
	)
	(gr_poly
		(pts
			(xy 335.681066 -272.264378) (xy 335.681066 -272.216626) (xy 335.480914 -272.216626) (xy 335.480914 -272.264378)
			(xy 335.58099 -272.3642)
		)
		(stroke
			(width 0)
			(type solid)
		)
		(fill yes)
		(layer "In4.Cu")
		(net "M_D_CPU0_SB_DQS_DP<4>")
	)
	(gr_poly
		(pts
			(xy 335.681066 -271.047718) (xy 335.58099 -270.947896) (xy 335.480914 -271.047718) (xy 335.480914 -271.09547)
			(xy 335.681066 -271.09547)
		)
		(stroke
			(width 0)
			(type solid)
		)
		(fill yes)
		(layer "In4.Cu")
		(net "M_D_CPU0_SB_DQS_DP<9>")
	)
	(gr_poly
		(pts
			(xy 335.681066 -270.644112) (xy 335.681066 -270.599662) (xy 335.480914 -270.599662) (xy 335.480914 -270.644112)
			(xy 335.58099 -270.744188)
		)
		(stroke
			(width 0)
			(type solid)
		)
		(fill yes)
		(layer "In4.Cu")
		(net "M_D_CPU0_SB_CB<7>")
	)
	(gr_poly
		(pts
			(xy 335.681066 -269.42796) (xy 335.58099 -269.327884) (xy 335.480914 -269.42796) (xy 335.480914 -269.47241)
			(xy 335.681066 -269.47241)
		)
		(stroke
			(width 0)
			(type solid)
		)
		(fill yes)
		(layer "In4.Cu")
		(net "M_D_CPU0_SB_CB<4>")
	)
	(gr_poly
		(pts
			(xy 335.681066 -265.784076) (xy 335.681066 -265.739626) (xy 335.480914 -265.739626) (xy 335.480914 -265.784076)
			(xy 335.58099 -265.884152)
		)
		(stroke
			(width 0)
			(type solid)
		)
		(fill yes)
		(layer "In4.Cu")
		(net "M_D_CPU0_SB_CS_N<0>")
	)
	(gr_poly
		(pts
			(xy 335.681066 -264.567924) (xy 335.58099 -264.467848) (xy 335.480914 -264.567924) (xy 335.480914 -264.612374)
			(xy 335.681066 -264.612374)
		)
		(stroke
			(width 0)
			(type solid)
		)
		(fill yes)
		(layer "In4.Cu")
		(net "M_D_CPU0_SB_CA<6>")
	)
	(gr_poly
		(pts
			(xy 335.681066 -264.164064) (xy 335.681066 -264.119614) (xy 335.480914 -264.119614) (xy 335.480914 -264.164064)
			(xy 335.58099 -264.26414)
		)
		(stroke
			(width 0)
			(type solid)
		)
		(fill yes)
		(layer "In4.Cu")
		(net "M_D_CPU0_SB_CA<5>")
	)
	(gr_poly
		(pts
			(xy 335.681066 -262.947912) (xy 335.58099 -262.847836) (xy 335.480914 -262.947912) (xy 335.480914 -262.992362)
			(xy 335.681066 -262.992362)
		)
		(stroke
			(width 0)
			(type solid)
		)
		(fill yes)
		(layer "In4.Cu")
		(net "M_D_CPU0_SB_CA<2>")
	)
	(gr_poly
		(pts
			(xy 335.681066 -262.544052) (xy 335.681066 -262.499602) (xy 335.480914 -262.499602) (xy 335.480914 -262.544052)
			(xy 335.58099 -262.644128)
		)
		(stroke
			(width 0)
			(type solid)
		)
		(fill yes)
		(layer "In4.Cu")
		(net "M_D_CPU0_SB_CA<1>")
	)
	(gr_poly
		(pts
			(xy 335.687162 -267.801598) (xy 335.58734 -267.701522) (xy 335.487264 -267.801598) (xy 335.487264 -267.846048)
			(xy 335.687162 -267.846048)
		)
		(stroke
			(width 0)
			(type solid)
		)
		(fill yes)
		(layer "In4.Cu")
		(net "M_D_CPU0_SB_RSP<0>")
	)
	(gr_poly
		(pts
			(xy 335.688432 -277.12416) (xy 335.688432 -277.076662) (xy 335.48828 -277.076662) (xy 335.48828 -277.12416)
			(xy 335.588356 -277.224236)
		)
		(stroke
			(width 0)
			(type solid)
		)
		(fill yes)
		(layer "In4.Cu")
		(net "M_D_CPU0_SB_DQS_DP<5>")
	)
	(gr_poly
		(pts
			(xy 335.688432 -275.908008) (xy 335.588356 -275.807932) (xy 335.48828 -275.908008) (xy 335.48828 -275.955506)
			(xy 335.688432 -275.955506)
		)
		(stroke
			(width 0)
			(type solid)
		)
		(fill yes)
		(layer "In4.Cu")
		(net "M_D_CPU0_SB_DQS_DP<0>")
	)
	(gr_poly
		(pts
			(xy 335.851246 -256.025904) (xy 335.75117 -255.926082) (xy 335.651094 -256.025904) (xy 335.651094 -256.073656)
			(xy 335.851246 -256.073656)
		)
		(stroke
			(width 0)
			(type solid)
		)
		(fill yes)
		(layer "In4.Cu")
		(net "M_D_CPU0_CLK_DP<0>")
	)
	(gr_poly
		(pts
			(xy 335.851246 -255.622298) (xy 335.851246 -255.577848) (xy 335.651094 -255.577848) (xy 335.651094 -255.622298)
			(xy 335.75117 -255.722374)
		)
		(stroke
			(width 0)
			(type solid)
		)
		(fill yes)
		(layer "In4.Cu")
		(net "M_D_CPU0_SA_PAR")
	)
	(gr_poly
		(pts
			(xy 335.851246 -254.406146) (xy 335.75117 -254.30607) (xy 335.651094 -254.406146) (xy 335.651094 -254.450596)
			(xy 335.851246 -254.450596)
		)
		(stroke
			(width 0)
			(type solid)
		)
		(fill yes)
		(layer "In4.Cu")
		(net "M_D_CPU0_SA_CA<4>")
	)
	(gr_poly
		(pts
			(xy 335.851246 -254.002286) (xy 335.851246 -253.957836) (xy 335.651094 -253.957836) (xy 335.651094 -254.002286)
			(xy 335.75117 -254.102362)
		)
		(stroke
			(width 0)
			(type solid)
		)
		(fill yes)
		(layer "In4.Cu")
		(net "M_D_CPU0_SA_CA<3>")
	)
	(gr_poly
		(pts
			(xy 335.851246 -252.786134) (xy 335.75117 -252.686058) (xy 335.651094 -252.786134) (xy 335.651094 -252.830584)
			(xy 335.851246 -252.830584)
		)
		(stroke
			(width 0)
			(type solid)
		)
		(fill yes)
		(layer "In4.Cu")
		(net "M_D_CPU0_SA_CA<0>")
	)
	(gr_poly
		(pts
			(xy 335.851246 -252.382274) (xy 335.851246 -252.337824) (xy 335.651094 -252.337824) (xy 335.651094 -252.382274)
			(xy 335.75117 -252.48235)
		)
		(stroke
			(width 0)
			(type solid)
		)
		(fill yes)
		(layer "In4.Cu")
		(net "M_D_CPU0_SA_CS_N<1>")
	)
	(gr_poly
		(pts
			(xy 335.851246 -250.762262) (xy 335.851246 -250.717812) (xy 335.651094 -250.717812) (xy 335.651094 -250.762262)
			(xy 335.75117 -250.862338)
		)
		(stroke
			(width 0)
			(type solid)
		)
		(fill yes)
		(layer "In4.Cu")
		(net "M_D_CPU0_RESET_N")
	)
	(gr_poly
		(pts
			(xy 335.851246 -249.14225) (xy 335.851246 -249.0978) (xy 335.651094 -249.0978) (xy 335.651094 -249.14225)
			(xy 335.75117 -249.242326)
		)
		(stroke
			(width 0)
			(type solid)
		)
		(fill yes)
		(layer "In4.Cu")
		(net "M_D_CPU0_SA_CB<7>")
	)
	(gr_poly
		(pts
			(xy 335.851246 -247.926098) (xy 335.75117 -247.826022) (xy 335.651094 -247.926098) (xy 335.651094 -247.970548)
			(xy 335.851246 -247.970548)
		)
		(stroke
			(width 0)
			(type solid)
		)
		(fill yes)
		(layer "In4.Cu")
		(net "M_D_CPU0_SA_CB<4>")
	)
	(gr_poly
		(pts
			(xy 335.851246 -247.522492) (xy 335.851246 -247.47474) (xy 335.651094 -247.47474) (xy 335.651094 -247.522492)
			(xy 335.75117 -247.622314)
		)
		(stroke
			(width 0)
			(type solid)
		)
		(fill yes)
		(layer "In4.Cu")
		(net "M_D_CPU0_SA_DQS_DP<9>")
	)
	(gr_poly
		(pts
			(xy 335.851246 -246.305832) (xy 335.75117 -246.20601) (xy 335.651094 -246.305832) (xy 335.651094 -246.353584)
			(xy 335.851246 -246.353584)
		)
		(stroke
			(width 0)
			(type solid)
		)
		(fill yes)
		(layer "In4.Cu")
		(net "M_D_CPU0_SA_DQS_DP<4>")
	)
	(gr_poly
		(pts
			(xy 335.851246 -245.902226) (xy 335.851246 -245.857776) (xy 335.651094 -245.857776) (xy 335.651094 -245.902226)
			(xy 335.75117 -246.002302)
		)
		(stroke
			(width 0)
			(type solid)
		)
		(fill yes)
		(layer "In4.Cu")
		(net "M_D_CPU0_SA_CB<3>")
	)
	(gr_poly
		(pts
			(xy 335.851246 -244.686074) (xy 335.75117 -244.585998) (xy 335.651094 -244.686074) (xy 335.651094 -244.730524)
			(xy 335.851246 -244.730524)
		)
		(stroke
			(width 0)
			(type solid)
		)
		(fill yes)
		(layer "In4.Cu")
		(net "M_D_CPU0_SA_CB<0>")
	)
	(gr_poly
		(pts
			(xy 335.851246 -244.282214) (xy 335.851246 -244.237764) (xy 335.651094 -244.237764) (xy 335.651094 -244.282214)
			(xy 335.75117 -244.38229)
		)
		(stroke
			(width 0)
			(type solid)
		)
		(fill yes)
		(layer "In4.Cu")
		(net "M_D_CPU0_SA_DQ<31>")
	)
	(gr_poly
		(pts
			(xy 335.851246 -243.066062) (xy 335.75117 -242.965986) (xy 335.651094 -243.066062) (xy 335.651094 -243.110512)
			(xy 335.851246 -243.110512)
		)
		(stroke
			(width 0)
			(type solid)
		)
		(fill yes)
		(layer "In4.Cu")
		(net "M_D_CPU0_SA_DQ<28>")
	)
	(gr_poly
		(pts
			(xy 335.851246 -242.662456) (xy 335.851246 -242.614704) (xy 335.651094 -242.614704) (xy 335.651094 -242.662456)
			(xy 335.75117 -242.762278)
		)
		(stroke
			(width 0)
			(type solid)
		)
		(fill yes)
		(layer "In4.Cu")
		(net "M_D_CPU0_SA_DQS_DP<8>")
	)
	(gr_poly
		(pts
			(xy 335.851246 -241.445796) (xy 335.75117 -241.345974) (xy 335.651094 -241.445796) (xy 335.651094 -241.493548)
			(xy 335.851246 -241.493548)
		)
		(stroke
			(width 0)
			(type solid)
		)
		(fill yes)
		(layer "In4.Cu")
		(net "M_D_CPU0_SA_DQS_DP<3>")
	)
	(gr_poly
		(pts
			(xy 335.851246 -241.04219) (xy 335.851246 -240.99774) (xy 335.651094 -240.99774) (xy 335.651094 -241.04219)
			(xy 335.75117 -241.142266)
		)
		(stroke
			(width 0)
			(type solid)
		)
		(fill yes)
		(layer "In4.Cu")
		(net "M_D_CPU0_SA_DQ<27>")
	)
	(gr_poly
		(pts
			(xy 335.851246 -239.826038) (xy 335.75117 -239.725962) (xy 335.651094 -239.826038) (xy 335.651094 -239.870488)
			(xy 335.851246 -239.870488)
		)
		(stroke
			(width 0)
			(type solid)
		)
		(fill yes)
		(layer "In4.Cu")
		(net "M_D_CPU0_SA_DQ<24>")
	)
	(gr_poly
		(pts
			(xy 335.851246 -239.422178) (xy 335.851246 -239.377728) (xy 335.651094 -239.377728) (xy 335.651094 -239.422178)
			(xy 335.75117 -239.522254)
		)
		(stroke
			(width 0)
			(type solid)
		)
		(fill yes)
		(layer "In4.Cu")
		(net "M_D_CPU0_SA_DQ<23>")
	)
	(gr_poly
		(pts
			(xy 335.851246 -238.206026) (xy 335.75117 -238.10595) (xy 335.651094 -238.206026) (xy 335.651094 -238.250476)
			(xy 335.851246 -238.250476)
		)
		(stroke
			(width 0)
			(type solid)
		)
		(fill yes)
		(layer "In4.Cu")
		(net "M_D_CPU0_SA_DQ<20>")
	)
	(gr_poly
		(pts
			(xy 335.851246 -237.80242) (xy 335.851246 -237.754668) (xy 335.651094 -237.754668) (xy 335.651094 -237.80242)
			(xy 335.75117 -237.902242)
		)
		(stroke
			(width 0)
			(type solid)
		)
		(fill yes)
		(layer "In4.Cu")
		(net "M_D_CPU0_SA_DQS_DP<7>")
	)
	(gr_poly
		(pts
			(xy 335.851246 -236.58576) (xy 335.75117 -236.485938) (xy 335.651094 -236.58576) (xy 335.651094 -236.633512)
			(xy 335.851246 -236.633512)
		)
		(stroke
			(width 0)
			(type solid)
		)
		(fill yes)
		(layer "In4.Cu")
		(net "M_D_CPU0_SA_DQS_DP<2>")
	)
	(gr_poly
		(pts
			(xy 335.851246 -236.182154) (xy 335.851246 -236.137704) (xy 335.651094 -236.137704) (xy 335.651094 -236.182154)
			(xy 335.75117 -236.28223)
		)
		(stroke
			(width 0)
			(type solid)
		)
		(fill yes)
		(layer "In4.Cu")
		(net "M_D_CPU0_SA_DQ<19>")
	)
	(gr_poly
		(pts
			(xy 335.851246 -234.966002) (xy 335.75117 -234.865926) (xy 335.651094 -234.966002) (xy 335.651094 -235.010452)
			(xy 335.851246 -235.010452)
		)
		(stroke
			(width 0)
			(type solid)
		)
		(fill yes)
		(layer "In4.Cu")
		(net "M_D_CPU0_SA_DQ<16>")
	)
	(gr_poly
		(pts
			(xy 335.851246 -234.562142) (xy 335.851246 -234.517692) (xy 335.651094 -234.517692) (xy 335.651094 -234.562142)
			(xy 335.75117 -234.662218)
		)
		(stroke
			(width 0)
			(type solid)
		)
		(fill yes)
		(layer "In4.Cu")
		(net "M_D_CPU0_SA_DQ<15>")
	)
	(gr_poly
		(pts
			(xy 335.851246 -233.34599) (xy 335.75117 -233.245914) (xy 335.651094 -233.34599) (xy 335.651094 -233.39044)
			(xy 335.851246 -233.39044)
		)
		(stroke
			(width 0)
			(type solid)
		)
		(fill yes)
		(layer "In4.Cu")
		(net "M_D_CPU0_SA_DQ<12>")
	)
	(gr_poly
		(pts
			(xy 335.851246 -232.942384) (xy 335.851246 -232.894632) (xy 335.651094 -232.894632) (xy 335.651094 -232.942384)
			(xy 335.75117 -233.042206)
		)
		(stroke
			(width 0)
			(type solid)
		)
		(fill yes)
		(layer "In4.Cu")
		(net "M_D_CPU0_SA_DQS_DP<6>")
	)
	(gr_poly
		(pts
			(xy 335.851246 -231.725724) (xy 335.75117 -231.625902) (xy 335.651094 -231.725724) (xy 335.651094 -231.773476)
			(xy 335.851246 -231.773476)
		)
		(stroke
			(width 0)
			(type solid)
		)
		(fill yes)
		(layer "In4.Cu")
		(net "M_D_CPU0_SA_DQS_DP<1>")
	)
	(gr_poly
		(pts
			(xy 335.851246 -231.322372) (xy 335.851246 -231.277922) (xy 335.651094 -231.277922) (xy 335.651094 -231.322372)
			(xy 335.75117 -231.422448)
		)
		(stroke
			(width 0)
			(type solid)
		)
		(fill yes)
		(layer "In4.Cu")
		(net "M_D_CPU0_SA_DQ<11>")
	)
	(gr_poly
		(pts
			(xy 335.851246 -230.105966) (xy 335.75117 -230.006144) (xy 335.651094 -230.105966) (xy 335.651094 -230.150416)
			(xy 335.851246 -230.150416)
		)
		(stroke
			(width 0)
			(type solid)
		)
		(fill yes)
		(layer "In4.Cu")
		(net "M_D_CPU0_SA_DQ<8>")
	)
	(gr_poly
		(pts
			(xy 335.851246 -229.70236) (xy 335.851246 -229.65791) (xy 335.651094 -229.65791) (xy 335.651094 -229.70236)
			(xy 335.75117 -229.802436)
		)
		(stroke
			(width 0)
			(type solid)
		)
		(fill yes)
		(layer "In4.Cu")
		(net "M_D_CPU0_SA_DQ<7>")
	)
	(gr_poly
		(pts
			(xy 335.851246 -228.486208) (xy 335.75117 -228.386132) (xy 335.651094 -228.486208) (xy 335.651094 -228.530658)
			(xy 335.851246 -228.530658)
		)
		(stroke
			(width 0)
			(type solid)
		)
		(fill yes)
		(layer "In4.Cu")
		(net "M_D_CPU0_SA_DQ<4>")
	)
	(gr_poly
		(pts
			(xy 335.851246 -228.082602) (xy 335.851246 -228.03485) (xy 335.651094 -228.03485) (xy 335.651094 -228.082602)
			(xy 335.75117 -228.182424)
		)
		(stroke
			(width 0)
			(type solid)
		)
		(fill yes)
		(layer "In4.Cu")
		(net "M_D_CPU0_SA_DQS_DP<5>")
	)
	(gr_poly
		(pts
			(xy 335.851246 -226.865942) (xy 335.75117 -226.76612) (xy 335.651094 -226.865942) (xy 335.651094 -226.913694)
			(xy 335.851246 -226.913694)
		)
		(stroke
			(width 0)
			(type solid)
		)
		(fill yes)
		(layer "In4.Cu")
		(net "M_D_CPU0_SA_DQS_DP<0>")
	)
	(gr_poly
		(pts
			(xy 335.851246 -226.462336) (xy 335.851246 -226.417886) (xy 335.651094 -226.417886) (xy 335.651094 -226.462336)
			(xy 335.75117 -226.562412)
		)
		(stroke
			(width 0)
			(type solid)
		)
		(fill yes)
		(layer "In4.Cu")
		(net "M_D_CPU0_SA_DQ<3>")
	)
	(gr_poly
		(pts
			(xy 335.851246 -225.246184) (xy 335.75117 -225.146108) (xy 335.651094 -225.246184) (xy 335.651094 -225.290634)
			(xy 335.851246 -225.290634)
		)
		(stroke
			(width 0)
			(type solid)
		)
		(fill yes)
		(layer "In4.Cu")
		(net "M_D_CPU0_SA_DQ<0>")
	)
	(gr_poly
		(pts
			(xy 336.14487 -266.991592) (xy 336.044794 -266.891516) (xy 335.944972 -266.991592) (xy 335.944972 -267.036042)
			(xy 336.14487 -267.036042)
		)
		(stroke
			(width 0)
			(type solid)
		)
		(fill yes)
		(layer "In4.Cu")
		(net "M_D_CPU0_SA_RSP<0>")
	)
	(gr_poly
		(pts
			(xy 336.15122 -292.91788) (xy 336.051144 -292.817804) (xy 335.951068 -292.91788) (xy 335.951068 -292.96233)
			(xy 336.15122 -292.96233)
		)
		(stroke
			(width 0)
			(type solid)
		)
		(fill yes)
		(layer "In4.Cu")
		(net "M_D_CPU0_SB_DQ<29>")
	)
	(gr_poly
		(pts
			(xy 336.15122 -292.51402) (xy 336.15122 -292.46957) (xy 335.951068 -292.46957) (xy 335.951068 -292.51402)
			(xy 336.051144 -292.614096)
		)
		(stroke
			(width 0)
			(type solid)
		)
		(fill yes)
		(layer "In4.Cu")
		(net "M_D_CPU0_SB_DQ<30>")
	)
	(gr_poly
		(pts
			(xy 336.15122 -291.297614) (xy 336.051144 -291.197792) (xy 335.951068 -291.297614) (xy 335.951068 -291.345366)
			(xy 336.15122 -291.345366)
		)
		(stroke
			(width 0)
			(type solid)
		)
		(fill yes)
		(layer "In4.Cu")
		(net "M_D_CPU0_SB_DQS_DN<8>")
	)
	(gr_poly
		(pts
			(xy 336.15122 -290.894262) (xy 336.15122 -290.84651) (xy 335.951068 -290.84651) (xy 335.951068 -290.894262)
			(xy 336.051144 -290.994084)
		)
		(stroke
			(width 0)
			(type solid)
		)
		(fill yes)
		(layer "In4.Cu")
		(net "M_D_CPU0_SB_DQS_DN<3>")
	)
	(gr_poly
		(pts
			(xy 336.15122 -289.677856) (xy 336.051144 -289.57778) (xy 335.951068 -289.677856) (xy 335.951068 -289.722306)
			(xy 336.15122 -289.722306)
		)
		(stroke
			(width 0)
			(type solid)
		)
		(fill yes)
		(layer "In4.Cu")
		(net "M_D_CPU0_SB_DQ<25>")
	)
	(gr_poly
		(pts
			(xy 336.15122 -289.273996) (xy 336.15122 -289.229546) (xy 335.951068 -289.229546) (xy 335.951068 -289.273996)
			(xy 336.051144 -289.374072)
		)
		(stroke
			(width 0)
			(type solid)
		)
		(fill yes)
		(layer "In4.Cu")
		(net "M_D_CPU0_SB_DQ<26>")
	)
	(gr_poly
		(pts
			(xy 336.15122 -288.057844) (xy 336.051144 -287.957768) (xy 335.951068 -288.057844) (xy 335.951068 -288.102294)
			(xy 336.15122 -288.102294)
		)
		(stroke
			(width 0)
			(type solid)
		)
		(fill yes)
		(layer "In4.Cu")
		(net "M_D_CPU0_SB_DQ<21>")
	)
	(gr_poly
		(pts
			(xy 336.15122 -287.654238) (xy 336.15122 -287.609788) (xy 335.951068 -287.609788) (xy 335.951068 -287.654238)
			(xy 336.051144 -287.75406)
		)
		(stroke
			(width 0)
			(type solid)
		)
		(fill yes)
		(layer "In4.Cu")
		(net "M_D_CPU0_SB_DQ<22>")
	)
	(gr_poly
		(pts
			(xy 336.15122 -286.437832) (xy 336.051144 -286.337756) (xy 335.951068 -286.437832) (xy 335.951068 -286.485584)
			(xy 336.15122 -286.485584)
		)
		(stroke
			(width 0)
			(type solid)
		)
		(fill yes)
		(layer "In4.Cu")
		(net "M_D_CPU0_SB_DQS_DN<7>")
	)
	(gr_poly
		(pts
			(xy 336.15122 -286.03448) (xy 336.15122 -285.986728) (xy 335.951068 -285.986728) (xy 335.951068 -286.03448)
			(xy 336.051144 -286.134302)
		)
		(stroke
			(width 0)
			(type solid)
		)
		(fill yes)
		(layer "In4.Cu")
		(net "M_D_CPU0_SB_DQS_DN<2>")
	)
	(gr_poly
		(pts
			(xy 336.15122 -284.818074) (xy 336.051144 -284.717998) (xy 335.951068 -284.818074) (xy 335.951068 -284.862524)
			(xy 336.15122 -284.862524)
		)
		(stroke
			(width 0)
			(type solid)
		)
		(fill yes)
		(layer "In4.Cu")
		(net "M_D_CPU0_SB_DQ<17>")
	)
	(gr_poly
		(pts
			(xy 336.15122 -284.414214) (xy 336.15122 -284.369764) (xy 335.951068 -284.369764) (xy 335.951068 -284.414214)
			(xy 336.051144 -284.51429)
		)
		(stroke
			(width 0)
			(type solid)
		)
		(fill yes)
		(layer "In4.Cu")
		(net "M_D_CPU0_SB_DQ<18>")
	)
	(gr_poly
		(pts
			(xy 336.15122 -283.198062) (xy 336.051144 -283.097986) (xy 335.951068 -283.198062) (xy 335.951068 -283.242512)
			(xy 336.15122 -283.242512)
		)
		(stroke
			(width 0)
			(type solid)
		)
		(fill yes)
		(layer "In4.Cu")
		(net "M_D_CPU0_SB_DQ<13>")
	)
	(gr_poly
		(pts
			(xy 336.15122 -282.794202) (xy 336.15122 -282.749752) (xy 335.951068 -282.749752) (xy 335.951068 -282.794202)
			(xy 336.051144 -282.894278)
		)
		(stroke
			(width 0)
			(type solid)
		)
		(fill yes)
		(layer "In4.Cu")
		(net "M_D_CPU0_SB_DQ<14>")
	)
	(gr_poly
		(pts
			(xy 336.15122 -281.577796) (xy 336.051144 -281.477974) (xy 335.951068 -281.577796) (xy 335.951068 -281.625548)
			(xy 336.15122 -281.625548)
		)
		(stroke
			(width 0)
			(type solid)
		)
		(fill yes)
		(layer "In4.Cu")
		(net "M_D_CPU0_SB_DQS_DN<6>")
	)
	(gr_poly
		(pts
			(xy 336.15122 -281.174444) (xy 336.15122 -281.126692) (xy 335.951068 -281.126692) (xy 335.951068 -281.174444)
			(xy 336.051144 -281.274266)
		)
		(stroke
			(width 0)
			(type solid)
		)
		(fill yes)
		(layer "In4.Cu")
		(net "M_D_CPU0_SB_DQS_DN<1>")
	)
	(gr_poly
		(pts
			(xy 336.15122 -279.958038) (xy 336.051144 -279.857962) (xy 335.951068 -279.958038) (xy 335.951068 -280.002488)
			(xy 336.15122 -280.002488)
		)
		(stroke
			(width 0)
			(type solid)
		)
		(fill yes)
		(layer "In4.Cu")
		(net "M_D_CPU0_SB_DQ<9>")
	)
	(gr_poly
		(pts
			(xy 336.15122 -279.554178) (xy 336.15122 -279.509728) (xy 335.951068 -279.509728) (xy 335.951068 -279.554178)
			(xy 336.051144 -279.654254)
		)
		(stroke
			(width 0)
			(type solid)
		)
		(fill yes)
		(layer "In4.Cu")
		(net "M_D_CPU0_SB_DQ<10>")
	)
	(gr_poly
		(pts
			(xy 336.15122 -278.338026) (xy 336.051144 -278.23795) (xy 335.951068 -278.338026) (xy 335.951068 -278.382476)
			(xy 336.15122 -278.382476)
		)
		(stroke
			(width 0)
			(type solid)
		)
		(fill yes)
		(layer "In4.Cu")
		(net "M_D_CPU0_SB_DQ<5>")
	)
	(gr_poly
		(pts
			(xy 336.15122 -277.934166) (xy 336.15122 -277.889716) (xy 335.951068 -277.889716) (xy 335.951068 -277.934166)
			(xy 336.051144 -278.034242)
		)
		(stroke
			(width 0)
			(type solid)
		)
		(fill yes)
		(layer "In4.Cu")
		(net "M_D_CPU0_SB_DQ<6>")
	)
	(gr_poly
		(pts
			(xy 336.15122 -276.71776) (xy 336.051144 -276.617938) (xy 335.951068 -276.71776) (xy 335.951068 -276.765512)
			(xy 336.15122 -276.765512)
		)
		(stroke
			(width 0)
			(type solid)
		)
		(fill yes)
		(layer "In4.Cu")
		(net "M_D_CPU0_SB_DQS_DN<5>")
	)
	(gr_poly
		(pts
			(xy 336.15122 -276.314408) (xy 336.15122 -276.266656) (xy 335.951068 -276.266656) (xy 335.951068 -276.314408)
			(xy 336.051144 -276.41423)
		)
		(stroke
			(width 0)
			(type solid)
		)
		(fill yes)
		(layer "In4.Cu")
		(net "M_D_CPU0_SB_DQS_DN<0>")
	)
	(gr_poly
		(pts
			(xy 336.15122 -275.098002) (xy 336.051144 -274.997926) (xy 335.951068 -275.098002) (xy 335.951068 -275.142452)
			(xy 336.15122 -275.142452)
		)
		(stroke
			(width 0)
			(type solid)
		)
		(fill yes)
		(layer "In4.Cu")
		(net "M_D_CPU0_SB_DQ<1>")
	)
	(gr_poly
		(pts
			(xy 336.15122 -274.694142) (xy 336.15122 -274.649692) (xy 335.951068 -274.649692) (xy 335.951068 -274.694142)
			(xy 336.051144 -274.794218)
		)
		(stroke
			(width 0)
			(type solid)
		)
		(fill yes)
		(layer "In4.Cu")
		(net "M_D_CPU0_SB_DQ<2>")
	)
	(gr_poly
		(pts
			(xy 336.15122 -273.47799) (xy 336.051144 -273.377914) (xy 335.951068 -273.47799) (xy 335.951068 -273.52244)
			(xy 336.15122 -273.52244)
		)
		(stroke
			(width 0)
			(type solid)
		)
		(fill yes)
		(layer "In4.Cu")
		(net "M_D_CPU0_SB_CB<1>")
	)
	(gr_poly
		(pts
			(xy 336.15122 -273.07413) (xy 336.15122 -273.02968) (xy 335.951068 -273.02968) (xy 335.951068 -273.07413)
			(xy 336.051144 -273.174206)
		)
		(stroke
			(width 0)
			(type solid)
		)
		(fill yes)
		(layer "In4.Cu")
		(net "M_D_CPU0_SB_CB<2>")
	)
	(gr_poly
		(pts
			(xy 336.15122 -271.857724) (xy 336.051144 -271.757902) (xy 335.951068 -271.857724) (xy 335.951068 -271.905476)
			(xy 336.15122 -271.905476)
		)
		(stroke
			(width 0)
			(type solid)
		)
		(fill yes)
		(layer "In4.Cu")
		(net "M_D_CPU0_SB_DQS_DN<4>")
	)
	(gr_poly
		(pts
			(xy 336.15122 -271.454372) (xy 336.15122 -271.40662) (xy 335.951068 -271.40662) (xy 335.951068 -271.454372)
			(xy 336.051144 -271.554194)
		)
		(stroke
			(width 0)
			(type solid)
		)
		(fill yes)
		(layer "In4.Cu")
		(net "M_D_CPU0_SB_DQS_DN<9>")
	)
	(gr_poly
		(pts
			(xy 336.15122 -270.237966) (xy 336.051144 -270.13789) (xy 335.951068 -270.237966) (xy 335.951068 -270.282416)
			(xy 336.15122 -270.282416)
		)
		(stroke
			(width 0)
			(type solid)
		)
		(fill yes)
		(layer "In4.Cu")
		(net "M_D_CPU0_SB_CB<5>")
	)
	(gr_poly
		(pts
			(xy 336.15122 -269.834106) (xy 336.15122 -269.789656) (xy 335.951068 -269.789656) (xy 335.951068 -269.834106)
			(xy 336.051144 -269.934182)
		)
		(stroke
			(width 0)
			(type solid)
		)
		(fill yes)
		(layer "In4.Cu")
		(net "M_D_CPU0_SB_CB<6>")
	)
	(gr_poly
		(pts
			(xy 336.15122 -266.594082) (xy 336.15122 -266.549632) (xy 335.951068 -266.549632) (xy 335.951068 -266.594082)
			(xy 336.051144 -266.694158)
		)
		(stroke
			(width 0)
			(type solid)
		)
		(fill yes)
		(layer "In4.Cu")
		(net "M_D_CPU0_SB_CS_N<1>")
	)
	(gr_poly
		(pts
			(xy 336.15122 -264.97407) (xy 336.15122 -264.92962) (xy 335.951068 -264.92962) (xy 335.951068 -264.97407)
			(xy 336.051144 -265.074146)
		)
		(stroke
			(width 0)
			(type solid)
		)
		(fill yes)
		(layer "In4.Cu")
		(net "M_D_CPU0_SB_PAR")
	)
	(gr_poly
		(pts
			(xy 336.15122 -263.757918) (xy 336.051144 -263.657842) (xy 335.951068 -263.757918) (xy 335.951068 -263.802368)
			(xy 336.15122 -263.802368)
		)
		(stroke
			(width 0)
			(type solid)
		)
		(fill yes)
		(layer "In4.Cu")
		(net "M_D_CPU0_SB_CA<4>")
	)
	(gr_poly
		(pts
			(xy 336.15122 -263.354058) (xy 336.15122 -263.309608) (xy 335.951068 -263.309608) (xy 335.951068 -263.354058)
			(xy 336.051144 -263.454134)
		)
		(stroke
			(width 0)
			(type solid)
		)
		(fill yes)
		(layer "In4.Cu")
		(net "M_D_CPU0_SB_CA<3>")
	)
	(gr_poly
		(pts
			(xy 336.15122 -262.137906) (xy 336.051144 -262.03783) (xy 335.951068 -262.137906) (xy 335.951068 -262.182356)
			(xy 336.15122 -262.182356)
		)
		(stroke
			(width 0)
			(type solid)
		)
		(fill yes)
		(layer "In4.Cu")
		(net "M_D_CPU0_SB_CA<0>")
	)
	(gr_poly
		(pts
			(xy 336.321146 -256.432558) (xy 336.321146 -256.384806) (xy 336.120994 -256.384806) (xy 336.120994 -256.432558)
			(xy 336.22107 -256.53238)
		)
		(stroke
			(width 0)
			(type solid)
		)
		(fill yes)
		(layer "In4.Cu")
		(net "M_D_CPU0_CLK_DN<0>")
	)
	(gr_poly
		(pts
			(xy 336.321146 -255.216152) (xy 336.22107 -255.116076) (xy 336.120994 -255.216152) (xy 336.120994 -255.260602)
			(xy 336.321146 -255.260602)
		)
		(stroke
			(width 0)
			(type solid)
		)
		(fill yes)
		(layer "In4.Cu")
		(net "M_D_CPU0_SA_CA<6>")
	)
	(gr_poly
		(pts
			(xy 336.321146 -254.812292) (xy 336.321146 -254.767842) (xy 336.120994 -254.767842) (xy 336.120994 -254.812292)
			(xy 336.22107 -254.912368)
		)
		(stroke
			(width 0)
			(type solid)
		)
		(fill yes)
		(layer "In4.Cu")
		(net "M_D_CPU0_SA_CA<5>")
	)
	(gr_poly
		(pts
			(xy 336.321146 -253.59614) (xy 336.22107 -253.496064) (xy 336.120994 -253.59614) (xy 336.120994 -253.64059)
			(xy 336.321146 -253.64059)
		)
		(stroke
			(width 0)
			(type solid)
		)
		(fill yes)
		(layer "In4.Cu")
		(net "M_D_CPU0_SA_CA<2>")
	)
	(gr_poly
		(pts
			(xy 336.321146 -253.19228) (xy 336.321146 -253.14783) (xy 336.120994 -253.14783) (xy 336.120994 -253.19228)
			(xy 336.22107 -253.292356)
		)
		(stroke
			(width 0)
			(type solid)
		)
		(fill yes)
		(layer "In4.Cu")
		(net "M_D_CPU0_SA_CA<1>")
	)
	(gr_poly
		(pts
			(xy 336.321146 -251.572268) (xy 336.321146 -251.527818) (xy 336.120994 -251.527818) (xy 336.120994 -251.572268)
			(xy 336.22107 -251.672344)
		)
		(stroke
			(width 0)
			(type solid)
		)
		(fill yes)
		(layer "In4.Cu")
		(net "M_D_CPU0_SA_CS_N<0>")
	)
	(gr_poly
		(pts
			(xy 336.321146 -250.356116) (xy 336.22107 -250.25604) (xy 336.120994 -250.356116) (xy 336.120994 -250.400566)
			(xy 336.321146 -250.400566)
		)
		(stroke
			(width 0)
			(type solid)
		)
		(fill yes)
		(layer "In4.Cu")
		(net "M_D_CPU0_ALERT_R_N")
	)
	(gr_poly
		(pts
			(xy 336.321146 -248.736104) (xy 336.22107 -248.636028) (xy 336.120994 -248.736104) (xy 336.120994 -248.780554)
			(xy 336.321146 -248.780554)
		)
		(stroke
			(width 0)
			(type solid)
		)
		(fill yes)
		(layer "In4.Cu")
		(net "M_D_CPU0_SA_CB<5>")
	)
	(gr_poly
		(pts
			(xy 336.321146 -248.332244) (xy 336.321146 -248.287794) (xy 336.120994 -248.287794) (xy 336.120994 -248.332244)
			(xy 336.22107 -248.43232)
		)
		(stroke
			(width 0)
			(type solid)
		)
		(fill yes)
		(layer "In4.Cu")
		(net "M_D_CPU0_SA_CB<6>")
	)
	(gr_poly
		(pts
			(xy 336.321146 -247.115838) (xy 336.22107 -247.016016) (xy 336.120994 -247.115838) (xy 336.120994 -247.16359)
			(xy 336.321146 -247.16359)
		)
		(stroke
			(width 0)
			(type solid)
		)
		(fill yes)
		(layer "In4.Cu")
		(net "M_D_CPU0_SA_DQS_DN<9>")
	)
	(gr_poly
		(pts
			(xy 336.321146 -246.712486) (xy 336.321146 -246.664734) (xy 336.120994 -246.664734) (xy 336.120994 -246.712486)
			(xy 336.22107 -246.812308)
		)
		(stroke
			(width 0)
			(type solid)
		)
		(fill yes)
		(layer "In4.Cu")
		(net "M_D_CPU0_SA_DQS_DN<4>")
	)
	(gr_poly
		(pts
			(xy 336.321146 -245.49608) (xy 336.22107 -245.396004) (xy 336.120994 -245.49608) (xy 336.120994 -245.54053)
			(xy 336.321146 -245.54053)
		)
		(stroke
			(width 0)
			(type solid)
		)
		(fill yes)
		(layer "In4.Cu")
		(net "M_D_CPU0_SA_CB<1>")
	)
	(gr_poly
		(pts
			(xy 336.321146 -245.09222) (xy 336.321146 -245.04777) (xy 336.120994 -245.04777) (xy 336.120994 -245.09222)
			(xy 336.22107 -245.192296)
		)
		(stroke
			(width 0)
			(type solid)
		)
		(fill yes)
		(layer "In4.Cu")
		(net "M_D_CPU0_SA_CB<2>")
	)
	(gr_poly
		(pts
			(xy 336.321146 -243.876068) (xy 336.22107 -243.775992) (xy 336.120994 -243.876068) (xy 336.120994 -243.920518)
			(xy 336.321146 -243.920518)
		)
		(stroke
			(width 0)
			(type solid)
		)
		(fill yes)
		(layer "In4.Cu")
		(net "M_D_CPU0_SA_DQ<29>")
	)
	(gr_poly
		(pts
			(xy 336.321146 -243.472208) (xy 336.321146 -243.427758) (xy 336.120994 -243.427758) (xy 336.120994 -243.472208)
			(xy 336.22107 -243.572284)
		)
		(stroke
			(width 0)
			(type solid)
		)
		(fill yes)
		(layer "In4.Cu")
		(net "M_D_CPU0_SA_DQ<30>")
	)
	(gr_poly
		(pts
			(xy 336.321146 -242.255802) (xy 336.22107 -242.15598) (xy 336.120994 -242.255802) (xy 336.120994 -242.303554)
			(xy 336.321146 -242.303554)
		)
		(stroke
			(width 0)
			(type solid)
		)
		(fill yes)
		(layer "In4.Cu")
		(net "M_D_CPU0_SA_DQS_DN<8>")
	)
	(gr_poly
		(pts
			(xy 336.321146 -241.85245) (xy 336.321146 -241.804698) (xy 336.120994 -241.804698) (xy 336.120994 -241.85245)
			(xy 336.22107 -241.952272)
		)
		(stroke
			(width 0)
			(type solid)
		)
		(fill yes)
		(layer "In4.Cu")
		(net "M_D_CPU0_SA_DQS_DN<3>")
	)
	(gr_poly
		(pts
			(xy 336.321146 -240.636044) (xy 336.22107 -240.535968) (xy 336.120994 -240.636044) (xy 336.120994 -240.680494)
			(xy 336.321146 -240.680494)
		)
		(stroke
			(width 0)
			(type solid)
		)
		(fill yes)
		(layer "In4.Cu")
		(net "M_D_CPU0_SA_DQ<25>")
	)
	(gr_poly
		(pts
			(xy 336.321146 -240.232184) (xy 336.321146 -240.187734) (xy 336.120994 -240.187734) (xy 336.120994 -240.232184)
			(xy 336.22107 -240.33226)
		)
		(stroke
			(width 0)
			(type solid)
		)
		(fill yes)
		(layer "In4.Cu")
		(net "M_D_CPU0_SA_DQ<26>")
	)
	(gr_poly
		(pts
			(xy 336.321146 -239.016032) (xy 336.22107 -238.915956) (xy 336.120994 -239.016032) (xy 336.120994 -239.060482)
			(xy 336.321146 -239.060482)
		)
		(stroke
			(width 0)
			(type solid)
		)
		(fill yes)
		(layer "In4.Cu")
		(net "M_D_CPU0_SA_DQ<21>")
	)
	(gr_poly
		(pts
			(xy 336.321146 -238.612172) (xy 336.321146 -238.567722) (xy 336.120994 -238.567722) (xy 336.120994 -238.612172)
			(xy 336.22107 -238.712248)
		)
		(stroke
			(width 0)
			(type solid)
		)
		(fill yes)
		(layer "In4.Cu")
		(net "M_D_CPU0_SA_DQ<22>")
	)
	(gr_poly
		(pts
			(xy 336.321146 -237.395766) (xy 336.22107 -237.295944) (xy 336.120994 -237.395766) (xy 336.120994 -237.443518)
			(xy 336.321146 -237.443518)
		)
		(stroke
			(width 0)
			(type solid)
		)
		(fill yes)
		(layer "In4.Cu")
		(net "M_D_CPU0_SA_DQS_DN<7>")
	)
	(gr_poly
		(pts
			(xy 336.321146 -236.992414) (xy 336.321146 -236.944662) (xy 336.120994 -236.944662) (xy 336.120994 -236.992414)
			(xy 336.22107 -237.092236)
		)
		(stroke
			(width 0)
			(type solid)
		)
		(fill yes)
		(layer "In4.Cu")
		(net "M_D_CPU0_SA_DQS_DN<2>")
	)
	(gr_poly
		(pts
			(xy 336.321146 -235.776008) (xy 336.22107 -235.675932) (xy 336.120994 -235.776008) (xy 336.120994 -235.820458)
			(xy 336.321146 -235.820458)
		)
		(stroke
			(width 0)
			(type solid)
		)
		(fill yes)
		(layer "In4.Cu")
		(net "M_D_CPU0_SA_DQ<17>")
	)
	(gr_poly
		(pts
			(xy 336.321146 -235.372148) (xy 336.321146 -235.327698) (xy 336.120994 -235.327698) (xy 336.120994 -235.372148)
			(xy 336.22107 -235.472224)
		)
		(stroke
			(width 0)
			(type solid)
		)
		(fill yes)
		(layer "In4.Cu")
		(net "M_D_CPU0_SA_DQ<18>")
	)
	(gr_poly
		(pts
			(xy 336.321146 -234.155996) (xy 336.22107 -234.05592) (xy 336.120994 -234.155996) (xy 336.120994 -234.200446)
			(xy 336.321146 -234.200446)
		)
		(stroke
			(width 0)
			(type solid)
		)
		(fill yes)
		(layer "In4.Cu")
		(net "M_D_CPU0_SA_DQ<13>")
	)
	(gr_poly
		(pts
			(xy 336.321146 -233.752136) (xy 336.321146 -233.707686) (xy 336.120994 -233.707686) (xy 336.120994 -233.752136)
			(xy 336.22107 -233.852212)
		)
		(stroke
			(width 0)
			(type solid)
		)
		(fill yes)
		(layer "In4.Cu")
		(net "M_D_CPU0_SA_DQ<14>")
	)
	(gr_poly
		(pts
			(xy 336.321146 -232.53573) (xy 336.22107 -232.435908) (xy 336.120994 -232.53573) (xy 336.120994 -232.583482)
			(xy 336.321146 -232.583482)
		)
		(stroke
			(width 0)
			(type solid)
		)
		(fill yes)
		(layer "In4.Cu")
		(net "M_D_CPU0_SA_DQS_DN<6>")
	)
	(gr_poly
		(pts
			(xy 336.321146 -232.132378) (xy 336.321146 -232.084626) (xy 336.120994 -232.084626) (xy 336.120994 -232.132378)
			(xy 336.22107 -232.2322)
		)
		(stroke
			(width 0)
			(type solid)
		)
		(fill yes)
		(layer "In4.Cu")
		(net "M_D_CPU0_SA_DQS_DN<1>")
	)
	(gr_poly
		(pts
			(xy 336.321146 -230.915972) (xy 336.22107 -230.815896) (xy 336.120994 -230.915972) (xy 336.120994 -230.960422)
			(xy 336.321146 -230.960422)
		)
		(stroke
			(width 0)
			(type solid)
		)
		(fill yes)
		(layer "In4.Cu")
		(net "M_D_CPU0_SA_DQ<9>")
	)
	(gr_poly
		(pts
			(xy 336.321146 -230.512366) (xy 336.321146 -230.467916) (xy 336.120994 -230.467916) (xy 336.120994 -230.512366)
			(xy 336.22107 -230.612188)
		)
		(stroke
			(width 0)
			(type solid)
		)
		(fill yes)
		(layer "In4.Cu")
		(net "M_D_CPU0_SA_DQ<10>")
	)
	(gr_poly
		(pts
			(xy 336.321146 -229.29596) (xy 336.22107 -229.195884) (xy 336.120994 -229.29596) (xy 336.120994 -229.34041)
			(xy 336.321146 -229.34041)
		)
		(stroke
			(width 0)
			(type solid)
		)
		(fill yes)
		(layer "In4.Cu")
		(net "M_D_CPU0_SA_DQ<5>")
	)
	(gr_poly
		(pts
			(xy 336.321146 -228.892354) (xy 336.321146 -228.847904) (xy 336.120994 -228.847904) (xy 336.120994 -228.892354)
			(xy 336.22107 -228.99243)
		)
		(stroke
			(width 0)
			(type solid)
		)
		(fill yes)
		(layer "In4.Cu")
		(net "M_D_CPU0_SA_DQ<6>")
	)
	(gr_poly
		(pts
			(xy 336.321146 -227.272596) (xy 336.321146 -227.224844) (xy 336.120994 -227.224844) (xy 336.120994 -227.272596)
			(xy 336.22107 -227.372418)
		)
		(stroke
			(width 0)
			(type solid)
		)
		(fill yes)
		(layer "In4.Cu")
		(net "M_D_CPU0_SA_DQS_DN<0>")
	)
	(gr_poly
		(pts
			(xy 336.321146 -226.05619) (xy 336.22107 -225.956114) (xy 336.120994 -226.05619) (xy 336.120994 -226.10064)
			(xy 336.321146 -226.10064)
		)
		(stroke
			(width 0)
			(type solid)
		)
		(fill yes)
		(layer "In4.Cu")
		(net "M_D_CPU0_SA_DQ<1>")
	)
	(gr_poly
		(pts
			(xy 336.321146 -225.65233) (xy 336.321146 -225.60788) (xy 336.120994 -225.60788) (xy 336.120994 -225.65233)
			(xy 336.22107 -225.752406)
		)
		(stroke
			(width 0)
			(type solid)
		)
		(fill yes)
		(layer "In4.Cu")
		(net "M_D_CPU0_SA_DQ<2>")
	)
	(gr_poly
		(pts
			(xy 336.327242 -227.676456) (xy 336.227166 -227.57638) (xy 336.12709 -227.676456) (xy 336.12709 -227.723954)
			(xy 336.327242 -227.723954)
		)
		(stroke
			(width 0)
			(type solid)
		)
		(fill yes)
		(layer "In4.Cu")
		(net "M_D_CPU0_SA_DQS_DN<5>")
	)
	(gr_poly
		(pts
			(xy 336.62112 -293.324026) (xy 336.62112 -293.279576) (xy 336.420968 -293.279576) (xy 336.420968 -293.324026)
			(xy 336.521044 -293.424102)
		)
		(stroke
			(width 0)
			(type solid)
		)
		(fill yes)
		(layer "In4.Cu")
		(net "M_D_CPU0_SB_DQ<31>")
	)
	(gr_poly
		(pts
			(xy 336.62112 -292.107874) (xy 336.521044 -292.007798) (xy 336.420968 -292.107874) (xy 336.420968 -292.152324)
			(xy 336.62112 -292.152324)
		)
		(stroke
			(width 0)
			(type solid)
		)
		(fill yes)
		(layer "In4.Cu")
		(net "M_D_CPU0_SB_DQ<28>")
	)
	(gr_poly
		(pts
			(xy 336.62112 -291.704268) (xy 336.62112 -291.656516) (xy 336.420968 -291.656516) (xy 336.420968 -291.704268)
			(xy 336.521044 -291.80409)
		)
		(stroke
			(width 0)
			(type solid)
		)
		(fill yes)
		(layer "In4.Cu")
		(net "M_D_CPU0_SB_DQS_DP<8>")
	)
	(gr_poly
		(pts
			(xy 336.62112 -290.487608) (xy 336.521044 -290.387786) (xy 336.420968 -290.487608) (xy 336.420968 -290.53536)
			(xy 336.62112 -290.53536)
		)
		(stroke
			(width 0)
			(type solid)
		)
		(fill yes)
		(layer "In4.Cu")
		(net "M_D_CPU0_SB_DQS_DP<3>")
	)
	(gr_poly
		(pts
			(xy 336.62112 -290.084002) (xy 336.62112 -290.039552) (xy 336.420968 -290.039552) (xy 336.420968 -290.084002)
			(xy 336.521044 -290.184078)
		)
		(stroke
			(width 0)
			(type solid)
		)
		(fill yes)
		(layer "In4.Cu")
		(net "M_D_CPU0_SB_DQ<27>")
	)
	(gr_poly
		(pts
			(xy 336.62112 -288.86785) (xy 336.521044 -288.767774) (xy 336.420968 -288.86785) (xy 336.420968 -288.9123)
			(xy 336.62112 -288.9123)
		)
		(stroke
			(width 0)
			(type solid)
		)
		(fill yes)
		(layer "In4.Cu")
		(net "M_D_CPU0_SB_DQ<24>")
	)
	(gr_poly
		(pts
			(xy 336.62112 -288.464244) (xy 336.62112 -288.419794) (xy 336.420968 -288.419794) (xy 336.420968 -288.464244)
			(xy 336.521044 -288.56432)
		)
		(stroke
			(width 0)
			(type solid)
		)
		(fill yes)
		(layer "In4.Cu")
		(net "M_D_CPU0_SB_DQ<23>")
	)
	(gr_poly
		(pts
			(xy 336.62112 -287.247838) (xy 336.521044 -287.148016) (xy 336.420968 -287.247838) (xy 336.420968 -287.292288)
			(xy 336.62112 -287.292288)
		)
		(stroke
			(width 0)
			(type solid)
		)
		(fill yes)
		(layer "In4.Cu")
		(net "M_D_CPU0_SB_DQ<20>")
	)
	(gr_poly
		(pts
			(xy 336.62112 -286.844232) (xy 336.62112 -286.79648) (xy 336.420968 -286.79648) (xy 336.420968 -286.844232)
			(xy 336.521044 -286.944308)
		)
		(stroke
			(width 0)
			(type solid)
		)
		(fill yes)
		(layer "In4.Cu")
		(net "M_D_CPU0_SB_DQS_DP<7>")
	)
	(gr_poly
		(pts
			(xy 336.62112 -285.627826) (xy 336.521044 -285.528004) (xy 336.420968 -285.627826) (xy 336.420968 -285.675578)
			(xy 336.62112 -285.675578)
		)
		(stroke
			(width 0)
			(type solid)
		)
		(fill yes)
		(layer "In4.Cu")
		(net "M_D_CPU0_SB_DQS_DP<2>")
	)
	(gr_poly
		(pts
			(xy 336.62112 -285.22422) (xy 336.62112 -285.17977) (xy 336.420968 -285.17977) (xy 336.420968 -285.22422)
			(xy 336.521044 -285.324296)
		)
		(stroke
			(width 0)
			(type solid)
		)
		(fill yes)
		(layer "In4.Cu")
		(net "M_D_CPU0_SB_DQ<19>")
	)
	(gr_poly
		(pts
			(xy 336.62112 -284.008068) (xy 336.521044 -283.907992) (xy 336.420968 -284.008068) (xy 336.420968 -284.052518)
			(xy 336.62112 -284.052518)
		)
		(stroke
			(width 0)
			(type solid)
		)
		(fill yes)
		(layer "In4.Cu")
		(net "M_D_CPU0_SB_DQ<16>")
	)
	(gr_poly
		(pts
			(xy 336.62112 -283.604208) (xy 336.62112 -283.559758) (xy 336.420968 -283.559758) (xy 336.420968 -283.604208)
			(xy 336.521044 -283.704284)
		)
		(stroke
			(width 0)
			(type solid)
		)
		(fill yes)
		(layer "In4.Cu")
		(net "M_D_CPU0_SB_DQ<15>")
	)
	(gr_poly
		(pts
			(xy 336.62112 -282.388056) (xy 336.521044 -282.28798) (xy 336.420968 -282.388056) (xy 336.420968 -282.432506)
			(xy 336.62112 -282.432506)
		)
		(stroke
			(width 0)
			(type solid)
		)
		(fill yes)
		(layer "In4.Cu")
		(net "M_D_CPU0_SB_DQ<12>")
	)
	(gr_poly
		(pts
			(xy 336.62112 -281.98445) (xy 336.62112 -281.936698) (xy 336.420968 -281.936698) (xy 336.420968 -281.98445)
			(xy 336.521044 -282.084272)
		)
		(stroke
			(width 0)
			(type solid)
		)
		(fill yes)
		(layer "In4.Cu")
		(net "M_D_CPU0_SB_DQS_DP<6>")
	)
	(gr_poly
		(pts
			(xy 336.62112 -280.76779) (xy 336.521044 -280.667968) (xy 336.420968 -280.76779) (xy 336.420968 -280.815542)
			(xy 336.62112 -280.815542)
		)
		(stroke
			(width 0)
			(type solid)
		)
		(fill yes)
		(layer "In4.Cu")
		(net "M_D_CPU0_SB_DQS_DP<1>")
	)
	(gr_poly
		(pts
			(xy 336.62112 -280.364184) (xy 336.62112 -280.319734) (xy 336.420968 -280.319734) (xy 336.420968 -280.364184)
			(xy 336.521044 -280.46426)
		)
		(stroke
			(width 0)
			(type solid)
		)
		(fill yes)
		(layer "In4.Cu")
		(net "M_D_CPU0_SB_DQ<11>")
	)
	(gr_poly
		(pts
			(xy 336.62112 -279.148032) (xy 336.521044 -279.047956) (xy 336.420968 -279.148032) (xy 336.420968 -279.192482)
			(xy 336.62112 -279.192482)
		)
		(stroke
			(width 0)
			(type solid)
		)
		(fill yes)
		(layer "In4.Cu")
		(net "M_D_CPU0_SB_DQ<8>")
	)
	(gr_poly
		(pts
			(xy 336.62112 -278.744172) (xy 336.62112 -278.699722) (xy 336.420968 -278.699722) (xy 336.420968 -278.744172)
			(xy 336.521044 -278.844248)
		)
		(stroke
			(width 0)
			(type solid)
		)
		(fill yes)
		(layer "In4.Cu")
		(net "M_D_CPU0_SB_DQ<7>")
	)
	(gr_poly
		(pts
			(xy 336.62112 -277.52802) (xy 336.521044 -277.427944) (xy 336.420968 -277.52802) (xy 336.420968 -277.57247)
			(xy 336.62112 -277.57247)
		)
		(stroke
			(width 0)
			(type solid)
		)
		(fill yes)
		(layer "In4.Cu")
		(net "M_D_CPU0_SB_DQ<4>")
	)
	(gr_poly
		(pts
			(xy 336.62112 -275.504148) (xy 336.62112 -275.459698) (xy 336.420968 -275.459698) (xy 336.420968 -275.504148)
			(xy 336.521044 -275.604224)
		)
		(stroke
			(width 0)
			(type solid)
		)
		(fill yes)
		(layer "In4.Cu")
		(net "M_D_CPU0_SB_DQ<3>")
	)
	(gr_poly
		(pts
			(xy 336.62112 -274.287996) (xy 336.521044 -274.18792) (xy 336.420968 -274.287996) (xy 336.420968 -274.332446)
			(xy 336.62112 -274.332446)
		)
		(stroke
			(width 0)
			(type solid)
		)
		(fill yes)
		(layer "In4.Cu")
		(net "M_D_CPU0_SB_DQ<0>")
	)
	(gr_poly
		(pts
			(xy 336.62112 -273.884136) (xy 336.62112 -273.839686) (xy 336.420968 -273.839686) (xy 336.420968 -273.884136)
			(xy 336.521044 -273.984212)
		)
		(stroke
			(width 0)
			(type solid)
		)
		(fill yes)
		(layer "In4.Cu")
		(net "M_D_CPU0_SB_CB<3>")
	)
	(gr_poly
		(pts
			(xy 336.62112 -272.667984) (xy 336.521044 -272.567908) (xy 336.420968 -272.667984) (xy 336.420968 -272.712434)
			(xy 336.62112 -272.712434)
		)
		(stroke
			(width 0)
			(type solid)
		)
		(fill yes)
		(layer "In4.Cu")
		(net "M_D_CPU0_SB_CB<0>")
	)
	(gr_poly
		(pts
			(xy 336.62112 -272.264378) (xy 336.62112 -272.216626) (xy 336.420968 -272.216626) (xy 336.420968 -272.264378)
			(xy 336.521044 -272.3642)
		)
		(stroke
			(width 0)
			(type solid)
		)
		(fill yes)
		(layer "In4.Cu")
		(net "M_D_CPU0_SB_DQS_DP<4>")
	)
	(gr_poly
		(pts
			(xy 336.62112 -271.047718) (xy 336.521044 -270.947896) (xy 336.420968 -271.047718) (xy 336.420968 -271.09547)
			(xy 336.62112 -271.09547)
		)
		(stroke
			(width 0)
			(type solid)
		)
		(fill yes)
		(layer "In4.Cu")
		(net "M_D_CPU0_SB_DQS_DP<9>")
	)
	(gr_poly
		(pts
			(xy 336.62112 -270.644112) (xy 336.62112 -270.599662) (xy 336.420968 -270.599662) (xy 336.420968 -270.644112)
			(xy 336.521044 -270.744188)
		)
		(stroke
			(width 0)
			(type solid)
		)
		(fill yes)
		(layer "In4.Cu")
		(net "M_D_CPU0_SB_CB<7>")
	)
	(gr_poly
		(pts
			(xy 336.62112 -269.42796) (xy 336.521044 -269.327884) (xy 336.420968 -269.42796) (xy 336.420968 -269.47241)
			(xy 336.62112 -269.47241)
		)
		(stroke
			(width 0)
			(type solid)
		)
		(fill yes)
		(layer "In4.Cu")
		(net "M_D_CPU0_SB_CB<4>")
	)
	(gr_poly
		(pts
			(xy 336.62112 -265.784076) (xy 336.62112 -265.739626) (xy 336.420968 -265.739626) (xy 336.420968 -265.784076)
			(xy 336.521044 -265.884152)
		)
		(stroke
			(width 0)
			(type solid)
		)
		(fill yes)
		(layer "In4.Cu")
		(net "M_D_CPU0_SB_CS_N<0>")
	)
	(gr_poly
		(pts
			(xy 336.62112 -264.567924) (xy 336.521044 -264.467848) (xy 336.420968 -264.567924) (xy 336.420968 -264.612374)
			(xy 336.62112 -264.612374)
		)
		(stroke
			(width 0)
			(type solid)
		)
		(fill yes)
		(layer "In4.Cu")
		(net "M_D_CPU0_SB_CA<6>")
	)
	(gr_poly
		(pts
			(xy 336.62112 -264.164064) (xy 336.62112 -264.119614) (xy 336.420968 -264.119614) (xy 336.420968 -264.164064)
			(xy 336.521044 -264.26414)
		)
		(stroke
			(width 0)
			(type solid)
		)
		(fill yes)
		(layer "In4.Cu")
		(net "M_D_CPU0_SB_CA<5>")
	)
	(gr_poly
		(pts
			(xy 336.62112 -262.947912) (xy 336.521044 -262.847836) (xy 336.420968 -262.947912) (xy 336.420968 -262.992362)
			(xy 336.62112 -262.992362)
		)
		(stroke
			(width 0)
			(type solid)
		)
		(fill yes)
		(layer "In4.Cu")
		(net "M_D_CPU0_SB_CA<2>")
	)
	(gr_poly
		(pts
			(xy 336.62112 -262.544052) (xy 336.62112 -262.499602) (xy 336.420968 -262.499602) (xy 336.420968 -262.544052)
			(xy 336.521044 -262.644128)
		)
		(stroke
			(width 0)
			(type solid)
		)
		(fill yes)
		(layer "In4.Cu")
		(net "M_D_CPU0_SB_CA<1>")
	)
	(gr_poly
		(pts
			(xy 336.627216 -267.801598) (xy 336.527394 -267.701522) (xy 336.427318 -267.801598) (xy 336.427318 -267.846048)
			(xy 336.627216 -267.846048)
		)
		(stroke
			(width 0)
			(type solid)
		)
		(fill yes)
		(layer "In4.Cu")
		(net "M_D_CPU0_SB_RSP<0>")
	)
	(gr_poly
		(pts
			(xy 336.628486 -277.12416) (xy 336.628486 -277.076662) (xy 336.428334 -277.076662) (xy 336.428334 -277.12416)
			(xy 336.52841 -277.224236)
		)
		(stroke
			(width 0)
			(type solid)
		)
		(fill yes)
		(layer "In4.Cu")
		(net "M_D_CPU0_SB_DQS_DP<5>")
	)
	(gr_poly
		(pts
			(xy 336.628486 -275.908008) (xy 336.52841 -275.807932) (xy 336.428334 -275.908008) (xy 336.428334 -275.955506)
			(xy 336.628486 -275.955506)
		)
		(stroke
			(width 0)
			(type solid)
		)
		(fill yes)
		(layer "In4.Cu")
		(net "M_D_CPU0_SB_DQS_DP<0>")
	)
	(gr_poly
		(pts
			(xy 336.7913 -256.025904) (xy 336.691224 -255.926082) (xy 336.591148 -256.025904) (xy 336.591148 -256.073656)
			(xy 336.7913 -256.073656)
		)
		(stroke
			(width 0)
			(type solid)
		)
		(fill yes)
		(layer "In4.Cu")
		(net "M_D_CPU0_CLK_DP<0>")
	)
	(gr_poly
		(pts
			(xy 336.7913 -255.622298) (xy 336.7913 -255.577848) (xy 336.591148 -255.577848) (xy 336.591148 -255.622298)
			(xy 336.691224 -255.722374)
		)
		(stroke
			(width 0)
			(type solid)
		)
		(fill yes)
		(layer "In4.Cu")
		(net "M_D_CPU0_SA_PAR")
	)
	(gr_poly
		(pts
			(xy 336.7913 -254.406146) (xy 336.691224 -254.30607) (xy 336.591148 -254.406146) (xy 336.591148 -254.450596)
			(xy 336.7913 -254.450596)
		)
		(stroke
			(width 0)
			(type solid)
		)
		(fill yes)
		(layer "In4.Cu")
		(net "M_D_CPU0_SA_CA<4>")
	)
	(gr_poly
		(pts
			(xy 336.7913 -254.002286) (xy 336.7913 -253.957836) (xy 336.591148 -253.957836) (xy 336.591148 -254.002286)
			(xy 336.691224 -254.102362)
		)
		(stroke
			(width 0)
			(type solid)
		)
		(fill yes)
		(layer "In4.Cu")
		(net "M_D_CPU0_SA_CA<3>")
	)
	(gr_poly
		(pts
			(xy 336.7913 -252.786134) (xy 336.691224 -252.686058) (xy 336.591148 -252.786134) (xy 336.591148 -252.830584)
			(xy 336.7913 -252.830584)
		)
		(stroke
			(width 0)
			(type solid)
		)
		(fill yes)
		(layer "In4.Cu")
		(net "M_D_CPU0_SA_CA<0>")
	)
	(gr_poly
		(pts
			(xy 336.7913 -252.382274) (xy 336.7913 -252.337824) (xy 336.591148 -252.337824) (xy 336.591148 -252.382274)
			(xy 336.691224 -252.48235)
		)
		(stroke
			(width 0)
			(type solid)
		)
		(fill yes)
		(layer "In4.Cu")
		(net "M_D_CPU0_SA_CS_N<1>")
	)
	(gr_poly
		(pts
			(xy 336.7913 -250.762262) (xy 336.7913 -250.717812) (xy 336.591148 -250.717812) (xy 336.591148 -250.762262)
			(xy 336.691224 -250.862338)
		)
		(stroke
			(width 0)
			(type solid)
		)
		(fill yes)
		(layer "In4.Cu")
		(net "M_D_CPU0_RESET_N")
	)
	(gr_poly
		(pts
			(xy 336.7913 -249.14225) (xy 336.7913 -249.0978) (xy 336.591148 -249.0978) (xy 336.591148 -249.14225)
			(xy 336.691224 -249.242326)
		)
		(stroke
			(width 0)
			(type solid)
		)
		(fill yes)
		(layer "In4.Cu")
		(net "M_D_CPU0_SA_CB<7>")
	)
	(gr_poly
		(pts
			(xy 336.7913 -247.926098) (xy 336.691224 -247.826022) (xy 336.591148 -247.926098) (xy 336.591148 -247.970548)
			(xy 336.7913 -247.970548)
		)
		(stroke
			(width 0)
			(type solid)
		)
		(fill yes)
		(layer "In4.Cu")
		(net "M_D_CPU0_SA_CB<4>")
	)
	(gr_poly
		(pts
			(xy 336.7913 -247.522492) (xy 336.7913 -247.47474) (xy 336.591148 -247.47474) (xy 336.591148 -247.522492)
			(xy 336.691224 -247.622314)
		)
		(stroke
			(width 0)
			(type solid)
		)
		(fill yes)
		(layer "In4.Cu")
		(net "M_D_CPU0_SA_DQS_DP<9>")
	)
	(gr_poly
		(pts
			(xy 336.7913 -246.305832) (xy 336.691224 -246.20601) (xy 336.591148 -246.305832) (xy 336.591148 -246.353584)
			(xy 336.7913 -246.353584)
		)
		(stroke
			(width 0)
			(type solid)
		)
		(fill yes)
		(layer "In4.Cu")
		(net "M_D_CPU0_SA_DQS_DP<4>")
	)
	(gr_poly
		(pts
			(xy 336.7913 -245.902226) (xy 336.7913 -245.857776) (xy 336.591148 -245.857776) (xy 336.591148 -245.902226)
			(xy 336.691224 -246.002302)
		)
		(stroke
			(width 0)
			(type solid)
		)
		(fill yes)
		(layer "In4.Cu")
		(net "M_D_CPU0_SA_CB<3>")
	)
	(gr_poly
		(pts
			(xy 336.7913 -244.686074) (xy 336.691224 -244.585998) (xy 336.591148 -244.686074) (xy 336.591148 -244.730524)
			(xy 336.7913 -244.730524)
		)
		(stroke
			(width 0)
			(type solid)
		)
		(fill yes)
		(layer "In4.Cu")
		(net "M_D_CPU0_SA_CB<0>")
	)
	(gr_poly
		(pts
			(xy 336.7913 -244.282214) (xy 336.7913 -244.237764) (xy 336.591148 -244.237764) (xy 336.591148 -244.282214)
			(xy 336.691224 -244.38229)
		)
		(stroke
			(width 0)
			(type solid)
		)
		(fill yes)
		(layer "In4.Cu")
		(net "M_D_CPU0_SA_DQ<31>")
	)
	(gr_poly
		(pts
			(xy 336.7913 -243.066062) (xy 336.691224 -242.965986) (xy 336.591148 -243.066062) (xy 336.591148 -243.110512)
			(xy 336.7913 -243.110512)
		)
		(stroke
			(width 0)
			(type solid)
		)
		(fill yes)
		(layer "In4.Cu")
		(net "M_D_CPU0_SA_DQ<28>")
	)
	(gr_poly
		(pts
			(xy 336.7913 -242.662456) (xy 336.7913 -242.614704) (xy 336.591148 -242.614704) (xy 336.591148 -242.662456)
			(xy 336.691224 -242.762278)
		)
		(stroke
			(width 0)
			(type solid)
		)
		(fill yes)
		(layer "In4.Cu")
		(net "M_D_CPU0_SA_DQS_DP<8>")
	)
	(gr_poly
		(pts
			(xy 336.7913 -241.445796) (xy 336.691224 -241.345974) (xy 336.591148 -241.445796) (xy 336.591148 -241.493548)
			(xy 336.7913 -241.493548)
		)
		(stroke
			(width 0)
			(type solid)
		)
		(fill yes)
		(layer "In4.Cu")
		(net "M_D_CPU0_SA_DQS_DP<3>")
	)
	(gr_poly
		(pts
			(xy 336.7913 -241.04219) (xy 336.7913 -240.99774) (xy 336.591148 -240.99774) (xy 336.591148 -241.04219)
			(xy 336.691224 -241.142266)
		)
		(stroke
			(width 0)
			(type solid)
		)
		(fill yes)
		(layer "In4.Cu")
		(net "M_D_CPU0_SA_DQ<27>")
	)
	(gr_poly
		(pts
			(xy 336.7913 -239.826038) (xy 336.691224 -239.725962) (xy 336.591148 -239.826038) (xy 336.591148 -239.870488)
			(xy 336.7913 -239.870488)
		)
		(stroke
			(width 0)
			(type solid)
		)
		(fill yes)
		(layer "In4.Cu")
		(net "M_D_CPU0_SA_DQ<24>")
	)
	(gr_poly
		(pts
			(xy 336.7913 -239.422178) (xy 336.7913 -239.377728) (xy 336.591148 -239.377728) (xy 336.591148 -239.422178)
			(xy 336.691224 -239.522254)
		)
		(stroke
			(width 0)
			(type solid)
		)
		(fill yes)
		(layer "In4.Cu")
		(net "M_D_CPU0_SA_DQ<23>")
	)
	(gr_poly
		(pts
			(xy 336.7913 -238.206026) (xy 336.691224 -238.10595) (xy 336.591148 -238.206026) (xy 336.591148 -238.250476)
			(xy 336.7913 -238.250476)
		)
		(stroke
			(width 0)
			(type solid)
		)
		(fill yes)
		(layer "In4.Cu")
		(net "M_D_CPU0_SA_DQ<20>")
	)
	(gr_poly
		(pts
			(xy 336.7913 -237.80242) (xy 336.7913 -237.754668) (xy 336.591148 -237.754668) (xy 336.591148 -237.80242)
			(xy 336.691224 -237.902242)
		)
		(stroke
			(width 0)
			(type solid)
		)
		(fill yes)
		(layer "In4.Cu")
		(net "M_D_CPU0_SA_DQS_DP<7>")
	)
	(gr_poly
		(pts
			(xy 336.7913 -236.58576) (xy 336.691224 -236.485938) (xy 336.591148 -236.58576) (xy 336.591148 -236.633512)
			(xy 336.7913 -236.633512)
		)
		(stroke
			(width 0)
			(type solid)
		)
		(fill yes)
		(layer "In4.Cu")
		(net "M_D_CPU0_SA_DQS_DP<2>")
	)
	(gr_poly
		(pts
			(xy 336.7913 -236.182154) (xy 336.7913 -236.137704) (xy 336.591148 -236.137704) (xy 336.591148 -236.182154)
			(xy 336.691224 -236.28223)
		)
		(stroke
			(width 0)
			(type solid)
		)
		(fill yes)
		(layer "In4.Cu")
		(net "M_D_CPU0_SA_DQ<19>")
	)
	(gr_poly
		(pts
			(xy 336.7913 -234.966002) (xy 336.691224 -234.865926) (xy 336.591148 -234.966002) (xy 336.591148 -235.010452)
			(xy 336.7913 -235.010452)
		)
		(stroke
			(width 0)
			(type solid)
		)
		(fill yes)
		(layer "In4.Cu")
		(net "M_D_CPU0_SA_DQ<16>")
	)
	(gr_poly
		(pts
			(xy 336.7913 -234.562142) (xy 336.7913 -234.517692) (xy 336.591148 -234.517692) (xy 336.591148 -234.562142)
			(xy 336.691224 -234.662218)
		)
		(stroke
			(width 0)
			(type solid)
		)
		(fill yes)
		(layer "In4.Cu")
		(net "M_D_CPU0_SA_DQ<15>")
	)
	(gr_poly
		(pts
			(xy 336.7913 -233.34599) (xy 336.691224 -233.245914) (xy 336.591148 -233.34599) (xy 336.591148 -233.39044)
			(xy 336.7913 -233.39044)
		)
		(stroke
			(width 0)
			(type solid)
		)
		(fill yes)
		(layer "In4.Cu")
		(net "M_D_CPU0_SA_DQ<12>")
	)
	(gr_poly
		(pts
			(xy 336.7913 -232.942384) (xy 336.7913 -232.894632) (xy 336.591148 -232.894632) (xy 336.591148 -232.942384)
			(xy 336.691224 -233.042206)
		)
		(stroke
			(width 0)
			(type solid)
		)
		(fill yes)
		(layer "In4.Cu")
		(net "M_D_CPU0_SA_DQS_DP<6>")
	)
	(gr_poly
		(pts
			(xy 336.7913 -231.725724) (xy 336.691224 -231.625902) (xy 336.591148 -231.725724) (xy 336.591148 -231.773476)
			(xy 336.7913 -231.773476)
		)
		(stroke
			(width 0)
			(type solid)
		)
		(fill yes)
		(layer "In4.Cu")
		(net "M_D_CPU0_SA_DQS_DP<1>")
	)
	(gr_poly
		(pts
			(xy 336.7913 -231.322372) (xy 336.7913 -231.277922) (xy 336.591148 -231.277922) (xy 336.591148 -231.322372)
			(xy 336.691224 -231.422448)
		)
		(stroke
			(width 0)
			(type solid)
		)
		(fill yes)
		(layer "In4.Cu")
		(net "M_D_CPU0_SA_DQ<11>")
	)
	(gr_poly
		(pts
			(xy 336.7913 -230.105966) (xy 336.691224 -230.006144) (xy 336.591148 -230.105966) (xy 336.591148 -230.150416)
			(xy 336.7913 -230.150416)
		)
		(stroke
			(width 0)
			(type solid)
		)
		(fill yes)
		(layer "In4.Cu")
		(net "M_D_CPU0_SA_DQ<8>")
	)
	(gr_poly
		(pts
			(xy 336.7913 -229.70236) (xy 336.7913 -229.65791) (xy 336.591148 -229.65791) (xy 336.591148 -229.70236)
			(xy 336.691224 -229.802436)
		)
		(stroke
			(width 0)
			(type solid)
		)
		(fill yes)
		(layer "In4.Cu")
		(net "M_D_CPU0_SA_DQ<7>")
	)
	(gr_poly
		(pts
			(xy 336.7913 -228.486208) (xy 336.691224 -228.386132) (xy 336.591148 -228.486208) (xy 336.591148 -228.530658)
			(xy 336.7913 -228.530658)
		)
		(stroke
			(width 0)
			(type solid)
		)
		(fill yes)
		(layer "In4.Cu")
		(net "M_D_CPU0_SA_DQ<4>")
	)
	(gr_poly
		(pts
			(xy 336.7913 -228.082602) (xy 336.7913 -228.03485) (xy 336.591148 -228.03485) (xy 336.591148 -228.082602)
			(xy 336.691224 -228.182424)
		)
		(stroke
			(width 0)
			(type solid)
		)
		(fill yes)
		(layer "In4.Cu")
		(net "M_D_CPU0_SA_DQS_DP<5>")
	)
	(gr_poly
		(pts
			(xy 336.7913 -226.865942) (xy 336.691224 -226.76612) (xy 336.591148 -226.865942) (xy 336.591148 -226.913694)
			(xy 336.7913 -226.913694)
		)
		(stroke
			(width 0)
			(type solid)
		)
		(fill yes)
		(layer "In4.Cu")
		(net "M_D_CPU0_SA_DQS_DP<0>")
	)
	(gr_poly
		(pts
			(xy 336.7913 -226.462336) (xy 336.7913 -226.417886) (xy 336.591148 -226.417886) (xy 336.591148 -226.462336)
			(xy 336.691224 -226.562412)
		)
		(stroke
			(width 0)
			(type solid)
		)
		(fill yes)
		(layer "In4.Cu")
		(net "M_D_CPU0_SA_DQ<3>")
	)
	(gr_poly
		(pts
			(xy 336.7913 -225.246184) (xy 336.691224 -225.146108) (xy 336.591148 -225.246184) (xy 336.591148 -225.290634)
			(xy 336.7913 -225.290634)
		)
		(stroke
			(width 0)
			(type solid)
		)
		(fill yes)
		(layer "In4.Cu")
		(net "M_D_CPU0_SA_DQ<0>")
	)
	(gr_poly
		(pts
			(xy 337.084924 -266.991592) (xy 336.984848 -266.891516) (xy 336.885026 -266.991592) (xy 336.885026 -267.036042)
			(xy 337.084924 -267.036042)
		)
		(stroke
			(width 0)
			(type solid)
		)
		(fill yes)
		(layer "In4.Cu")
		(net "M_D_CPU0_SA_RSP<0>")
	)
	(gr_poly
		(pts
			(xy 337.091274 -292.91788) (xy 336.991198 -292.817804) (xy 336.891122 -292.91788) (xy 336.891122 -292.96233)
			(xy 337.091274 -292.96233)
		)
		(stroke
			(width 0)
			(type solid)
		)
		(fill yes)
		(layer "In4.Cu")
		(net "M_D_CPU0_SB_DQ<29>")
	)
	(gr_poly
		(pts
			(xy 337.091274 -292.51402) (xy 337.091274 -292.46957) (xy 336.891122 -292.46957) (xy 336.891122 -292.51402)
			(xy 336.991198 -292.614096)
		)
		(stroke
			(width 0)
			(type solid)
		)
		(fill yes)
		(layer "In4.Cu")
		(net "M_D_CPU0_SB_DQ<30>")
	)
	(gr_poly
		(pts
			(xy 337.091274 -291.297614) (xy 336.991198 -291.197792) (xy 336.891122 -291.297614) (xy 336.891122 -291.345366)
			(xy 337.091274 -291.345366)
		)
		(stroke
			(width 0)
			(type solid)
		)
		(fill yes)
		(layer "In4.Cu")
		(net "M_D_CPU0_SB_DQS_DN<8>")
	)
	(gr_poly
		(pts
			(xy 337.091274 -290.894262) (xy 337.091274 -290.84651) (xy 336.891122 -290.84651) (xy 336.891122 -290.894262)
			(xy 336.991198 -290.994084)
		)
		(stroke
			(width 0)
			(type solid)
		)
		(fill yes)
		(layer "In4.Cu")
		(net "M_D_CPU0_SB_DQS_DN<3>")
	)
	(gr_poly
		(pts
			(xy 337.091274 -289.677856) (xy 336.991198 -289.57778) (xy 336.891122 -289.677856) (xy 336.891122 -289.722306)
			(xy 337.091274 -289.722306)
		)
		(stroke
			(width 0)
			(type solid)
		)
		(fill yes)
		(layer "In4.Cu")
		(net "M_D_CPU0_SB_DQ<25>")
	)
	(gr_poly
		(pts
			(xy 337.091274 -289.273996) (xy 337.091274 -289.229546) (xy 336.891122 -289.229546) (xy 336.891122 -289.273996)
			(xy 336.991198 -289.374072)
		)
		(stroke
			(width 0)
			(type solid)
		)
		(fill yes)
		(layer "In4.Cu")
		(net "M_D_CPU0_SB_DQ<26>")
	)
	(gr_poly
		(pts
			(xy 337.091274 -288.057844) (xy 336.991198 -287.957768) (xy 336.891122 -288.057844) (xy 336.891122 -288.102294)
			(xy 337.091274 -288.102294)
		)
		(stroke
			(width 0)
			(type solid)
		)
		(fill yes)
		(layer "In4.Cu")
		(net "M_D_CPU0_SB_DQ<21>")
	)
	(gr_poly
		(pts
			(xy 337.091274 -287.654238) (xy 337.091274 -287.609788) (xy 336.891122 -287.609788) (xy 336.891122 -287.654238)
			(xy 336.991198 -287.75406)
		)
		(stroke
			(width 0)
			(type solid)
		)
		(fill yes)
		(layer "In4.Cu")
		(net "M_D_CPU0_SB_DQ<22>")
	)
	(gr_poly
		(pts
			(xy 337.091274 -286.437832) (xy 336.991198 -286.337756) (xy 336.891122 -286.437832) (xy 336.891122 -286.485584)
			(xy 337.091274 -286.485584)
		)
		(stroke
			(width 0)
			(type solid)
		)
		(fill yes)
		(layer "In4.Cu")
		(net "M_D_CPU0_SB_DQS_DN<7>")
	)
	(gr_poly
		(pts
			(xy 337.091274 -286.03448) (xy 337.091274 -285.986728) (xy 336.891122 -285.986728) (xy 336.891122 -286.03448)
			(xy 336.991198 -286.134302)
		)
		(stroke
			(width 0)
			(type solid)
		)
		(fill yes)
		(layer "In4.Cu")
		(net "M_D_CPU0_SB_DQS_DN<2>")
	)
	(gr_poly
		(pts
			(xy 337.091274 -284.818074) (xy 336.991198 -284.717998) (xy 336.891122 -284.818074) (xy 336.891122 -284.862524)
			(xy 337.091274 -284.862524)
		)
		(stroke
			(width 0)
			(type solid)
		)
		(fill yes)
		(layer "In4.Cu")
		(net "M_D_CPU0_SB_DQ<17>")
	)
	(gr_poly
		(pts
			(xy 337.091274 -284.414214) (xy 337.091274 -284.369764) (xy 336.891122 -284.369764) (xy 336.891122 -284.414214)
			(xy 336.991198 -284.51429)
		)
		(stroke
			(width 0)
			(type solid)
		)
		(fill yes)
		(layer "In4.Cu")
		(net "M_D_CPU0_SB_DQ<18>")
	)
	(gr_poly
		(pts
			(xy 337.091274 -283.198062) (xy 336.991198 -283.097986) (xy 336.891122 -283.198062) (xy 336.891122 -283.242512)
			(xy 337.091274 -283.242512)
		)
		(stroke
			(width 0)
			(type solid)
		)
		(fill yes)
		(layer "In4.Cu")
		(net "M_D_CPU0_SB_DQ<13>")
	)
	(gr_poly
		(pts
			(xy 337.091274 -282.794202) (xy 337.091274 -282.749752) (xy 336.891122 -282.749752) (xy 336.891122 -282.794202)
			(xy 336.991198 -282.894278)
		)
		(stroke
			(width 0)
			(type solid)
		)
		(fill yes)
		(layer "In4.Cu")
		(net "M_D_CPU0_SB_DQ<14>")
	)
	(gr_poly
		(pts
			(xy 337.091274 -281.577796) (xy 336.991198 -281.477974) (xy 336.891122 -281.577796) (xy 336.891122 -281.625548)
			(xy 337.091274 -281.625548)
		)
		(stroke
			(width 0)
			(type solid)
		)
		(fill yes)
		(layer "In4.Cu")
		(net "M_D_CPU0_SB_DQS_DN<6>")
	)
	(gr_poly
		(pts
			(xy 337.091274 -281.174444) (xy 337.091274 -281.126692) (xy 336.891122 -281.126692) (xy 336.891122 -281.174444)
			(xy 336.991198 -281.274266)
		)
		(stroke
			(width 0)
			(type solid)
		)
		(fill yes)
		(layer "In4.Cu")
		(net "M_D_CPU0_SB_DQS_DN<1>")
	)
	(gr_poly
		(pts
			(xy 337.091274 -279.958038) (xy 336.991198 -279.857962) (xy 336.891122 -279.958038) (xy 336.891122 -280.002488)
			(xy 337.091274 -280.002488)
		)
		(stroke
			(width 0)
			(type solid)
		)
		(fill yes)
		(layer "In4.Cu")
		(net "M_D_CPU0_SB_DQ<9>")
	)
	(gr_poly
		(pts
			(xy 337.091274 -279.554178) (xy 337.091274 -279.509728) (xy 336.891122 -279.509728) (xy 336.891122 -279.554178)
			(xy 336.991198 -279.654254)
		)
		(stroke
			(width 0)
			(type solid)
		)
		(fill yes)
		(layer "In4.Cu")
		(net "M_D_CPU0_SB_DQ<10>")
	)
	(gr_poly
		(pts
			(xy 337.091274 -278.338026) (xy 336.991198 -278.23795) (xy 336.891122 -278.338026) (xy 336.891122 -278.382476)
			(xy 337.091274 -278.382476)
		)
		(stroke
			(width 0)
			(type solid)
		)
		(fill yes)
		(layer "In4.Cu")
		(net "M_D_CPU0_SB_DQ<5>")
	)
	(gr_poly
		(pts
			(xy 337.091274 -277.934166) (xy 337.091274 -277.889716) (xy 336.891122 -277.889716) (xy 336.891122 -277.934166)
			(xy 336.991198 -278.034242)
		)
		(stroke
			(width 0)
			(type solid)
		)
		(fill yes)
		(layer "In4.Cu")
		(net "M_D_CPU0_SB_DQ<6>")
	)
	(gr_poly
		(pts
			(xy 337.091274 -276.71776) (xy 336.991198 -276.617938) (xy 336.891122 -276.71776) (xy 336.891122 -276.765512)
			(xy 337.091274 -276.765512)
		)
		(stroke
			(width 0)
			(type solid)
		)
		(fill yes)
		(layer "In4.Cu")
		(net "M_D_CPU0_SB_DQS_DN<5>")
	)
	(gr_poly
		(pts
			(xy 337.091274 -276.314408) (xy 337.091274 -276.266656) (xy 336.891122 -276.266656) (xy 336.891122 -276.314408)
			(xy 336.991198 -276.41423)
		)
		(stroke
			(width 0)
			(type solid)
		)
		(fill yes)
		(layer "In4.Cu")
		(net "M_D_CPU0_SB_DQS_DN<0>")
	)
	(gr_poly
		(pts
			(xy 337.091274 -275.098002) (xy 336.991198 -274.997926) (xy 336.891122 -275.098002) (xy 336.891122 -275.142452)
			(xy 337.091274 -275.142452)
		)
		(stroke
			(width 0)
			(type solid)
		)
		(fill yes)
		(layer "In4.Cu")
		(net "M_D_CPU0_SB_DQ<1>")
	)
	(gr_poly
		(pts
			(xy 337.091274 -274.694142) (xy 337.091274 -274.649692) (xy 336.891122 -274.649692) (xy 336.891122 -274.694142)
			(xy 336.991198 -274.794218)
		)
		(stroke
			(width 0)
			(type solid)
		)
		(fill yes)
		(layer "In4.Cu")
		(net "M_D_CPU0_SB_DQ<2>")
	)
	(gr_poly
		(pts
			(xy 337.091274 -273.47799) (xy 336.991198 -273.377914) (xy 336.891122 -273.47799) (xy 336.891122 -273.52244)
			(xy 337.091274 -273.52244)
		)
		(stroke
			(width 0)
			(type solid)
		)
		(fill yes)
		(layer "In4.Cu")
		(net "M_D_CPU0_SB_CB<1>")
	)
	(gr_poly
		(pts
			(xy 337.091274 -273.07413) (xy 337.091274 -273.02968) (xy 336.891122 -273.02968) (xy 336.891122 -273.07413)
			(xy 336.991198 -273.174206)
		)
		(stroke
			(width 0)
			(type solid)
		)
		(fill yes)
		(layer "In4.Cu")
		(net "M_D_CPU0_SB_CB<2>")
	)
	(gr_poly
		(pts
			(xy 337.091274 -271.857724) (xy 336.991198 -271.757902) (xy 336.891122 -271.857724) (xy 336.891122 -271.905476)
			(xy 337.091274 -271.905476)
		)
		(stroke
			(width 0)
			(type solid)
		)
		(fill yes)
		(layer "In4.Cu")
		(net "M_D_CPU0_SB_DQS_DN<4>")
	)
	(gr_poly
		(pts
			(xy 337.091274 -271.454372) (xy 337.091274 -271.40662) (xy 336.891122 -271.40662) (xy 336.891122 -271.454372)
			(xy 336.991198 -271.554194)
		)
		(stroke
			(width 0)
			(type solid)
		)
		(fill yes)
		(layer "In4.Cu")
		(net "M_D_CPU0_SB_DQS_DN<9>")
	)
	(gr_poly
		(pts
			(xy 337.091274 -270.237966) (xy 336.991198 -270.13789) (xy 336.891122 -270.237966) (xy 336.891122 -270.282416)
			(xy 337.091274 -270.282416)
		)
		(stroke
			(width 0)
			(type solid)
		)
		(fill yes)
		(layer "In4.Cu")
		(net "M_D_CPU0_SB_CB<5>")
	)
	(gr_poly
		(pts
			(xy 337.091274 -269.834106) (xy 337.091274 -269.789656) (xy 336.891122 -269.789656) (xy 336.891122 -269.834106)
			(xy 336.991198 -269.934182)
		)
		(stroke
			(width 0)
			(type solid)
		)
		(fill yes)
		(layer "In4.Cu")
		(net "M_D_CPU0_SB_CB<6>")
	)
	(gr_poly
		(pts
			(xy 337.091274 -266.594082) (xy 337.091274 -266.549632) (xy 336.891122 -266.549632) (xy 336.891122 -266.594082)
			(xy 336.991198 -266.694158)
		)
		(stroke
			(width 0)
			(type solid)
		)
		(fill yes)
		(layer "In4.Cu")
		(net "M_D_CPU0_SB_CS_N<1>")
	)
	(gr_poly
		(pts
			(xy 337.091274 -264.97407) (xy 337.091274 -264.92962) (xy 336.891122 -264.92962) (xy 336.891122 -264.97407)
			(xy 336.991198 -265.074146)
		)
		(stroke
			(width 0)
			(type solid)
		)
		(fill yes)
		(layer "In4.Cu")
		(net "M_D_CPU0_SB_PAR")
	)
	(gr_poly
		(pts
			(xy 337.091274 -263.757918) (xy 336.991198 -263.657842) (xy 336.891122 -263.757918) (xy 336.891122 -263.802368)
			(xy 337.091274 -263.802368)
		)
		(stroke
			(width 0)
			(type solid)
		)
		(fill yes)
		(layer "In4.Cu")
		(net "M_D_CPU0_SB_CA<4>")
	)
	(gr_poly
		(pts
			(xy 337.091274 -263.354058) (xy 337.091274 -263.309608) (xy 336.891122 -263.309608) (xy 336.891122 -263.354058)
			(xy 336.991198 -263.454134)
		)
		(stroke
			(width 0)
			(type solid)
		)
		(fill yes)
		(layer "In4.Cu")
		(net "M_D_CPU0_SB_CA<3>")
	)
	(gr_poly
		(pts
			(xy 337.091274 -262.137906) (xy 336.991198 -262.03783) (xy 336.891122 -262.137906) (xy 336.891122 -262.182356)
			(xy 337.091274 -262.182356)
		)
		(stroke
			(width 0)
			(type solid)
		)
		(fill yes)
		(layer "In4.Cu")
		(net "M_D_CPU0_SB_CA<0>")
	)
	(gr_poly
		(pts
			(xy 337.2612 -256.432558) (xy 337.2612 -256.384806) (xy 337.061048 -256.384806) (xy 337.061048 -256.432558)
			(xy 337.161124 -256.53238)
		)
		(stroke
			(width 0)
			(type solid)
		)
		(fill yes)
		(layer "In4.Cu")
		(net "M_D_CPU0_CLK_DN<0>")
	)
	(gr_poly
		(pts
			(xy 337.2612 -255.216152) (xy 337.161124 -255.116076) (xy 337.061048 -255.216152) (xy 337.061048 -255.260602)
			(xy 337.2612 -255.260602)
		)
		(stroke
			(width 0)
			(type solid)
		)
		(fill yes)
		(layer "In4.Cu")
		(net "M_D_CPU0_SA_CA<6>")
	)
	(gr_poly
		(pts
			(xy 337.2612 -254.812292) (xy 337.2612 -254.767842) (xy 337.061048 -254.767842) (xy 337.061048 -254.812292)
			(xy 337.161124 -254.912368)
		)
		(stroke
			(width 0)
			(type solid)
		)
		(fill yes)
		(layer "In4.Cu")
		(net "M_D_CPU0_SA_CA<5>")
	)
	(gr_poly
		(pts
			(xy 337.2612 -253.59614) (xy 337.161124 -253.496064) (xy 337.061048 -253.59614) (xy 337.061048 -253.64059)
			(xy 337.2612 -253.64059)
		)
		(stroke
			(width 0)
			(type solid)
		)
		(fill yes)
		(layer "In4.Cu")
		(net "M_D_CPU0_SA_CA<2>")
	)
	(gr_poly
		(pts
			(xy 337.2612 -253.19228) (xy 337.2612 -253.14783) (xy 337.061048 -253.14783) (xy 337.061048 -253.19228)
			(xy 337.161124 -253.292356)
		)
		(stroke
			(width 0)
			(type solid)
		)
		(fill yes)
		(layer "In4.Cu")
		(net "M_D_CPU0_SA_CA<1>")
	)
	(gr_poly
		(pts
			(xy 337.2612 -251.572268) (xy 337.2612 -251.527818) (xy 337.061048 -251.527818) (xy 337.061048 -251.572268)
			(xy 337.161124 -251.672344)
		)
		(stroke
			(width 0)
			(type solid)
		)
		(fill yes)
		(layer "In4.Cu")
		(net "M_D_CPU0_SA_CS_N<0>")
	)
	(gr_poly
		(pts
			(xy 337.2612 -250.356116) (xy 337.161124 -250.25604) (xy 337.061048 -250.356116) (xy 337.061048 -250.400566)
			(xy 337.2612 -250.400566)
		)
		(stroke
			(width 0)
			(type solid)
		)
		(fill yes)
		(layer "In4.Cu")
		(net "M_D_CPU0_ALERT_R_N")
	)
	(gr_poly
		(pts
			(xy 337.2612 -248.736104) (xy 337.161124 -248.636028) (xy 337.061048 -248.736104) (xy 337.061048 -248.780554)
			(xy 337.2612 -248.780554)
		)
		(stroke
			(width 0)
			(type solid)
		)
		(fill yes)
		(layer "In4.Cu")
		(net "M_D_CPU0_SA_CB<5>")
	)
	(gr_poly
		(pts
			(xy 337.2612 -248.332244) (xy 337.2612 -248.287794) (xy 337.061048 -248.287794) (xy 337.061048 -248.332244)
			(xy 337.161124 -248.43232)
		)
		(stroke
			(width 0)
			(type solid)
		)
		(fill yes)
		(layer "In4.Cu")
		(net "M_D_CPU0_SA_CB<6>")
	)
	(gr_poly
		(pts
			(xy 337.2612 -247.115838) (xy 337.161124 -247.016016) (xy 337.061048 -247.115838) (xy 337.061048 -247.16359)
			(xy 337.2612 -247.16359)
		)
		(stroke
			(width 0)
			(type solid)
		)
		(fill yes)
		(layer "In4.Cu")
		(net "M_D_CPU0_SA_DQS_DN<9>")
	)
	(gr_poly
		(pts
			(xy 337.2612 -246.712486) (xy 337.2612 -246.664734) (xy 337.061048 -246.664734) (xy 337.061048 -246.712486)
			(xy 337.161124 -246.812308)
		)
		(stroke
			(width 0)
			(type solid)
		)
		(fill yes)
		(layer "In4.Cu")
		(net "M_D_CPU0_SA_DQS_DN<4>")
	)
	(gr_poly
		(pts
			(xy 337.2612 -245.49608) (xy 337.161124 -245.396004) (xy 337.061048 -245.49608) (xy 337.061048 -245.54053)
			(xy 337.2612 -245.54053)
		)
		(stroke
			(width 0)
			(type solid)
		)
		(fill yes)
		(layer "In4.Cu")
		(net "M_D_CPU0_SA_CB<1>")
	)
	(gr_poly
		(pts
			(xy 337.2612 -245.09222) (xy 337.2612 -245.04777) (xy 337.061048 -245.04777) (xy 337.061048 -245.09222)
			(xy 337.161124 -245.192296)
		)
		(stroke
			(width 0)
			(type solid)
		)
		(fill yes)
		(layer "In4.Cu")
		(net "M_D_CPU0_SA_CB<2>")
	)
	(gr_poly
		(pts
			(xy 337.2612 -243.876068) (xy 337.161124 -243.775992) (xy 337.061048 -243.876068) (xy 337.061048 -243.920518)
			(xy 337.2612 -243.920518)
		)
		(stroke
			(width 0)
			(type solid)
		)
		(fill yes)
		(layer "In4.Cu")
		(net "M_D_CPU0_SA_DQ<29>")
	)
	(gr_poly
		(pts
			(xy 337.2612 -243.472208) (xy 337.2612 -243.427758) (xy 337.061048 -243.427758) (xy 337.061048 -243.472208)
			(xy 337.161124 -243.572284)
		)
		(stroke
			(width 0)
			(type solid)
		)
		(fill yes)
		(layer "In4.Cu")
		(net "M_D_CPU0_SA_DQ<30>")
	)
	(gr_poly
		(pts
			(xy 337.2612 -242.255802) (xy 337.161124 -242.15598) (xy 337.061048 -242.255802) (xy 337.061048 -242.303554)
			(xy 337.2612 -242.303554)
		)
		(stroke
			(width 0)
			(type solid)
		)
		(fill yes)
		(layer "In4.Cu")
		(net "M_D_CPU0_SA_DQS_DN<8>")
	)
	(gr_poly
		(pts
			(xy 337.2612 -241.85245) (xy 337.2612 -241.804698) (xy 337.061048 -241.804698) (xy 337.061048 -241.85245)
			(xy 337.161124 -241.952272)
		)
		(stroke
			(width 0)
			(type solid)
		)
		(fill yes)
		(layer "In4.Cu")
		(net "M_D_CPU0_SA_DQS_DN<3>")
	)
	(gr_poly
		(pts
			(xy 337.2612 -240.636044) (xy 337.161124 -240.535968) (xy 337.061048 -240.636044) (xy 337.061048 -240.680494)
			(xy 337.2612 -240.680494)
		)
		(stroke
			(width 0)
			(type solid)
		)
		(fill yes)
		(layer "In4.Cu")
		(net "M_D_CPU0_SA_DQ<25>")
	)
	(gr_poly
		(pts
			(xy 337.2612 -240.232184) (xy 337.2612 -240.187734) (xy 337.061048 -240.187734) (xy 337.061048 -240.232184)
			(xy 337.161124 -240.33226)
		)
		(stroke
			(width 0)
			(type solid)
		)
		(fill yes)
		(layer "In4.Cu")
		(net "M_D_CPU0_SA_DQ<26>")
	)
	(gr_poly
		(pts
			(xy 337.2612 -239.016032) (xy 337.161124 -238.915956) (xy 337.061048 -239.016032) (xy 337.061048 -239.060482)
			(xy 337.2612 -239.060482)
		)
		(stroke
			(width 0)
			(type solid)
		)
		(fill yes)
		(layer "In4.Cu")
		(net "M_D_CPU0_SA_DQ<21>")
	)
	(gr_poly
		(pts
			(xy 337.2612 -238.612172) (xy 337.2612 -238.567722) (xy 337.061048 -238.567722) (xy 337.061048 -238.612172)
			(xy 337.161124 -238.712248)
		)
		(stroke
			(width 0)
			(type solid)
		)
		(fill yes)
		(layer "In4.Cu")
		(net "M_D_CPU0_SA_DQ<22>")
	)
	(gr_poly
		(pts
			(xy 337.2612 -237.395766) (xy 337.161124 -237.295944) (xy 337.061048 -237.395766) (xy 337.061048 -237.443518)
			(xy 337.2612 -237.443518)
		)
		(stroke
			(width 0)
			(type solid)
		)
		(fill yes)
		(layer "In4.Cu")
		(net "M_D_CPU0_SA_DQS_DN<7>")
	)
	(gr_poly
		(pts
			(xy 337.2612 -236.992414) (xy 337.2612 -236.944662) (xy 337.061048 -236.944662) (xy 337.061048 -236.992414)
			(xy 337.161124 -237.092236)
		)
		(stroke
			(width 0)
			(type solid)
		)
		(fill yes)
		(layer "In4.Cu")
		(net "M_D_CPU0_SA_DQS_DN<2>")
	)
	(gr_poly
		(pts
			(xy 337.2612 -235.776008) (xy 337.161124 -235.675932) (xy 337.061048 -235.776008) (xy 337.061048 -235.820458)
			(xy 337.2612 -235.820458)
		)
		(stroke
			(width 0)
			(type solid)
		)
		(fill yes)
		(layer "In4.Cu")
		(net "M_D_CPU0_SA_DQ<17>")
	)
	(gr_poly
		(pts
			(xy 337.2612 -235.372148) (xy 337.2612 -235.327698) (xy 337.061048 -235.327698) (xy 337.061048 -235.372148)
			(xy 337.161124 -235.472224)
		)
		(stroke
			(width 0)
			(type solid)
		)
		(fill yes)
		(layer "In4.Cu")
		(net "M_D_CPU0_SA_DQ<18>")
	)
	(gr_poly
		(pts
			(xy 337.2612 -234.155996) (xy 337.161124 -234.05592) (xy 337.061048 -234.155996) (xy 337.061048 -234.200446)
			(xy 337.2612 -234.200446)
		)
		(stroke
			(width 0)
			(type solid)
		)
		(fill yes)
		(layer "In4.Cu")
		(net "M_D_CPU0_SA_DQ<13>")
	)
	(gr_poly
		(pts
			(xy 337.2612 -233.752136) (xy 337.2612 -233.707686) (xy 337.061048 -233.707686) (xy 337.061048 -233.752136)
			(xy 337.161124 -233.852212)
		)
		(stroke
			(width 0)
			(type solid)
		)
		(fill yes)
		(layer "In4.Cu")
		(net "M_D_CPU0_SA_DQ<14>")
	)
	(gr_poly
		(pts
			(xy 337.2612 -232.53573) (xy 337.161124 -232.435908) (xy 337.061048 -232.53573) (xy 337.061048 -232.583482)
			(xy 337.2612 -232.583482)
		)
		(stroke
			(width 0)
			(type solid)
		)
		(fill yes)
		(layer "In4.Cu")
		(net "M_D_CPU0_SA_DQS_DN<6>")
	)
	(gr_poly
		(pts
			(xy 337.2612 -232.132378) (xy 337.2612 -232.084626) (xy 337.061048 -232.084626) (xy 337.061048 -232.132378)
			(xy 337.161124 -232.2322)
		)
		(stroke
			(width 0)
			(type solid)
		)
		(fill yes)
		(layer "In4.Cu")
		(net "M_D_CPU0_SA_DQS_DN<1>")
	)
	(gr_poly
		(pts
			(xy 337.2612 -230.915972) (xy 337.161124 -230.815896) (xy 337.061048 -230.915972) (xy 337.061048 -230.960422)
			(xy 337.2612 -230.960422)
		)
		(stroke
			(width 0)
			(type solid)
		)
		(fill yes)
		(layer "In4.Cu")
		(net "M_D_CPU0_SA_DQ<9>")
	)
	(gr_poly
		(pts
			(xy 337.2612 -230.512366) (xy 337.2612 -230.467916) (xy 337.061048 -230.467916) (xy 337.061048 -230.512366)
			(xy 337.161124 -230.612188)
		)
		(stroke
			(width 0)
			(type solid)
		)
		(fill yes)
		(layer "In4.Cu")
		(net "M_D_CPU0_SA_DQ<10>")
	)
	(gr_poly
		(pts
			(xy 337.2612 -229.29596) (xy 337.161124 -229.195884) (xy 337.061048 -229.29596) (xy 337.061048 -229.34041)
			(xy 337.2612 -229.34041)
		)
		(stroke
			(width 0)
			(type solid)
		)
		(fill yes)
		(layer "In4.Cu")
		(net "M_D_CPU0_SA_DQ<5>")
	)
	(gr_poly
		(pts
			(xy 337.2612 -228.892354) (xy 337.2612 -228.847904) (xy 337.061048 -228.847904) (xy 337.061048 -228.892354)
			(xy 337.161124 -228.99243)
		)
		(stroke
			(width 0)
			(type solid)
		)
		(fill yes)
		(layer "In4.Cu")
		(net "M_D_CPU0_SA_DQ<6>")
	)
	(gr_poly
		(pts
			(xy 337.2612 -227.676456) (xy 337.161124 -227.57638) (xy 337.061048 -227.676456) (xy 337.061048 -227.724208)
			(xy 337.2612 -227.724208)
		)
		(stroke
			(width 0)
			(type solid)
		)
		(fill yes)
		(layer "In4.Cu")
		(net "M_D_CPU0_SA_DQS_DN<5>")
	)
	(gr_poly
		(pts
			(xy 337.2612 -227.272596) (xy 337.2612 -227.224844) (xy 337.061048 -227.224844) (xy 337.061048 -227.272596)
			(xy 337.161124 -227.372418)
		)
		(stroke
			(width 0)
			(type solid)
		)
		(fill yes)
		(layer "In4.Cu")
		(net "M_D_CPU0_SA_DQS_DN<0>")
	)
	(gr_poly
		(pts
			(xy 337.2612 -226.05619) (xy 337.161124 -225.956114) (xy 337.061048 -226.05619) (xy 337.061048 -226.10064)
			(xy 337.2612 -226.10064)
		)
		(stroke
			(width 0)
			(type solid)
		)
		(fill yes)
		(layer "In4.Cu")
		(net "M_D_CPU0_SA_DQ<1>")
	)
	(gr_poly
		(pts
			(xy 337.2612 -225.65233) (xy 337.2612 -225.60788) (xy 337.061048 -225.60788) (xy 337.061048 -225.65233)
			(xy 337.161124 -225.752406)
		)
		(stroke
			(width 0)
			(type solid)
		)
		(fill yes)
		(layer "In4.Cu")
		(net "M_D_CPU0_SA_DQ<2>")
	)
	(gr_poly
		(pts
			(xy 337.561174 -293.324026) (xy 337.561174 -293.279576) (xy 337.361022 -293.279576) (xy 337.361022 -293.324026)
			(xy 337.461098 -293.424102)
		)
		(stroke
			(width 0)
			(type solid)
		)
		(fill yes)
		(layer "In4.Cu")
		(net "M_D_CPU0_SB_DQ<31>")
	)
	(gr_poly
		(pts
			(xy 337.561174 -292.107874) (xy 337.461098 -292.007798) (xy 337.361022 -292.107874) (xy 337.361022 -292.152324)
			(xy 337.561174 -292.152324)
		)
		(stroke
			(width 0)
			(type solid)
		)
		(fill yes)
		(layer "In4.Cu")
		(net "M_D_CPU0_SB_DQ<28>")
	)
	(gr_poly
		(pts
			(xy 337.561174 -291.704268) (xy 337.561174 -291.656516) (xy 337.361022 -291.656516) (xy 337.361022 -291.704268)
			(xy 337.461098 -291.80409)
		)
		(stroke
			(width 0)
			(type solid)
		)
		(fill yes)
		(layer "In4.Cu")
		(net "M_D_CPU0_SB_DQS_DP<8>")
	)
	(gr_poly
		(pts
			(xy 337.561174 -290.487608) (xy 337.461098 -290.387786) (xy 337.361022 -290.487608) (xy 337.361022 -290.53536)
			(xy 337.561174 -290.53536)
		)
		(stroke
			(width 0)
			(type solid)
		)
		(fill yes)
		(layer "In4.Cu")
		(net "M_D_CPU0_SB_DQS_DP<3>")
	)
	(gr_poly
		(pts
			(xy 337.561174 -290.084002) (xy 337.561174 -290.039552) (xy 337.361022 -290.039552) (xy 337.361022 -290.084002)
			(xy 337.461098 -290.184078)
		)
		(stroke
			(width 0)
			(type solid)
		)
		(fill yes)
		(layer "In4.Cu")
		(net "M_D_CPU0_SB_DQ<27>")
	)
	(gr_poly
		(pts
			(xy 337.561174 -288.86785) (xy 337.461098 -288.767774) (xy 337.361022 -288.86785) (xy 337.361022 -288.9123)
			(xy 337.561174 -288.9123)
		)
		(stroke
			(width 0)
			(type solid)
		)
		(fill yes)
		(layer "In4.Cu")
		(net "M_D_CPU0_SB_DQ<24>")
	)
	(gr_poly
		(pts
			(xy 337.561174 -288.464244) (xy 337.561174 -288.419794) (xy 337.361022 -288.419794) (xy 337.361022 -288.464244)
			(xy 337.461098 -288.56432)
		)
		(stroke
			(width 0)
			(type solid)
		)
		(fill yes)
		(layer "In4.Cu")
		(net "M_D_CPU0_SB_DQ<23>")
	)
	(gr_poly
		(pts
			(xy 337.561174 -287.247838) (xy 337.461098 -287.148016) (xy 337.361022 -287.247838) (xy 337.361022 -287.292288)
			(xy 337.561174 -287.292288)
		)
		(stroke
			(width 0)
			(type solid)
		)
		(fill yes)
		(layer "In4.Cu")
		(net "M_D_CPU0_SB_DQ<20>")
	)
	(gr_poly
		(pts
			(xy 337.561174 -286.844232) (xy 337.561174 -286.79648) (xy 337.361022 -286.79648) (xy 337.361022 -286.844232)
			(xy 337.461098 -286.944308)
		)
		(stroke
			(width 0)
			(type solid)
		)
		(fill yes)
		(layer "In4.Cu")
		(net "M_D_CPU0_SB_DQS_DP<7>")
	)
	(gr_poly
		(pts
			(xy 337.561174 -285.627826) (xy 337.461098 -285.528004) (xy 337.361022 -285.627826) (xy 337.361022 -285.675578)
			(xy 337.561174 -285.675578)
		)
		(stroke
			(width 0)
			(type solid)
		)
		(fill yes)
		(layer "In4.Cu")
		(net "M_D_CPU0_SB_DQS_DP<2>")
	)
	(gr_poly
		(pts
			(xy 337.561174 -285.22422) (xy 337.561174 -285.17977) (xy 337.361022 -285.17977) (xy 337.361022 -285.22422)
			(xy 337.461098 -285.324296)
		)
		(stroke
			(width 0)
			(type solid)
		)
		(fill yes)
		(layer "In4.Cu")
		(net "M_D_CPU0_SB_DQ<19>")
	)
	(gr_poly
		(pts
			(xy 337.561174 -284.008068) (xy 337.461098 -283.907992) (xy 337.361022 -284.008068) (xy 337.361022 -284.052518)
			(xy 337.561174 -284.052518)
		)
		(stroke
			(width 0)
			(type solid)
		)
		(fill yes)
		(layer "In4.Cu")
		(net "M_D_CPU0_SB_DQ<16>")
	)
	(gr_poly
		(pts
			(xy 337.561174 -283.604208) (xy 337.561174 -283.559758) (xy 337.361022 -283.559758) (xy 337.361022 -283.604208)
			(xy 337.461098 -283.704284)
		)
		(stroke
			(width 0)
			(type solid)
		)
		(fill yes)
		(layer "In4.Cu")
		(net "M_D_CPU0_SB_DQ<15>")
	)
	(gr_poly
		(pts
			(xy 337.561174 -282.388056) (xy 337.461098 -282.28798) (xy 337.361022 -282.388056) (xy 337.361022 -282.432506)
			(xy 337.561174 -282.432506)
		)
		(stroke
			(width 0)
			(type solid)
		)
		(fill yes)
		(layer "In4.Cu")
		(net "M_D_CPU0_SB_DQ<12>")
	)
	(gr_poly
		(pts
			(xy 337.561174 -281.98445) (xy 337.561174 -281.936698) (xy 337.361022 -281.936698) (xy 337.361022 -281.98445)
			(xy 337.461098 -282.084272)
		)
		(stroke
			(width 0)
			(type solid)
		)
		(fill yes)
		(layer "In4.Cu")
		(net "M_D_CPU0_SB_DQS_DP<6>")
	)
	(gr_poly
		(pts
			(xy 337.561174 -280.76779) (xy 337.461098 -280.667968) (xy 337.361022 -280.76779) (xy 337.361022 -280.815542)
			(xy 337.561174 -280.815542)
		)
		(stroke
			(width 0)
			(type solid)
		)
		(fill yes)
		(layer "In4.Cu")
		(net "M_D_CPU0_SB_DQS_DP<1>")
	)
	(gr_poly
		(pts
			(xy 337.561174 -280.364184) (xy 337.561174 -280.319734) (xy 337.361022 -280.319734) (xy 337.361022 -280.364184)
			(xy 337.461098 -280.46426)
		)
		(stroke
			(width 0)
			(type solid)
		)
		(fill yes)
		(layer "In4.Cu")
		(net "M_D_CPU0_SB_DQ<11>")
	)
	(gr_poly
		(pts
			(xy 337.561174 -279.148032) (xy 337.461098 -279.047956) (xy 337.361022 -279.148032) (xy 337.361022 -279.192482)
			(xy 337.561174 -279.192482)
		)
		(stroke
			(width 0)
			(type solid)
		)
		(fill yes)
		(layer "In4.Cu")
		(net "M_D_CPU0_SB_DQ<8>")
	)
	(gr_poly
		(pts
			(xy 337.561174 -278.744172) (xy 337.561174 -278.699722) (xy 337.361022 -278.699722) (xy 337.361022 -278.744172)
			(xy 337.461098 -278.844248)
		)
		(stroke
			(width 0)
			(type solid)
		)
		(fill yes)
		(layer "In4.Cu")
		(net "M_D_CPU0_SB_DQ<7>")
	)
	(gr_poly
		(pts
			(xy 337.561174 -277.52802) (xy 337.461098 -277.427944) (xy 337.361022 -277.52802) (xy 337.361022 -277.57247)
			(xy 337.561174 -277.57247)
		)
		(stroke
			(width 0)
			(type solid)
		)
		(fill yes)
		(layer "In4.Cu")
		(net "M_D_CPU0_SB_DQ<4>")
	)
	(gr_poly
		(pts
			(xy 337.561174 -277.12416) (xy 337.561174 -277.076662) (xy 337.361022 -277.076662) (xy 337.361022 -277.12416)
			(xy 337.461098 -277.224236)
		)
		(stroke
			(width 0)
			(type solid)
		)
		(fill yes)
		(layer "In4.Cu")
		(net "M_D_CPU0_SB_DQS_DP<5>")
	)
	(gr_poly
		(pts
			(xy 337.561174 -275.908008) (xy 337.461098 -275.807932) (xy 337.361022 -275.908008) (xy 337.361022 -275.955506)
			(xy 337.561174 -275.955506)
		)
		(stroke
			(width 0)
			(type solid)
		)
		(fill yes)
		(layer "In4.Cu")
		(net "M_D_CPU0_SB_DQS_DP<0>")
	)
	(gr_poly
		(pts
			(xy 337.561174 -275.504148) (xy 337.561174 -275.459698) (xy 337.361022 -275.459698) (xy 337.361022 -275.504148)
			(xy 337.461098 -275.604224)
		)
		(stroke
			(width 0)
			(type solid)
		)
		(fill yes)
		(layer "In4.Cu")
		(net "M_D_CPU0_SB_DQ<3>")
	)
	(gr_poly
		(pts
			(xy 337.561174 -274.287996) (xy 337.461098 -274.18792) (xy 337.361022 -274.287996) (xy 337.361022 -274.332446)
			(xy 337.561174 -274.332446)
		)
		(stroke
			(width 0)
			(type solid)
		)
		(fill yes)
		(layer "In4.Cu")
		(net "M_D_CPU0_SB_DQ<0>")
	)
	(gr_poly
		(pts
			(xy 337.561174 -273.884136) (xy 337.561174 -273.839686) (xy 337.361022 -273.839686) (xy 337.361022 -273.884136)
			(xy 337.461098 -273.984212)
		)
		(stroke
			(width 0)
			(type solid)
		)
		(fill yes)
		(layer "In4.Cu")
		(net "M_D_CPU0_SB_CB<3>")
	)
	(gr_poly
		(pts
			(xy 337.561174 -272.667984) (xy 337.461098 -272.567908) (xy 337.361022 -272.667984) (xy 337.361022 -272.712434)
			(xy 337.561174 -272.712434)
		)
		(stroke
			(width 0)
			(type solid)
		)
		(fill yes)
		(layer "In4.Cu")
		(net "M_D_CPU0_SB_CB<0>")
	)
	(gr_poly
		(pts
			(xy 337.561174 -272.264378) (xy 337.561174 -272.216626) (xy 337.361022 -272.216626) (xy 337.361022 -272.264378)
			(xy 337.461098 -272.3642)
		)
		(stroke
			(width 0)
			(type solid)
		)
		(fill yes)
		(layer "In4.Cu")
		(net "M_D_CPU0_SB_DQS_DP<4>")
	)
	(gr_poly
		(pts
			(xy 337.561174 -271.047718) (xy 337.461098 -270.947896) (xy 337.361022 -271.047718) (xy 337.361022 -271.09547)
			(xy 337.561174 -271.09547)
		)
		(stroke
			(width 0)
			(type solid)
		)
		(fill yes)
		(layer "In4.Cu")
		(net "M_D_CPU0_SB_DQS_DP<9>")
	)
	(gr_poly
		(pts
			(xy 337.561174 -270.644112) (xy 337.561174 -270.599662) (xy 337.361022 -270.599662) (xy 337.361022 -270.644112)
			(xy 337.461098 -270.744188)
		)
		(stroke
			(width 0)
			(type solid)
		)
		(fill yes)
		(layer "In4.Cu")
		(net "M_D_CPU0_SB_CB<7>")
	)
	(gr_poly
		(pts
			(xy 337.561174 -269.42796) (xy 337.461098 -269.327884) (xy 337.361022 -269.42796) (xy 337.361022 -269.47241)
			(xy 337.561174 -269.47241)
		)
		(stroke
			(width 0)
			(type solid)
		)
		(fill yes)
		(layer "In4.Cu")
		(net "M_D_CPU0_SB_CB<4>")
	)
	(gr_poly
		(pts
			(xy 337.561174 -267.801598) (xy 337.461098 -267.701522) (xy 337.361022 -267.801598) (xy 337.361022 -267.846048)
			(xy 337.561174 -267.846048)
		)
		(stroke
			(width 0)
			(type solid)
		)
		(fill yes)
		(layer "In4.Cu")
		(net "M_D_CPU0_SB_RSP<0>")
	)
	(gr_poly
		(pts
			(xy 337.561174 -265.784076) (xy 337.561174 -265.739626) (xy 337.361022 -265.739626) (xy 337.361022 -265.784076)
			(xy 337.461098 -265.884152)
		)
		(stroke
			(width 0)
			(type solid)
		)
		(fill yes)
		(layer "In4.Cu")
		(net "M_D_CPU0_SB_CS_N<0>")
	)
	(gr_poly
		(pts
			(xy 337.561174 -264.567924) (xy 337.461098 -264.467848) (xy 337.361022 -264.567924) (xy 337.361022 -264.612374)
			(xy 337.561174 -264.612374)
		)
		(stroke
			(width 0)
			(type solid)
		)
		(fill yes)
		(layer "In4.Cu")
		(net "M_D_CPU0_SB_CA<6>")
	)
	(gr_poly
		(pts
			(xy 337.561174 -264.164064) (xy 337.561174 -264.119614) (xy 337.361022 -264.119614) (xy 337.361022 -264.164064)
			(xy 337.461098 -264.26414)
		)
		(stroke
			(width 0)
			(type solid)
		)
		(fill yes)
		(layer "In4.Cu")
		(net "M_D_CPU0_SB_CA<5>")
	)
	(gr_poly
		(pts
			(xy 337.561174 -262.947912) (xy 337.461098 -262.847836) (xy 337.361022 -262.947912) (xy 337.361022 -262.992362)
			(xy 337.561174 -262.992362)
		)
		(stroke
			(width 0)
			(type solid)
		)
		(fill yes)
		(layer "In4.Cu")
		(net "M_D_CPU0_SB_CA<2>")
	)
	(gr_poly
		(pts
			(xy 337.561174 -262.544052) (xy 337.561174 -262.499602) (xy 337.361022 -262.499602) (xy 337.361022 -262.544052)
			(xy 337.461098 -262.644128)
		)
		(stroke
			(width 0)
			(type solid)
		)
		(fill yes)
		(layer "In4.Cu")
		(net "M_D_CPU0_SB_CA<1>")
	)
	(gr_poly
		(pts
			(xy 337.7311 -256.025904) (xy 337.631024 -255.926082) (xy 337.530948 -256.025904) (xy 337.530948 -256.073656)
			(xy 337.7311 -256.073656)
		)
		(stroke
			(width 0)
			(type solid)
		)
		(fill yes)
		(layer "In4.Cu")
		(net "M_D_CPU0_CLK_DP<0>")
	)
	(gr_poly
		(pts
			(xy 337.7311 -255.622298) (xy 337.7311 -255.577848) (xy 337.530948 -255.577848) (xy 337.530948 -255.622298)
			(xy 337.631024 -255.722374)
		)
		(stroke
			(width 0)
			(type solid)
		)
		(fill yes)
		(layer "In4.Cu")
		(net "M_D_CPU0_SA_PAR")
	)
	(gr_poly
		(pts
			(xy 337.7311 -254.406146) (xy 337.631024 -254.30607) (xy 337.530948 -254.406146) (xy 337.530948 -254.450596)
			(xy 337.7311 -254.450596)
		)
		(stroke
			(width 0)
			(type solid)
		)
		(fill yes)
		(layer "In4.Cu")
		(net "M_D_CPU0_SA_CA<4>")
	)
	(gr_poly
		(pts
			(xy 337.7311 -254.002286) (xy 337.7311 -253.957836) (xy 337.530948 -253.957836) (xy 337.530948 -254.002286)
			(xy 337.631024 -254.102362)
		)
		(stroke
			(width 0)
			(type solid)
		)
		(fill yes)
		(layer "In4.Cu")
		(net "M_D_CPU0_SA_CA<3>")
	)
	(gr_poly
		(pts
			(xy 337.7311 -252.786134) (xy 337.631024 -252.686058) (xy 337.530948 -252.786134) (xy 337.530948 -252.830584)
			(xy 337.7311 -252.830584)
		)
		(stroke
			(width 0)
			(type solid)
		)
		(fill yes)
		(layer "In4.Cu")
		(net "M_D_CPU0_SA_CA<0>")
	)
	(gr_poly
		(pts
			(xy 337.7311 -252.382274) (xy 337.7311 -252.337824) (xy 337.530948 -252.337824) (xy 337.530948 -252.382274)
			(xy 337.631024 -252.48235)
		)
		(stroke
			(width 0)
			(type solid)
		)
		(fill yes)
		(layer "In4.Cu")
		(net "M_D_CPU0_SA_CS_N<1>")
	)
	(gr_poly
		(pts
			(xy 337.7311 -250.762262) (xy 337.7311 -250.717812) (xy 337.530948 -250.717812) (xy 337.530948 -250.762262)
			(xy 337.631024 -250.862338)
		)
		(stroke
			(width 0)
			(type solid)
		)
		(fill yes)
		(layer "In4.Cu")
		(net "M_D_CPU0_RESET_N")
	)
	(gr_poly
		(pts
			(xy 337.7311 -249.14225) (xy 337.7311 -249.0978) (xy 337.530948 -249.0978) (xy 337.530948 -249.14225)
			(xy 337.631024 -249.242326)
		)
		(stroke
			(width 0)
			(type solid)
		)
		(fill yes)
		(layer "In4.Cu")
		(net "M_D_CPU0_SA_CB<7>")
	)
	(gr_poly
		(pts
			(xy 337.7311 -247.926098) (xy 337.631024 -247.826022) (xy 337.530948 -247.926098) (xy 337.530948 -247.970548)
			(xy 337.7311 -247.970548)
		)
		(stroke
			(width 0)
			(type solid)
		)
		(fill yes)
		(layer "In4.Cu")
		(net "M_D_CPU0_SA_CB<4>")
	)
	(gr_poly
		(pts
			(xy 337.7311 -247.522492) (xy 337.7311 -247.47474) (xy 337.530948 -247.47474) (xy 337.530948 -247.522492)
			(xy 337.631024 -247.622314)
		)
		(stroke
			(width 0)
			(type solid)
		)
		(fill yes)
		(layer "In4.Cu")
		(net "M_D_CPU0_SA_DQS_DP<9>")
	)
	(gr_poly
		(pts
			(xy 337.7311 -246.305832) (xy 337.631024 -246.20601) (xy 337.530948 -246.305832) (xy 337.530948 -246.353584)
			(xy 337.7311 -246.353584)
		)
		(stroke
			(width 0)
			(type solid)
		)
		(fill yes)
		(layer "In4.Cu")
		(net "M_D_CPU0_SA_DQS_DP<4>")
	)
	(gr_poly
		(pts
			(xy 337.7311 -245.902226) (xy 337.7311 -245.857776) (xy 337.530948 -245.857776) (xy 337.530948 -245.902226)
			(xy 337.631024 -246.002302)
		)
		(stroke
			(width 0)
			(type solid)
		)
		(fill yes)
		(layer "In4.Cu")
		(net "M_D_CPU0_SA_CB<3>")
	)
	(gr_poly
		(pts
			(xy 337.7311 -244.686074) (xy 337.631024 -244.585998) (xy 337.530948 -244.686074) (xy 337.530948 -244.730524)
			(xy 337.7311 -244.730524)
		)
		(stroke
			(width 0)
			(type solid)
		)
		(fill yes)
		(layer "In4.Cu")
		(net "M_D_CPU0_SA_CB<0>")
	)
	(gr_poly
		(pts
			(xy 337.7311 -244.282214) (xy 337.7311 -244.237764) (xy 337.530948 -244.237764) (xy 337.530948 -244.282214)
			(xy 337.631024 -244.38229)
		)
		(stroke
			(width 0)
			(type solid)
		)
		(fill yes)
		(layer "In4.Cu")
		(net "M_D_CPU0_SA_DQ<31>")
	)
	(gr_poly
		(pts
			(xy 337.7311 -243.066062) (xy 337.631024 -242.965986) (xy 337.530948 -243.066062) (xy 337.530948 -243.110512)
			(xy 337.7311 -243.110512)
		)
		(stroke
			(width 0)
			(type solid)
		)
		(fill yes)
		(layer "In4.Cu")
		(net "M_D_CPU0_SA_DQ<28>")
	)
	(gr_poly
		(pts
			(xy 337.7311 -242.662456) (xy 337.7311 -242.614704) (xy 337.530948 -242.614704) (xy 337.530948 -242.662456)
			(xy 337.631024 -242.762278)
		)
		(stroke
			(width 0)
			(type solid)
		)
		(fill yes)
		(layer "In4.Cu")
		(net "M_D_CPU0_SA_DQS_DP<8>")
	)
	(gr_poly
		(pts
			(xy 337.7311 -241.445796) (xy 337.631024 -241.345974) (xy 337.530948 -241.445796) (xy 337.530948 -241.493548)
			(xy 337.7311 -241.493548)
		)
		(stroke
			(width 0)
			(type solid)
		)
		(fill yes)
		(layer "In4.Cu")
		(net "M_D_CPU0_SA_DQS_DP<3>")
	)
	(gr_poly
		(pts
			(xy 337.7311 -241.04219) (xy 337.7311 -240.99774) (xy 337.530948 -240.99774) (xy 337.530948 -241.04219)
			(xy 337.631024 -241.142266)
		)
		(stroke
			(width 0)
			(type solid)
		)
		(fill yes)
		(layer "In4.Cu")
		(net "M_D_CPU0_SA_DQ<27>")
	)
	(gr_poly
		(pts
			(xy 337.7311 -239.826038) (xy 337.631024 -239.725962) (xy 337.530948 -239.826038) (xy 337.530948 -239.870488)
			(xy 337.7311 -239.870488)
		)
		(stroke
			(width 0)
			(type solid)
		)
		(fill yes)
		(layer "In4.Cu")
		(net "M_D_CPU0_SA_DQ<24>")
	)
	(gr_poly
		(pts
			(xy 337.7311 -239.422178) (xy 337.7311 -239.377728) (xy 337.530948 -239.377728) (xy 337.530948 -239.422178)
			(xy 337.631024 -239.522254)
		)
		(stroke
			(width 0)
			(type solid)
		)
		(fill yes)
		(layer "In4.Cu")
		(net "M_D_CPU0_SA_DQ<23>")
	)
	(gr_poly
		(pts
			(xy 337.7311 -238.206026) (xy 337.631024 -238.10595) (xy 337.530948 -238.206026) (xy 337.530948 -238.250476)
			(xy 337.7311 -238.250476)
		)
		(stroke
			(width 0)
			(type solid)
		)
		(fill yes)
		(layer "In4.Cu")
		(net "M_D_CPU0_SA_DQ<20>")
	)
	(gr_poly
		(pts
			(xy 337.7311 -237.80242) (xy 337.7311 -237.754668) (xy 337.530948 -237.754668) (xy 337.530948 -237.80242)
			(xy 337.631024 -237.902242)
		)
		(stroke
			(width 0)
			(type solid)
		)
		(fill yes)
		(layer "In4.Cu")
		(net "M_D_CPU0_SA_DQS_DP<7>")
	)
	(gr_poly
		(pts
			(xy 337.7311 -236.58576) (xy 337.631024 -236.485938) (xy 337.530948 -236.58576) (xy 337.530948 -236.633512)
			(xy 337.7311 -236.633512)
		)
		(stroke
			(width 0)
			(type solid)
		)
		(fill yes)
		(layer "In4.Cu")
		(net "M_D_CPU0_SA_DQS_DP<2>")
	)
	(gr_poly
		(pts
			(xy 337.7311 -236.182154) (xy 337.7311 -236.137704) (xy 337.530948 -236.137704) (xy 337.530948 -236.182154)
			(xy 337.631024 -236.28223)
		)
		(stroke
			(width 0)
			(type solid)
		)
		(fill yes)
		(layer "In4.Cu")
		(net "M_D_CPU0_SA_DQ<19>")
	)
	(gr_poly
		(pts
			(xy 337.7311 -234.966002) (xy 337.631024 -234.865926) (xy 337.530948 -234.966002) (xy 337.530948 -235.010452)
			(xy 337.7311 -235.010452)
		)
		(stroke
			(width 0)
			(type solid)
		)
		(fill yes)
		(layer "In4.Cu")
		(net "M_D_CPU0_SA_DQ<16>")
	)
	(gr_poly
		(pts
			(xy 337.7311 -234.562142) (xy 337.7311 -234.517692) (xy 337.530948 -234.517692) (xy 337.530948 -234.562142)
			(xy 337.631024 -234.662218)
		)
		(stroke
			(width 0)
			(type solid)
		)
		(fill yes)
		(layer "In4.Cu")
		(net "M_D_CPU0_SA_DQ<15>")
	)
	(gr_poly
		(pts
			(xy 337.7311 -233.34599) (xy 337.631024 -233.245914) (xy 337.530948 -233.34599) (xy 337.530948 -233.39044)
			(xy 337.7311 -233.39044)
		)
		(stroke
			(width 0)
			(type solid)
		)
		(fill yes)
		(layer "In4.Cu")
		(net "M_D_CPU0_SA_DQ<12>")
	)
	(gr_poly
		(pts
			(xy 337.7311 -232.942384) (xy 337.7311 -232.894632) (xy 337.530948 -232.894632) (xy 337.530948 -232.942384)
			(xy 337.631024 -233.042206)
		)
		(stroke
			(width 0)
			(type solid)
		)
		(fill yes)
		(layer "In4.Cu")
		(net "M_D_CPU0_SA_DQS_DP<6>")
	)
	(gr_poly
		(pts
			(xy 337.7311 -231.725724) (xy 337.631024 -231.625902) (xy 337.530948 -231.725724) (xy 337.530948 -231.773476)
			(xy 337.7311 -231.773476)
		)
		(stroke
			(width 0)
			(type solid)
		)
		(fill yes)
		(layer "In4.Cu")
		(net "M_D_CPU0_SA_DQS_DP<1>")
	)
	(gr_poly
		(pts
			(xy 337.7311 -231.322372) (xy 337.7311 -231.277922) (xy 337.530948 -231.277922) (xy 337.530948 -231.322372)
			(xy 337.631024 -231.422448)
		)
		(stroke
			(width 0)
			(type solid)
		)
		(fill yes)
		(layer "In4.Cu")
		(net "M_D_CPU0_SA_DQ<11>")
	)
	(gr_poly
		(pts
			(xy 337.7311 -230.105966) (xy 337.631024 -230.006144) (xy 337.530948 -230.105966) (xy 337.530948 -230.150416)
			(xy 337.7311 -230.150416)
		)
		(stroke
			(width 0)
			(type solid)
		)
		(fill yes)
		(layer "In4.Cu")
		(net "M_D_CPU0_SA_DQ<8>")
	)
	(gr_poly
		(pts
			(xy 337.7311 -229.70236) (xy 337.7311 -229.65791) (xy 337.530948 -229.65791) (xy 337.530948 -229.70236)
			(xy 337.631024 -229.802436)
		)
		(stroke
			(width 0)
			(type solid)
		)
		(fill yes)
		(layer "In4.Cu")
		(net "M_D_CPU0_SA_DQ<7>")
	)
	(gr_poly
		(pts
			(xy 337.7311 -228.486208) (xy 337.631024 -228.386132) (xy 337.530948 -228.486208) (xy 337.530948 -228.530658)
			(xy 337.7311 -228.530658)
		)
		(stroke
			(width 0)
			(type solid)
		)
		(fill yes)
		(layer "In4.Cu")
		(net "M_D_CPU0_SA_DQ<4>")
	)
	(gr_poly
		(pts
			(xy 337.7311 -228.082602) (xy 337.7311 -228.03485) (xy 337.530948 -228.03485) (xy 337.530948 -228.082602)
			(xy 337.631024 -228.182424)
		)
		(stroke
			(width 0)
			(type solid)
		)
		(fill yes)
		(layer "In4.Cu")
		(net "M_D_CPU0_SA_DQS_DP<5>")
	)
	(gr_poly
		(pts
			(xy 337.7311 -226.865942) (xy 337.631024 -226.76612) (xy 337.530948 -226.865942) (xy 337.530948 -226.913694)
			(xy 337.7311 -226.913694)
		)
		(stroke
			(width 0)
			(type solid)
		)
		(fill yes)
		(layer "In4.Cu")
		(net "M_D_CPU0_SA_DQS_DP<0>")
	)
	(gr_poly
		(pts
			(xy 337.7311 -226.462336) (xy 337.7311 -226.417886) (xy 337.530948 -226.417886) (xy 337.530948 -226.462336)
			(xy 337.631024 -226.562412)
		)
		(stroke
			(width 0)
			(type solid)
		)
		(fill yes)
		(layer "In4.Cu")
		(net "M_D_CPU0_SA_DQ<3>")
	)
	(gr_poly
		(pts
			(xy 337.7311 -225.246184) (xy 337.631024 -225.146108) (xy 337.530948 -225.246184) (xy 337.530948 -225.290634)
			(xy 337.7311 -225.290634)
		)
		(stroke
			(width 0)
			(type solid)
		)
		(fill yes)
		(layer "In4.Cu")
		(net "M_D_CPU0_SA_DQ<0>")
	)
	(gr_poly
		(pts
			(xy 338.031074 -292.91788) (xy 337.930998 -292.817804) (xy 337.830922 -292.91788) (xy 337.830922 -292.96233)
			(xy 338.031074 -292.96233)
		)
		(stroke
			(width 0)
			(type solid)
		)
		(fill yes)
		(layer "In4.Cu")
		(net "M_D_CPU0_SB_DQ<29>")
	)
	(gr_poly
		(pts
			(xy 338.031074 -292.51402) (xy 338.031074 -292.46957) (xy 337.830922 -292.46957) (xy 337.830922 -292.51402)
			(xy 337.930998 -292.614096)
		)
		(stroke
			(width 0)
			(type solid)
		)
		(fill yes)
		(layer "In4.Cu")
		(net "M_D_CPU0_SB_DQ<30>")
	)
	(gr_poly
		(pts
			(xy 338.031074 -291.297614) (xy 337.930998 -291.197792) (xy 337.830922 -291.297614) (xy 337.830922 -291.345366)
			(xy 338.031074 -291.345366)
		)
		(stroke
			(width 0)
			(type solid)
		)
		(fill yes)
		(layer "In4.Cu")
		(net "M_D_CPU0_SB_DQS_DN<8>")
	)
	(gr_poly
		(pts
			(xy 338.031074 -290.894262) (xy 338.031074 -290.84651) (xy 337.830922 -290.84651) (xy 337.830922 -290.894262)
			(xy 337.930998 -290.994084)
		)
		(stroke
			(width 0)
			(type solid)
		)
		(fill yes)
		(layer "In4.Cu")
		(net "M_D_CPU0_SB_DQS_DN<3>")
	)
	(gr_poly
		(pts
			(xy 338.031074 -289.677856) (xy 337.930998 -289.57778) (xy 337.830922 -289.677856) (xy 337.830922 -289.722306)
			(xy 338.031074 -289.722306)
		)
		(stroke
			(width 0)
			(type solid)
		)
		(fill yes)
		(layer "In4.Cu")
		(net "M_D_CPU0_SB_DQ<25>")
	)
	(gr_poly
		(pts
			(xy 338.031074 -289.273996) (xy 338.031074 -289.229546) (xy 337.830922 -289.229546) (xy 337.830922 -289.273996)
			(xy 337.930998 -289.374072)
		)
		(stroke
			(width 0)
			(type solid)
		)
		(fill yes)
		(layer "In4.Cu")
		(net "M_D_CPU0_SB_DQ<26>")
	)
	(gr_poly
		(pts
			(xy 338.031074 -288.057844) (xy 337.930998 -287.957768) (xy 337.830922 -288.057844) (xy 337.830922 -288.102294)
			(xy 338.031074 -288.102294)
		)
		(stroke
			(width 0)
			(type solid)
		)
		(fill yes)
		(layer "In4.Cu")
		(net "M_D_CPU0_SB_DQ<21>")
	)
	(gr_poly
		(pts
			(xy 338.031074 -287.654238) (xy 338.031074 -287.609788) (xy 337.830922 -287.609788) (xy 337.830922 -287.654238)
			(xy 337.930998 -287.75406)
		)
		(stroke
			(width 0)
			(type solid)
		)
		(fill yes)
		(layer "In4.Cu")
		(net "M_D_CPU0_SB_DQ<22>")
	)
	(gr_poly
		(pts
			(xy 338.031074 -286.437832) (xy 337.930998 -286.337756) (xy 337.830922 -286.437832) (xy 337.830922 -286.485584)
			(xy 338.031074 -286.485584)
		)
		(stroke
			(width 0)
			(type solid)
		)
		(fill yes)
		(layer "In4.Cu")
		(net "M_D_CPU0_SB_DQS_DN<7>")
	)
	(gr_poly
		(pts
			(xy 338.031074 -286.03448) (xy 338.031074 -285.986728) (xy 337.830922 -285.986728) (xy 337.830922 -286.03448)
			(xy 337.930998 -286.134302)
		)
		(stroke
			(width 0)
			(type solid)
		)
		(fill yes)
		(layer "In4.Cu")
		(net "M_D_CPU0_SB_DQS_DN<2>")
	)
	(gr_poly
		(pts
			(xy 338.031074 -284.818074) (xy 337.930998 -284.717998) (xy 337.830922 -284.818074) (xy 337.830922 -284.862524)
			(xy 338.031074 -284.862524)
		)
		(stroke
			(width 0)
			(type solid)
		)
		(fill yes)
		(layer "In4.Cu")
		(net "M_D_CPU0_SB_DQ<17>")
	)
	(gr_poly
		(pts
			(xy 338.031074 -284.414214) (xy 338.031074 -284.369764) (xy 337.830922 -284.369764) (xy 337.830922 -284.414214)
			(xy 337.930998 -284.51429)
		)
		(stroke
			(width 0)
			(type solid)
		)
		(fill yes)
		(layer "In4.Cu")
		(net "M_D_CPU0_SB_DQ<18>")
	)
	(gr_poly
		(pts
			(xy 338.031074 -283.198062) (xy 337.930998 -283.097986) (xy 337.830922 -283.198062) (xy 337.830922 -283.242512)
			(xy 338.031074 -283.242512)
		)
		(stroke
			(width 0)
			(type solid)
		)
		(fill yes)
		(layer "In4.Cu")
		(net "M_D_CPU0_SB_DQ<13>")
	)
	(gr_poly
		(pts
			(xy 338.031074 -282.794202) (xy 338.031074 -282.749752) (xy 337.830922 -282.749752) (xy 337.830922 -282.794202)
			(xy 337.930998 -282.894278)
		)
		(stroke
			(width 0)
			(type solid)
		)
		(fill yes)
		(layer "In4.Cu")
		(net "M_D_CPU0_SB_DQ<14>")
	)
	(gr_poly
		(pts
			(xy 338.031074 -281.577796) (xy 337.930998 -281.477974) (xy 337.830922 -281.577796) (xy 337.830922 -281.625548)
			(xy 338.031074 -281.625548)
		)
		(stroke
			(width 0)
			(type solid)
		)
		(fill yes)
		(layer "In4.Cu")
		(net "M_D_CPU0_SB_DQS_DN<6>")
	)
	(gr_poly
		(pts
			(xy 338.031074 -281.174444) (xy 338.031074 -281.126692) (xy 337.830922 -281.126692) (xy 337.830922 -281.174444)
			(xy 337.930998 -281.274266)
		)
		(stroke
			(width 0)
			(type solid)
		)
		(fill yes)
		(layer "In4.Cu")
		(net "M_D_CPU0_SB_DQS_DN<1>")
	)
	(gr_poly
		(pts
			(xy 338.031074 -279.958038) (xy 337.930998 -279.857962) (xy 337.830922 -279.958038) (xy 337.830922 -280.002488)
			(xy 338.031074 -280.002488)
		)
		(stroke
			(width 0)
			(type solid)
		)
		(fill yes)
		(layer "In4.Cu")
		(net "M_D_CPU0_SB_DQ<9>")
	)
	(gr_poly
		(pts
			(xy 338.031074 -279.554178) (xy 338.031074 -279.509728) (xy 337.830922 -279.509728) (xy 337.830922 -279.554178)
			(xy 337.930998 -279.654254)
		)
		(stroke
			(width 0)
			(type solid)
		)
		(fill yes)
		(layer "In4.Cu")
		(net "M_D_CPU0_SB_DQ<10>")
	)
	(gr_poly
		(pts
			(xy 338.031074 -278.338026) (xy 337.930998 -278.23795) (xy 337.830922 -278.338026) (xy 337.830922 -278.382476)
			(xy 338.031074 -278.382476)
		)
		(stroke
			(width 0)
			(type solid)
		)
		(fill yes)
		(layer "In4.Cu")
		(net "M_D_CPU0_SB_DQ<5>")
	)
	(gr_poly
		(pts
			(xy 338.031074 -277.934166) (xy 338.031074 -277.889716) (xy 337.830922 -277.889716) (xy 337.830922 -277.934166)
			(xy 337.930998 -278.034242)
		)
		(stroke
			(width 0)
			(type solid)
		)
		(fill yes)
		(layer "In4.Cu")
		(net "M_D_CPU0_SB_DQ<6>")
	)
	(gr_poly
		(pts
			(xy 338.031074 -275.098002) (xy 337.930998 -274.997926) (xy 337.830922 -275.098002) (xy 337.830922 -275.142452)
			(xy 338.031074 -275.142452)
		)
		(stroke
			(width 0)
			(type solid)
		)
		(fill yes)
		(layer "In4.Cu")
		(net "M_D_CPU0_SB_DQ<1>")
	)
	(gr_poly
		(pts
			(xy 338.031074 -274.694142) (xy 338.031074 -274.649692) (xy 337.830922 -274.649692) (xy 337.830922 -274.694142)
			(xy 337.930998 -274.794218)
		)
		(stroke
			(width 0)
			(type solid)
		)
		(fill yes)
		(layer "In4.Cu")
		(net "M_D_CPU0_SB_DQ<2>")
	)
	(gr_poly
		(pts
			(xy 338.031074 -273.47799) (xy 337.930998 -273.377914) (xy 337.830922 -273.47799) (xy 337.830922 -273.52244)
			(xy 338.031074 -273.52244)
		)
		(stroke
			(width 0)
			(type solid)
		)
		(fill yes)
		(layer "In4.Cu")
		(net "M_D_CPU0_SB_CB<1>")
	)
	(gr_poly
		(pts
			(xy 338.031074 -273.07413) (xy 338.031074 -273.02968) (xy 337.830922 -273.02968) (xy 337.830922 -273.07413)
			(xy 337.930998 -273.174206)
		)
		(stroke
			(width 0)
			(type solid)
		)
		(fill yes)
		(layer "In4.Cu")
		(net "M_D_CPU0_SB_CB<2>")
	)
	(gr_poly
		(pts
			(xy 338.031074 -271.857724) (xy 337.930998 -271.757902) (xy 337.830922 -271.857724) (xy 337.830922 -271.905476)
			(xy 338.031074 -271.905476)
		)
		(stroke
			(width 0)
			(type solid)
		)
		(fill yes)
		(layer "In4.Cu")
		(net "M_D_CPU0_SB_DQS_DN<4>")
	)
	(gr_poly
		(pts
			(xy 338.031074 -271.454372) (xy 338.031074 -271.40662) (xy 337.830922 -271.40662) (xy 337.830922 -271.454372)
			(xy 337.930998 -271.554194)
		)
		(stroke
			(width 0)
			(type solid)
		)
		(fill yes)
		(layer "In4.Cu")
		(net "M_D_CPU0_SB_DQS_DN<9>")
	)
	(gr_poly
		(pts
			(xy 338.031074 -270.237966) (xy 337.930998 -270.13789) (xy 337.830922 -270.237966) (xy 337.830922 -270.282416)
			(xy 338.031074 -270.282416)
		)
		(stroke
			(width 0)
			(type solid)
		)
		(fill yes)
		(layer "In4.Cu")
		(net "M_D_CPU0_SB_CB<5>")
	)
	(gr_poly
		(pts
			(xy 338.031074 -269.834106) (xy 338.031074 -269.789656) (xy 337.830922 -269.789656) (xy 337.830922 -269.834106)
			(xy 337.930998 -269.934182)
		)
		(stroke
			(width 0)
			(type solid)
		)
		(fill yes)
		(layer "In4.Cu")
		(net "M_D_CPU0_SB_CB<6>")
	)
	(gr_poly
		(pts
			(xy 338.031074 -266.594082) (xy 338.031074 -266.549632) (xy 337.830922 -266.549632) (xy 337.830922 -266.594082)
			(xy 337.930998 -266.694158)
		)
		(stroke
			(width 0)
			(type solid)
		)
		(fill yes)
		(layer "In4.Cu")
		(net "M_D_CPU0_SB_CS_N<1>")
	)
	(gr_poly
		(pts
			(xy 338.031074 -264.97407) (xy 338.031074 -264.92962) (xy 337.830922 -264.92962) (xy 337.830922 -264.97407)
			(xy 337.930998 -265.074146)
		)
		(stroke
			(width 0)
			(type solid)
		)
		(fill yes)
		(layer "In4.Cu")
		(net "M_D_CPU0_SB_PAR")
	)
	(gr_poly
		(pts
			(xy 338.031074 -263.757918) (xy 337.930998 -263.657842) (xy 337.830922 -263.757918) (xy 337.830922 -263.802368)
			(xy 338.031074 -263.802368)
		)
		(stroke
			(width 0)
			(type solid)
		)
		(fill yes)
		(layer "In4.Cu")
		(net "M_D_CPU0_SB_CA<4>")
	)
	(gr_poly
		(pts
			(xy 338.031074 -263.354058) (xy 338.031074 -263.309608) (xy 337.830922 -263.309608) (xy 337.830922 -263.354058)
			(xy 337.930998 -263.454134)
		)
		(stroke
			(width 0)
			(type solid)
		)
		(fill yes)
		(layer "In4.Cu")
		(net "M_D_CPU0_SB_CA<3>")
	)
	(gr_poly
		(pts
			(xy 338.031074 -262.137906) (xy 337.930998 -262.03783) (xy 337.830922 -262.137906) (xy 337.830922 -262.182356)
			(xy 338.031074 -262.182356)
		)
		(stroke
			(width 0)
			(type solid)
		)
		(fill yes)
		(layer "In4.Cu")
		(net "M_D_CPU0_SB_CA<0>")
	)
	(gr_poly
		(pts
			(xy 338.03717 -266.991592) (xy 337.937348 -266.891516) (xy 337.837272 -266.991592) (xy 337.837272 -267.036042)
			(xy 338.03717 -267.036042)
		)
		(stroke
			(width 0)
			(type solid)
		)
		(fill yes)
		(layer "In4.Cu")
		(net "M_D_CPU0_SA_RSP<0>")
	)
	(gr_poly
		(pts
			(xy 338.03844 -276.71776) (xy 337.938364 -276.617938) (xy 337.838288 -276.71776) (xy 337.838288 -276.765512)
			(xy 338.03844 -276.765512)
		)
		(stroke
			(width 0)
			(type solid)
		)
		(fill yes)
		(layer "In4.Cu")
		(net "M_D_CPU0_SB_DQS_DN<5>")
	)
	(gr_poly
		(pts
			(xy 338.03844 -276.314408) (xy 338.03844 -276.266656) (xy 337.838288 -276.266656) (xy 337.838288 -276.314408)
			(xy 337.938364 -276.41423)
		)
		(stroke
			(width 0)
			(type solid)
		)
		(fill yes)
		(layer "In4.Cu")
		(net "M_D_CPU0_SB_DQS_DN<0>")
	)
	(gr_poly
		(pts
			(xy 338.195158 -227.676456) (xy 338.095082 -227.57638) (xy 337.995006 -227.676456) (xy 337.995006 -227.723954)
			(xy 338.195158 -227.723954)
		)
		(stroke
			(width 0)
			(type solid)
		)
		(fill yes)
		(layer "In4.Cu")
		(net "M_D_CPU0_SA_DQS_DN<5>")
	)
	(gr_poly
		(pts
			(xy 338.201254 -256.432558) (xy 338.201254 -256.384806) (xy 338.001102 -256.384806) (xy 338.001102 -256.432558)
			(xy 338.101178 -256.53238)
		)
		(stroke
			(width 0)
			(type solid)
		)
		(fill yes)
		(layer "In4.Cu")
		(net "M_D_CPU0_CLK_DN<0>")
	)
	(gr_poly
		(pts
			(xy 338.201254 -255.216152) (xy 338.101178 -255.116076) (xy 338.001102 -255.216152) (xy 338.001102 -255.260602)
			(xy 338.201254 -255.260602)
		)
		(stroke
			(width 0)
			(type solid)
		)
		(fill yes)
		(layer "In4.Cu")
		(net "M_D_CPU0_SA_CA<6>")
	)
	(gr_poly
		(pts
			(xy 338.201254 -254.812292) (xy 338.201254 -254.767842) (xy 338.001102 -254.767842) (xy 338.001102 -254.812292)
			(xy 338.101178 -254.912368)
		)
		(stroke
			(width 0)
			(type solid)
		)
		(fill yes)
		(layer "In4.Cu")
		(net "M_D_CPU0_SA_CA<5>")
	)
	(gr_poly
		(pts
			(xy 338.201254 -253.59614) (xy 338.101178 -253.496064) (xy 338.001102 -253.59614) (xy 338.001102 -253.64059)
			(xy 338.201254 -253.64059)
		)
		(stroke
			(width 0)
			(type solid)
		)
		(fill yes)
		(layer "In4.Cu")
		(net "M_D_CPU0_SA_CA<2>")
	)
	(gr_poly
		(pts
			(xy 338.201254 -253.19228) (xy 338.201254 -253.14783) (xy 338.001102 -253.14783) (xy 338.001102 -253.19228)
			(xy 338.101178 -253.292356)
		)
		(stroke
			(width 0)
			(type solid)
		)
		(fill yes)
		(layer "In4.Cu")
		(net "M_D_CPU0_SA_CA<1>")
	)
	(gr_poly
		(pts
			(xy 338.201254 -251.572268) (xy 338.201254 -251.527818) (xy 338.001102 -251.527818) (xy 338.001102 -251.572268)
			(xy 338.101178 -251.672344)
		)
		(stroke
			(width 0)
			(type solid)
		)
		(fill yes)
		(layer "In4.Cu")
		(net "M_D_CPU0_SA_CS_N<0>")
	)
	(gr_poly
		(pts
			(xy 338.201254 -250.356116) (xy 338.101178 -250.25604) (xy 338.001102 -250.356116) (xy 338.001102 -250.400566)
			(xy 338.201254 -250.400566)
		)
		(stroke
			(width 0)
			(type solid)
		)
		(fill yes)
		(layer "In4.Cu")
		(net "M_D_CPU0_ALERT_R_N")
	)
	(gr_poly
		(pts
			(xy 338.201254 -248.736104) (xy 338.101178 -248.636028) (xy 338.001102 -248.736104) (xy 338.001102 -248.780554)
			(xy 338.201254 -248.780554)
		)
		(stroke
			(width 0)
			(type solid)
		)
		(fill yes)
		(layer "In4.Cu")
		(net "M_D_CPU0_SA_CB<5>")
	)
	(gr_poly
		(pts
			(xy 338.201254 -248.332244) (xy 338.201254 -248.287794) (xy 338.001102 -248.287794) (xy 338.001102 -248.332244)
			(xy 338.101178 -248.43232)
		)
		(stroke
			(width 0)
			(type solid)
		)
		(fill yes)
		(layer "In4.Cu")
		(net "M_D_CPU0_SA_CB<6>")
	)
	(gr_poly
		(pts
			(xy 338.201254 -247.115838) (xy 338.101178 -247.016016) (xy 338.001102 -247.115838) (xy 338.001102 -247.16359)
			(xy 338.201254 -247.16359)
		)
		(stroke
			(width 0)
			(type solid)
		)
		(fill yes)
		(layer "In4.Cu")
		(net "M_D_CPU0_SA_DQS_DN<9>")
	)
	(gr_poly
		(pts
			(xy 338.201254 -246.712486) (xy 338.201254 -246.664734) (xy 338.001102 -246.664734) (xy 338.001102 -246.712486)
			(xy 338.101178 -246.812308)
		)
		(stroke
			(width 0)
			(type solid)
		)
		(fill yes)
		(layer "In4.Cu")
		(net "M_D_CPU0_SA_DQS_DN<4>")
	)
	(gr_poly
		(pts
			(xy 338.201254 -245.49608) (xy 338.101178 -245.396004) (xy 338.001102 -245.49608) (xy 338.001102 -245.54053)
			(xy 338.201254 -245.54053)
		)
		(stroke
			(width 0)
			(type solid)
		)
		(fill yes)
		(layer "In4.Cu")
		(net "M_D_CPU0_SA_CB<1>")
	)
	(gr_poly
		(pts
			(xy 338.201254 -245.09222) (xy 338.201254 -245.04777) (xy 338.001102 -245.04777) (xy 338.001102 -245.09222)
			(xy 338.101178 -245.192296)
		)
		(stroke
			(width 0)
			(type solid)
		)
		(fill yes)
		(layer "In4.Cu")
		(net "M_D_CPU0_SA_CB<2>")
	)
	(gr_poly
		(pts
			(xy 338.201254 -243.876068) (xy 338.101178 -243.775992) (xy 338.001102 -243.876068) (xy 338.001102 -243.920518)
			(xy 338.201254 -243.920518)
		)
		(stroke
			(width 0)
			(type solid)
		)
		(fill yes)
		(layer "In4.Cu")
		(net "M_D_CPU0_SA_DQ<29>")
	)
	(gr_poly
		(pts
			(xy 338.201254 -243.472208) (xy 338.201254 -243.427758) (xy 338.001102 -243.427758) (xy 338.001102 -243.472208)
			(xy 338.101178 -243.572284)
		)
		(stroke
			(width 0)
			(type solid)
		)
		(fill yes)
		(layer "In4.Cu")
		(net "M_D_CPU0_SA_DQ<30>")
	)
	(gr_poly
		(pts
			(xy 338.201254 -242.255802) (xy 338.101178 -242.15598) (xy 338.001102 -242.255802) (xy 338.001102 -242.303554)
			(xy 338.201254 -242.303554)
		)
		(stroke
			(width 0)
			(type solid)
		)
		(fill yes)
		(layer "In4.Cu")
		(net "M_D_CPU0_SA_DQS_DN<8>")
	)
	(gr_poly
		(pts
			(xy 338.201254 -241.85245) (xy 338.201254 -241.804698) (xy 338.001102 -241.804698) (xy 338.001102 -241.85245)
			(xy 338.101178 -241.952272)
		)
		(stroke
			(width 0)
			(type solid)
		)
		(fill yes)
		(layer "In4.Cu")
		(net "M_D_CPU0_SA_DQS_DN<3>")
	)
	(gr_poly
		(pts
			(xy 338.201254 -240.636044) (xy 338.101178 -240.535968) (xy 338.001102 -240.636044) (xy 338.001102 -240.680494)
			(xy 338.201254 -240.680494)
		)
		(stroke
			(width 0)
			(type solid)
		)
		(fill yes)
		(layer "In4.Cu")
		(net "M_D_CPU0_SA_DQ<25>")
	)
	(gr_poly
		(pts
			(xy 338.201254 -240.232184) (xy 338.201254 -240.187734) (xy 338.001102 -240.187734) (xy 338.001102 -240.232184)
			(xy 338.101178 -240.33226)
		)
		(stroke
			(width 0)
			(type solid)
		)
		(fill yes)
		(layer "In4.Cu")
		(net "M_D_CPU0_SA_DQ<26>")
	)
	(gr_poly
		(pts
			(xy 338.201254 -239.016032) (xy 338.101178 -238.915956) (xy 338.001102 -239.016032) (xy 338.001102 -239.060482)
			(xy 338.201254 -239.060482)
		)
		(stroke
			(width 0)
			(type solid)
		)
		(fill yes)
		(layer "In4.Cu")
		(net "M_D_CPU0_SA_DQ<21>")
	)
	(gr_poly
		(pts
			(xy 338.201254 -238.612172) (xy 338.201254 -238.567722) (xy 338.001102 -238.567722) (xy 338.001102 -238.612172)
			(xy 338.101178 -238.712248)
		)
		(stroke
			(width 0)
			(type solid)
		)
		(fill yes)
		(layer "In4.Cu")
		(net "M_D_CPU0_SA_DQ<22>")
	)
	(gr_poly
		(pts
			(xy 338.201254 -237.395766) (xy 338.101178 -237.295944) (xy 338.001102 -237.395766) (xy 338.001102 -237.443518)
			(xy 338.201254 -237.443518)
		)
		(stroke
			(width 0)
			(type solid)
		)
		(fill yes)
		(layer "In4.Cu")
		(net "M_D_CPU0_SA_DQS_DN<7>")
	)
	(gr_poly
		(pts
			(xy 338.201254 -236.992414) (xy 338.201254 -236.944662) (xy 338.001102 -236.944662) (xy 338.001102 -236.992414)
			(xy 338.101178 -237.092236)
		)
		(stroke
			(width 0)
			(type solid)
		)
		(fill yes)
		(layer "In4.Cu")
		(net "M_D_CPU0_SA_DQS_DN<2>")
	)
	(gr_poly
		(pts
			(xy 338.201254 -235.776008) (xy 338.101178 -235.675932) (xy 338.001102 -235.776008) (xy 338.001102 -235.820458)
			(xy 338.201254 -235.820458)
		)
		(stroke
			(width 0)
			(type solid)
		)
		(fill yes)
		(layer "In4.Cu")
		(net "M_D_CPU0_SA_DQ<17>")
	)
	(gr_poly
		(pts
			(xy 338.201254 -235.372148) (xy 338.201254 -235.327698) (xy 338.001102 -235.327698) (xy 338.001102 -235.372148)
			(xy 338.101178 -235.472224)
		)
		(stroke
			(width 0)
			(type solid)
		)
		(fill yes)
		(layer "In4.Cu")
		(net "M_D_CPU0_SA_DQ<18>")
	)
	(gr_poly
		(pts
			(xy 338.201254 -234.155996) (xy 338.101178 -234.05592) (xy 338.001102 -234.155996) (xy 338.001102 -234.200446)
			(xy 338.201254 -234.200446)
		)
		(stroke
			(width 0)
			(type solid)
		)
		(fill yes)
		(layer "In4.Cu")
		(net "M_D_CPU0_SA_DQ<13>")
	)
	(gr_poly
		(pts
			(xy 338.201254 -233.752136) (xy 338.201254 -233.707686) (xy 338.001102 -233.707686) (xy 338.001102 -233.752136)
			(xy 338.101178 -233.852212)
		)
		(stroke
			(width 0)
			(type solid)
		)
		(fill yes)
		(layer "In4.Cu")
		(net "M_D_CPU0_SA_DQ<14>")
	)
	(gr_poly
		(pts
			(xy 338.201254 -232.53573) (xy 338.101178 -232.435908) (xy 338.001102 -232.53573) (xy 338.001102 -232.583482)
			(xy 338.201254 -232.583482)
		)
		(stroke
			(width 0)
			(type solid)
		)
		(fill yes)
		(layer "In4.Cu")
		(net "M_D_CPU0_SA_DQS_DN<6>")
	)
	(gr_poly
		(pts
			(xy 338.201254 -232.132378) (xy 338.201254 -232.084626) (xy 338.001102 -232.084626) (xy 338.001102 -232.132378)
			(xy 338.101178 -232.2322)
		)
		(stroke
			(width 0)
			(type solid)
		)
		(fill yes)
		(layer "In4.Cu")
		(net "M_D_CPU0_SA_DQS_DN<1>")
	)
	(gr_poly
		(pts
			(xy 338.201254 -230.915972) (xy 338.101178 -230.815896) (xy 338.001102 -230.915972) (xy 338.001102 -230.960422)
			(xy 338.201254 -230.960422)
		)
		(stroke
			(width 0)
			(type solid)
		)
		(fill yes)
		(layer "In4.Cu")
		(net "M_D_CPU0_SA_DQ<9>")
	)
	(gr_poly
		(pts
			(xy 338.201254 -230.512366) (xy 338.201254 -230.467916) (xy 338.001102 -230.467916) (xy 338.001102 -230.512366)
			(xy 338.101178 -230.612188)
		)
		(stroke
			(width 0)
			(type solid)
		)
		(fill yes)
		(layer "In4.Cu")
		(net "M_D_CPU0_SA_DQ<10>")
	)
	(gr_poly
		(pts
			(xy 338.201254 -229.29596) (xy 338.101178 -229.195884) (xy 338.001102 -229.29596) (xy 338.001102 -229.34041)
			(xy 338.201254 -229.34041)
		)
		(stroke
			(width 0)
			(type solid)
		)
		(fill yes)
		(layer "In4.Cu")
		(net "M_D_CPU0_SA_DQ<5>")
	)
	(gr_poly
		(pts
			(xy 338.201254 -228.892354) (xy 338.201254 -228.847904) (xy 338.001102 -228.847904) (xy 338.001102 -228.892354)
			(xy 338.101178 -228.99243)
		)
		(stroke
			(width 0)
			(type solid)
		)
		(fill yes)
		(layer "In4.Cu")
		(net "M_D_CPU0_SA_DQ<6>")
	)
	(gr_poly
		(pts
			(xy 338.201254 -227.272596) (xy 338.201254 -227.224844) (xy 338.001102 -227.224844) (xy 338.001102 -227.272596)
			(xy 338.101178 -227.372418)
		)
		(stroke
			(width 0)
			(type solid)
		)
		(fill yes)
		(layer "In4.Cu")
		(net "M_D_CPU0_SA_DQS_DN<0>")
	)
	(gr_poly
		(pts
			(xy 338.201254 -226.05619) (xy 338.101178 -225.956114) (xy 338.001102 -226.05619) (xy 338.001102 -226.10064)
			(xy 338.201254 -226.10064)
		)
		(stroke
			(width 0)
			(type solid)
		)
		(fill yes)
		(layer "In4.Cu")
		(net "M_D_CPU0_SA_DQ<1>")
	)
	(gr_poly
		(pts
			(xy 338.201254 -225.65233) (xy 338.201254 -225.60788) (xy 338.001102 -225.60788) (xy 338.001102 -225.65233)
			(xy 338.101178 -225.752406)
		)
		(stroke
			(width 0)
			(type solid)
		)
		(fill yes)
		(layer "In4.Cu")
		(net "M_D_CPU0_SA_DQ<2>")
	)
	(gr_poly
		(pts
			(xy 338.461604 -293.331646) (xy 338.465414 -293.287196) (xy 338.266278 -293.269924) (xy 338.262468 -293.31412)
			(xy 338.3534 -293.422578)
		)
		(stroke
			(width 0)
			(type solid)
		)
		(fill yes)
		(layer "In4.Cu")
		(net "M_D_CPU0_SB_DQ<31>")
	)
	(gr_poly
		(pts
			(xy 338.494878 -267.801598) (xy 338.394802 -267.701522) (xy 338.29498 -267.801598) (xy 338.29498 -267.846048)
			(xy 338.494878 -267.846048)
		)
		(stroke
			(width 0)
			(type solid)
		)
		(fill yes)
		(layer "In4.Cu")
		(net "M_D_CPU0_SB_RSP<0>")
	)
	(gr_poly
		(pts
			(xy 338.501228 -292.107874) (xy 338.401152 -292.007798) (xy 338.301076 -292.107874) (xy 338.301076 -292.152324)
			(xy 338.501228 -292.152324)
		)
		(stroke
			(width 0)
			(type solid)
		)
		(fill yes)
		(layer "In4.Cu")
		(net "M_D_CPU0_SB_DQ<28>")
	)
	(gr_poly
		(pts
			(xy 338.501228 -291.704268) (xy 338.501228 -291.656516) (xy 338.301076 -291.656516) (xy 338.301076 -291.704268)
			(xy 338.401152 -291.80409)
		)
		(stroke
			(width 0)
			(type solid)
		)
		(fill yes)
		(layer "In4.Cu")
		(net "M_D_CPU0_SB_DQS_DP<8>")
	)
	(gr_poly
		(pts
			(xy 338.501228 -290.487608) (xy 338.401152 -290.387786) (xy 338.301076 -290.487608) (xy 338.301076 -290.53536)
			(xy 338.501228 -290.53536)
		)
		(stroke
			(width 0)
			(type solid)
		)
		(fill yes)
		(layer "In4.Cu")
		(net "M_D_CPU0_SB_DQS_DP<3>")
	)
	(gr_poly
		(pts
			(xy 338.501228 -290.084002) (xy 338.501228 -290.039552) (xy 338.301076 -290.039552) (xy 338.301076 -290.084002)
			(xy 338.401152 -290.184078)
		)
		(stroke
			(width 0)
			(type solid)
		)
		(fill yes)
		(layer "In4.Cu")
		(net "M_D_CPU0_SB_DQ<27>")
	)
	(gr_poly
		(pts
			(xy 338.501228 -288.86785) (xy 338.401152 -288.767774) (xy 338.301076 -288.86785) (xy 338.301076 -288.9123)
			(xy 338.501228 -288.9123)
		)
		(stroke
			(width 0)
			(type solid)
		)
		(fill yes)
		(layer "In4.Cu")
		(net "M_D_CPU0_SB_DQ<24>")
	)
	(gr_poly
		(pts
			(xy 338.501228 -288.464244) (xy 338.501228 -288.419794) (xy 338.301076 -288.419794) (xy 338.301076 -288.464244)
			(xy 338.401152 -288.56432)
		)
		(stroke
			(width 0)
			(type solid)
		)
		(fill yes)
		(layer "In4.Cu")
		(net "M_D_CPU0_SB_DQ<23>")
	)
	(gr_poly
		(pts
			(xy 338.501228 -287.247838) (xy 338.401152 -287.148016) (xy 338.301076 -287.247838) (xy 338.301076 -287.292288)
			(xy 338.501228 -287.292288)
		)
		(stroke
			(width 0)
			(type solid)
		)
		(fill yes)
		(layer "In4.Cu")
		(net "M_D_CPU0_SB_DQ<20>")
	)
	(gr_poly
		(pts
			(xy 338.501228 -286.844232) (xy 338.501228 -286.79648) (xy 338.301076 -286.79648) (xy 338.301076 -286.844232)
			(xy 338.401152 -286.944308)
		)
		(stroke
			(width 0)
			(type solid)
		)
		(fill yes)
		(layer "In4.Cu")
		(net "M_D_CPU0_SB_DQS_DP<7>")
	)
	(gr_poly
		(pts
			(xy 338.501228 -285.627826) (xy 338.401152 -285.528004) (xy 338.301076 -285.627826) (xy 338.301076 -285.675578)
			(xy 338.501228 -285.675578)
		)
		(stroke
			(width 0)
			(type solid)
		)
		(fill yes)
		(layer "In4.Cu")
		(net "M_D_CPU0_SB_DQS_DP<2>")
	)
	(gr_poly
		(pts
			(xy 338.501228 -285.22422) (xy 338.501228 -285.17977) (xy 338.301076 -285.17977) (xy 338.301076 -285.22422)
			(xy 338.401152 -285.324296)
		)
		(stroke
			(width 0)
			(type solid)
		)
		(fill yes)
		(layer "In4.Cu")
		(net "M_D_CPU0_SB_DQ<19>")
	)
	(gr_poly
		(pts
			(xy 338.501228 -284.008068) (xy 338.401152 -283.907992) (xy 338.301076 -284.008068) (xy 338.301076 -284.052518)
			(xy 338.501228 -284.052518)
		)
		(stroke
			(width 0)
			(type solid)
		)
		(fill yes)
		(layer "In4.Cu")
		(net "M_D_CPU0_SB_DQ<16>")
	)
	(gr_poly
		(pts
			(xy 338.501228 -283.604208) (xy 338.501228 -283.559758) (xy 338.301076 -283.559758) (xy 338.301076 -283.604208)
			(xy 338.401152 -283.704284)
		)
		(stroke
			(width 0)
			(type solid)
		)
		(fill yes)
		(layer "In4.Cu")
		(net "M_D_CPU0_SB_DQ<15>")
	)
	(gr_poly
		(pts
			(xy 338.501228 -282.388056) (xy 338.401152 -282.28798) (xy 338.301076 -282.388056) (xy 338.301076 -282.432506)
			(xy 338.501228 -282.432506)
		)
		(stroke
			(width 0)
			(type solid)
		)
		(fill yes)
		(layer "In4.Cu")
		(net "M_D_CPU0_SB_DQ<12>")
	)
	(gr_poly
		(pts
			(xy 338.501228 -281.98445) (xy 338.501228 -281.936698) (xy 338.301076 -281.936698) (xy 338.301076 -281.98445)
			(xy 338.401152 -282.084272)
		)
		(stroke
			(width 0)
			(type solid)
		)
		(fill yes)
		(layer "In4.Cu")
		(net "M_D_CPU0_SB_DQS_DP<6>")
	)
	(gr_poly
		(pts
			(xy 338.501228 -280.76779) (xy 338.401152 -280.667968) (xy 338.301076 -280.76779) (xy 338.301076 -280.815542)
			(xy 338.501228 -280.815542)
		)
		(stroke
			(width 0)
			(type solid)
		)
		(fill yes)
		(layer "In4.Cu")
		(net "M_D_CPU0_SB_DQS_DP<1>")
	)
	(gr_poly
		(pts
			(xy 338.501228 -280.364184) (xy 338.501228 -280.319734) (xy 338.301076 -280.319734) (xy 338.301076 -280.364184)
			(xy 338.401152 -280.46426)
		)
		(stroke
			(width 0)
			(type solid)
		)
		(fill yes)
		(layer "In4.Cu")
		(net "M_D_CPU0_SB_DQ<11>")
	)
	(gr_poly
		(pts
			(xy 338.501228 -279.148032) (xy 338.401152 -279.047956) (xy 338.301076 -279.148032) (xy 338.301076 -279.192482)
			(xy 338.501228 -279.192482)
		)
		(stroke
			(width 0)
			(type solid)
		)
		(fill yes)
		(layer "In4.Cu")
		(net "M_D_CPU0_SB_DQ<8>")
	)
	(gr_poly
		(pts
			(xy 338.501228 -278.744172) (xy 338.501228 -278.699722) (xy 338.301076 -278.699722) (xy 338.301076 -278.744172)
			(xy 338.401152 -278.844248)
		)
		(stroke
			(width 0)
			(type solid)
		)
		(fill yes)
		(layer "In4.Cu")
		(net "M_D_CPU0_SB_DQ<7>")
	)
	(gr_poly
		(pts
			(xy 338.501228 -277.52802) (xy 338.401152 -277.427944) (xy 338.301076 -277.52802) (xy 338.301076 -277.57247)
			(xy 338.501228 -277.57247)
		)
		(stroke
			(width 0)
			(type solid)
		)
		(fill yes)
		(layer "In4.Cu")
		(net "M_D_CPU0_SB_DQ<4>")
	)
	(gr_poly
		(pts
			(xy 338.501228 -277.12416) (xy 338.501228 -277.076662) (xy 338.301076 -277.076662) (xy 338.301076 -277.12416)
			(xy 338.401152 -277.224236)
		)
		(stroke
			(width 0)
			(type solid)
		)
		(fill yes)
		(layer "In4.Cu")
		(net "M_D_CPU0_SB_DQS_DP<5>")
	)
	(gr_poly
		(pts
			(xy 338.501228 -275.908008) (xy 338.401152 -275.807932) (xy 338.301076 -275.908008) (xy 338.301076 -275.955506)
			(xy 338.501228 -275.955506)
		)
		(stroke
			(width 0)
			(type solid)
		)
		(fill yes)
		(layer "In4.Cu")
		(net "M_D_CPU0_SB_DQS_DP<0>")
	)
	(gr_poly
		(pts
			(xy 338.501228 -275.504148) (xy 338.501228 -275.459698) (xy 338.301076 -275.459698) (xy 338.301076 -275.504148)
			(xy 338.401152 -275.604224)
		)
		(stroke
			(width 0)
			(type solid)
		)
		(fill yes)
		(layer "In4.Cu")
		(net "M_D_CPU0_SB_DQ<3>")
	)
	(gr_poly
		(pts
			(xy 338.501228 -274.287996) (xy 338.401152 -274.18792) (xy 338.301076 -274.287996) (xy 338.301076 -274.332446)
			(xy 338.501228 -274.332446)
		)
		(stroke
			(width 0)
			(type solid)
		)
		(fill yes)
		(layer "In4.Cu")
		(net "M_D_CPU0_SB_DQ<0>")
	)
	(gr_poly
		(pts
			(xy 338.501228 -273.884136) (xy 338.501228 -273.839686) (xy 338.301076 -273.839686) (xy 338.301076 -273.884136)
			(xy 338.401152 -273.984212)
		)
		(stroke
			(width 0)
			(type solid)
		)
		(fill yes)
		(layer "In4.Cu")
		(net "M_D_CPU0_SB_CB<3>")
	)
	(gr_poly
		(pts
			(xy 338.501228 -272.667984) (xy 338.401152 -272.567908) (xy 338.301076 -272.667984) (xy 338.301076 -272.712434)
			(xy 338.501228 -272.712434)
		)
		(stroke
			(width 0)
			(type solid)
		)
		(fill yes)
		(layer "In4.Cu")
		(net "M_D_CPU0_SB_CB<0>")
	)
	(gr_poly
		(pts
			(xy 338.501228 -272.264378) (xy 338.501228 -272.216626) (xy 338.301076 -272.216626) (xy 338.301076 -272.264378)
			(xy 338.401152 -272.3642)
		)
		(stroke
			(width 0)
			(type solid)
		)
		(fill yes)
		(layer "In4.Cu")
		(net "M_D_CPU0_SB_DQS_DP<4>")
	)
	(gr_poly
		(pts
			(xy 338.501228 -271.047718) (xy 338.401152 -270.947896) (xy 338.301076 -271.047718) (xy 338.301076 -271.09547)
			(xy 338.501228 -271.09547)
		)
		(stroke
			(width 0)
			(type solid)
		)
		(fill yes)
		(layer "In4.Cu")
		(net "M_D_CPU0_SB_DQS_DP<9>")
	)
	(gr_poly
		(pts
			(xy 338.501228 -270.644112) (xy 338.501228 -270.599662) (xy 338.301076 -270.599662) (xy 338.301076 -270.644112)
			(xy 338.401152 -270.744188)
		)
		(stroke
			(width 0)
			(type solid)
		)
		(fill yes)
		(layer "In4.Cu")
		(net "M_D_CPU0_SB_CB<7>")
	)
	(gr_poly
		(pts
			(xy 338.501228 -269.42796) (xy 338.401152 -269.327884) (xy 338.301076 -269.42796) (xy 338.301076 -269.47241)
			(xy 338.501228 -269.47241)
		)
		(stroke
			(width 0)
			(type solid)
		)
		(fill yes)
		(layer "In4.Cu")
		(net "M_D_CPU0_SB_CB<4>")
	)
	(gr_poly
		(pts
			(xy 338.501228 -265.784076) (xy 338.501228 -265.739626) (xy 338.301076 -265.739626) (xy 338.301076 -265.784076)
			(xy 338.401152 -265.884152)
		)
		(stroke
			(width 0)
			(type solid)
		)
		(fill yes)
		(layer "In4.Cu")
		(net "M_D_CPU0_SB_CS_N<0>")
	)
	(gr_poly
		(pts
			(xy 338.501228 -264.567924) (xy 338.401152 -264.467848) (xy 338.301076 -264.567924) (xy 338.301076 -264.612374)
			(xy 338.501228 -264.612374)
		)
		(stroke
			(width 0)
			(type solid)
		)
		(fill yes)
		(layer "In4.Cu")
		(net "M_D_CPU0_SB_CA<6>")
	)
	(gr_poly
		(pts
			(xy 338.501228 -264.164064) (xy 338.501228 -264.119614) (xy 338.301076 -264.119614) (xy 338.301076 -264.164064)
			(xy 338.401152 -264.26414)
		)
		(stroke
			(width 0)
			(type solid)
		)
		(fill yes)
		(layer "In4.Cu")
		(net "M_D_CPU0_SB_CA<5>")
	)
	(gr_poly
		(pts
			(xy 338.501228 -262.947912) (xy 338.401152 -262.847836) (xy 338.301076 -262.947912) (xy 338.301076 -262.992362)
			(xy 338.501228 -262.992362)
		)
		(stroke
			(width 0)
			(type solid)
		)
		(fill yes)
		(layer "In4.Cu")
		(net "M_D_CPU0_SB_CA<2>")
	)
	(gr_poly
		(pts
			(xy 338.501228 -262.544052) (xy 338.501228 -262.499602) (xy 338.301076 -262.499602) (xy 338.301076 -262.544052)
			(xy 338.401152 -262.644128)
		)
		(stroke
			(width 0)
			(type solid)
		)
		(fill yes)
		(layer "In4.Cu")
		(net "M_D_CPU0_SB_CA<1>")
	)
	(gr_poly
		(pts
			(xy 338.623148 -246.346726) (xy 338.61883 -246.299228) (xy 338.510626 -246.208296) (xy 338.419694 -246.316754)
			(xy 338.423758 -246.364252)
		)
		(stroke
			(width 0)
			(type solid)
		)
		(fill yes)
		(layer "In4.Cu")
		(net "M_D_CPU0_SA_DQS_DP<4>")
	)
	(gr_poly
		(pts
			(xy 338.623148 -241.48669) (xy 338.61883 -241.439192) (xy 338.510626 -241.34826) (xy 338.419694 -241.456718)
			(xy 338.423758 -241.504216)
		)
		(stroke
			(width 0)
			(type solid)
		)
		(fill yes)
		(layer "In4.Cu")
		(net "M_D_CPU0_SA_DQS_DP<3>")
	)
	(gr_poly
		(pts
			(xy 338.623148 -236.626654) (xy 338.61883 -236.579156) (xy 338.510626 -236.488224) (xy 338.419694 -236.596682)
			(xy 338.423758 -236.64418)
		)
		(stroke
			(width 0)
			(type solid)
		)
		(fill yes)
		(layer "In4.Cu")
		(net "M_D_CPU0_SA_DQS_DP<2>")
	)
	(gr_poly
		(pts
			(xy 338.623148 -231.766618) (xy 338.61883 -231.71912) (xy 338.510626 -231.628188) (xy 338.419694 -231.736646)
			(xy 338.423758 -231.784144)
		)
		(stroke
			(width 0)
			(type solid)
		)
		(fill yes)
		(layer "In4.Cu")
		(net "M_D_CPU0_SA_DQS_DP<1>")
	)
	(gr_poly
		(pts
			(xy 338.623148 -226.906836) (xy 338.61883 -226.859338) (xy 338.510626 -226.768406) (xy 338.419694 -226.876864)
			(xy 338.423758 -226.924108)
		)
		(stroke
			(width 0)
			(type solid)
		)
		(fill yes)
		(layer "In4.Cu")
		(net "M_D_CPU0_SA_DQS_DP<0>")
	)
	(gr_poly
		(pts
			(xy 338.633562 -256.066036) (xy 338.629498 -256.018538) (xy 338.521294 -255.927606) (xy 338.430362 -256.036064)
			(xy 338.434426 -256.083308)
		)
		(stroke
			(width 0)
			(type solid)
		)
		(fill yes)
		(layer "In4.Cu")
		(net "M_D_CPU0_CLK_DP<0>")
	)
	(gr_poly
		(pts
			(xy 338.63534 -233.38282) (xy 338.63153 -233.33837) (xy 338.523072 -233.247438) (xy 338.432394 -233.355896)
			(xy 338.436204 -233.400092)
		)
		(stroke
			(width 0)
			(type solid)
		)
		(fill yes)
		(layer "In4.Cu")
		(net "M_D_CPU0_SA_DQ<12>")
	)
	(gr_poly
		(pts
			(xy 338.635594 -254.442976) (xy 338.63153 -254.398526) (xy 338.523326 -254.307594) (xy 338.432394 -254.416052)
			(xy 338.436204 -254.460248)
		)
		(stroke
			(width 0)
			(type solid)
		)
		(fill yes)
		(layer "In4.Cu")
		(net "M_D_CPU0_SA_CA<4>")
	)
	(gr_poly
		(pts
			(xy 338.635594 -252.822964) (xy 338.63153 -252.778514) (xy 338.523326 -252.687582) (xy 338.432394 -252.79604)
			(xy 338.436204 -252.840236)
		)
		(stroke
			(width 0)
			(type solid)
		)
		(fill yes)
		(layer "In4.Cu")
		(net "M_D_CPU0_SA_CA<0>")
	)
	(gr_poly
		(pts
			(xy 338.635594 -247.962928) (xy 338.63153 -247.918478) (xy 338.523326 -247.827546) (xy 338.432394 -247.936004)
			(xy 338.436204 -247.9802)
		)
		(stroke
			(width 0)
			(type solid)
		)
		(fill yes)
		(layer "In4.Cu")
		(net "M_D_CPU0_SA_CB<4>")
	)
	(gr_poly
		(pts
			(xy 338.635594 -244.722904) (xy 338.63153 -244.678454) (xy 338.523326 -244.587522) (xy 338.432394 -244.69598)
			(xy 338.436204 -244.740176)
		)
		(stroke
			(width 0)
			(type solid)
		)
		(fill yes)
		(layer "In4.Cu")
		(net "M_D_CPU0_SA_CB<0>")
	)
	(gr_poly
		(pts
			(xy 338.635594 -243.102892) (xy 338.63153 -243.058442) (xy 338.523326 -242.96751) (xy 338.432394 -243.075968)
			(xy 338.436204 -243.120164)
		)
		(stroke
			(width 0)
			(type solid)
		)
		(fill yes)
		(layer "In4.Cu")
		(net "M_D_CPU0_SA_DQ<28>")
	)
	(gr_poly
		(pts
			(xy 338.635594 -239.862868) (xy 338.63153 -239.818418) (xy 338.523326 -239.727486) (xy 338.432394 -239.835944)
			(xy 338.436204 -239.88014)
		)
		(stroke
			(width 0)
			(type solid)
		)
		(fill yes)
		(layer "In4.Cu")
		(net "M_D_CPU0_SA_DQ<24>")
	)
	(gr_poly
		(pts
			(xy 338.635594 -238.242856) (xy 338.63153 -238.198406) (xy 338.523326 -238.107474) (xy 338.432394 -238.215932)
			(xy 338.436204 -238.260128)
		)
		(stroke
			(width 0)
			(type solid)
		)
		(fill yes)
		(layer "In4.Cu")
		(net "M_D_CPU0_SA_DQ<20>")
	)
	(gr_poly
		(pts
			(xy 338.635594 -235.002832) (xy 338.63153 -234.958382) (xy 338.523326 -234.86745) (xy 338.432394 -234.975908)
			(xy 338.436204 -235.020104)
		)
		(stroke
			(width 0)
			(type solid)
		)
		(fill yes)
		(layer "In4.Cu")
		(net "M_D_CPU0_SA_DQ<16>")
	)
	(gr_poly
		(pts
			(xy 338.635594 -230.142796) (xy 338.63153 -230.098346) (xy 338.523326 -230.007668) (xy 338.432394 -230.115872)
			(xy 338.436204 -230.160068)
		)
		(stroke
			(width 0)
			(type solid)
		)
		(fill yes)
		(layer "In4.Cu")
		(net "M_D_CPU0_SA_DQ<8>")
	)
	(gr_poly
		(pts
			(xy 338.635594 -228.523038) (xy 338.63153 -228.478588) (xy 338.523326 -228.387656) (xy 338.432394 -228.496114)
			(xy 338.436204 -228.54031)
		)
		(stroke
			(width 0)
			(type solid)
		)
		(fill yes)
		(layer "In4.Cu")
		(net "M_D_CPU0_SA_DQ<4>")
	)
	(gr_poly
		(pts
			(xy 338.635594 -225.283014) (xy 338.63153 -225.238564) (xy 338.523326 -225.147632) (xy 338.432394 -225.25609)
			(xy 338.436204 -225.300286)
		)
		(stroke
			(width 0)
			(type solid)
		)
		(fill yes)
		(layer "In4.Cu")
		(net "M_D_CPU0_SA_DQ<0>")
	)
	(gr_poly
		(pts
			(xy 338.671154 -255.622298) (xy 338.671154 -255.577848) (xy 338.471002 -255.577848) (xy 338.471002 -255.622298)
			(xy 338.571078 -255.722374)
		)
		(stroke
			(width 0)
			(type solid)
		)
		(fill yes)
		(layer "In4.Cu")
		(net "M_D_CPU0_SA_PAR")
	)
	(gr_poly
		(pts
			(xy 338.671154 -254.002286) (xy 338.671154 -253.957836) (xy 338.471002 -253.957836) (xy 338.471002 -254.002286)
			(xy 338.571078 -254.102362)
		)
		(stroke
			(width 0)
			(type solid)
		)
		(fill yes)
		(layer "In4.Cu")
		(net "M_D_CPU0_SA_CA<3>")
	)
	(gr_poly
		(pts
			(xy 338.671154 -252.382274) (xy 338.671154 -252.337824) (xy 338.471002 -252.337824) (xy 338.471002 -252.382274)
			(xy 338.571078 -252.48235)
		)
		(stroke
			(width 0)
			(type solid)
		)
		(fill yes)
		(layer "In4.Cu")
		(net "M_D_CPU0_SA_CS_N<1>")
	)
	(gr_poly
		(pts
			(xy 338.671154 -250.762262) (xy 338.671154 -250.717812) (xy 338.471002 -250.717812) (xy 338.471002 -250.762262)
			(xy 338.571078 -250.862338)
		)
		(stroke
			(width 0)
			(type solid)
		)
		(fill yes)
		(layer "In4.Cu")
		(net "M_D_CPU0_RESET_N")
	)
	(gr_poly
		(pts
			(xy 338.671154 -249.14225) (xy 338.671154 -249.0978) (xy 338.471002 -249.0978) (xy 338.471002 -249.14225)
			(xy 338.571078 -249.242326)
		)
		(stroke
			(width 0)
			(type solid)
		)
		(fill yes)
		(layer "In4.Cu")
		(net "M_D_CPU0_SA_CB<7>")
	)
	(gr_poly
		(pts
			(xy 338.671154 -247.522492) (xy 338.671154 -247.47474) (xy 338.471002 -247.47474) (xy 338.471002 -247.522492)
			(xy 338.571078 -247.622314)
		)
		(stroke
			(width 0)
			(type solid)
		)
		(fill yes)
		(layer "In4.Cu")
		(net "M_D_CPU0_SA_DQS_DP<9>")
	)
	(gr_poly
		(pts
			(xy 338.671154 -245.902226) (xy 338.671154 -245.857776) (xy 338.471002 -245.857776) (xy 338.471002 -245.902226)
			(xy 338.571078 -246.002302)
		)
		(stroke
			(width 0)
			(type solid)
		)
		(fill yes)
		(layer "In4.Cu")
		(net "M_D_CPU0_SA_CB<3>")
	)
	(gr_poly
		(pts
			(xy 338.671154 -244.282214) (xy 338.671154 -244.237764) (xy 338.471002 -244.237764) (xy 338.471002 -244.282214)
			(xy 338.571078 -244.38229)
		)
		(stroke
			(width 0)
			(type solid)
		)
		(fill yes)
		(layer "In4.Cu")
		(net "M_D_CPU0_SA_DQ<31>")
	)
	(gr_poly
		(pts
			(xy 338.671154 -242.662456) (xy 338.671154 -242.614704) (xy 338.471002 -242.614704) (xy 338.471002 -242.662456)
			(xy 338.571078 -242.762278)
		)
		(stroke
			(width 0)
			(type solid)
		)
		(fill yes)
		(layer "In4.Cu")
		(net "M_D_CPU0_SA_DQS_DP<8>")
	)
	(gr_poly
		(pts
			(xy 338.671154 -241.04219) (xy 338.671154 -240.99774) (xy 338.471002 -240.99774) (xy 338.471002 -241.04219)
			(xy 338.571078 -241.142266)
		)
		(stroke
			(width 0)
			(type solid)
		)
		(fill yes)
		(layer "In4.Cu")
		(net "M_D_CPU0_SA_DQ<27>")
	)
	(gr_poly
		(pts
			(xy 338.671154 -239.422178) (xy 338.671154 -239.377728) (xy 338.471002 -239.377728) (xy 338.471002 -239.422178)
			(xy 338.571078 -239.522254)
		)
		(stroke
			(width 0)
			(type solid)
		)
		(fill yes)
		(layer "In4.Cu")
		(net "M_D_CPU0_SA_DQ<23>")
	)
	(gr_poly
		(pts
			(xy 338.671154 -237.80242) (xy 338.671154 -237.754668) (xy 338.471002 -237.754668) (xy 338.471002 -237.80242)
			(xy 338.571078 -237.902242)
		)
		(stroke
			(width 0)
			(type solid)
		)
		(fill yes)
		(layer "In4.Cu")
		(net "M_D_CPU0_SA_DQS_DP<7>")
	)
	(gr_poly
		(pts
			(xy 338.671154 -236.182154) (xy 338.671154 -236.137704) (xy 338.471002 -236.137704) (xy 338.471002 -236.182154)
			(xy 338.571078 -236.28223)
		)
		(stroke
			(width 0)
			(type solid)
		)
		(fill yes)
		(layer "In4.Cu")
		(net "M_D_CPU0_SA_DQ<19>")
	)
	(gr_poly
		(pts
			(xy 338.671154 -234.562142) (xy 338.671154 -234.517692) (xy 338.471002 -234.517692) (xy 338.471002 -234.562142)
			(xy 338.571078 -234.662218)
		)
		(stroke
			(width 0)
			(type solid)
		)
		(fill yes)
		(layer "In4.Cu")
		(net "M_D_CPU0_SA_DQ<15>")
	)
	(gr_poly
		(pts
			(xy 338.671154 -232.942384) (xy 338.671154 -232.894632) (xy 338.471002 -232.894632) (xy 338.471002 -232.942384)
			(xy 338.571078 -233.042206)
		)
		(stroke
			(width 0)
			(type solid)
		)
		(fill yes)
		(layer "In4.Cu")
		(net "M_D_CPU0_SA_DQS_DP<6>")
	)
	(gr_poly
		(pts
			(xy 338.671154 -231.322372) (xy 338.671154 -231.277922) (xy 338.471002 -231.277922) (xy 338.471002 -231.322372)
			(xy 338.571078 -231.422448)
		)
		(stroke
			(width 0)
			(type solid)
		)
		(fill yes)
		(layer "In4.Cu")
		(net "M_D_CPU0_SA_DQ<11>")
	)
	(gr_poly
		(pts
			(xy 338.671154 -229.70236) (xy 338.671154 -229.65791) (xy 338.471002 -229.65791) (xy 338.471002 -229.70236)
			(xy 338.571078 -229.802436)
		)
		(stroke
			(width 0)
			(type solid)
		)
		(fill yes)
		(layer "In4.Cu")
		(net "M_D_CPU0_SA_DQ<7>")
	)
	(gr_poly
		(pts
			(xy 338.671154 -228.082602) (xy 338.671154 -228.03485) (xy 338.471002 -228.03485) (xy 338.471002 -228.082602)
			(xy 338.571078 -228.182424)
		)
		(stroke
			(width 0)
			(type solid)
		)
		(fill yes)
		(layer "In4.Cu")
		(net "M_D_CPU0_SA_DQS_DP<5>")
	)
	(gr_poly
		(pts
			(xy 338.671154 -226.462336) (xy 338.671154 -226.417886) (xy 338.471002 -226.417886) (xy 338.471002 -226.462336)
			(xy 338.571078 -226.562412)
		)
		(stroke
			(width 0)
			(type solid)
		)
		(fill yes)
		(layer "In4.Cu")
		(net "M_D_CPU0_SA_DQ<3>")
	)
	(gr_poly
		(pts
			(xy 338.91855 -290.900866) (xy 338.922868 -290.853368) (xy 338.723478 -290.836096) (xy 338.719414 -290.88334)
			(xy 338.810346 -290.991798)
		)
		(stroke
			(width 0)
			(type solid)
		)
		(fill yes)
		(layer "In4.Cu")
		(net "M_D_CPU0_SB_DQS_DN<3>")
	)
	(gr_poly
		(pts
			(xy 338.91855 -286.041084) (xy 338.922868 -285.993586) (xy 338.723478 -285.97606) (xy 338.719414 -286.023558)
			(xy 338.810346 -286.132016)
		)
		(stroke
			(width 0)
			(type solid)
		)
		(fill yes)
		(layer "In4.Cu")
		(net "M_D_CPU0_SB_DQS_DN<2>")
	)
	(gr_poly
		(pts
			(xy 338.91855 -281.181048) (xy 338.922868 -281.13355) (xy 338.723478 -281.116024) (xy 338.719414 -281.163522)
			(xy 338.810346 -281.27198)
		)
		(stroke
			(width 0)
			(type solid)
		)
		(fill yes)
		(layer "In4.Cu")
		(net "M_D_CPU0_SB_DQS_DN<1>")
	)
	(gr_poly
		(pts
			(xy 338.91855 -276.321012) (xy 338.922614 -276.273514) (xy 338.723478 -276.256242) (xy 338.71916 -276.303486)
			(xy 338.810092 -276.411944)
		)
		(stroke
			(width 0)
			(type solid)
		)
		(fill yes)
		(layer "In4.Cu")
		(net "M_D_CPU0_SB_DQS_DN<0>")
	)
	(gr_poly
		(pts
			(xy 338.91855 -271.460976) (xy 338.922868 -271.413478) (xy 338.723478 -271.395952) (xy 338.719414 -271.44345)
			(xy 338.810346 -271.551908)
		)
		(stroke
			(width 0)
			(type solid)
		)
		(fill yes)
		(layer "In4.Cu")
		(net "M_D_CPU0_SB_DQS_DN<9>")
	)
	(gr_poly
		(pts
			(xy 338.931504 -292.52164) (xy 338.935314 -292.47719) (xy 338.736178 -292.459918) (xy 338.732114 -292.504114)
			(xy 338.823046 -292.612318)
		)
		(stroke
			(width 0)
			(type solid)
		)
		(fill yes)
		(layer "In4.Cu")
		(net "M_D_CPU0_SB_DQ<30>")
	)
	(gr_poly
		(pts
			(xy 338.931504 -289.281616) (xy 338.935314 -289.237166) (xy 338.736178 -289.219894) (xy 338.732114 -289.26409)
			(xy 338.823046 -289.372294)
		)
		(stroke
			(width 0)
			(type solid)
		)
		(fill yes)
		(layer "In4.Cu")
		(net "M_D_CPU0_SB_DQ<26>")
	)
	(gr_poly
		(pts
			(xy 338.931504 -287.661604) (xy 338.935314 -287.617408) (xy 338.736178 -287.600136) (xy 338.732114 -287.644332)
			(xy 338.823046 -287.752536)
		)
		(stroke
			(width 0)
			(type solid)
		)
		(fill yes)
		(layer "In4.Cu")
		(net "M_D_CPU0_SB_DQ<22>")
	)
	(gr_poly
		(pts
			(xy 338.931504 -284.42158) (xy 338.935314 -284.377384) (xy 338.736178 -284.360112) (xy 338.732114 -284.404308)
			(xy 338.823046 -284.512512)
		)
		(stroke
			(width 0)
			(type solid)
		)
		(fill yes)
		(layer "In4.Cu")
		(net "M_D_CPU0_SB_DQ<18>")
	)
	(gr_poly
		(pts
			(xy 338.931504 -282.801568) (xy 338.935314 -282.757372) (xy 338.736178 -282.7401) (xy 338.732114 -282.784296)
			(xy 338.823046 -282.8925)
		)
		(stroke
			(width 0)
			(type solid)
		)
		(fill yes)
		(layer "In4.Cu")
		(net "M_D_CPU0_SB_DQ<14>")
	)
	(gr_poly
		(pts
			(xy 338.931504 -279.561544) (xy 338.935314 -279.517348) (xy 338.736178 -279.500076) (xy 338.732114 -279.544272)
			(xy 338.823046 -279.652476)
		)
		(stroke
			(width 0)
			(type solid)
		)
		(fill yes)
		(layer "In4.Cu")
		(net "M_D_CPU0_SB_DQ<10>")
	)
	(gr_poly
		(pts
			(xy 338.931504 -277.941532) (xy 338.935314 -277.897336) (xy 338.736178 -277.880064) (xy 338.732114 -277.92426)
			(xy 338.823046 -278.032464)
		)
		(stroke
			(width 0)
			(type solid)
		)
		(fill yes)
		(layer "In4.Cu")
		(net "M_D_CPU0_SB_DQ<6>")
	)
	(gr_poly
		(pts
			(xy 338.931504 -274.701508) (xy 338.935314 -274.657312) (xy 338.736178 -274.64004) (xy 338.732114 -274.684236)
			(xy 338.823046 -274.79244)
		)
		(stroke
			(width 0)
			(type solid)
		)
		(fill yes)
		(layer "In4.Cu")
		(net "M_D_CPU0_SB_DQ<2>")
	)
	(gr_poly
		(pts
			(xy 338.931504 -273.081496) (xy 338.935314 -273.0373) (xy 338.736178 -273.020028) (xy 338.732114 -273.064224)
			(xy 338.823046 -273.172428)
		)
		(stroke
			(width 0)
			(type solid)
		)
		(fill yes)
		(layer "In4.Cu")
		(net "M_D_CPU0_SB_CB<2>")
	)
	(gr_poly
		(pts
			(xy 338.931504 -269.841472) (xy 338.935314 -269.797276) (xy 338.736178 -269.780004) (xy 338.732114 -269.8242)
			(xy 338.823046 -269.932404)
		)
		(stroke
			(width 0)
			(type solid)
		)
		(fill yes)
		(layer "In4.Cu")
		(net "M_D_CPU0_SB_CB<6>")
	)
	(gr_poly
		(pts
			(xy 338.931504 -266.601448) (xy 338.935314 -266.557252) (xy 338.736178 -266.53998) (xy 338.732114 -266.584176)
			(xy 338.823046 -266.69238)
		)
		(stroke
			(width 0)
			(type solid)
		)
		(fill yes)
		(layer "In4.Cu")
		(net "M_D_CPU0_SB_CS_N<1>")
	)
	(gr_poly
		(pts
			(xy 338.931504 -264.981436) (xy 338.935314 -264.93724) (xy 338.736178 -264.919968) (xy 338.732114 -264.964164)
			(xy 338.823046 -265.072368)
		)
		(stroke
			(width 0)
			(type solid)
		)
		(fill yes)
		(layer "In4.Cu")
		(net "M_D_CPU0_SB_PAR")
	)
	(gr_poly
		(pts
			(xy 338.931504 -263.361424) (xy 338.935314 -263.317228) (xy 338.736178 -263.299956) (xy 338.732114 -263.344152)
			(xy 338.823046 -263.452356)
		)
		(stroke
			(width 0)
			(type solid)
		)
		(fill yes)
		(layer "In4.Cu")
		(net "M_D_CPU0_SB_CA<3>")
	)
	(gr_poly
		(pts
			(xy 338.971128 -292.91788) (xy 338.871052 -292.817804) (xy 338.770976 -292.91788) (xy 338.770976 -292.96233)
			(xy 338.971128 -292.96233)
		)
		(stroke
			(width 0)
			(type solid)
		)
		(fill yes)
		(layer "In4.Cu")
		(net "M_D_CPU0_SB_DQ<29>")
	)
	(gr_poly
		(pts
			(xy 338.971128 -291.297614) (xy 338.871052 -291.197792) (xy 338.770976 -291.297614) (xy 338.770976 -291.345366)
			(xy 338.971128 -291.345366)
		)
		(stroke
			(width 0)
			(type solid)
		)
		(fill yes)
		(layer "In4.Cu")
		(net "M_D_CPU0_SB_DQS_DN<8>")
	)
	(gr_poly
		(pts
			(xy 338.971128 -289.677856) (xy 338.871052 -289.57778) (xy 338.770976 -289.677856) (xy 338.770976 -289.722306)
			(xy 338.971128 -289.722306)
		)
		(stroke
			(width 0)
			(type solid)
		)
		(fill yes)
		(layer "In4.Cu")
		(net "M_D_CPU0_SB_DQ<25>")
	)
	(gr_poly
		(pts
			(xy 338.971128 -288.057844) (xy 338.871052 -287.957768) (xy 338.770976 -288.057844) (xy 338.770976 -288.102294)
			(xy 338.971128 -288.102294)
		)
		(stroke
			(width 0)
			(type solid)
		)
		(fill yes)
		(layer "In4.Cu")
		(net "M_D_CPU0_SB_DQ<21>")
	)
	(gr_poly
		(pts
			(xy 338.971128 -286.437832) (xy 338.871052 -286.337756) (xy 338.770976 -286.437832) (xy 338.770976 -286.485584)
			(xy 338.971128 -286.485584)
		)
		(stroke
			(width 0)
			(type solid)
		)
		(fill yes)
		(layer "In4.Cu")
		(net "M_D_CPU0_SB_DQS_DN<7>")
	)
	(gr_poly
		(pts
			(xy 338.971128 -284.818074) (xy 338.871052 -284.717998) (xy 338.770976 -284.818074) (xy 338.770976 -284.862524)
			(xy 338.971128 -284.862524)
		)
		(stroke
			(width 0)
			(type solid)
		)
		(fill yes)
		(layer "In4.Cu")
		(net "M_D_CPU0_SB_DQ<17>")
	)
	(gr_poly
		(pts
			(xy 338.971128 -283.198062) (xy 338.871052 -283.097986) (xy 338.770976 -283.198062) (xy 338.770976 -283.242512)
			(xy 338.971128 -283.242512)
		)
		(stroke
			(width 0)
			(type solid)
		)
		(fill yes)
		(layer "In4.Cu")
		(net "M_D_CPU0_SB_DQ<13>")
	)
	(gr_poly
		(pts
			(xy 338.971128 -281.577796) (xy 338.871052 -281.477974) (xy 338.770976 -281.577796) (xy 338.770976 -281.625548)
			(xy 338.971128 -281.625548)
		)
		(stroke
			(width 0)
			(type solid)
		)
		(fill yes)
		(layer "In4.Cu")
		(net "M_D_CPU0_SB_DQS_DN<6>")
	)
	(gr_poly
		(pts
			(xy 338.971128 -279.958038) (xy 338.871052 -279.857962) (xy 338.770976 -279.958038) (xy 338.770976 -280.002488)
			(xy 338.971128 -280.002488)
		)
		(stroke
			(width 0)
			(type solid)
		)
		(fill yes)
		(layer "In4.Cu")
		(net "M_D_CPU0_SB_DQ<9>")
	)
	(gr_poly
		(pts
			(xy 338.971128 -278.338026) (xy 338.871052 -278.23795) (xy 338.770976 -278.338026) (xy 338.770976 -278.382476)
			(xy 338.971128 -278.382476)
		)
		(stroke
			(width 0)
			(type solid)
		)
		(fill yes)
		(layer "In4.Cu")
		(net "M_D_CPU0_SB_DQ<5>")
	)
	(gr_poly
		(pts
			(xy 338.971128 -275.098002) (xy 338.871052 -274.997926) (xy 338.770976 -275.098002) (xy 338.770976 -275.142452)
			(xy 338.971128 -275.142452)
		)
		(stroke
			(width 0)
			(type solid)
		)
		(fill yes)
		(layer "In4.Cu")
		(net "M_D_CPU0_SB_DQ<1>")
	)
	(gr_poly
		(pts
			(xy 338.971128 -273.47799) (xy 338.871052 -273.377914) (xy 338.770976 -273.47799) (xy 338.770976 -273.52244)
			(xy 338.971128 -273.52244)
		)
		(stroke
			(width 0)
			(type solid)
		)
		(fill yes)
		(layer "In4.Cu")
		(net "M_D_CPU0_SB_CB<1>")
	)
	(gr_poly
		(pts
			(xy 338.971128 -271.857724) (xy 338.871052 -271.757902) (xy 338.770976 -271.857724) (xy 338.770976 -271.905476)
			(xy 338.971128 -271.905476)
		)
		(stroke
			(width 0)
			(type solid)
		)
		(fill yes)
		(layer "In4.Cu")
		(net "M_D_CPU0_SB_DQS_DN<4>")
	)
	(gr_poly
		(pts
			(xy 338.971128 -270.237966) (xy 338.871052 -270.13789) (xy 338.770976 -270.237966) (xy 338.770976 -270.282416)
			(xy 338.971128 -270.282416)
		)
		(stroke
			(width 0)
			(type solid)
		)
		(fill yes)
		(layer "In4.Cu")
		(net "M_D_CPU0_SB_CB<5>")
	)
	(gr_poly
		(pts
			(xy 338.971128 -263.757918) (xy 338.871052 -263.657842) (xy 338.770976 -263.757918) (xy 338.770976 -263.802368)
			(xy 338.971128 -263.802368)
		)
		(stroke
			(width 0)
			(type solid)
		)
		(fill yes)
		(layer "In4.Cu")
		(net "M_D_CPU0_SB_CA<4>")
	)
	(gr_poly
		(pts
			(xy 338.971128 -262.137906) (xy 338.871052 -262.03783) (xy 338.770976 -262.137906) (xy 338.770976 -262.182356)
			(xy 338.971128 -262.182356)
		)
		(stroke
			(width 0)
			(type solid)
		)
		(fill yes)
		(layer "In4.Cu")
		(net "M_D_CPU0_SB_CA<0>")
	)
	(gr_poly
		(pts
			(xy 338.977224 -266.991592) (xy 338.877402 -266.891516) (xy 338.777326 -266.991592) (xy 338.777326 -267.036042)
			(xy 338.977224 -267.036042)
		)
		(stroke
			(width 0)
			(type solid)
		)
		(fill yes)
		(layer "In4.Cu")
		(net "M_D_CPU0_SA_RSP<0>")
	)
	(gr_poly
		(pts
			(xy 338.978494 -276.71776) (xy 338.878418 -276.617938) (xy 338.778342 -276.71776) (xy 338.778342 -276.765512)
			(xy 338.978494 -276.765512)
		)
		(stroke
			(width 0)
			(type solid)
		)
		(fill yes)
		(layer "In4.Cu")
		(net "M_D_CPU0_SB_DQS_DN<5>")
	)
	(gr_poly
		(pts
			(xy 339.141054 -255.216152) (xy 339.040978 -255.116076) (xy 338.940902 -255.216152) (xy 338.940902 -255.260602)
			(xy 339.141054 -255.260602)
		)
		(stroke
			(width 0)
			(type solid)
		)
		(fill yes)
		(layer "In4.Cu")
		(net "M_D_CPU0_SA_CA<6>")
	)
	(gr_poly
		(pts
			(xy 339.141054 -253.59614) (xy 339.040978 -253.496064) (xy 338.940902 -253.59614) (xy 338.940902 -253.64059)
			(xy 339.141054 -253.64059)
		)
		(stroke
			(width 0)
			(type solid)
		)
		(fill yes)
		(layer "In4.Cu")
		(net "M_D_CPU0_SA_CA<2>")
	)
	(gr_poly
		(pts
			(xy 339.141054 -248.736104) (xy 339.040978 -248.636028) (xy 338.940902 -248.736104) (xy 338.940902 -248.780554)
			(xy 339.141054 -248.780554)
		)
		(stroke
			(width 0)
			(type solid)
		)
		(fill yes)
		(layer "In4.Cu")
		(net "M_D_CPU0_SA_CB<5>")
	)
	(gr_poly
		(pts
			(xy 339.141054 -247.115838) (xy 339.040978 -247.016016) (xy 338.940902 -247.115838) (xy 338.940902 -247.16359)
			(xy 339.141054 -247.16359)
		)
		(stroke
			(width 0)
			(type solid)
		)
		(fill yes)
		(layer "In4.Cu")
		(net "M_D_CPU0_SA_DQS_DN<9>")
	)
	(gr_poly
		(pts
			(xy 339.141054 -245.49608) (xy 339.040978 -245.396004) (xy 338.940902 -245.49608) (xy 338.940902 -245.54053)
			(xy 339.141054 -245.54053)
		)
		(stroke
			(width 0)
			(type solid)
		)
		(fill yes)
		(layer "In4.Cu")
		(net "M_D_CPU0_SA_CB<1>")
	)
	(gr_poly
		(pts
			(xy 339.141054 -243.876068) (xy 339.040978 -243.775992) (xy 338.940902 -243.876068) (xy 338.940902 -243.920518)
			(xy 339.141054 -243.920518)
		)
		(stroke
			(width 0)
			(type solid)
		)
		(fill yes)
		(layer "In4.Cu")
		(net "M_D_CPU0_SA_DQ<29>")
	)
	(gr_poly
		(pts
			(xy 339.141054 -242.255802) (xy 339.040978 -242.15598) (xy 338.940902 -242.255802) (xy 338.940902 -242.303554)
			(xy 339.141054 -242.303554)
		)
		(stroke
			(width 0)
			(type solid)
		)
		(fill yes)
		(layer "In4.Cu")
		(net "M_D_CPU0_SA_DQS_DN<8>")
	)
	(gr_poly
		(pts
			(xy 339.141054 -240.636044) (xy 339.040978 -240.535968) (xy 338.940902 -240.636044) (xy 338.940902 -240.680494)
			(xy 339.141054 -240.680494)
		)
		(stroke
			(width 0)
			(type solid)
		)
		(fill yes)
		(layer "In4.Cu")
		(net "M_D_CPU0_SA_DQ<25>")
	)
	(gr_poly
		(pts
			(xy 339.141054 -239.016032) (xy 339.040978 -238.915956) (xy 338.940902 -239.016032) (xy 338.940902 -239.060482)
			(xy 339.141054 -239.060482)
		)
		(stroke
			(width 0)
			(type solid)
		)
		(fill yes)
		(layer "In4.Cu")
		(net "M_D_CPU0_SA_DQ<21>")
	)
	(gr_poly
		(pts
			(xy 339.141054 -237.395766) (xy 339.040978 -237.295944) (xy 338.940902 -237.395766) (xy 338.940902 -237.443518)
			(xy 339.141054 -237.443518)
		)
		(stroke
			(width 0)
			(type solid)
		)
		(fill yes)
		(layer "In4.Cu")
		(net "M_D_CPU0_SA_DQS_DN<7>")
	)
	(gr_poly
		(pts
			(xy 339.141054 -235.776008) (xy 339.040978 -235.675932) (xy 338.940902 -235.776008) (xy 338.940902 -235.820458)
			(xy 339.141054 -235.820458)
		)
		(stroke
			(width 0)
			(type solid)
		)
		(fill yes)
		(layer "In4.Cu")
		(net "M_D_CPU0_SA_DQ<17>")
	)
	(gr_poly
		(pts
			(xy 339.141054 -234.155996) (xy 339.040978 -234.05592) (xy 338.940902 -234.155996) (xy 338.940902 -234.200446)
			(xy 339.141054 -234.200446)
		)
		(stroke
			(width 0)
			(type solid)
		)
		(fill yes)
		(layer "In4.Cu")
		(net "M_D_CPU0_SA_DQ<13>")
	)
	(gr_poly
		(pts
			(xy 339.141054 -232.53573) (xy 339.040978 -232.435908) (xy 338.940902 -232.53573) (xy 338.940902 -232.583482)
			(xy 339.141054 -232.583482)
		)
		(stroke
			(width 0)
			(type solid)
		)
		(fill yes)
		(layer "In4.Cu")
		(net "M_D_CPU0_SA_DQS_DN<6>")
	)
	(gr_poly
		(pts
			(xy 339.141054 -230.915972) (xy 339.040978 -230.815896) (xy 338.940902 -230.915972) (xy 338.940902 -230.960422)
			(xy 339.141054 -230.960422)
		)
		(stroke
			(width 0)
			(type solid)
		)
		(fill yes)
		(layer "In4.Cu")
		(net "M_D_CPU0_SA_DQ<9>")
	)
	(gr_poly
		(pts
			(xy 339.141054 -229.29596) (xy 339.040978 -229.195884) (xy 338.940902 -229.29596) (xy 338.940902 -229.34041)
			(xy 339.141054 -229.34041)
		)
		(stroke
			(width 0)
			(type solid)
		)
		(fill yes)
		(layer "In4.Cu")
		(net "M_D_CPU0_SA_DQ<5>")
	)
	(gr_poly
		(pts
			(xy 339.141054 -226.05619) (xy 339.040978 -225.956114) (xy 338.940902 -226.05619) (xy 338.940902 -226.10064)
			(xy 339.141054 -226.10064)
		)
		(stroke
			(width 0)
			(type solid)
		)
		(fill yes)
		(layer "In4.Cu")
		(net "M_D_CPU0_SA_DQ<1>")
	)
	(gr_poly
		(pts
			(xy 339.141308 -250.356116) (xy 339.041232 -250.25604) (xy 338.941156 -250.356116) (xy 338.941156 -250.400566)
			(xy 339.141308 -250.400566)
		)
		(stroke
			(width 0)
			(type solid)
		)
		(fill yes)
		(layer "In4.Cu")
		(net "M_D_CPU0_ALERT_R_N")
	)
	(gr_poly
		(pts
			(xy 339.14715 -227.676456) (xy 339.047074 -227.57638) (xy 338.946998 -227.676456) (xy 338.946998 -227.723954)
			(xy 339.14715 -227.723954)
		)
		(stroke
			(width 0)
			(type solid)
		)
		(fill yes)
		(layer "In4.Cu")
		(net "M_D_CPU0_SA_DQS_DN<5>")
	)
	(gr_poly
		(pts
			(xy 339.441282 -291.704268) (xy 339.441282 -291.656516) (xy 339.24113 -291.656516) (xy 339.24113 -291.704268)
			(xy 339.341206 -291.80409)
		)
		(stroke
			(width 0)
			(type solid)
		)
		(fill yes)
		(layer "In4.Cu")
		(net "M_D_CPU0_SB_DQS_DP<8>")
	)
	(gr_poly
		(pts
			(xy 339.441282 -290.084002) (xy 339.441282 -290.039552) (xy 339.24113 -290.039552) (xy 339.24113 -290.084002)
			(xy 339.341206 -290.184078)
		)
		(stroke
			(width 0)
			(type solid)
		)
		(fill yes)
		(layer "In4.Cu")
		(net "M_D_CPU0_SB_DQ<27>")
	)
	(gr_poly
		(pts
			(xy 339.441282 -288.464244) (xy 339.441282 -288.419794) (xy 339.24113 -288.419794) (xy 339.24113 -288.464244)
			(xy 339.341206 -288.56432)
		)
		(stroke
			(width 0)
			(type solid)
		)
		(fill yes)
		(layer "In4.Cu")
		(net "M_D_CPU0_SB_DQ<23>")
	)
	(gr_poly
		(pts
			(xy 339.441282 -286.844232) (xy 339.441282 -286.79648) (xy 339.24113 -286.79648) (xy 339.24113 -286.844232)
			(xy 339.341206 -286.944308)
		)
		(stroke
			(width 0)
			(type solid)
		)
		(fill yes)
		(layer "In4.Cu")
		(net "M_D_CPU0_SB_DQS_DP<7>")
	)
	(gr_poly
		(pts
			(xy 339.441282 -285.22422) (xy 339.441282 -285.17977) (xy 339.24113 -285.17977) (xy 339.24113 -285.22422)
			(xy 339.341206 -285.324296)
		)
		(stroke
			(width 0)
			(type solid)
		)
		(fill yes)
		(layer "In4.Cu")
		(net "M_D_CPU0_SB_DQ<19>")
	)
	(gr_poly
		(pts
			(xy 339.441282 -283.604208) (xy 339.441282 -283.559758) (xy 339.24113 -283.559758) (xy 339.24113 -283.604208)
			(xy 339.341206 -283.704284)
		)
		(stroke
			(width 0)
			(type solid)
		)
		(fill yes)
		(layer "In4.Cu")
		(net "M_D_CPU0_SB_DQ<15>")
	)
	(gr_poly
		(pts
			(xy 339.441282 -281.98445) (xy 339.441282 -281.936698) (xy 339.24113 -281.936698) (xy 339.24113 -281.98445)
			(xy 339.341206 -282.084272)
		)
		(stroke
			(width 0)
			(type solid)
		)
		(fill yes)
		(layer "In4.Cu")
		(net "M_D_CPU0_SB_DQS_DP<6>")
	)
	(gr_poly
		(pts
			(xy 339.441282 -280.364184) (xy 339.441282 -280.319734) (xy 339.24113 -280.319734) (xy 339.24113 -280.364184)
			(xy 339.341206 -280.46426)
		)
		(stroke
			(width 0)
			(type solid)
		)
		(fill yes)
		(layer "In4.Cu")
		(net "M_D_CPU0_SB_DQ<11>")
	)
	(gr_poly
		(pts
			(xy 339.441282 -278.744172) (xy 339.441282 -278.699722) (xy 339.24113 -278.699722) (xy 339.24113 -278.744172)
			(xy 339.341206 -278.844248)
		)
		(stroke
			(width 0)
			(type solid)
		)
		(fill yes)
		(layer "In4.Cu")
		(net "M_D_CPU0_SB_DQ<7>")
	)
	(gr_poly
		(pts
			(xy 339.441282 -277.12416) (xy 339.441282 -277.076662) (xy 339.24113 -277.076662) (xy 339.24113 -277.12416)
			(xy 339.341206 -277.224236)
		)
		(stroke
			(width 0)
			(type solid)
		)
		(fill yes)
		(layer "In4.Cu")
		(net "M_D_CPU0_SB_DQS_DP<5>")
	)
	(gr_poly
		(pts
			(xy 339.441282 -275.504148) (xy 339.441282 -275.459698) (xy 339.24113 -275.459698) (xy 339.24113 -275.504148)
			(xy 339.341206 -275.604224)
		)
		(stroke
			(width 0)
			(type solid)
		)
		(fill yes)
		(layer "In4.Cu")
		(net "M_D_CPU0_SB_DQ<3>")
	)
	(gr_poly
		(pts
			(xy 339.441282 -273.884136) (xy 339.441282 -273.839686) (xy 339.24113 -273.839686) (xy 339.24113 -273.884136)
			(xy 339.341206 -273.984212)
		)
		(stroke
			(width 0)
			(type solid)
		)
		(fill yes)
		(layer "In4.Cu")
		(net "M_D_CPU0_SB_CB<3>")
	)
	(gr_poly
		(pts
			(xy 339.441282 -272.264378) (xy 339.441282 -272.216626) (xy 339.24113 -272.216626) (xy 339.24113 -272.264378)
			(xy 339.341206 -272.3642)
		)
		(stroke
			(width 0)
			(type solid)
		)
		(fill yes)
		(layer "In4.Cu")
		(net "M_D_CPU0_SB_DQS_DP<4>")
	)
	(gr_poly
		(pts
			(xy 339.441282 -270.644112) (xy 339.441282 -270.599662) (xy 339.24113 -270.599662) (xy 339.24113 -270.644112)
			(xy 339.341206 -270.744188)
		)
		(stroke
			(width 0)
			(type solid)
		)
		(fill yes)
		(layer "In4.Cu")
		(net "M_D_CPU0_SB_CB<7>")
	)
	(gr_poly
		(pts
			(xy 339.441282 -265.784076) (xy 339.441282 -265.739626) (xy 339.24113 -265.739626) (xy 339.24113 -265.784076)
			(xy 339.341206 -265.884152)
		)
		(stroke
			(width 0)
			(type solid)
		)
		(fill yes)
		(layer "In4.Cu")
		(net "M_D_CPU0_SB_CS_N<0>")
	)
	(gr_poly
		(pts
			(xy 339.441282 -264.164064) (xy 339.441282 -264.119614) (xy 339.24113 -264.119614) (xy 339.24113 -264.164064)
			(xy 339.341206 -264.26414)
		)
		(stroke
			(width 0)
			(type solid)
		)
		(fill yes)
		(layer "In4.Cu")
		(net "M_D_CPU0_SB_CA<5>")
	)
	(gr_poly
		(pts
			(xy 339.441282 -262.544052) (xy 339.441282 -262.499602) (xy 339.24113 -262.499602) (xy 339.24113 -262.544052)
			(xy 339.341206 -262.644128)
		)
		(stroke
			(width 0)
			(type solid)
		)
		(fill yes)
		(layer "In4.Cu")
		(net "M_D_CPU0_SB_CA<1>")
	)
	(gr_poly
		(pts
			(xy 339.611208 -255.622298) (xy 339.611208 -255.577848) (xy 339.411056 -255.577848) (xy 339.411056 -255.622298)
			(xy 339.511132 -255.722374)
		)
		(stroke
			(width 0)
			(type solid)
		)
		(fill yes)
		(layer "In4.Cu")
		(net "M_D_CPU0_SA_PAR")
	)
	(gr_poly
		(pts
			(xy 339.611208 -254.002286) (xy 339.611208 -253.957836) (xy 339.411056 -253.957836) (xy 339.411056 -254.002286)
			(xy 339.511132 -254.102362)
		)
		(stroke
			(width 0)
			(type solid)
		)
		(fill yes)
		(layer "In4.Cu")
		(net "M_D_CPU0_SA_CA<3>")
	)
	(gr_poly
		(pts
			(xy 339.611208 -252.382274) (xy 339.611208 -252.337824) (xy 339.411056 -252.337824) (xy 339.411056 -252.382274)
			(xy 339.511132 -252.48235)
		)
		(stroke
			(width 0)
			(type solid)
		)
		(fill yes)
		(layer "In4.Cu")
		(net "M_D_CPU0_SA_CS_N<1>")
	)
	(gr_poly
		(pts
			(xy 339.611208 -250.762262) (xy 339.611208 -250.717812) (xy 339.411056 -250.717812) (xy 339.411056 -250.762262)
			(xy 339.511132 -250.862338)
		)
		(stroke
			(width 0)
			(type solid)
		)
		(fill yes)
		(layer "In4.Cu")
		(net "M_D_CPU0_RESET_N")
	)
	(gr_poly
		(pts
			(xy 339.611208 -249.14225) (xy 339.611208 -249.0978) (xy 339.411056 -249.0978) (xy 339.411056 -249.14225)
			(xy 339.511132 -249.242326)
		)
		(stroke
			(width 0)
			(type solid)
		)
		(fill yes)
		(layer "In4.Cu")
		(net "M_D_CPU0_SA_CB<7>")
	)
	(gr_poly
		(pts
			(xy 339.611208 -247.522492) (xy 339.611208 -247.47474) (xy 339.411056 -247.47474) (xy 339.411056 -247.522492)
			(xy 339.511132 -247.622314)
		)
		(stroke
			(width 0)
			(type solid)
		)
		(fill yes)
		(layer "In4.Cu")
		(net "M_D_CPU0_SA_DQS_DP<9>")
	)
	(gr_poly
		(pts
			(xy 339.611208 -245.902226) (xy 339.611208 -245.857776) (xy 339.411056 -245.857776) (xy 339.411056 -245.902226)
			(xy 339.511132 -246.002302)
		)
		(stroke
			(width 0)
			(type solid)
		)
		(fill yes)
		(layer "In4.Cu")
		(net "M_D_CPU0_SA_CB<3>")
	)
	(gr_poly
		(pts
			(xy 339.611208 -244.282214) (xy 339.611208 -244.237764) (xy 339.411056 -244.237764) (xy 339.411056 -244.282214)
			(xy 339.511132 -244.38229)
		)
		(stroke
			(width 0)
			(type solid)
		)
		(fill yes)
		(layer "In4.Cu")
		(net "M_D_CPU0_SA_DQ<31>")
	)
	(gr_poly
		(pts
			(xy 339.611208 -242.662456) (xy 339.611208 -242.614704) (xy 339.411056 -242.614704) (xy 339.411056 -242.662456)
			(xy 339.511132 -242.762278)
		)
		(stroke
			(width 0)
			(type solid)
		)
		(fill yes)
		(layer "In4.Cu")
		(net "M_D_CPU0_SA_DQS_DP<8>")
	)
	(gr_poly
		(pts
			(xy 339.611208 -241.04219) (xy 339.611208 -240.99774) (xy 339.411056 -240.99774) (xy 339.411056 -241.04219)
			(xy 339.511132 -241.142266)
		)
		(stroke
			(width 0)
			(type solid)
		)
		(fill yes)
		(layer "In4.Cu")
		(net "M_D_CPU0_SA_DQ<27>")
	)
	(gr_poly
		(pts
			(xy 339.611208 -239.422178) (xy 339.611208 -239.377728) (xy 339.411056 -239.377728) (xy 339.411056 -239.422178)
			(xy 339.511132 -239.522254)
		)
		(stroke
			(width 0)
			(type solid)
		)
		(fill yes)
		(layer "In4.Cu")
		(net "M_D_CPU0_SA_DQ<23>")
	)
	(gr_poly
		(pts
			(xy 339.611208 -237.80242) (xy 339.611208 -237.754668) (xy 339.411056 -237.754668) (xy 339.411056 -237.80242)
			(xy 339.511132 -237.902242)
		)
		(stroke
			(width 0)
			(type solid)
		)
		(fill yes)
		(layer "In4.Cu")
		(net "M_D_CPU0_SA_DQS_DP<7>")
	)
	(gr_poly
		(pts
			(xy 339.611208 -236.182154) (xy 339.611208 -236.137704) (xy 339.411056 -236.137704) (xy 339.411056 -236.182154)
			(xy 339.511132 -236.28223)
		)
		(stroke
			(width 0)
			(type solid)
		)
		(fill yes)
		(layer "In4.Cu")
		(net "M_D_CPU0_SA_DQ<19>")
	)
	(gr_poly
		(pts
			(xy 339.611208 -234.562142) (xy 339.611208 -234.517692) (xy 339.411056 -234.517692) (xy 339.411056 -234.562142)
			(xy 339.511132 -234.662218)
		)
		(stroke
			(width 0)
			(type solid)
		)
		(fill yes)
		(layer "In4.Cu")
		(net "M_D_CPU0_SA_DQ<15>")
	)
	(gr_poly
		(pts
			(xy 339.611208 -232.942384) (xy 339.611208 -232.894632) (xy 339.411056 -232.894632) (xy 339.411056 -232.942384)
			(xy 339.511132 -233.042206)
		)
		(stroke
			(width 0)
			(type solid)
		)
		(fill yes)
		(layer "In4.Cu")
		(net "M_D_CPU0_SA_DQS_DP<6>")
	)
	(gr_poly
		(pts
			(xy 339.611208 -231.322372) (xy 339.611208 -231.277922) (xy 339.411056 -231.277922) (xy 339.411056 -231.322372)
			(xy 339.511132 -231.422448)
		)
		(stroke
			(width 0)
			(type solid)
		)
		(fill yes)
		(layer "In4.Cu")
		(net "M_D_CPU0_SA_DQ<11>")
	)
	(gr_poly
		(pts
			(xy 339.611208 -229.70236) (xy 339.611208 -229.65791) (xy 339.411056 -229.65791) (xy 339.411056 -229.70236)
			(xy 339.511132 -229.802436)
		)
		(stroke
			(width 0)
			(type solid)
		)
		(fill yes)
		(layer "In4.Cu")
		(net "M_D_CPU0_SA_DQ<7>")
	)
	(gr_poly
		(pts
			(xy 339.611208 -228.082602) (xy 339.611208 -228.03485) (xy 339.411056 -228.03485) (xy 339.411056 -228.082602)
			(xy 339.511132 -228.182424)
		)
		(stroke
			(width 0)
			(type solid)
		)
		(fill yes)
		(layer "In4.Cu")
		(net "M_D_CPU0_SA_DQS_DP<5>")
	)
	(gr_poly
		(pts
			(xy 339.611208 -226.462336) (xy 339.611208 -226.417886) (xy 339.411056 -226.417886) (xy 339.411056 -226.462336)
			(xy 339.511132 -226.562412)
		)
		(stroke
			(width 0)
			(type solid)
		)
		(fill yes)
		(layer "In4.Cu")
		(net "M_D_CPU0_SA_DQ<3>")
	)
	(gr_poly
		(pts
			(xy 339.911182 -292.91788) (xy 339.811106 -292.817804) (xy 339.71103 -292.91788) (xy 339.71103 -292.96233)
			(xy 339.911182 -292.96233)
		)
		(stroke
			(width 0)
			(type solid)
		)
		(fill yes)
		(layer "In4.Cu")
		(net "M_D_CPU0_SB_DQ<29>")
	)
	(gr_poly
		(pts
			(xy 339.911182 -291.297614) (xy 339.811106 -291.197792) (xy 339.71103 -291.297614) (xy 339.71103 -291.345366)
			(xy 339.911182 -291.345366)
		)
		(stroke
			(width 0)
			(type solid)
		)
		(fill yes)
		(layer "In4.Cu")
		(net "M_D_CPU0_SB_DQS_DN<8>")
	)
	(gr_poly
		(pts
			(xy 339.911182 -289.677856) (xy 339.811106 -289.57778) (xy 339.71103 -289.677856) (xy 339.71103 -289.722306)
			(xy 339.911182 -289.722306)
		)
		(stroke
			(width 0)
			(type solid)
		)
		(fill yes)
		(layer "In4.Cu")
		(net "M_D_CPU0_SB_DQ<25>")
	)
	(gr_poly
		(pts
			(xy 339.911182 -288.057844) (xy 339.811106 -287.957768) (xy 339.71103 -288.057844) (xy 339.71103 -288.102294)
			(xy 339.911182 -288.102294)
		)
		(stroke
			(width 0)
			(type solid)
		)
		(fill yes)
		(layer "In4.Cu")
		(net "M_D_CPU0_SB_DQ<21>")
	)
	(gr_poly
		(pts
			(xy 339.911182 -286.437832) (xy 339.811106 -286.337756) (xy 339.71103 -286.437832) (xy 339.71103 -286.485584)
			(xy 339.911182 -286.485584)
		)
		(stroke
			(width 0)
			(type solid)
		)
		(fill yes)
		(layer "In4.Cu")
		(net "M_D_CPU0_SB_DQS_DN<7>")
	)
	(gr_poly
		(pts
			(xy 339.911182 -284.818074) (xy 339.811106 -284.717998) (xy 339.71103 -284.818074) (xy 339.71103 -284.862524)
			(xy 339.911182 -284.862524)
		)
		(stroke
			(width 0)
			(type solid)
		)
		(fill yes)
		(layer "In4.Cu")
		(net "M_D_CPU0_SB_DQ<17>")
	)
	(gr_poly
		(pts
			(xy 339.911182 -283.198062) (xy 339.811106 -283.097986) (xy 339.71103 -283.198062) (xy 339.71103 -283.242512)
			(xy 339.911182 -283.242512)
		)
		(stroke
			(width 0)
			(type solid)
		)
		(fill yes)
		(layer "In4.Cu")
		(net "M_D_CPU0_SB_DQ<13>")
	)
	(gr_poly
		(pts
			(xy 339.911182 -281.577796) (xy 339.811106 -281.477974) (xy 339.71103 -281.577796) (xy 339.71103 -281.625548)
			(xy 339.911182 -281.625548)
		)
		(stroke
			(width 0)
			(type solid)
		)
		(fill yes)
		(layer "In4.Cu")
		(net "M_D_CPU0_SB_DQS_DN<6>")
	)
	(gr_poly
		(pts
			(xy 339.911182 -279.958038) (xy 339.811106 -279.857962) (xy 339.71103 -279.958038) (xy 339.71103 -280.002488)
			(xy 339.911182 -280.002488)
		)
		(stroke
			(width 0)
			(type solid)
		)
		(fill yes)
		(layer "In4.Cu")
		(net "M_D_CPU0_SB_DQ<9>")
	)
	(gr_poly
		(pts
			(xy 339.911182 -278.338026) (xy 339.811106 -278.23795) (xy 339.71103 -278.338026) (xy 339.71103 -278.382476)
			(xy 339.911182 -278.382476)
		)
		(stroke
			(width 0)
			(type solid)
		)
		(fill yes)
		(layer "In4.Cu")
		(net "M_D_CPU0_SB_DQ<5>")
	)
	(gr_poly
		(pts
			(xy 339.911182 -276.71776) (xy 339.811106 -276.617938) (xy 339.71103 -276.71776) (xy 339.71103 -276.765512)
			(xy 339.911182 -276.765512)
		)
		(stroke
			(width 0)
			(type solid)
		)
		(fill yes)
		(layer "In4.Cu")
		(net "M_D_CPU0_SB_DQS_DN<5>")
	)
	(gr_poly
		(pts
			(xy 339.911182 -275.098002) (xy 339.811106 -274.997926) (xy 339.71103 -275.098002) (xy 339.71103 -275.142452)
			(xy 339.911182 -275.142452)
		)
		(stroke
			(width 0)
			(type solid)
		)
		(fill yes)
		(layer "In4.Cu")
		(net "M_D_CPU0_SB_DQ<1>")
	)
	(gr_poly
		(pts
			(xy 339.911182 -273.47799) (xy 339.811106 -273.377914) (xy 339.71103 -273.47799) (xy 339.71103 -273.52244)
			(xy 339.911182 -273.52244)
		)
		(stroke
			(width 0)
			(type solid)
		)
		(fill yes)
		(layer "In4.Cu")
		(net "M_D_CPU0_SB_CB<1>")
	)
	(gr_poly
		(pts
			(xy 339.911182 -271.857724) (xy 339.811106 -271.757902) (xy 339.71103 -271.857724) (xy 339.71103 -271.905476)
			(xy 339.911182 -271.905476)
		)
		(stroke
			(width 0)
			(type solid)
		)
		(fill yes)
		(layer "In4.Cu")
		(net "M_D_CPU0_SB_DQS_DN<4>")
	)
	(gr_poly
		(pts
			(xy 339.911182 -270.237966) (xy 339.811106 -270.13789) (xy 339.71103 -270.237966) (xy 339.71103 -270.282416)
			(xy 339.911182 -270.282416)
		)
		(stroke
			(width 0)
			(type solid)
		)
		(fill yes)
		(layer "In4.Cu")
		(net "M_D_CPU0_SB_CB<5>")
	)
	(gr_poly
		(pts
			(xy 339.911182 -266.991592) (xy 339.811106 -266.891516) (xy 339.71103 -266.991592) (xy 339.71103 -267.036042)
			(xy 339.911182 -267.036042)
		)
		(stroke
			(width 0)
			(type solid)
		)
		(fill yes)
		(layer "In4.Cu")
		(net "M_D_CPU0_SA_RSP<0>")
	)
	(gr_poly
		(pts
			(xy 339.911182 -263.757918) (xy 339.811106 -263.657842) (xy 339.71103 -263.757918) (xy 339.71103 -263.802368)
			(xy 339.911182 -263.802368)
		)
		(stroke
			(width 0)
			(type solid)
		)
		(fill yes)
		(layer "In4.Cu")
		(net "M_D_CPU0_SB_CA<4>")
	)
	(gr_poly
		(pts
			(xy 339.911182 -262.137906) (xy 339.811106 -262.03783) (xy 339.71103 -262.137906) (xy 339.71103 -262.182356)
			(xy 339.911182 -262.182356)
		)
		(stroke
			(width 0)
			(type solid)
		)
		(fill yes)
		(layer "In4.Cu")
		(net "M_D_CPU0_SB_CA<0>")
	)
	(gr_poly
		(pts
			(xy 340.032848 -247.156732) (xy 340.02853 -247.109234) (xy 339.920326 -247.018302) (xy 339.829394 -247.12676)
			(xy 339.833458 -247.174004)
		)
		(stroke
			(width 0)
			(type solid)
		)
		(fill yes)
		(layer "In4.Cu")
		(net "M_D_CPU0_SA_DQS_DN<9>")
	)
	(gr_poly
		(pts
			(xy 340.032848 -242.296696) (xy 340.02853 -242.249198) (xy 339.920326 -242.158266) (xy 339.829394 -242.266724)
			(xy 339.833458 -242.313968)
		)
		(stroke
			(width 0)
			(type solid)
		)
		(fill yes)
		(layer "In4.Cu")
		(net "M_D_CPU0_SA_DQS_DN<8>")
	)
	(gr_poly
		(pts
			(xy 340.032848 -237.43666) (xy 340.02853 -237.389162) (xy 339.920326 -237.29823) (xy 339.829394 -237.406688)
			(xy 339.833458 -237.453932)
		)
		(stroke
			(width 0)
			(type solid)
		)
		(fill yes)
		(layer "In4.Cu")
		(net "M_D_CPU0_SA_DQS_DN<7>")
	)
	(gr_poly
		(pts
			(xy 340.032848 -232.576624) (xy 340.02853 -232.529126) (xy 339.920326 -232.438194) (xy 339.829394 -232.546652)
			(xy 339.833458 -232.593896)
		)
		(stroke
			(width 0)
			(type solid)
		)
		(fill yes)
		(layer "In4.Cu")
		(net "M_D_CPU0_SA_DQS_DN<6>")
	)
	(gr_poly
		(pts
			(xy 340.045294 -255.252982) (xy 340.041484 -255.208532) (xy 339.933026 -255.117854) (xy 339.842094 -255.226058)
			(xy 339.846158 -255.270254)
		)
		(stroke
			(width 0)
			(type solid)
		)
		(fill yes)
		(layer "In4.Cu")
		(net "M_D_CPU0_SA_CA<6>")
	)
	(gr_poly
		(pts
			(xy 340.045294 -253.63297) (xy 340.041484 -253.58852) (xy 339.933026 -253.497842) (xy 339.842094 -253.606046)
			(xy 339.846158 -253.650242)
		)
		(stroke
			(width 0)
			(type solid)
		)
		(fill yes)
		(layer "In4.Cu")
		(net "M_D_CPU0_SA_CA<2>")
	)
	(gr_poly
		(pts
			(xy 340.045294 -250.392946) (xy 340.041484 -250.348496) (xy 339.933026 -250.257818) (xy 339.842094 -250.366022)
			(xy 339.846158 -250.410218)
		)
		(stroke
			(width 0)
			(type solid)
		)
		(fill yes)
		(layer "In4.Cu")
		(net "M_D_CPU0_ALERT_R_N")
	)
	(gr_poly
		(pts
			(xy 340.045294 -248.772934) (xy 340.041484 -248.728484) (xy 339.933026 -248.637806) (xy 339.842094 -248.74601)
			(xy 339.846158 -248.790206)
		)
		(stroke
			(width 0)
			(type solid)
		)
		(fill yes)
		(layer "In4.Cu")
		(net "M_D_CPU0_SA_CB<5>")
	)
	(gr_poly
		(pts
			(xy 340.045294 -245.53291) (xy 340.041484 -245.48846) (xy 339.933026 -245.397782) (xy 339.842094 -245.505986)
			(xy 339.846158 -245.550182)
		)
		(stroke
			(width 0)
			(type solid)
		)
		(fill yes)
		(layer "In4.Cu")
		(net "M_D_CPU0_SA_CB<1>")
	)
	(gr_poly
		(pts
			(xy 340.045294 -243.912898) (xy 340.041484 -243.868702) (xy 339.933026 -243.77777) (xy 339.842094 -243.885974)
			(xy 339.846158 -243.93017)
		)
		(stroke
			(width 0)
			(type solid)
		)
		(fill yes)
		(layer "In4.Cu")
		(net "M_D_CPU0_SA_DQ<29>")
	)
	(gr_poly
		(pts
			(xy 340.045294 -240.672874) (xy 340.041484 -240.628424) (xy 339.933026 -240.537746) (xy 339.842094 -240.64595)
			(xy 339.846158 -240.690146)
		)
		(stroke
			(width 0)
			(type solid)
		)
		(fill yes)
		(layer "In4.Cu")
		(net "M_D_CPU0_SA_DQ<25>")
	)
	(gr_poly
		(pts
			(xy 340.045294 -239.052862) (xy 340.041484 -239.008666) (xy 339.933026 -238.917734) (xy 339.842094 -239.025938)
			(xy 339.846158 -239.070134)
		)
		(stroke
			(width 0)
			(type solid)
		)
		(fill yes)
		(layer "In4.Cu")
		(net "M_D_CPU0_SA_DQ<21>")
	)
	(gr_poly
		(pts
			(xy 340.045294 -235.812838) (xy 340.041484 -235.768388) (xy 339.933026 -235.67771) (xy 339.842094 -235.785914)
			(xy 339.846158 -235.83011)
		)
		(stroke
			(width 0)
			(type solid)
		)
		(fill yes)
		(layer "In4.Cu")
		(net "M_D_CPU0_SA_DQ<17>")
	)
	(gr_poly
		(pts
			(xy 340.045294 -234.192826) (xy 340.041484 -234.148376) (xy 339.933026 -234.057698) (xy 339.842094 -234.165902)
			(xy 339.846158 -234.210098)
		)
		(stroke
			(width 0)
			(type solid)
		)
		(fill yes)
		(layer "In4.Cu")
		(net "M_D_CPU0_SA_DQ<13>")
	)
	(gr_poly
		(pts
			(xy 340.045294 -226.09302) (xy 340.041484 -226.04857) (xy 339.933026 -225.957892) (xy 339.842094 -226.066096)
			(xy 339.846158 -226.110292)
		)
		(stroke
			(width 0)
			(type solid)
		)
		(fill yes)
		(layer "In4.Cu")
		(net "M_D_CPU0_SA_DQ<1>")
	)
	(gr_poly
		(pts
			(xy 340.045548 -230.952802) (xy 340.041738 -230.908352) (xy 339.93328 -230.817674) (xy 339.842348 -230.925878)
			(xy 339.846412 -230.970074)
		)
		(stroke
			(width 0)
			(type solid)
		)
		(fill yes)
		(layer "In4.Cu")
		(net "M_D_CPU0_SA_DQ<9>")
	)
	(gr_poly
		(pts
			(xy 340.045548 -229.33279) (xy 340.041738 -229.28834) (xy 339.93328 -229.197662) (xy 339.842348 -229.305866)
			(xy 339.846412 -229.350062)
		)
		(stroke
			(width 0)
			(type solid)
		)
		(fill yes)
		(layer "In4.Cu")
		(net "M_D_CPU0_SA_DQ<5>")
	)
	(gr_poly
		(pts
			(xy 340.328504 -291.710872) (xy 340.332822 -291.663374) (xy 340.133432 -291.645848) (xy 340.129368 -291.693346)
			(xy 340.2203 -291.801804)
		)
		(stroke
			(width 0)
			(type solid)
		)
		(fill yes)
		(layer "In4.Cu")
		(net "M_D_CPU0_SB_DQS_DP<8>")
	)
	(gr_poly
		(pts
			(xy 340.328504 -286.850836) (xy 340.332822 -286.803338) (xy 340.133432 -286.786066) (xy 340.129368 -286.83331)
			(xy 340.2203 -286.941768)
		)
		(stroke
			(width 0)
			(type solid)
		)
		(fill yes)
		(layer "In4.Cu")
		(net "M_D_CPU0_SB_DQS_DP<7>")
	)
	(gr_poly
		(pts
			(xy 340.328504 -281.991054) (xy 340.332822 -281.943556) (xy 340.133432 -281.926284) (xy 340.129368 -281.973528)
			(xy 340.2203 -282.081986)
		)
		(stroke
			(width 0)
			(type solid)
		)
		(fill yes)
		(layer "In4.Cu")
		(net "M_D_CPU0_SB_DQS_DP<6>")
	)
	(gr_poly
		(pts
			(xy 340.328504 -277.131018) (xy 340.332568 -277.08352) (xy 340.133432 -277.066248) (xy 340.129114 -277.113492)
			(xy 340.220046 -277.22195)
		)
		(stroke
			(width 0)
			(type solid)
		)
		(fill yes)
		(layer "In4.Cu")
		(net "M_D_CPU0_SB_DQS_DP<5>")
	)
	(gr_poly
		(pts
			(xy 340.328504 -272.270982) (xy 340.332822 -272.223484) (xy 340.133432 -272.206212) (xy 340.129368 -272.253456)
			(xy 340.2203 -272.361914)
		)
		(stroke
			(width 0)
			(type solid)
		)
		(fill yes)
		(layer "In4.Cu")
		(net "M_D_CPU0_SB_DQS_DP<4>")
	)
	(gr_poly
		(pts
			(xy 340.341458 -290.091368) (xy 340.345268 -290.047172) (xy 340.146132 -290.0299) (xy 340.142068 -290.074096)
			(xy 340.233 -290.1823)
		)
		(stroke
			(width 0)
			(type solid)
		)
		(fill yes)
		(layer "In4.Cu")
		(net "M_D_CPU0_SB_DQ<27>")
	)
	(gr_poly
		(pts
			(xy 340.341458 -285.23184) (xy 340.345268 -285.18739) (xy 340.146132 -285.170118) (xy 340.142068 -285.214314)
			(xy 340.233 -285.322518)
		)
		(stroke
			(width 0)
			(type solid)
		)
		(fill yes)
		(layer "In4.Cu")
		(net "M_D_CPU0_SB_DQ<19>")
	)
	(gr_poly
		(pts
			(xy 340.341458 -283.611828) (xy 340.345268 -283.567378) (xy 340.146132 -283.550106) (xy 340.142068 -283.594302)
			(xy 340.233 -283.702506)
		)
		(stroke
			(width 0)
			(type solid)
		)
		(fill yes)
		(layer "In4.Cu")
		(net "M_D_CPU0_SB_DQ<15>")
	)
	(gr_poly
		(pts
			(xy 340.341458 -280.371804) (xy 340.345268 -280.327354) (xy 340.146132 -280.310082) (xy 340.142068 -280.354278)
			(xy 340.233 -280.462482)
		)
		(stroke
			(width 0)
			(type solid)
		)
		(fill yes)
		(layer "In4.Cu")
		(net "M_D_CPU0_SB_DQ<11>")
	)
	(gr_poly
		(pts
			(xy 340.341458 -278.751792) (xy 340.345268 -278.707342) (xy 340.146132 -278.69007) (xy 340.142068 -278.734266)
			(xy 340.233 -278.84247)
		)
		(stroke
			(width 0)
			(type solid)
		)
		(fill yes)
		(layer "In4.Cu")
		(net "M_D_CPU0_SB_DQ<7>")
	)
	(gr_poly
		(pts
			(xy 340.341458 -275.511768) (xy 340.345268 -275.467318) (xy 340.146132 -275.450046) (xy 340.142068 -275.494242)
			(xy 340.233 -275.602446)
		)
		(stroke
			(width 0)
			(type solid)
		)
		(fill yes)
		(layer "In4.Cu")
		(net "M_D_CPU0_SB_DQ<3>")
	)
	(gr_poly
		(pts
			(xy 340.341458 -273.891756) (xy 340.345268 -273.847306) (xy 340.146132 -273.830034) (xy 340.142068 -273.87423)
			(xy 340.233 -273.982434)
		)
		(stroke
			(width 0)
			(type solid)
		)
		(fill yes)
		(layer "In4.Cu")
		(net "M_D_CPU0_SB_CB<3>")
	)
	(gr_poly
		(pts
			(xy 340.341458 -270.651732) (xy 340.345268 -270.607282) (xy 340.146132 -270.59001) (xy 340.142068 -270.634206)
			(xy 340.233 -270.74241)
		)
		(stroke
			(width 0)
			(type solid)
		)
		(fill yes)
		(layer "In4.Cu")
		(net "M_D_CPU0_SB_CB<7>")
	)
	(gr_poly
		(pts
			(xy 340.341458 -265.791696) (xy 340.345268 -265.747246) (xy 340.146132 -265.729974) (xy 340.142068 -265.77417)
			(xy 340.233 -265.882374)
		)
		(stroke
			(width 0)
			(type solid)
		)
		(fill yes)
		(layer "In4.Cu")
		(net "M_D_CPU0_SB_CS_N<0>")
	)
	(gr_poly
		(pts
			(xy 340.341458 -264.171684) (xy 340.345268 -264.127234) (xy 340.146132 -264.109962) (xy 340.142068 -264.154158)
			(xy 340.233 -264.262362)
		)
		(stroke
			(width 0)
			(type solid)
		)
		(fill yes)
		(layer "In4.Cu")
		(net "M_D_CPU0_SB_CA<5>")
	)
	(gr_poly
		(pts
			(xy 340.341458 -262.551672) (xy 340.345268 -262.507222) (xy 340.146132 -262.48995) (xy 340.142068 -262.534146)
			(xy 340.233 -262.64235)
		)
		(stroke
			(width 0)
			(type solid)
		)
		(fill yes)
		(layer "In4.Cu")
		(net "M_D_CPU0_SB_CA<1>")
	)
	(gr_poly
		(pts
			(xy 340.341712 -288.471864) (xy 340.345522 -288.427414) (xy 340.146386 -288.410142) (xy 340.142322 -288.454338)
			(xy 340.233254 -288.562542)
		)
		(stroke
			(width 0)
			(type solid)
		)
		(fill yes)
		(layer "In4.Cu")
		(net "M_D_CPU0_SB_DQ<23>")
	)
	(gr_poly
		(pts
			(xy 379.593602 -230.925878) (xy 379.50267 -230.817674) (xy 379.394212 -230.908352) (xy 379.390402 -230.952802)
			(xy 379.589538 -230.970074)
		)
		(stroke
			(width 0)
			(type solid)
		)
		(fill yes)
		(layer "In4.Cu")
		(net "M_J_CPU0_SA_DQ<9>")
	)
	(gr_poly
		(pts
			(xy 379.593602 -229.305866) (xy 379.50267 -229.197662) (xy 379.394212 -229.28834) (xy 379.390402 -229.33279)
			(xy 379.589538 -229.350062)
		)
		(stroke
			(width 0)
			(type solid)
		)
		(fill yes)
		(layer "In4.Cu")
		(net "M_J_CPU0_SA_DQ<5>")
	)
	(gr_poly
		(pts
			(xy 379.593856 -255.226058) (xy 379.502924 -255.117854) (xy 379.394466 -255.208532) (xy 379.390656 -255.252982)
			(xy 379.589792 -255.270254)
		)
		(stroke
			(width 0)
			(type solid)
		)
		(fill yes)
		(layer "In4.Cu")
		(net "M_J_CPU0_SA_CA<6>")
	)
	(gr_poly
		(pts
			(xy 379.593856 -253.606046) (xy 379.502924 -253.497842) (xy 379.394466 -253.58852) (xy 379.390656 -253.63297)
			(xy 379.589792 -253.650242)
		)
		(stroke
			(width 0)
			(type solid)
		)
		(fill yes)
		(layer "In4.Cu")
		(net "M_J_CPU0_SA_CA<2>")
	)
	(gr_poly
		(pts
			(xy 379.593856 -251.986034) (xy 379.502924 -251.87783) (xy 379.394466 -251.968508) (xy 379.390656 -252.012958)
			(xy 379.589792 -252.03023)
		)
		(stroke
			(width 0)
			(type solid)
		)
		(fill yes)
		(layer "In4.Cu")
		(net "M_J_CPU0_SA_CS_N<1>")
	)
	(gr_poly
		(pts
			(xy 379.593856 -250.366022) (xy 379.502924 -250.257818) (xy 379.394466 -250.348496) (xy 379.390656 -250.392946)
			(xy 379.589792 -250.410218)
		)
		(stroke
			(width 0)
			(type solid)
		)
		(fill yes)
		(layer "In4.Cu")
		(net "M_J_CPU0_ALERT_R_N")
	)
	(gr_poly
		(pts
			(xy 379.593856 -248.74601) (xy 379.502924 -248.637806) (xy 379.394466 -248.728484) (xy 379.390656 -248.772934)
			(xy 379.589792 -248.790206)
		)
		(stroke
			(width 0)
			(type solid)
		)
		(fill yes)
		(layer "In4.Cu")
		(net "M_J_CPU0_SA_CB<5>")
	)
	(gr_poly
		(pts
			(xy 379.593856 -245.505986) (xy 379.502924 -245.397782) (xy 379.394466 -245.48846) (xy 379.390656 -245.53291)
			(xy 379.589792 -245.550182)
		)
		(stroke
			(width 0)
			(type solid)
		)
		(fill yes)
		(layer "In4.Cu")
		(net "M_J_CPU0_SA_CB<1>")
	)
	(gr_poly
		(pts
			(xy 379.593856 -243.885974) (xy 379.502924 -243.77777) (xy 379.394466 -243.868702) (xy 379.390656 -243.912898)
			(xy 379.589792 -243.93017)
		)
		(stroke
			(width 0)
			(type solid)
		)
		(fill yes)
		(layer "In4.Cu")
		(net "M_J_CPU0_SA_DQ<29>")
	)
	(gr_poly
		(pts
			(xy 379.593856 -240.64595) (xy 379.502924 -240.537746) (xy 379.394466 -240.628424) (xy 379.390656 -240.672874)
			(xy 379.589792 -240.690146)
		)
		(stroke
			(width 0)
			(type solid)
		)
		(fill yes)
		(layer "In4.Cu")
		(net "M_J_CPU0_SA_DQ<25>")
	)
	(gr_poly
		(pts
			(xy 379.593856 -239.025938) (xy 379.502924 -238.917734) (xy 379.394466 -239.008666) (xy 379.390656 -239.052862)
			(xy 379.589792 -239.070134)
		)
		(stroke
			(width 0)
			(type solid)
		)
		(fill yes)
		(layer "In4.Cu")
		(net "M_J_CPU0_SA_DQ<21>")
	)
	(gr_poly
		(pts
			(xy 379.593856 -235.785914) (xy 379.502924 -235.67771) (xy 379.394466 -235.768388) (xy 379.390656 -235.812838)
			(xy 379.589792 -235.83011)
		)
		(stroke
			(width 0)
			(type solid)
		)
		(fill yes)
		(layer "In4.Cu")
		(net "M_J_CPU0_SA_DQ<17>")
	)
	(gr_poly
		(pts
			(xy 379.593856 -234.165902) (xy 379.502924 -234.057698) (xy 379.394466 -234.148376) (xy 379.390656 -234.192826)
			(xy 379.589792 -234.210098)
		)
		(stroke
			(width 0)
			(type solid)
		)
		(fill yes)
		(layer "In4.Cu")
		(net "M_J_CPU0_SA_DQ<13>")
	)
	(gr_poly
		(pts
			(xy 379.593856 -226.066096) (xy 379.502924 -225.957892) (xy 379.394466 -226.04857) (xy 379.390656 -226.09302)
			(xy 379.589792 -226.110292)
		)
		(stroke
			(width 0)
			(type solid)
		)
		(fill yes)
		(layer "In4.Cu")
		(net "M_J_CPU0_SA_DQ<1>")
	)
	(gr_poly
		(pts
			(xy 379.595634 -242.265708) (xy 379.504702 -242.157504) (xy 379.396244 -242.248436) (xy 379.39218 -242.295934)
			(xy 379.591316 -242.313206)
		)
		(stroke
			(width 0)
			(type solid)
		)
		(fill yes)
		(layer "In4.Cu")
		(net "M_J_CPU0_SA_DQS_DN<8>")
	)
	(gr_poly
		(pts
			(xy 379.595634 -227.685854) (xy 379.504702 -227.57765) (xy 379.396244 -227.668582) (xy 379.39218 -227.71608)
			(xy 379.591316 -227.733352)
		)
		(stroke
			(width 0)
			(type solid)
		)
		(fill yes)
		(layer "In4.Cu")
		(net "M_J_CPU0_SA_DQS_DN<5>")
	)
	(gr_poly
		(pts
			(xy 379.606556 -247.12676) (xy 379.515624 -247.018302) (xy 379.40742 -247.109234) (xy 379.403102 -247.156732)
			(xy 379.602492 -247.174004)
		)
		(stroke
			(width 0)
			(type solid)
		)
		(fill yes)
		(layer "In4.Cu")
		(net "M_J_CPU0_SA_DQS_DN<9>")
	)
	(gr_poly
		(pts
			(xy 379.606556 -237.406688) (xy 379.515624 -237.29823) (xy 379.40742 -237.389162) (xy 379.403102 -237.43666)
			(xy 379.602492 -237.453932)
		)
		(stroke
			(width 0)
			(type solid)
		)
		(fill yes)
		(layer "In4.Cu")
		(net "M_J_CPU0_SA_DQS_DN<7>")
	)
	(gr_poly
		(pts
			(xy 379.606556 -232.546652) (xy 379.515624 -232.438194) (xy 379.40742 -232.529126) (xy 379.403102 -232.576624)
			(xy 379.602492 -232.593896)
		)
		(stroke
			(width 0)
			(type solid)
		)
		(fill yes)
		(layer "In4.Cu")
		(net "M_J_CPU0_SA_DQS_DN<6>")
	)
	(gr_poly
		(pts
			(xy 379.893576 -288.454338) (xy 379.889512 -288.410142) (xy 379.690376 -288.427414) (xy 379.694186 -288.471864)
			(xy 379.802644 -288.562542)
		)
		(stroke
			(width 0)
			(type solid)
		)
		(fill yes)
		(layer "In4.Cu")
		(net "M_J_CPU0_SB_DQ<23>")
	)
	(gr_poly
		(pts
			(xy 379.89383 -290.074096) (xy 379.889766 -290.0299) (xy 379.69063 -290.047172) (xy 379.69444 -290.091368)
			(xy 379.802898 -290.1823)
		)
		(stroke
			(width 0)
			(type solid)
		)
		(fill yes)
		(layer "In4.Cu")
		(net "M_J_CPU0_SB_DQ<27>")
	)
	(gr_poly
		(pts
			(xy 379.89383 -285.214314) (xy 379.889766 -285.170118) (xy 379.69063 -285.18739) (xy 379.69444 -285.23184)
			(xy 379.802898 -285.322518)
		)
		(stroke
			(width 0)
			(type solid)
		)
		(fill yes)
		(layer "In4.Cu")
		(net "M_J_CPU0_SB_DQ<19>")
	)
	(gr_poly
		(pts
			(xy 379.89383 -283.594302) (xy 379.889766 -283.550106) (xy 379.69063 -283.567378) (xy 379.69444 -283.611828)
			(xy 379.802898 -283.702506)
		)
		(stroke
			(width 0)
			(type solid)
		)
		(fill yes)
		(layer "In4.Cu")
		(net "M_J_CPU0_SB_DQ<15>")
	)
	(gr_poly
		(pts
			(xy 379.89383 -280.354278) (xy 379.889766 -280.310082) (xy 379.69063 -280.327354) (xy 379.69444 -280.371804)
			(xy 379.802898 -280.462482)
		)
		(stroke
			(width 0)
			(type solid)
		)
		(fill yes)
		(layer "In4.Cu")
		(net "M_J_CPU0_SB_DQ<11>")
	)
	(gr_poly
		(pts
			(xy 379.89383 -278.734266) (xy 379.889766 -278.69007) (xy 379.69063 -278.707342) (xy 379.69444 -278.751792)
			(xy 379.802898 -278.84247)
		)
		(stroke
			(width 0)
			(type solid)
		)
		(fill yes)
		(layer "In4.Cu")
		(net "M_J_CPU0_SB_DQ<7>")
	)
	(gr_poly
		(pts
			(xy 379.89383 -275.494242) (xy 379.889766 -275.450046) (xy 379.69063 -275.467318) (xy 379.69444 -275.511768)
			(xy 379.802898 -275.602446)
		)
		(stroke
			(width 0)
			(type solid)
		)
		(fill yes)
		(layer "In4.Cu")
		(net "M_J_CPU0_SB_DQ<3>")
	)
	(gr_poly
		(pts
			(xy 379.89383 -273.87423) (xy 379.889766 -273.830034) (xy 379.69063 -273.847306) (xy 379.69444 -273.891756)
			(xy 379.802898 -273.982434)
		)
		(stroke
			(width 0)
			(type solid)
		)
		(fill yes)
		(layer "In4.Cu")
		(net "M_J_CPU0_SB_CB<3>")
	)
	(gr_poly
		(pts
			(xy 379.89383 -270.634206) (xy 379.889766 -270.59001) (xy 379.69063 -270.607282) (xy 379.69444 -270.651732)
			(xy 379.802898 -270.74241)
		)
		(stroke
			(width 0)
			(type solid)
		)
		(fill yes)
		(layer "In4.Cu")
		(net "M_J_CPU0_SB_CB<7>")
	)
	(gr_poly
		(pts
			(xy 379.89383 -265.77417) (xy 379.889766 -265.729974) (xy 379.69063 -265.747246) (xy 379.69444 -265.791696)
			(xy 379.802898 -265.882374)
		)
		(stroke
			(width 0)
			(type solid)
		)
		(fill yes)
		(layer "In4.Cu")
		(net "M_J_CPU0_SB_CS_N<0>")
	)
	(gr_poly
		(pts
			(xy 379.89383 -264.154158) (xy 379.889766 -264.109962) (xy 379.69063 -264.127234) (xy 379.69444 -264.171684)
			(xy 379.802898 -264.262362)
		)
		(stroke
			(width 0)
			(type solid)
		)
		(fill yes)
		(layer "In4.Cu")
		(net "M_J_CPU0_SB_CA<5>")
	)
	(gr_poly
		(pts
			(xy 379.89383 -262.534146) (xy 379.889766 -262.48995) (xy 379.69063 -262.507222) (xy 379.69444 -262.551672)
			(xy 379.802898 -262.64235)
		)
		(stroke
			(width 0)
			(type solid)
		)
		(fill yes)
		(layer "In4.Cu")
		(net "M_J_CPU0_SB_CA<1>")
	)
	(gr_poly
		(pts
			(xy 379.895608 -286.834326) (xy 379.89129 -286.786828) (xy 379.692154 -286.8041) (xy 379.696218 -286.851598)
			(xy 379.804676 -286.94253)
		)
		(stroke
			(width 0)
			(type solid)
		)
		(fill yes)
		(layer "In4.Cu")
		(net "M_J_CPU0_SB_DQS_DP<7>")
	)
	(gr_poly
		(pts
			(xy 379.895608 -272.254472) (xy 379.89129 -272.206974) (xy 379.692154 -272.224246) (xy 379.696218 -272.271744)
			(xy 379.804676 -272.362676)
		)
		(stroke
			(width 0)
			(type solid)
		)
		(fill yes)
		(layer "In4.Cu")
		(net "M_J_CPU0_SB_DQS_DP<4>")
	)
	(gr_poly
		(pts
			(xy 379.90653 -291.693346) (xy 379.902466 -291.645848) (xy 379.703076 -291.663374) (xy 379.707394 -291.710872)
			(xy 379.815598 -291.801804)
		)
		(stroke
			(width 0)
			(type solid)
		)
		(fill yes)
		(layer "In4.Cu")
		(net "M_J_CPU0_SB_DQS_DP<8>")
	)
	(gr_poly
		(pts
			(xy 379.90653 -281.973528) (xy 379.902466 -281.926284) (xy 379.703076 -281.943556) (xy 379.707394 -281.991054)
			(xy 379.815598 -282.081986)
		)
		(stroke
			(width 0)
			(type solid)
		)
		(fill yes)
		(layer "In4.Cu")
		(net "M_J_CPU0_SB_DQS_DP<6>")
	)
	(gr_poly
		(pts
			(xy 379.90653 -277.113492) (xy 379.902466 -277.066248) (xy 379.703076 -277.08352) (xy 379.707394 -277.131018)
			(xy 379.815598 -277.22195)
		)
		(stroke
			(width 0)
			(type solid)
		)
		(fill yes)
		(layer "In4.Cu")
		(net "M_J_CPU0_SB_DQS_DP<5>")
	)
	(gr_poly
		(pts
			(xy 380.024894 -255.622298) (xy 380.024894 -255.577848) (xy 379.824742 -255.577848) (xy 379.824742 -255.622298)
			(xy 379.924818 -255.722374)
		)
		(stroke
			(width 0)
			(type solid)
		)
		(fill yes)
		(layer "In4.Cu")
		(net "M_J_CPU0_SA_PAR")
	)
	(gr_poly
		(pts
			(xy 380.024894 -254.002286) (xy 380.024894 -253.957836) (xy 379.824742 -253.957836) (xy 379.824742 -254.002286)
			(xy 379.924818 -254.102362)
		)
		(stroke
			(width 0)
			(type solid)
		)
		(fill yes)
		(layer "In4.Cu")
		(net "M_J_CPU0_SA_CA<3>")
	)
	(gr_poly
		(pts
			(xy 380.024894 -250.762262) (xy 380.024894 -250.717812) (xy 379.824742 -250.717812) (xy 379.824742 -250.762262)
			(xy 379.924818 -250.862338)
		)
		(stroke
			(width 0)
			(type solid)
		)
		(fill yes)
		(layer "In4.Cu")
		(net "M_J_CPU0_RESET_N")
	)
	(gr_poly
		(pts
			(xy 380.024894 -249.14225) (xy 380.024894 -249.0978) (xy 379.824742 -249.0978) (xy 379.824742 -249.14225)
			(xy 379.924818 -249.242326)
		)
		(stroke
			(width 0)
			(type solid)
		)
		(fill yes)
		(layer "In4.Cu")
		(net "M_J_CPU0_SA_CB<7>")
	)
	(gr_poly
		(pts
			(xy 380.024894 -247.522492) (xy 380.024894 -247.47474) (xy 379.824742 -247.47474) (xy 379.824742 -247.522492)
			(xy 379.924818 -247.622314)
		)
		(stroke
			(width 0)
			(type solid)
		)
		(fill yes)
		(layer "In4.Cu")
		(net "M_J_CPU0_SA_DQS_DP<9>")
	)
	(gr_poly
		(pts
			(xy 380.024894 -245.902226) (xy 380.024894 -245.857776) (xy 379.824742 -245.857776) (xy 379.824742 -245.902226)
			(xy 379.924818 -246.002302)
		)
		(stroke
			(width 0)
			(type solid)
		)
		(fill yes)
		(layer "In4.Cu")
		(net "M_J_CPU0_SA_CB<3>")
	)
	(gr_poly
		(pts
			(xy 380.024894 -244.282214) (xy 380.024894 -244.237764) (xy 379.824742 -244.237764) (xy 379.824742 -244.282214)
			(xy 379.924818 -244.38229)
		)
		(stroke
			(width 0)
			(type solid)
		)
		(fill yes)
		(layer "In4.Cu")
		(net "M_J_CPU0_SA_DQ<31>")
	)
	(gr_poly
		(pts
			(xy 380.024894 -242.662456) (xy 380.024894 -242.614704) (xy 379.824742 -242.614704) (xy 379.824742 -242.662456)
			(xy 379.924818 -242.762278)
		)
		(stroke
			(width 0)
			(type solid)
		)
		(fill yes)
		(layer "In4.Cu")
		(net "M_J_CPU0_SA_DQS_DP<8>")
	)
	(gr_poly
		(pts
			(xy 380.024894 -241.04219) (xy 380.024894 -240.99774) (xy 379.824742 -240.99774) (xy 379.824742 -241.04219)
			(xy 379.924818 -241.142266)
		)
		(stroke
			(width 0)
			(type solid)
		)
		(fill yes)
		(layer "In4.Cu")
		(net "M_J_CPU0_SA_DQ<27>")
	)
	(gr_poly
		(pts
			(xy 380.024894 -239.422178) (xy 380.024894 -239.377728) (xy 379.824742 -239.377728) (xy 379.824742 -239.422178)
			(xy 379.924818 -239.522254)
		)
		(stroke
			(width 0)
			(type solid)
		)
		(fill yes)
		(layer "In4.Cu")
		(net "M_J_CPU0_SA_DQ<23>")
	)
	(gr_poly
		(pts
			(xy 380.024894 -237.80242) (xy 380.024894 -237.754668) (xy 379.824742 -237.754668) (xy 379.824742 -237.80242)
			(xy 379.924818 -237.902242)
		)
		(stroke
			(width 0)
			(type solid)
		)
		(fill yes)
		(layer "In4.Cu")
		(net "M_J_CPU0_SA_DQS_DP<7>")
	)
	(gr_poly
		(pts
			(xy 380.024894 -236.182154) (xy 380.024894 -236.137704) (xy 379.824742 -236.137704) (xy 379.824742 -236.182154)
			(xy 379.924818 -236.28223)
		)
		(stroke
			(width 0)
			(type solid)
		)
		(fill yes)
		(layer "In4.Cu")
		(net "M_J_CPU0_SA_DQ<19>")
	)
	(gr_poly
		(pts
			(xy 380.024894 -234.562142) (xy 380.024894 -234.517692) (xy 379.824742 -234.517692) (xy 379.824742 -234.562142)
			(xy 379.924818 -234.662218)
		)
		(stroke
			(width 0)
			(type solid)
		)
		(fill yes)
		(layer "In4.Cu")
		(net "M_J_CPU0_SA_DQ<15>")
	)
	(gr_poly
		(pts
			(xy 380.024894 -232.942384) (xy 380.024894 -232.894632) (xy 379.824742 -232.894632) (xy 379.824742 -232.942384)
			(xy 379.924818 -233.042206)
		)
		(stroke
			(width 0)
			(type solid)
		)
		(fill yes)
		(layer "In4.Cu")
		(net "M_J_CPU0_SA_DQS_DP<6>")
	)
	(gr_poly
		(pts
			(xy 380.024894 -231.322372) (xy 380.024894 -231.277922) (xy 379.824742 -231.277922) (xy 379.824742 -231.322372)
			(xy 379.924818 -231.422448)
		)
		(stroke
			(width 0)
			(type solid)
		)
		(fill yes)
		(layer "In4.Cu")
		(net "M_J_CPU0_SA_DQ<11>")
	)
	(gr_poly
		(pts
			(xy 380.024894 -229.70236) (xy 380.024894 -229.65791) (xy 379.824742 -229.65791) (xy 379.824742 -229.70236)
			(xy 379.924818 -229.802436)
		)
		(stroke
			(width 0)
			(type solid)
		)
		(fill yes)
		(layer "In4.Cu")
		(net "M_J_CPU0_SA_DQ<7>")
	)
	(gr_poly
		(pts
			(xy 380.024894 -228.082602) (xy 380.024894 -228.03485) (xy 379.824742 -228.03485) (xy 379.824742 -228.082602)
			(xy 379.924818 -228.182424)
		)
		(stroke
			(width 0)
			(type solid)
		)
		(fill yes)
		(layer "In4.Cu")
		(net "M_J_CPU0_SA_DQS_DP<5>")
	)
	(gr_poly
		(pts
			(xy 380.024894 -226.462336) (xy 380.024894 -226.417886) (xy 379.824742 -226.417886) (xy 379.824742 -226.462336)
			(xy 379.924818 -226.562412)
		)
		(stroke
			(width 0)
			(type solid)
		)
		(fill yes)
		(layer "In4.Cu")
		(net "M_J_CPU0_SA_DQ<3>")
	)
	(gr_poly
		(pts
			(xy 380.324868 -291.297614) (xy 380.224792 -291.197792) (xy 380.124716 -291.297614) (xy 380.124716 -291.345366)
			(xy 380.324868 -291.345366)
		)
		(stroke
			(width 0)
			(type solid)
		)
		(fill yes)
		(layer "In4.Cu")
		(net "M_J_CPU0_SB_DQS_DN<8>")
	)
	(gr_poly
		(pts
			(xy 380.324868 -289.677856) (xy 380.224792 -289.57778) (xy 380.124716 -289.677856) (xy 380.124716 -289.722306)
			(xy 380.324868 -289.722306)
		)
		(stroke
			(width 0)
			(type solid)
		)
		(fill yes)
		(layer "In4.Cu")
		(net "M_J_CPU0_SB_DQ<25>")
	)
	(gr_poly
		(pts
			(xy 380.324868 -288.057844) (xy 380.224792 -287.957768) (xy 380.124716 -288.057844) (xy 380.124716 -288.102294)
			(xy 380.324868 -288.102294)
		)
		(stroke
			(width 0)
			(type solid)
		)
		(fill yes)
		(layer "In4.Cu")
		(net "M_J_CPU0_SB_DQ<21>")
	)
	(gr_poly
		(pts
			(xy 380.324868 -286.437832) (xy 380.224792 -286.337756) (xy 380.124716 -286.437832) (xy 380.124716 -286.485584)
			(xy 380.324868 -286.485584)
		)
		(stroke
			(width 0)
			(type solid)
		)
		(fill yes)
		(layer "In4.Cu")
		(net "M_J_CPU0_SB_DQS_DN<7>")
	)
	(gr_poly
		(pts
			(xy 380.324868 -284.818074) (xy 380.224792 -284.717998) (xy 380.124716 -284.818074) (xy 380.124716 -284.862524)
			(xy 380.324868 -284.862524)
		)
		(stroke
			(width 0)
			(type solid)
		)
		(fill yes)
		(layer "In4.Cu")
		(net "M_J_CPU0_SB_DQ<17>")
	)
	(gr_poly
		(pts
			(xy 380.324868 -283.198062) (xy 380.224792 -283.097986) (xy 380.124716 -283.198062) (xy 380.124716 -283.242512)
			(xy 380.324868 -283.242512)
		)
		(stroke
			(width 0)
			(type solid)
		)
		(fill yes)
		(layer "In4.Cu")
		(net "M_J_CPU0_SB_DQ<13>")
	)
	(gr_poly
		(pts
			(xy 380.324868 -281.577796) (xy 380.224792 -281.477974) (xy 380.124716 -281.577796) (xy 380.124716 -281.625548)
			(xy 380.324868 -281.625548)
		)
		(stroke
			(width 0)
			(type solid)
		)
		(fill yes)
		(layer "In4.Cu")
		(net "M_J_CPU0_SB_DQS_DN<6>")
	)
	(gr_poly
		(pts
			(xy 380.324868 -279.958038) (xy 380.224792 -279.857962) (xy 380.124716 -279.958038) (xy 380.124716 -280.002488)
			(xy 380.324868 -280.002488)
		)
		(stroke
			(width 0)
			(type solid)
		)
		(fill yes)
		(layer "In4.Cu")
		(net "M_J_CPU0_SB_DQ<9>")
	)
	(gr_poly
		(pts
			(xy 380.324868 -278.338026) (xy 380.224792 -278.23795) (xy 380.124716 -278.338026) (xy 380.124716 -278.382476)
			(xy 380.324868 -278.382476)
		)
		(stroke
			(width 0)
			(type solid)
		)
		(fill yes)
		(layer "In4.Cu")
		(net "M_J_CPU0_SB_DQ<5>")
	)
	(gr_poly
		(pts
			(xy 380.324868 -276.71776) (xy 380.224792 -276.617938) (xy 380.124716 -276.71776) (xy 380.124716 -276.765512)
			(xy 380.324868 -276.765512)
		)
		(stroke
			(width 0)
			(type solid)
		)
		(fill yes)
		(layer "In4.Cu")
		(net "M_J_CPU0_SB_DQS_DN<5>")
	)
	(gr_poly
		(pts
			(xy 380.324868 -275.098002) (xy 380.224792 -274.997926) (xy 380.124716 -275.098002) (xy 380.124716 -275.142452)
			(xy 380.324868 -275.142452)
		)
		(stroke
			(width 0)
			(type solid)
		)
		(fill yes)
		(layer "In4.Cu")
		(net "M_J_CPU0_SB_DQ<1>")
	)
	(gr_poly
		(pts
			(xy 380.324868 -273.47799) (xy 380.224792 -273.377914) (xy 380.124716 -273.47799) (xy 380.124716 -273.52244)
			(xy 380.324868 -273.52244)
		)
		(stroke
			(width 0)
			(type solid)
		)
		(fill yes)
		(layer "In4.Cu")
		(net "M_J_CPU0_SB_CB<1>")
	)
	(gr_poly
		(pts
			(xy 380.324868 -271.857724) (xy 380.224792 -271.757902) (xy 380.124716 -271.857724) (xy 380.124716 -271.905476)
			(xy 380.324868 -271.905476)
		)
		(stroke
			(width 0)
			(type solid)
		)
		(fill yes)
		(layer "In4.Cu")
		(net "M_J_CPU0_SB_DQS_DN<4>")
	)
	(gr_poly
		(pts
			(xy 380.324868 -270.237966) (xy 380.224792 -270.13789) (xy 380.124716 -270.237966) (xy 380.124716 -270.282416)
			(xy 380.324868 -270.282416)
		)
		(stroke
			(width 0)
			(type solid)
		)
		(fill yes)
		(layer "In4.Cu")
		(net "M_J_CPU0_SB_CB<5>")
	)
	(gr_poly
		(pts
			(xy 380.324868 -266.997942) (xy 380.224792 -266.897866) (xy 380.124716 -266.997942) (xy 380.124716 -267.042392)
			(xy 380.324868 -267.042392)
		)
		(stroke
			(width 0)
			(type solid)
		)
		(fill yes)
		(layer "In4.Cu")
		(net "M_J_CPU0_SA_RSP<0>")
	)
	(gr_poly
		(pts
			(xy 380.324868 -265.37793) (xy 380.224792 -265.277854) (xy 380.124716 -265.37793) (xy 380.124716 -265.42238)
			(xy 380.324868 -265.42238)
		)
		(stroke
			(width 0)
			(type solid)
		)
		(fill yes)
		(layer "In4.Cu")
		(net "M_J_CPU0_SB_PAR")
	)
	(gr_poly
		(pts
			(xy 380.324868 -263.757918) (xy 380.224792 -263.657842) (xy 380.124716 -263.757918) (xy 380.124716 -263.802368)
			(xy 380.324868 -263.802368)
		)
		(stroke
			(width 0)
			(type solid)
		)
		(fill yes)
		(layer "In4.Cu")
		(net "M_J_CPU0_SB_CA<4>")
	)
	(gr_poly
		(pts
			(xy 380.324868 -262.137906) (xy 380.224792 -262.03783) (xy 380.124716 -262.137906) (xy 380.124716 -262.182356)
			(xy 380.324868 -262.182356)
		)
		(stroke
			(width 0)
			(type solid)
		)
		(fill yes)
		(layer "In4.Cu")
		(net "M_J_CPU0_SB_CA<0>")
	)
	(gr_poly
		(pts
			(xy 380.494794 -255.216152) (xy 380.394718 -255.116076) (xy 380.294642 -255.216152) (xy 380.294642 -255.260602)
			(xy 380.494794 -255.260602)
		)
		(stroke
			(width 0)
			(type solid)
		)
		(fill yes)
		(layer "In4.Cu")
		(net "M_J_CPU0_SA_CA<6>")
	)
	(gr_poly
		(pts
			(xy 380.494794 -253.59614) (xy 380.394718 -253.496064) (xy 380.294642 -253.59614) (xy 380.294642 -253.64059)
			(xy 380.494794 -253.64059)
		)
		(stroke
			(width 0)
			(type solid)
		)
		(fill yes)
		(layer "In4.Cu")
		(net "M_J_CPU0_SA_CA<2>")
	)
	(gr_poly
		(pts
			(xy 380.494794 -251.976128) (xy 380.394718 -251.876052) (xy 380.294642 -251.976128) (xy 380.294642 -252.020578)
			(xy 380.494794 -252.020578)
		)
		(stroke
			(width 0)
			(type solid)
		)
		(fill yes)
		(layer "In4.Cu")
		(net "M_J_CPU0_SA_CS_N<1>")
	)
	(gr_poly
		(pts
			(xy 380.494794 -250.356116) (xy 380.394718 -250.25604) (xy 380.294642 -250.356116) (xy 380.294642 -250.400566)
			(xy 380.494794 -250.400566)
		)
		(stroke
			(width 0)
			(type solid)
		)
		(fill yes)
		(layer "In4.Cu")
		(net "M_J_CPU0_ALERT_R_N")
	)
	(gr_poly
		(pts
			(xy 380.494794 -248.736104) (xy 380.394718 -248.636028) (xy 380.294642 -248.736104) (xy 380.294642 -248.780554)
			(xy 380.494794 -248.780554)
		)
		(stroke
			(width 0)
			(type solid)
		)
		(fill yes)
		(layer "In4.Cu")
		(net "M_J_CPU0_SA_CB<5>")
	)
	(gr_poly
		(pts
			(xy 380.494794 -247.115838) (xy 380.394718 -247.016016) (xy 380.294642 -247.115838) (xy 380.294642 -247.16359)
			(xy 380.494794 -247.16359)
		)
		(stroke
			(width 0)
			(type solid)
		)
		(fill yes)
		(layer "In4.Cu")
		(net "M_J_CPU0_SA_DQS_DN<9>")
	)
	(gr_poly
		(pts
			(xy 380.494794 -245.49608) (xy 380.394718 -245.396004) (xy 380.294642 -245.49608) (xy 380.294642 -245.54053)
			(xy 380.494794 -245.54053)
		)
		(stroke
			(width 0)
			(type solid)
		)
		(fill yes)
		(layer "In4.Cu")
		(net "M_J_CPU0_SA_CB<1>")
	)
	(gr_poly
		(pts
			(xy 380.494794 -243.876068) (xy 380.394718 -243.775992) (xy 380.294642 -243.876068) (xy 380.294642 -243.920518)
			(xy 380.494794 -243.920518)
		)
		(stroke
			(width 0)
			(type solid)
		)
		(fill yes)
		(layer "In4.Cu")
		(net "M_J_CPU0_SA_DQ<29>")
	)
	(gr_poly
		(pts
			(xy 380.494794 -242.255802) (xy 380.394718 -242.15598) (xy 380.294642 -242.255802) (xy 380.294642 -242.303554)
			(xy 380.494794 -242.303554)
		)
		(stroke
			(width 0)
			(type solid)
		)
		(fill yes)
		(layer "In4.Cu")
		(net "M_J_CPU0_SA_DQS_DN<8>")
	)
	(gr_poly
		(pts
			(xy 380.494794 -240.636044) (xy 380.394718 -240.535968) (xy 380.294642 -240.636044) (xy 380.294642 -240.680494)
			(xy 380.494794 -240.680494)
		)
		(stroke
			(width 0)
			(type solid)
		)
		(fill yes)
		(layer "In4.Cu")
		(net "M_J_CPU0_SA_DQ<25>")
	)
	(gr_poly
		(pts
			(xy 380.494794 -239.016032) (xy 380.394718 -238.915956) (xy 380.294642 -239.016032) (xy 380.294642 -239.060482)
			(xy 380.494794 -239.060482)
		)
		(stroke
			(width 0)
			(type solid)
		)
		(fill yes)
		(layer "In4.Cu")
		(net "M_J_CPU0_SA_DQ<21>")
	)
	(gr_poly
		(pts
			(xy 380.494794 -237.395766) (xy 380.394718 -237.295944) (xy 380.294642 -237.395766) (xy 380.294642 -237.443518)
			(xy 380.494794 -237.443518)
		)
		(stroke
			(width 0)
			(type solid)
		)
		(fill yes)
		(layer "In4.Cu")
		(net "M_J_CPU0_SA_DQS_DN<7>")
	)
	(gr_poly
		(pts
			(xy 380.494794 -235.776008) (xy 380.394718 -235.675932) (xy 380.294642 -235.776008) (xy 380.294642 -235.820458)
			(xy 380.494794 -235.820458)
		)
		(stroke
			(width 0)
			(type solid)
		)
		(fill yes)
		(layer "In4.Cu")
		(net "M_J_CPU0_SA_DQ<17>")
	)
	(gr_poly
		(pts
			(xy 380.494794 -234.155996) (xy 380.394718 -234.05592) (xy 380.294642 -234.155996) (xy 380.294642 -234.200446)
			(xy 380.494794 -234.200446)
		)
		(stroke
			(width 0)
			(type solid)
		)
		(fill yes)
		(layer "In4.Cu")
		(net "M_J_CPU0_SA_DQ<13>")
	)
	(gr_poly
		(pts
			(xy 380.494794 -232.53573) (xy 380.394718 -232.435908) (xy 380.294642 -232.53573) (xy 380.294642 -232.583482)
			(xy 380.494794 -232.583482)
		)
		(stroke
			(width 0)
			(type solid)
		)
		(fill yes)
		(layer "In4.Cu")
		(net "M_J_CPU0_SA_DQS_DN<6>")
	)
	(gr_poly
		(pts
			(xy 380.494794 -230.915972) (xy 380.394718 -230.815896) (xy 380.294642 -230.915972) (xy 380.294642 -230.960422)
			(xy 380.494794 -230.960422)
		)
		(stroke
			(width 0)
			(type solid)
		)
		(fill yes)
		(layer "In4.Cu")
		(net "M_J_CPU0_SA_DQ<9>")
	)
	(gr_poly
		(pts
			(xy 380.494794 -229.29596) (xy 380.394718 -229.195884) (xy 380.294642 -229.29596) (xy 380.294642 -229.34041)
			(xy 380.494794 -229.34041)
		)
		(stroke
			(width 0)
			(type solid)
		)
		(fill yes)
		(layer "In4.Cu")
		(net "M_J_CPU0_SA_DQ<5>")
	)
	(gr_poly
		(pts
			(xy 380.494794 -227.675948) (xy 380.394718 -227.576126) (xy 380.294642 -227.675948) (xy 380.294642 -227.7237)
			(xy 380.494794 -227.7237)
		)
		(stroke
			(width 0)
			(type solid)
		)
		(fill yes)
		(layer "In4.Cu")
		(net "M_J_CPU0_SA_DQS_DN<5>")
	)
	(gr_poly
		(pts
			(xy 380.494794 -226.05619) (xy 380.394718 -225.956114) (xy 380.294642 -226.05619) (xy 380.294642 -226.10064)
			(xy 380.494794 -226.10064)
		)
		(stroke
			(width 0)
			(type solid)
		)
		(fill yes)
		(layer "In4.Cu")
		(net "M_J_CPU0_SA_DQ<1>")
	)
	(gr_poly
		(pts
			(xy 380.795022 -291.704268) (xy 380.795022 -291.656516) (xy 380.59487 -291.656516) (xy 380.59487 -291.704268)
			(xy 380.694946 -291.80409)
		)
		(stroke
			(width 0)
			(type solid)
		)
		(fill yes)
		(layer "In4.Cu")
		(net "M_J_CPU0_SB_DQS_DP<8>")
	)
	(gr_poly
		(pts
			(xy 380.795022 -290.084002) (xy 380.795022 -290.039552) (xy 380.59487 -290.039552) (xy 380.59487 -290.084002)
			(xy 380.694946 -290.184078)
		)
		(stroke
			(width 0)
			(type solid)
		)
		(fill yes)
		(layer "In4.Cu")
		(net "M_J_CPU0_SB_DQ<27>")
	)
	(gr_poly
		(pts
			(xy 380.795022 -288.464244) (xy 380.795022 -288.419794) (xy 380.59487 -288.419794) (xy 380.59487 -288.464244)
			(xy 380.694946 -288.56432)
		)
		(stroke
			(width 0)
			(type solid)
		)
		(fill yes)
		(layer "In4.Cu")
		(net "M_J_CPU0_SB_DQ<23>")
	)
	(gr_poly
		(pts
			(xy 380.795022 -286.844232) (xy 380.795022 -286.79648) (xy 380.59487 -286.79648) (xy 380.59487 -286.844232)
			(xy 380.694946 -286.944308)
		)
		(stroke
			(width 0)
			(type solid)
		)
		(fill yes)
		(layer "In4.Cu")
		(net "M_J_CPU0_SB_DQS_DP<7>")
	)
	(gr_poly
		(pts
			(xy 380.795022 -285.22422) (xy 380.795022 -285.17977) (xy 380.59487 -285.17977) (xy 380.59487 -285.22422)
			(xy 380.694946 -285.324296)
		)
		(stroke
			(width 0)
			(type solid)
		)
		(fill yes)
		(layer "In4.Cu")
		(net "M_J_CPU0_SB_DQ<19>")
	)
	(gr_poly
		(pts
			(xy 380.795022 -283.604208) (xy 380.795022 -283.559758) (xy 380.59487 -283.559758) (xy 380.59487 -283.604208)
			(xy 380.694946 -283.704284)
		)
		(stroke
			(width 0)
			(type solid)
		)
		(fill yes)
		(layer "In4.Cu")
		(net "M_J_CPU0_SB_DQ<15>")
	)
	(gr_poly
		(pts
			(xy 380.795022 -281.98445) (xy 380.795022 -281.936698) (xy 380.59487 -281.936698) (xy 380.59487 -281.98445)
			(xy 380.694946 -282.084272)
		)
		(stroke
			(width 0)
			(type solid)
		)
		(fill yes)
		(layer "In4.Cu")
		(net "M_J_CPU0_SB_DQS_DP<6>")
	)
	(gr_poly
		(pts
			(xy 380.795022 -280.364184) (xy 380.795022 -280.319734) (xy 380.59487 -280.319734) (xy 380.59487 -280.364184)
			(xy 380.694946 -280.46426)
		)
		(stroke
			(width 0)
			(type solid)
		)
		(fill yes)
		(layer "In4.Cu")
		(net "M_J_CPU0_SB_DQ<11>")
	)
	(gr_poly
		(pts
			(xy 380.795022 -278.744172) (xy 380.795022 -278.699722) (xy 380.59487 -278.699722) (xy 380.59487 -278.744172)
			(xy 380.694946 -278.844248)
		)
		(stroke
			(width 0)
			(type solid)
		)
		(fill yes)
		(layer "In4.Cu")
		(net "M_J_CPU0_SB_DQ<7>")
	)
	(gr_poly
		(pts
			(xy 380.795022 -277.124414) (xy 380.795022 -277.076662) (xy 380.59487 -277.076662) (xy 380.59487 -277.124414)
			(xy 380.694946 -277.224236)
		)
		(stroke
			(width 0)
			(type solid)
		)
		(fill yes)
		(layer "In4.Cu")
		(net "M_J_CPU0_SB_DQS_DP<5>")
	)
	(gr_poly
		(pts
			(xy 380.795022 -275.504148) (xy 380.795022 -275.459698) (xy 380.59487 -275.459698) (xy 380.59487 -275.504148)
			(xy 380.694946 -275.604224)
		)
		(stroke
			(width 0)
			(type solid)
		)
		(fill yes)
		(layer "In4.Cu")
		(net "M_J_CPU0_SB_DQ<3>")
	)
	(gr_poly
		(pts
			(xy 380.795022 -273.884136) (xy 380.795022 -273.839686) (xy 380.59487 -273.839686) (xy 380.59487 -273.884136)
			(xy 380.694946 -273.984212)
		)
		(stroke
			(width 0)
			(type solid)
		)
		(fill yes)
		(layer "In4.Cu")
		(net "M_J_CPU0_SB_CB<3>")
	)
	(gr_poly
		(pts
			(xy 380.795022 -272.264378) (xy 380.795022 -272.216626) (xy 380.59487 -272.216626) (xy 380.59487 -272.264378)
			(xy 380.694946 -272.3642)
		)
		(stroke
			(width 0)
			(type solid)
		)
		(fill yes)
		(layer "In4.Cu")
		(net "M_J_CPU0_SB_DQS_DP<4>")
	)
	(gr_poly
		(pts
			(xy 380.795022 -270.644112) (xy 380.795022 -270.599662) (xy 380.59487 -270.599662) (xy 380.59487 -270.644112)
			(xy 380.694946 -270.744188)
		)
		(stroke
			(width 0)
			(type solid)
		)
		(fill yes)
		(layer "In4.Cu")
		(net "M_J_CPU0_SB_CB<7>")
	)
	(gr_poly
		(pts
			(xy 380.795022 -265.784076) (xy 380.795022 -265.739626) (xy 380.59487 -265.739626) (xy 380.59487 -265.784076)
			(xy 380.694946 -265.884152)
		)
		(stroke
			(width 0)
			(type solid)
		)
		(fill yes)
		(layer "In4.Cu")
		(net "M_J_CPU0_SB_CS_N<0>")
	)
	(gr_poly
		(pts
			(xy 380.795022 -264.164064) (xy 380.795022 -264.119614) (xy 380.59487 -264.119614) (xy 380.59487 -264.164064)
			(xy 380.694946 -264.26414)
		)
		(stroke
			(width 0)
			(type solid)
		)
		(fill yes)
		(layer "In4.Cu")
		(net "M_J_CPU0_SB_CA<5>")
	)
	(gr_poly
		(pts
			(xy 380.795022 -262.544052) (xy 380.795022 -262.499602) (xy 380.59487 -262.499602) (xy 380.59487 -262.544052)
			(xy 380.694946 -262.644128)
		)
		(stroke
			(width 0)
			(type solid)
		)
		(fill yes)
		(layer "In4.Cu")
		(net "M_J_CPU0_SB_CA<1>")
	)
	(gr_poly
		(pts
			(xy 380.964948 -255.622298) (xy 380.964948 -255.577848) (xy 380.764796 -255.577848) (xy 380.764796 -255.622298)
			(xy 380.864872 -255.722374)
		)
		(stroke
			(width 0)
			(type solid)
		)
		(fill yes)
		(layer "In4.Cu")
		(net "M_J_CPU0_SA_PAR")
	)
	(gr_poly
		(pts
			(xy 380.964948 -254.002286) (xy 380.964948 -253.957836) (xy 380.764796 -253.957836) (xy 380.764796 -254.002286)
			(xy 380.864872 -254.102362)
		)
		(stroke
			(width 0)
			(type solid)
		)
		(fill yes)
		(layer "In4.Cu")
		(net "M_J_CPU0_SA_CA<3>")
	)
	(gr_poly
		(pts
			(xy 380.964948 -250.762262) (xy 380.964948 -250.717812) (xy 380.764796 -250.717812) (xy 380.764796 -250.762262)
			(xy 380.864872 -250.862338)
		)
		(stroke
			(width 0)
			(type solid)
		)
		(fill yes)
		(layer "In4.Cu")
		(net "M_J_CPU0_RESET_N")
	)
	(gr_poly
		(pts
			(xy 380.964948 -249.14225) (xy 380.964948 -249.0978) (xy 380.764796 -249.0978) (xy 380.764796 -249.14225)
			(xy 380.864872 -249.242326)
		)
		(stroke
			(width 0)
			(type solid)
		)
		(fill yes)
		(layer "In4.Cu")
		(net "M_J_CPU0_SA_CB<7>")
	)
	(gr_poly
		(pts
			(xy 380.964948 -247.522492) (xy 380.964948 -247.47474) (xy 380.764796 -247.47474) (xy 380.764796 -247.522492)
			(xy 380.864872 -247.622314)
		)
		(stroke
			(width 0)
			(type solid)
		)
		(fill yes)
		(layer "In4.Cu")
		(net "M_J_CPU0_SA_DQS_DP<9>")
	)
	(gr_poly
		(pts
			(xy 380.964948 -245.902226) (xy 380.964948 -245.857776) (xy 380.764796 -245.857776) (xy 380.764796 -245.902226)
			(xy 380.864872 -246.002302)
		)
		(stroke
			(width 0)
			(type solid)
		)
		(fill yes)
		(layer "In4.Cu")
		(net "M_J_CPU0_SA_CB<3>")
	)
	(gr_poly
		(pts
			(xy 380.964948 -244.282214) (xy 380.964948 -244.237764) (xy 380.764796 -244.237764) (xy 380.764796 -244.282214)
			(xy 380.864872 -244.38229)
		)
		(stroke
			(width 0)
			(type solid)
		)
		(fill yes)
		(layer "In4.Cu")
		(net "M_J_CPU0_SA_DQ<31>")
	)
	(gr_poly
		(pts
			(xy 380.964948 -242.662456) (xy 380.964948 -242.614704) (xy 380.764796 -242.614704) (xy 380.764796 -242.662456)
			(xy 380.864872 -242.762278)
		)
		(stroke
			(width 0)
			(type solid)
		)
		(fill yes)
		(layer "In4.Cu")
		(net "M_J_CPU0_SA_DQS_DP<8>")
	)
	(gr_poly
		(pts
			(xy 380.964948 -241.04219) (xy 380.964948 -240.99774) (xy 380.764796 -240.99774) (xy 380.764796 -241.04219)
			(xy 380.864872 -241.142266)
		)
		(stroke
			(width 0)
			(type solid)
		)
		(fill yes)
		(layer "In4.Cu")
		(net "M_J_CPU0_SA_DQ<27>")
	)
	(gr_poly
		(pts
			(xy 380.964948 -239.422178) (xy 380.964948 -239.377728) (xy 380.764796 -239.377728) (xy 380.764796 -239.422178)
			(xy 380.864872 -239.522254)
		)
		(stroke
			(width 0)
			(type solid)
		)
		(fill yes)
		(layer "In4.Cu")
		(net "M_J_CPU0_SA_DQ<23>")
	)
	(gr_poly
		(pts
			(xy 380.964948 -237.80242) (xy 380.964948 -237.754668) (xy 380.764796 -237.754668) (xy 380.764796 -237.80242)
			(xy 380.864872 -237.902242)
		)
		(stroke
			(width 0)
			(type solid)
		)
		(fill yes)
		(layer "In4.Cu")
		(net "M_J_CPU0_SA_DQS_DP<7>")
	)
	(gr_poly
		(pts
			(xy 380.964948 -236.182154) (xy 380.964948 -236.137704) (xy 380.764796 -236.137704) (xy 380.764796 -236.182154)
			(xy 380.864872 -236.28223)
		)
		(stroke
			(width 0)
			(type solid)
		)
		(fill yes)
		(layer "In4.Cu")
		(net "M_J_CPU0_SA_DQ<19>")
	)
	(gr_poly
		(pts
			(xy 380.964948 -234.562142) (xy 380.964948 -234.517692) (xy 380.764796 -234.517692) (xy 380.764796 -234.562142)
			(xy 380.864872 -234.662218)
		)
		(stroke
			(width 0)
			(type solid)
		)
		(fill yes)
		(layer "In4.Cu")
		(net "M_J_CPU0_SA_DQ<15>")
	)
	(gr_poly
		(pts
			(xy 380.964948 -232.942384) (xy 380.964948 -232.894632) (xy 380.764796 -232.894632) (xy 380.764796 -232.942384)
			(xy 380.864872 -233.042206)
		)
		(stroke
			(width 0)
			(type solid)
		)
		(fill yes)
		(layer "In4.Cu")
		(net "M_J_CPU0_SA_DQS_DP<6>")
	)
	(gr_poly
		(pts
			(xy 380.964948 -231.322372) (xy 380.964948 -231.277922) (xy 380.764796 -231.277922) (xy 380.764796 -231.322372)
			(xy 380.864872 -231.422448)
		)
		(stroke
			(width 0)
			(type solid)
		)
		(fill yes)
		(layer "In4.Cu")
		(net "M_J_CPU0_SA_DQ<11>")
	)
	(gr_poly
		(pts
			(xy 380.964948 -229.70236) (xy 380.964948 -229.65791) (xy 380.764796 -229.65791) (xy 380.764796 -229.70236)
			(xy 380.864872 -229.802436)
		)
		(stroke
			(width 0)
			(type solid)
		)
		(fill yes)
		(layer "In4.Cu")
		(net "M_J_CPU0_SA_DQ<7>")
	)
	(gr_poly
		(pts
			(xy 380.964948 -228.082602) (xy 380.964948 -228.03485) (xy 380.764796 -228.03485) (xy 380.764796 -228.082602)
			(xy 380.864872 -228.182424)
		)
		(stroke
			(width 0)
			(type solid)
		)
		(fill yes)
		(layer "In4.Cu")
		(net "M_J_CPU0_SA_DQS_DP<5>")
	)
	(gr_poly
		(pts
			(xy 380.964948 -226.462336) (xy 380.964948 -226.417886) (xy 380.764796 -226.417886) (xy 380.764796 -226.462336)
			(xy 380.864872 -226.562412)
		)
		(stroke
			(width 0)
			(type solid)
		)
		(fill yes)
		(layer "In4.Cu")
		(net "M_J_CPU0_SA_DQ<3>")
	)
	(gr_poly
		(pts
			(xy 381.00381 -254.416052) (xy 380.912878 -254.307848) (xy 380.80442 -254.39878) (xy 380.80061 -254.442976)
			(xy 380.999746 -254.460248)
		)
		(stroke
			(width 0)
			(type solid)
		)
		(fill yes)
		(layer "In4.Cu")
		(net "M_J_CPU0_SA_CA<4>")
	)
	(gr_poly
		(pts
			(xy 381.00381 -252.79604) (xy 380.912878 -252.687836) (xy 380.80442 -252.778768) (xy 380.80061 -252.822964)
			(xy 380.999746 -252.840236)
		)
		(stroke
			(width 0)
			(type solid)
		)
		(fill yes)
		(layer "In4.Cu")
		(net "M_J_CPU0_SA_CA<0>")
	)
	(gr_poly
		(pts
			(xy 381.00381 -251.176028) (xy 380.912878 -251.067824) (xy 380.80442 -251.158502) (xy 380.80061 -251.202952)
			(xy 380.999746 -251.220224)
		)
		(stroke
			(width 0)
			(type solid)
		)
		(fill yes)
		(layer "In4.Cu")
		(net "M_J_CPU0_SA_CS_N<0>")
	)
	(gr_poly
		(pts
			(xy 381.00381 -247.936004) (xy 380.912878 -247.8278) (xy 380.80442 -247.918732) (xy 380.80061 -247.962928)
			(xy 380.999746 -247.9802)
		)
		(stroke
			(width 0)
			(type solid)
		)
		(fill yes)
		(layer "In4.Cu")
		(net "M_J_CPU0_SA_CB<4>")
	)
	(gr_poly
		(pts
			(xy 381.00381 -244.69598) (xy 380.912878 -244.587776) (xy 380.80442 -244.678708) (xy 380.80061 -244.722904)
			(xy 380.999746 -244.740176)
		)
		(stroke
			(width 0)
			(type solid)
		)
		(fill yes)
		(layer "In4.Cu")
		(net "M_J_CPU0_SA_CB<0>")
	)
	(gr_poly
		(pts
			(xy 381.00381 -243.075968) (xy 380.912878 -242.967764) (xy 380.80442 -243.058696) (xy 380.80061 -243.102892)
			(xy 380.999746 -243.120164)
		)
		(stroke
			(width 0)
			(type solid)
		)
		(fill yes)
		(layer "In4.Cu")
		(net "M_J_CPU0_SA_DQ<28>")
	)
	(gr_poly
		(pts
			(xy 381.00381 -239.835944) (xy 380.912878 -239.72774) (xy 380.80442 -239.818672) (xy 380.80061 -239.862868)
			(xy 380.999746 -239.88014)
		)
		(stroke
			(width 0)
			(type solid)
		)
		(fill yes)
		(layer "In4.Cu")
		(net "M_J_CPU0_SA_DQ<24>")
	)
	(gr_poly
		(pts
			(xy 381.00381 -238.215932) (xy 380.912878 -238.107728) (xy 380.80442 -238.19866) (xy 380.80061 -238.242856)
			(xy 380.999746 -238.260128)
		)
		(stroke
			(width 0)
			(type solid)
		)
		(fill yes)
		(layer "In4.Cu")
		(net "M_J_CPU0_SA_DQ<20>")
	)
	(gr_poly
		(pts
			(xy 381.00381 -234.975908) (xy 380.912878 -234.867704) (xy 380.80442 -234.958636) (xy 380.80061 -235.002832)
			(xy 380.999746 -235.020104)
		)
		(stroke
			(width 0)
			(type solid)
		)
		(fill yes)
		(layer "In4.Cu")
		(net "M_J_CPU0_SA_DQ<16>")
	)
	(gr_poly
		(pts
			(xy 381.00381 -233.355896) (xy 380.912878 -233.247692) (xy 380.80442 -233.33837) (xy 380.80061 -233.38282)
			(xy 380.999746 -233.400092)
		)
		(stroke
			(width 0)
			(type solid)
		)
		(fill yes)
		(layer "In4.Cu")
		(net "M_J_CPU0_SA_DQ<12>")
	)
	(gr_poly
		(pts
			(xy 381.00381 -230.115872) (xy 380.912878 -230.007668) (xy 380.80442 -230.0986) (xy 380.80061 -230.142796)
			(xy 380.999746 -230.160068)
		)
		(stroke
			(width 0)
			(type solid)
		)
		(fill yes)
		(layer "In4.Cu")
		(net "M_J_CPU0_SA_DQ<8>")
	)
	(gr_poly
		(pts
			(xy 381.00381 -228.496114) (xy 380.912878 -228.38791) (xy 380.80442 -228.478588) (xy 380.80061 -228.523038)
			(xy 380.999746 -228.54031)
		)
		(stroke
			(width 0)
			(type solid)
		)
		(fill yes)
		(layer "In4.Cu")
		(net "M_J_CPU0_SA_DQ<4>")
	)
	(gr_poly
		(pts
			(xy 381.00381 -225.25609) (xy 380.912878 -225.147886) (xy 380.80442 -225.238564) (xy 380.80061 -225.283014)
			(xy 380.999746 -225.300286)
		)
		(stroke
			(width 0)
			(type solid)
		)
		(fill yes)
		(layer "In4.Cu")
		(net "M_J_CPU0_SA_DQ<0>")
	)
	(gr_poly
		(pts
			(xy 381.005588 -256.03581) (xy 380.914656 -255.927606) (xy 380.806198 -256.018538) (xy 380.802134 -256.066036)
			(xy 381.00127 -256.083308)
		)
		(stroke
			(width 0)
			(type solid)
		)
		(fill yes)
		(layer "In4.Cu")
		(net "M_J_CPU0_CLK_DP<0>")
	)
	(gr_poly
		(pts
			(xy 381.005588 -231.73563) (xy 380.914656 -231.627426) (xy 380.806198 -231.718358) (xy 380.802134 -231.765856)
			(xy 381.00127 -231.783128)
		)
		(stroke
			(width 0)
			(type solid)
		)
		(fill yes)
		(layer "In4.Cu")
		(net "M_J_CPU0_SA_DQS_DP<1>")
	)
	(gr_poly
		(pts
			(xy 381.005588 -226.875848) (xy 380.914656 -226.767644) (xy 380.806198 -226.858576) (xy 380.802134 -226.906074)
			(xy 381.00127 -226.923346)
		)
		(stroke
			(width 0)
			(type solid)
		)
		(fill yes)
		(layer "In4.Cu")
		(net "M_J_CPU0_SA_DQS_DP<0>")
	)
	(gr_poly
		(pts
			(xy 381.01651 -246.316754) (xy 380.925578 -246.208296) (xy 380.817374 -246.299228) (xy 380.813056 -246.346726)
			(xy 381.012446 -246.364252)
		)
		(stroke
			(width 0)
			(type solid)
		)
		(fill yes)
		(layer "In4.Cu")
		(net "M_J_CPU0_SA_DQS_DP<4>")
	)
	(gr_poly
		(pts
			(xy 381.01651 -241.456718) (xy 380.925578 -241.34826) (xy 380.817374 -241.439192) (xy 380.813056 -241.48669)
			(xy 381.012446 -241.504216)
		)
		(stroke
			(width 0)
			(type solid)
		)
		(fill yes)
		(layer "In4.Cu")
		(net "M_J_CPU0_SA_DQS_DP<3>")
	)
	(gr_poly
		(pts
			(xy 381.01651 -236.596682) (xy 380.925578 -236.488224) (xy 380.817374 -236.579156) (xy 380.813056 -236.626654)
			(xy 381.012446 -236.64418)
		)
		(stroke
			(width 0)
			(type solid)
		)
		(fill yes)
		(layer "In4.Cu")
		(net "M_J_CPU0_SA_DQS_DP<2>")
	)
	(gr_poly
		(pts
			(xy 381.264922 -292.91788) (xy 381.164846 -292.817804) (xy 381.06477 -292.91788) (xy 381.06477 -292.96233)
			(xy 381.264922 -292.96233)
		)
		(stroke
			(width 0)
			(type solid)
		)
		(fill yes)
		(layer "In4.Cu")
		(net "M_J_CPU0_SB_DQ<29>")
	)
	(gr_poly
		(pts
			(xy 381.264922 -291.297614) (xy 381.164846 -291.197792) (xy 381.06477 -291.297614) (xy 381.06477 -291.345366)
			(xy 381.264922 -291.345366)
		)
		(stroke
			(width 0)
			(type solid)
		)
		(fill yes)
		(layer "In4.Cu")
		(net "M_J_CPU0_SB_DQS_DN<8>")
	)
	(gr_poly
		(pts
			(xy 381.264922 -289.677856) (xy 381.164846 -289.57778) (xy 381.06477 -289.677856) (xy 381.06477 -289.722306)
			(xy 381.264922 -289.722306)
		)
		(stroke
			(width 0)
			(type solid)
		)
		(fill yes)
		(layer "In4.Cu")
		(net "M_J_CPU0_SB_DQ<25>")
	)
	(gr_poly
		(pts
			(xy 381.264922 -288.057844) (xy 381.164846 -287.957768) (xy 381.06477 -288.057844) (xy 381.06477 -288.102294)
			(xy 381.264922 -288.102294)
		)
		(stroke
			(width 0)
			(type solid)
		)
		(fill yes)
		(layer "In4.Cu")
		(net "M_J_CPU0_SB_DQ<21>")
	)
	(gr_poly
		(pts
			(xy 381.264922 -286.437832) (xy 381.164846 -286.337756) (xy 381.06477 -286.437832) (xy 381.06477 -286.485584)
			(xy 381.264922 -286.485584)
		)
		(stroke
			(width 0)
			(type solid)
		)
		(fill yes)
		(layer "In4.Cu")
		(net "M_J_CPU0_SB_DQS_DN<7>")
	)
	(gr_poly
		(pts
			(xy 381.264922 -284.818074) (xy 381.164846 -284.717998) (xy 381.06477 -284.818074) (xy 381.06477 -284.862524)
			(xy 381.264922 -284.862524)
		)
		(stroke
			(width 0)
			(type solid)
		)
		(fill yes)
		(layer "In4.Cu")
		(net "M_J_CPU0_SB_DQ<17>")
	)
	(gr_poly
		(pts
			(xy 381.264922 -283.198062) (xy 381.164846 -283.097986) (xy 381.06477 -283.198062) (xy 381.06477 -283.242512)
			(xy 381.264922 -283.242512)
		)
		(stroke
			(width 0)
			(type solid)
		)
		(fill yes)
		(layer "In4.Cu")
		(net "M_J_CPU0_SB_DQ<13>")
	)
	(gr_poly
		(pts
			(xy 381.264922 -281.577796) (xy 381.164846 -281.477974) (xy 381.06477 -281.577796) (xy 381.06477 -281.625548)
			(xy 381.264922 -281.625548)
		)
		(stroke
			(width 0)
			(type solid)
		)
		(fill yes)
		(layer "In4.Cu")
		(net "M_J_CPU0_SB_DQS_DN<6>")
	)
	(gr_poly
		(pts
			(xy 381.264922 -279.958038) (xy 381.164846 -279.857962) (xy 381.06477 -279.958038) (xy 381.06477 -280.002488)
			(xy 381.264922 -280.002488)
		)
		(stroke
			(width 0)
			(type solid)
		)
		(fill yes)
		(layer "In4.Cu")
		(net "M_J_CPU0_SB_DQ<9>")
	)
	(gr_poly
		(pts
			(xy 381.264922 -278.338026) (xy 381.164846 -278.23795) (xy 381.06477 -278.338026) (xy 381.06477 -278.382476)
			(xy 381.264922 -278.382476)
		)
		(stroke
			(width 0)
			(type solid)
		)
		(fill yes)
		(layer "In4.Cu")
		(net "M_J_CPU0_SB_DQ<5>")
	)
	(gr_poly
		(pts
			(xy 381.264922 -276.71776) (xy 381.164846 -276.617938) (xy 381.06477 -276.71776) (xy 381.06477 -276.765512)
			(xy 381.264922 -276.765512)
		)
		(stroke
			(width 0)
			(type solid)
		)
		(fill yes)
		(layer "In4.Cu")
		(net "M_J_CPU0_SB_DQS_DN<5>")
	)
	(gr_poly
		(pts
			(xy 381.264922 -275.098002) (xy 381.164846 -274.997926) (xy 381.06477 -275.098002) (xy 381.06477 -275.142452)
			(xy 381.264922 -275.142452)
		)
		(stroke
			(width 0)
			(type solid)
		)
		(fill yes)
		(layer "In4.Cu")
		(net "M_J_CPU0_SB_DQ<1>")
	)
	(gr_poly
		(pts
			(xy 381.264922 -273.47799) (xy 381.164846 -273.377914) (xy 381.06477 -273.47799) (xy 381.06477 -273.52244)
			(xy 381.264922 -273.52244)
		)
		(stroke
			(width 0)
			(type solid)
		)
		(fill yes)
		(layer "In4.Cu")
		(net "M_J_CPU0_SB_CB<1>")
	)
	(gr_poly
		(pts
			(xy 381.264922 -271.857724) (xy 381.164846 -271.757902) (xy 381.06477 -271.857724) (xy 381.06477 -271.905476)
			(xy 381.264922 -271.905476)
		)
		(stroke
			(width 0)
			(type solid)
		)
		(fill yes)
		(layer "In4.Cu")
		(net "M_J_CPU0_SB_DQS_DN<4>")
	)
	(gr_poly
		(pts
			(xy 381.264922 -270.237966) (xy 381.164846 -270.13789) (xy 381.06477 -270.237966) (xy 381.06477 -270.282416)
			(xy 381.264922 -270.282416)
		)
		(stroke
			(width 0)
			(type solid)
		)
		(fill yes)
		(layer "In4.Cu")
		(net "M_J_CPU0_SB_CB<5>")
	)
	(gr_poly
		(pts
			(xy 381.264922 -266.997942) (xy 381.164846 -266.897866) (xy 381.06477 -266.997942) (xy 381.06477 -267.042392)
			(xy 381.264922 -267.042392)
		)
		(stroke
			(width 0)
			(type solid)
		)
		(fill yes)
		(layer "In4.Cu")
		(net "M_J_CPU0_SA_RSP<0>")
	)
	(gr_poly
		(pts
			(xy 381.264922 -265.37793) (xy 381.164846 -265.277854) (xy 381.06477 -265.37793) (xy 381.06477 -265.42238)
			(xy 381.264922 -265.42238)
		)
		(stroke
			(width 0)
			(type solid)
		)
		(fill yes)
		(layer "In4.Cu")
		(net "M_J_CPU0_SB_PAR")
	)
	(gr_poly
		(pts
			(xy 381.264922 -263.757918) (xy 381.164846 -263.657842) (xy 381.06477 -263.757918) (xy 381.06477 -263.802368)
			(xy 381.264922 -263.802368)
		)
		(stroke
			(width 0)
			(type solid)
		)
		(fill yes)
		(layer "In4.Cu")
		(net "M_J_CPU0_SB_CA<4>")
	)
	(gr_poly
		(pts
			(xy 381.264922 -262.137906) (xy 381.164846 -262.03783) (xy 381.06477 -262.137906) (xy 381.06477 -262.182356)
			(xy 381.264922 -262.182356)
		)
		(stroke
			(width 0)
			(type solid)
		)
		(fill yes)
		(layer "In4.Cu")
		(net "M_J_CPU0_SB_CA<0>")
	)
	(gr_poly
		(pts
			(xy 381.30353 -292.504114) (xy 381.29972 -292.459918) (xy 381.100584 -292.47719) (xy 381.104394 -292.52164)
			(xy 381.212598 -292.612572)
		)
		(stroke
			(width 0)
			(type solid)
		)
		(fill yes)
		(layer "In4.Cu")
		(net "M_J_CPU0_SB_DQ<30>")
	)
	(gr_poly
		(pts
			(xy 381.30353 -289.26409) (xy 381.29972 -289.219894) (xy 381.100584 -289.237166) (xy 381.104394 -289.281616)
			(xy 381.212598 -289.372548)
		)
		(stroke
			(width 0)
			(type solid)
		)
		(fill yes)
		(layer "In4.Cu")
		(net "M_J_CPU0_SB_DQ<26>")
	)
	(gr_poly
		(pts
			(xy 381.30353 -287.644332) (xy 381.29972 -287.600136) (xy 381.100584 -287.617408) (xy 381.104394 -287.661858)
			(xy 381.212598 -287.752536)
		)
		(stroke
			(width 0)
			(type solid)
		)
		(fill yes)
		(layer "In4.Cu")
		(net "M_J_CPU0_SB_DQ<22>")
	)
	(gr_poly
		(pts
			(xy 381.30353 -284.404308) (xy 381.29972 -284.360112) (xy 381.100584 -284.377384) (xy 381.104394 -284.421834)
			(xy 381.212598 -284.512766)
		)
		(stroke
			(width 0)
			(type solid)
		)
		(fill yes)
		(layer "In4.Cu")
		(net "M_J_CPU0_SB_DQ<18>")
	)
	(gr_poly
		(pts
			(xy 381.30353 -282.784296) (xy 381.29972 -282.7401) (xy 381.100584 -282.757372) (xy 381.104394 -282.801822)
			(xy 381.212598 -282.892754)
		)
		(stroke
			(width 0)
			(type solid)
		)
		(fill yes)
		(layer "In4.Cu")
		(net "M_J_CPU0_SB_DQ<14>")
	)
	(gr_poly
		(pts
			(xy 381.30353 -279.544272) (xy 381.29972 -279.500076) (xy 381.100584 -279.517348) (xy 381.104394 -279.561798)
			(xy 381.212598 -279.65273)
		)
		(stroke
			(width 0)
			(type solid)
		)
		(fill yes)
		(layer "In4.Cu")
		(net "M_J_CPU0_SB_DQ<10>")
	)
	(gr_poly
		(pts
			(xy 381.30353 -277.92426) (xy 381.29972 -277.880064) (xy 381.100584 -277.897336) (xy 381.104394 -277.941786)
			(xy 381.212598 -278.032718)
		)
		(stroke
			(width 0)
			(type solid)
		)
		(fill yes)
		(layer "In4.Cu")
		(net "M_J_CPU0_SB_DQ<6>")
	)
	(gr_poly
		(pts
			(xy 381.30353 -274.684236) (xy 381.29972 -274.64004) (xy 381.100584 -274.657312) (xy 381.104394 -274.701762)
			(xy 381.212598 -274.792694)
		)
		(stroke
			(width 0)
			(type solid)
		)
		(fill yes)
		(layer "In4.Cu")
		(net "M_J_CPU0_SB_DQ<2>")
	)
	(gr_poly
		(pts
			(xy 381.30353 -273.064224) (xy 381.29972 -273.020028) (xy 381.100584 -273.0373) (xy 381.104394 -273.08175)
			(xy 381.212598 -273.172682)
		)
		(stroke
			(width 0)
			(type solid)
		)
		(fill yes)
		(layer "In4.Cu")
		(net "M_J_CPU0_SB_CB<2>")
	)
	(gr_poly
		(pts
			(xy 381.30353 -269.8242) (xy 381.29972 -269.780004) (xy 381.100584 -269.797276) (xy 381.104394 -269.841726)
			(xy 381.212598 -269.932658)
		)
		(stroke
			(width 0)
			(type solid)
		)
		(fill yes)
		(layer "In4.Cu")
		(net "M_J_CPU0_SB_CB<6>")
	)
	(gr_poly
		(pts
			(xy 381.30353 -266.584176) (xy 381.29972 -266.53998) (xy 381.100584 -266.557252) (xy 381.104394 -266.601702)
			(xy 381.212598 -266.692634)
		)
		(stroke
			(width 0)
			(type solid)
		)
		(fill yes)
		(layer "In4.Cu")
		(net "M_J_CPU0_SB_CS_N<1>")
	)
	(gr_poly
		(pts
			(xy 381.30353 -263.344152) (xy 381.29972 -263.299956) (xy 381.100584 -263.317228) (xy 381.104394 -263.361678)
			(xy 381.212598 -263.45261)
		)
		(stroke
			(width 0)
			(type solid)
		)
		(fill yes)
		(layer "In4.Cu")
		(net "M_J_CPU0_SB_CA<3>")
	)
	(gr_poly
		(pts
			(xy 381.31623 -290.88334) (xy 381.312166 -290.836096) (xy 381.112776 -290.853368) (xy 381.117094 -290.900866)
			(xy 381.225298 -290.991798)
		)
		(stroke
			(width 0)
			(type solid)
		)
		(fill yes)
		(layer "In4.Cu")
		(net "M_J_CPU0_SB_DQS_DN<3>")
	)
	(gr_poly
		(pts
			(xy 381.31623 -286.023558) (xy 381.312166 -285.97606) (xy 381.112776 -285.993586) (xy 381.117094 -286.041084)
			(xy 381.225298 -286.132016)
		)
		(stroke
			(width 0)
			(type solid)
		)
		(fill yes)
		(layer "In4.Cu")
		(net "M_J_CPU0_SB_DQS_DN<2>")
	)
	(gr_poly
		(pts
			(xy 381.31623 -281.163522) (xy 381.312166 -281.116024) (xy 381.112776 -281.13355) (xy 381.117094 -281.181048)
			(xy 381.225298 -281.27198)
		)
		(stroke
			(width 0)
			(type solid)
		)
		(fill yes)
		(layer "In4.Cu")
		(net "M_J_CPU0_SB_DQS_DN<1>")
	)
	(gr_poly
		(pts
			(xy 381.31623 -276.303486) (xy 381.312166 -276.255988) (xy 381.112776 -276.273514) (xy 381.117094 -276.321012)
			(xy 381.225298 -276.411944)
		)
		(stroke
			(width 0)
			(type solid)
		)
		(fill yes)
		(layer "In4.Cu")
		(net "M_J_CPU0_SB_DQS_DN<0>")
	)
	(gr_poly
		(pts
			(xy 381.31623 -271.44345) (xy 381.312166 -271.395952) (xy 381.112776 -271.413478) (xy 381.117094 -271.460976)
			(xy 381.225298 -271.551908)
		)
		(stroke
			(width 0)
			(type solid)
		)
		(fill yes)
		(layer "In4.Cu")
		(net "M_J_CPU0_SB_DQS_DN<9>")
	)
	(gr_poly
		(pts
			(xy 381.434848 -256.432558) (xy 381.434848 -256.384806) (xy 381.234696 -256.384806) (xy 381.234696 -256.432558)
			(xy 381.334772 -256.53238)
		)
		(stroke
			(width 0)
			(type solid)
		)
		(fill yes)
		(layer "In4.Cu")
		(net "M_J_CPU0_CLK_DN<0>")
	)
	(gr_poly
		(pts
			(xy 381.434848 -255.216152) (xy 381.334772 -255.116076) (xy 381.234696 -255.216152) (xy 381.234696 -255.260602)
			(xy 381.434848 -255.260602)
		)
		(stroke
			(width 0)
			(type solid)
		)
		(fill yes)
		(layer "In4.Cu")
		(net "M_J_CPU0_SA_CA<6>")
	)
	(gr_poly
		(pts
			(xy 381.434848 -254.812292) (xy 381.434848 -254.767842) (xy 381.234696 -254.767842) (xy 381.234696 -254.812292)
			(xy 381.334772 -254.912368)
		)
		(stroke
			(width 0)
			(type solid)
		)
		(fill yes)
		(layer "In4.Cu")
		(net "M_J_CPU0_SA_CA<5>")
	)
	(gr_poly
		(pts
			(xy 381.434848 -253.59614) (xy 381.334772 -253.496064) (xy 381.234696 -253.59614) (xy 381.234696 -253.64059)
			(xy 381.434848 -253.64059)
		)
		(stroke
			(width 0)
			(type solid)
		)
		(fill yes)
		(layer "In4.Cu")
		(net "M_J_CPU0_SA_CA<2>")
	)
	(gr_poly
		(pts
			(xy 381.434848 -253.19228) (xy 381.434848 -253.14783) (xy 381.234696 -253.14783) (xy 381.234696 -253.19228)
			(xy 381.334772 -253.292356)
		)
		(stroke
			(width 0)
			(type solid)
		)
		(fill yes)
		(layer "In4.Cu")
		(net "M_J_CPU0_SA_CA<1>")
	)
	(gr_poly
		(pts
			(xy 381.434848 -251.976128) (xy 381.334772 -251.876052) (xy 381.234696 -251.976128) (xy 381.234696 -252.020578)
			(xy 381.434848 -252.020578)
		)
		(stroke
			(width 0)
			(type solid)
		)
		(fill yes)
		(layer "In4.Cu")
		(net "M_J_CPU0_SA_CS_N<1>")
	)
	(gr_poly
		(pts
			(xy 381.434848 -250.356116) (xy 381.334772 -250.25604) (xy 381.234696 -250.356116) (xy 381.234696 -250.400566)
			(xy 381.434848 -250.400566)
		)
		(stroke
			(width 0)
			(type solid)
		)
		(fill yes)
		(layer "In4.Cu")
		(net "M_J_CPU0_ALERT_R_N")
	)
	(gr_poly
		(pts
			(xy 381.434848 -248.736104) (xy 381.334772 -248.636028) (xy 381.234696 -248.736104) (xy 381.234696 -248.780554)
			(xy 381.434848 -248.780554)
		)
		(stroke
			(width 0)
			(type solid)
		)
		(fill yes)
		(layer "In4.Cu")
		(net "M_J_CPU0_SA_CB<5>")
	)
	(gr_poly
		(pts
			(xy 381.434848 -248.332244) (xy 381.434848 -248.287794) (xy 381.234696 -248.287794) (xy 381.234696 -248.332244)
			(xy 381.334772 -248.43232)
		)
		(stroke
			(width 0)
			(type solid)
		)
		(fill yes)
		(layer "In4.Cu")
		(net "M_J_CPU0_SA_CB<6>")
	)
	(gr_poly
		(pts
			(xy 381.434848 -247.115838) (xy 381.334772 -247.016016) (xy 381.234696 -247.115838) (xy 381.234696 -247.16359)
			(xy 381.434848 -247.16359)
		)
		(stroke
			(width 0)
			(type solid)
		)
		(fill yes)
		(layer "In4.Cu")
		(net "M_J_CPU0_SA_DQS_DN<9>")
	)
	(gr_poly
		(pts
			(xy 381.434848 -246.712486) (xy 381.434848 -246.664734) (xy 381.234696 -246.664734) (xy 381.234696 -246.712486)
			(xy 381.334772 -246.812308)
		)
		(stroke
			(width 0)
			(type solid)
		)
		(fill yes)
		(layer "In4.Cu")
		(net "M_J_CPU0_SA_DQS_DN<4>")
	)
	(gr_poly
		(pts
			(xy 381.434848 -245.49608) (xy 381.334772 -245.396004) (xy 381.234696 -245.49608) (xy 381.234696 -245.54053)
			(xy 381.434848 -245.54053)
		)
		(stroke
			(width 0)
			(type solid)
		)
		(fill yes)
		(layer "In4.Cu")
		(net "M_J_CPU0_SA_CB<1>")
	)
	(gr_poly
		(pts
			(xy 381.434848 -245.09222) (xy 381.434848 -245.04777) (xy 381.234696 -245.04777) (xy 381.234696 -245.09222)
			(xy 381.334772 -245.192296)
		)
		(stroke
			(width 0)
			(type solid)
		)
		(fill yes)
		(layer "In4.Cu")
		(net "M_J_CPU0_SA_CB<2>")
	)
	(gr_poly
		(pts
			(xy 381.434848 -243.876068) (xy 381.334772 -243.775992) (xy 381.234696 -243.876068) (xy 381.234696 -243.920518)
			(xy 381.434848 -243.920518)
		)
		(stroke
			(width 0)
			(type solid)
		)
		(fill yes)
		(layer "In4.Cu")
		(net "M_J_CPU0_SA_DQ<29>")
	)
	(gr_poly
		(pts
			(xy 381.434848 -243.472208) (xy 381.434848 -243.427758) (xy 381.234696 -243.427758) (xy 381.234696 -243.472208)
			(xy 381.334772 -243.572284)
		)
		(stroke
			(width 0)
			(type solid)
		)
		(fill yes)
		(layer "In4.Cu")
		(net "M_J_CPU0_SA_DQ<30>")
	)
	(gr_poly
		(pts
			(xy 381.434848 -242.255802) (xy 381.334772 -242.15598) (xy 381.234696 -242.255802) (xy 381.234696 -242.303554)
			(xy 381.434848 -242.303554)
		)
		(stroke
			(width 0)
			(type solid)
		)
		(fill yes)
		(layer "In4.Cu")
		(net "M_J_CPU0_SA_DQS_DN<8>")
	)
	(gr_poly
		(pts
			(xy 381.434848 -241.85245) (xy 381.434848 -241.804698) (xy 381.234696 -241.804698) (xy 381.234696 -241.85245)
			(xy 381.334772 -241.952272)
		)
		(stroke
			(width 0)
			(type solid)
		)
		(fill yes)
		(layer "In4.Cu")
		(net "M_J_CPU0_SA_DQS_DN<3>")
	)
	(gr_poly
		(pts
			(xy 381.434848 -240.636044) (xy 381.334772 -240.535968) (xy 381.234696 -240.636044) (xy 381.234696 -240.680494)
			(xy 381.434848 -240.680494)
		)
		(stroke
			(width 0)
			(type solid)
		)
		(fill yes)
		(layer "In4.Cu")
		(net "M_J_CPU0_SA_DQ<25>")
	)
	(gr_poly
		(pts
			(xy 381.434848 -240.232184) (xy 381.434848 -240.187734) (xy 381.234696 -240.187734) (xy 381.234696 -240.232184)
			(xy 381.334772 -240.33226)
		)
		(stroke
			(width 0)
			(type solid)
		)
		(fill yes)
		(layer "In4.Cu")
		(net "M_J_CPU0_SA_DQ<26>")
	)
	(gr_poly
		(pts
			(xy 381.434848 -239.016032) (xy 381.334772 -238.915956) (xy 381.234696 -239.016032) (xy 381.234696 -239.060482)
			(xy 381.434848 -239.060482)
		)
		(stroke
			(width 0)
			(type solid)
		)
		(fill yes)
		(layer "In4.Cu")
		(net "M_J_CPU0_SA_DQ<21>")
	)
	(gr_poly
		(pts
			(xy 381.434848 -238.612172) (xy 381.434848 -238.567722) (xy 381.234696 -238.567722) (xy 381.234696 -238.612172)
			(xy 381.334772 -238.712248)
		)
		(stroke
			(width 0)
			(type solid)
		)
		(fill yes)
		(layer "In4.Cu")
		(net "M_J_CPU0_SA_DQ<22>")
	)
	(gr_poly
		(pts
			(xy 381.434848 -237.395766) (xy 381.334772 -237.295944) (xy 381.234696 -237.395766) (xy 381.234696 -237.443518)
			(xy 381.434848 -237.443518)
		)
		(stroke
			(width 0)
			(type solid)
		)
		(fill yes)
		(layer "In4.Cu")
		(net "M_J_CPU0_SA_DQS_DN<7>")
	)
	(gr_poly
		(pts
			(xy 381.434848 -236.992414) (xy 381.434848 -236.944662) (xy 381.234696 -236.944662) (xy 381.234696 -236.992414)
			(xy 381.334772 -237.092236)
		)
		(stroke
			(width 0)
			(type solid)
		)
		(fill yes)
		(layer "In4.Cu")
		(net "M_J_CPU0_SA_DQS_DN<2>")
	)
	(gr_poly
		(pts
			(xy 381.434848 -235.776008) (xy 381.334772 -235.675932) (xy 381.234696 -235.776008) (xy 381.234696 -235.820458)
			(xy 381.434848 -235.820458)
		)
		(stroke
			(width 0)
			(type solid)
		)
		(fill yes)
		(layer "In4.Cu")
		(net "M_J_CPU0_SA_DQ<17>")
	)
	(gr_poly
		(pts
			(xy 381.434848 -235.372148) (xy 381.434848 -235.327698) (xy 381.234696 -235.327698) (xy 381.234696 -235.372148)
			(xy 381.334772 -235.472224)
		)
		(stroke
			(width 0)
			(type solid)
		)
		(fill yes)
		(layer "In4.Cu")
		(net "M_J_CPU0_SA_DQ<18>")
	)
	(gr_poly
		(pts
			(xy 381.434848 -234.155996) (xy 381.334772 -234.05592) (xy 381.234696 -234.155996) (xy 381.234696 -234.200446)
			(xy 381.434848 -234.200446)
		)
		(stroke
			(width 0)
			(type solid)
		)
		(fill yes)
		(layer "In4.Cu")
		(net "M_J_CPU0_SA_DQ<13>")
	)
	(gr_poly
		(pts
			(xy 381.434848 -233.752136) (xy 381.434848 -233.707686) (xy 381.234696 -233.707686) (xy 381.234696 -233.752136)
			(xy 381.334772 -233.852212)
		)
		(stroke
			(width 0)
			(type solid)
		)
		(fill yes)
		(layer "In4.Cu")
		(net "M_J_CPU0_SA_DQ<14>")
	)
	(gr_poly
		(pts
			(xy 381.434848 -232.53573) (xy 381.334772 -232.435908) (xy 381.234696 -232.53573) (xy 381.234696 -232.583482)
			(xy 381.434848 -232.583482)
		)
		(stroke
			(width 0)
			(type solid)
		)
		(fill yes)
		(layer "In4.Cu")
		(net "M_J_CPU0_SA_DQS_DN<6>")
	)
	(gr_poly
		(pts
			(xy 381.434848 -232.132378) (xy 381.434848 -232.084626) (xy 381.234696 -232.084626) (xy 381.234696 -232.132378)
			(xy 381.334772 -232.2322)
		)
		(stroke
			(width 0)
			(type solid)
		)
		(fill yes)
		(layer "In4.Cu")
		(net "M_J_CPU0_SA_DQS_DN<1>")
	)
	(gr_poly
		(pts
			(xy 381.434848 -230.915972) (xy 381.334772 -230.815896) (xy 381.234696 -230.915972) (xy 381.234696 -230.960422)
			(xy 381.434848 -230.960422)
		)
		(stroke
			(width 0)
			(type solid)
		)
		(fill yes)
		(layer "In4.Cu")
		(net "M_J_CPU0_SA_DQ<9>")
	)
	(gr_poly
		(pts
			(xy 381.434848 -230.512366) (xy 381.434848 -230.467916) (xy 381.234696 -230.467916) (xy 381.234696 -230.512366)
			(xy 381.334772 -230.612188)
		)
		(stroke
			(width 0)
			(type solid)
		)
		(fill yes)
		(layer "In4.Cu")
		(net "M_J_CPU0_SA_DQ<10>")
	)
	(gr_poly
		(pts
			(xy 381.434848 -229.29596) (xy 381.334772 -229.195884) (xy 381.234696 -229.29596) (xy 381.234696 -229.34041)
			(xy 381.434848 -229.34041)
		)
		(stroke
			(width 0)
			(type solid)
		)
		(fill yes)
		(layer "In4.Cu")
		(net "M_J_CPU0_SA_DQ<5>")
	)
	(gr_poly
		(pts
			(xy 381.434848 -228.892354) (xy 381.434848 -228.847904) (xy 381.234696 -228.847904) (xy 381.234696 -228.892354)
			(xy 381.334772 -228.99243)
		)
		(stroke
			(width 0)
			(type solid)
		)
		(fill yes)
		(layer "In4.Cu")
		(net "M_J_CPU0_SA_DQ<6>")
	)
	(gr_poly
		(pts
			(xy 381.434848 -227.675948) (xy 381.334772 -227.576126) (xy 381.234696 -227.675948) (xy 381.234696 -227.7237)
			(xy 381.434848 -227.7237)
		)
		(stroke
			(width 0)
			(type solid)
		)
		(fill yes)
		(layer "In4.Cu")
		(net "M_J_CPU0_SA_DQS_DN<5>")
	)
	(gr_poly
		(pts
			(xy 381.434848 -227.272596) (xy 381.434848 -227.224844) (xy 381.234696 -227.224844) (xy 381.234696 -227.272596)
			(xy 381.334772 -227.372418)
		)
		(stroke
			(width 0)
			(type solid)
		)
		(fill yes)
		(layer "In4.Cu")
		(net "M_J_CPU0_SA_DQS_DN<0>")
	)
	(gr_poly
		(pts
			(xy 381.434848 -226.05619) (xy 381.334772 -225.956114) (xy 381.234696 -226.05619) (xy 381.234696 -226.10064)
			(xy 381.434848 -226.10064)
		)
		(stroke
			(width 0)
			(type solid)
		)
		(fill yes)
		(layer "In4.Cu")
		(net "M_J_CPU0_SA_DQ<1>")
	)
	(gr_poly
		(pts
			(xy 381.434848 -225.65233) (xy 381.434848 -225.60788) (xy 381.234696 -225.60788) (xy 381.234696 -225.65233)
			(xy 381.334772 -225.752406)
		)
		(stroke
			(width 0)
			(type solid)
		)
		(fill yes)
		(layer "In4.Cu")
		(net "M_J_CPU0_SA_DQ<2>")
	)
	(gr_poly
		(pts
			(xy 381.734822 -292.107874) (xy 381.634746 -292.007798) (xy 381.53467 -292.107874) (xy 381.53467 -292.152324)
			(xy 381.734822 -292.152324)
		)
		(stroke
			(width 0)
			(type solid)
		)
		(fill yes)
		(layer "In4.Cu")
		(net "M_J_CPU0_SB_DQ<28>")
	)
	(gr_poly
		(pts
			(xy 381.734822 -291.704268) (xy 381.734822 -291.656516) (xy 381.53467 -291.656516) (xy 381.53467 -291.704268)
			(xy 381.634746 -291.80409)
		)
		(stroke
			(width 0)
			(type solid)
		)
		(fill yes)
		(layer "In4.Cu")
		(net "M_J_CPU0_SB_DQS_DP<8>")
	)
	(gr_poly
		(pts
			(xy 381.734822 -290.487608) (xy 381.634746 -290.387786) (xy 381.53467 -290.487608) (xy 381.53467 -290.53536)
			(xy 381.734822 -290.53536)
		)
		(stroke
			(width 0)
			(type solid)
		)
		(fill yes)
		(layer "In4.Cu")
		(net "M_J_CPU0_SB_DQS_DP<3>")
	)
	(gr_poly
		(pts
			(xy 381.734822 -290.084002) (xy 381.734822 -290.039552) (xy 381.53467 -290.039552) (xy 381.53467 -290.084002)
			(xy 381.634746 -290.184078)
		)
		(stroke
			(width 0)
			(type solid)
		)
		(fill yes)
		(layer "In4.Cu")
		(net "M_J_CPU0_SB_DQ<27>")
	)
	(gr_poly
		(pts
			(xy 381.734822 -288.86785) (xy 381.634746 -288.767774) (xy 381.53467 -288.86785) (xy 381.53467 -288.9123)
			(xy 381.734822 -288.9123)
		)
		(stroke
			(width 0)
			(type solid)
		)
		(fill yes)
		(layer "In4.Cu")
		(net "M_J_CPU0_SB_DQ<24>")
	)
	(gr_poly
		(pts
			(xy 381.734822 -288.464244) (xy 381.734822 -288.419794) (xy 381.53467 -288.419794) (xy 381.53467 -288.464244)
			(xy 381.634746 -288.56432)
		)
		(stroke
			(width 0)
			(type solid)
		)
		(fill yes)
		(layer "In4.Cu")
		(net "M_J_CPU0_SB_DQ<23>")
	)
	(gr_poly
		(pts
			(xy 381.734822 -287.247838) (xy 381.634746 -287.148016) (xy 381.53467 -287.247838) (xy 381.53467 -287.292288)
			(xy 381.734822 -287.292288)
		)
		(stroke
			(width 0)
			(type solid)
		)
		(fill yes)
		(layer "In4.Cu")
		(net "M_J_CPU0_SB_DQ<20>")
	)
	(gr_poly
		(pts
			(xy 381.734822 -286.844232) (xy 381.734822 -286.79648) (xy 381.53467 -286.79648) (xy 381.53467 -286.844232)
			(xy 381.634746 -286.944308)
		)
		(stroke
			(width 0)
			(type solid)
		)
		(fill yes)
		(layer "In4.Cu")
		(net "M_J_CPU0_SB_DQS_DP<7>")
	)
	(gr_poly
		(pts
			(xy 381.734822 -285.627826) (xy 381.634746 -285.528004) (xy 381.53467 -285.627826) (xy 381.53467 -285.675578)
			(xy 381.734822 -285.675578)
		)
		(stroke
			(width 0)
			(type solid)
		)
		(fill yes)
		(layer "In4.Cu")
		(net "M_J_CPU0_SB_DQS_DP<2>")
	)
	(gr_poly
		(pts
			(xy 381.734822 -285.22422) (xy 381.734822 -285.17977) (xy 381.53467 -285.17977) (xy 381.53467 -285.22422)
			(xy 381.634746 -285.324296)
		)
		(stroke
			(width 0)
			(type solid)
		)
		(fill yes)
		(layer "In4.Cu")
		(net "M_J_CPU0_SB_DQ<19>")
	)
	(gr_poly
		(pts
			(xy 381.734822 -284.008068) (xy 381.634746 -283.907992) (xy 381.53467 -284.008068) (xy 381.53467 -284.052518)
			(xy 381.734822 -284.052518)
		)
		(stroke
			(width 0)
			(type solid)
		)
		(fill yes)
		(layer "In4.Cu")
		(net "M_J_CPU0_SB_DQ<16>")
	)
	(gr_poly
		(pts
			(xy 381.734822 -283.604208) (xy 381.734822 -283.559758) (xy 381.53467 -283.559758) (xy 381.53467 -283.604208)
			(xy 381.634746 -283.704284)
		)
		(stroke
			(width 0)
			(type solid)
		)
		(fill yes)
		(layer "In4.Cu")
		(net "M_J_CPU0_SB_DQ<15>")
	)
	(gr_poly
		(pts
			(xy 381.734822 -282.388056) (xy 381.634746 -282.28798) (xy 381.53467 -282.388056) (xy 381.53467 -282.432506)
			(xy 381.734822 -282.432506)
		)
		(stroke
			(width 0)
			(type solid)
		)
		(fill yes)
		(layer "In4.Cu")
		(net "M_J_CPU0_SB_DQ<12>")
	)
	(gr_poly
		(pts
			(xy 381.734822 -281.98445) (xy 381.734822 -281.936698) (xy 381.53467 -281.936698) (xy 381.53467 -281.98445)
			(xy 381.634746 -282.084272)
		)
		(stroke
			(width 0)
			(type solid)
		)
		(fill yes)
		(layer "In4.Cu")
		(net "M_J_CPU0_SB_DQS_DP<6>")
	)
	(gr_poly
		(pts
			(xy 381.734822 -280.76779) (xy 381.634746 -280.667968) (xy 381.53467 -280.76779) (xy 381.53467 -280.815542)
			(xy 381.734822 -280.815542)
		)
		(stroke
			(width 0)
			(type solid)
		)
		(fill yes)
		(layer "In4.Cu")
		(net "M_J_CPU0_SB_DQS_DP<1>")
	)
	(gr_poly
		(pts
			(xy 381.734822 -280.364184) (xy 381.734822 -280.319734) (xy 381.53467 -280.319734) (xy 381.53467 -280.364184)
			(xy 381.634746 -280.46426)
		)
		(stroke
			(width 0)
			(type solid)
		)
		(fill yes)
		(layer "In4.Cu")
		(net "M_J_CPU0_SB_DQ<11>")
	)
	(gr_poly
		(pts
			(xy 381.734822 -279.148032) (xy 381.634746 -279.047956) (xy 381.53467 -279.148032) (xy 381.53467 -279.192482)
			(xy 381.734822 -279.192482)
		)
		(stroke
			(width 0)
			(type solid)
		)
		(fill yes)
		(layer "In4.Cu")
		(net "M_J_CPU0_SB_DQ<8>")
	)
	(gr_poly
		(pts
			(xy 381.734822 -278.744172) (xy 381.734822 -278.699722) (xy 381.53467 -278.699722) (xy 381.53467 -278.744172)
			(xy 381.634746 -278.844248)
		)
		(stroke
			(width 0)
			(type solid)
		)
		(fill yes)
		(layer "In4.Cu")
		(net "M_J_CPU0_SB_DQ<7>")
	)
	(gr_poly
		(pts
			(xy 381.734822 -277.52802) (xy 381.634746 -277.427944) (xy 381.53467 -277.52802) (xy 381.53467 -277.57247)
			(xy 381.734822 -277.57247)
		)
		(stroke
			(width 0)
			(type solid)
		)
		(fill yes)
		(layer "In4.Cu")
		(net "M_J_CPU0_SB_DQ<4>")
	)
	(gr_poly
		(pts
			(xy 381.734822 -277.124414) (xy 381.734822 -277.076662) (xy 381.53467 -277.076662) (xy 381.53467 -277.124414)
			(xy 381.634746 -277.224236)
		)
		(stroke
			(width 0)
			(type solid)
		)
		(fill yes)
		(layer "In4.Cu")
		(net "M_J_CPU0_SB_DQS_DP<5>")
	)
	(gr_poly
		(pts
			(xy 381.734822 -275.907754) (xy 381.634746 -275.807932) (xy 381.53467 -275.907754) (xy 381.53467 -275.955506)
			(xy 381.734822 -275.955506)
		)
		(stroke
			(width 0)
			(type solid)
		)
		(fill yes)
		(layer "In4.Cu")
		(net "M_J_CPU0_SB_DQS_DP<0>")
	)
	(gr_poly
		(pts
			(xy 381.734822 -275.504148) (xy 381.734822 -275.459698) (xy 381.53467 -275.459698) (xy 381.53467 -275.504148)
			(xy 381.634746 -275.604224)
		)
		(stroke
			(width 0)
			(type solid)
		)
		(fill yes)
		(layer "In4.Cu")
		(net "M_J_CPU0_SB_DQ<3>")
	)
	(gr_poly
		(pts
			(xy 381.734822 -274.287996) (xy 381.634746 -274.18792) (xy 381.53467 -274.287996) (xy 381.53467 -274.332446)
			(xy 381.734822 -274.332446)
		)
		(stroke
			(width 0)
			(type solid)
		)
		(fill yes)
		(layer "In4.Cu")
		(net "M_J_CPU0_SB_DQ<0>")
	)
	(gr_poly
		(pts
			(xy 381.734822 -273.884136) (xy 381.734822 -273.839686) (xy 381.53467 -273.839686) (xy 381.53467 -273.884136)
			(xy 381.634746 -273.984212)
		)
		(stroke
			(width 0)
			(type solid)
		)
		(fill yes)
		(layer "In4.Cu")
		(net "M_J_CPU0_SB_CB<3>")
	)
	(gr_poly
		(pts
			(xy 381.734822 -272.667984) (xy 381.634746 -272.567908) (xy 381.53467 -272.667984) (xy 381.53467 -272.712434)
			(xy 381.734822 -272.712434)
		)
		(stroke
			(width 0)
			(type solid)
		)
		(fill yes)
		(layer "In4.Cu")
		(net "M_J_CPU0_SB_CB<0>")
	)
	(gr_poly
		(pts
			(xy 381.734822 -272.264378) (xy 381.734822 -272.216626) (xy 381.53467 -272.216626) (xy 381.53467 -272.264378)
			(xy 381.634746 -272.3642)
		)
		(stroke
			(width 0)
			(type solid)
		)
		(fill yes)
		(layer "In4.Cu")
		(net "M_J_CPU0_SB_DQS_DP<4>")
	)
	(gr_poly
		(pts
			(xy 381.734822 -271.047718) (xy 381.634746 -270.947896) (xy 381.53467 -271.047718) (xy 381.53467 -271.09547)
			(xy 381.734822 -271.09547)
		)
		(stroke
			(width 0)
			(type solid)
		)
		(fill yes)
		(layer "In4.Cu")
		(net "M_J_CPU0_SB_DQS_DP<9>")
	)
	(gr_poly
		(pts
			(xy 381.734822 -270.644112) (xy 381.734822 -270.599662) (xy 381.53467 -270.599662) (xy 381.53467 -270.644112)
			(xy 381.634746 -270.744188)
		)
		(stroke
			(width 0)
			(type solid)
		)
		(fill yes)
		(layer "In4.Cu")
		(net "M_J_CPU0_SB_CB<7>")
	)
	(gr_poly
		(pts
			(xy 381.734822 -269.42796) (xy 381.634746 -269.327884) (xy 381.53467 -269.42796) (xy 381.53467 -269.47241)
			(xy 381.734822 -269.47241)
		)
		(stroke
			(width 0)
			(type solid)
		)
		(fill yes)
		(layer "In4.Cu")
		(net "M_J_CPU0_SB_CB<4>")
	)
	(gr_poly
		(pts
			(xy 381.734822 -267.807948) (xy 381.634746 -267.707872) (xy 381.53467 -267.807948) (xy 381.53467 -267.852398)
			(xy 381.734822 -267.852398)
		)
		(stroke
			(width 0)
			(type solid)
		)
		(fill yes)
		(layer "In4.Cu")
		(net "M_J_CPU0_SB_RSP<0>")
	)
	(gr_poly
		(pts
			(xy 381.734822 -265.784076) (xy 381.734822 -265.739626) (xy 381.53467 -265.739626) (xy 381.53467 -265.784076)
			(xy 381.634746 -265.884152)
		)
		(stroke
			(width 0)
			(type solid)
		)
		(fill yes)
		(layer "In4.Cu")
		(net "M_J_CPU0_SB_CS_N<0>")
	)
	(gr_poly
		(pts
			(xy 381.734822 -264.567924) (xy 381.634746 -264.467848) (xy 381.53467 -264.567924) (xy 381.53467 -264.612374)
			(xy 381.734822 -264.612374)
		)
		(stroke
			(width 0)
			(type solid)
		)
		(fill yes)
		(layer "In4.Cu")
		(net "M_J_CPU0_SB_CA<6>")
	)
	(gr_poly
		(pts
			(xy 381.734822 -264.164064) (xy 381.734822 -264.119614) (xy 381.53467 -264.119614) (xy 381.53467 -264.164064)
			(xy 381.634746 -264.26414)
		)
		(stroke
			(width 0)
			(type solid)
		)
		(fill yes)
		(layer "In4.Cu")
		(net "M_J_CPU0_SB_CA<5>")
	)
	(gr_poly
		(pts
			(xy 381.734822 -262.947912) (xy 381.634746 -262.847836) (xy 381.53467 -262.947912) (xy 381.53467 -262.992362)
			(xy 381.734822 -262.992362)
		)
		(stroke
			(width 0)
			(type solid)
		)
		(fill yes)
		(layer "In4.Cu")
		(net "M_J_CPU0_SB_CA<2>")
	)
	(gr_poly
		(pts
			(xy 381.734822 -262.544052) (xy 381.734822 -262.499602) (xy 381.53467 -262.499602) (xy 381.53467 -262.544052)
			(xy 381.634746 -262.644128)
		)
		(stroke
			(width 0)
			(type solid)
		)
		(fill yes)
		(layer "In4.Cu")
		(net "M_J_CPU0_SB_CA<1>")
	)
	(gr_poly
		(pts
			(xy 381.905002 -256.025904) (xy 381.804926 -255.926082) (xy 381.70485 -256.025904) (xy 381.70485 -256.073656)
			(xy 381.905002 -256.073656)
		)
		(stroke
			(width 0)
			(type solid)
		)
		(fill yes)
		(layer "In4.Cu")
		(net "M_J_CPU0_CLK_DP<0>")
	)
	(gr_poly
		(pts
			(xy 381.905002 -255.622298) (xy 381.905002 -255.577848) (xy 381.70485 -255.577848) (xy 381.70485 -255.622298)
			(xy 381.804926 -255.722374)
		)
		(stroke
			(width 0)
			(type solid)
		)
		(fill yes)
		(layer "In4.Cu")
		(net "M_J_CPU0_SA_PAR")
	)
	(gr_poly
		(pts
			(xy 381.905002 -254.406146) (xy 381.804926 -254.30607) (xy 381.70485 -254.406146) (xy 381.70485 -254.450596)
			(xy 381.905002 -254.450596)
		)
		(stroke
			(width 0)
			(type solid)
		)
		(fill yes)
		(layer "In4.Cu")
		(net "M_J_CPU0_SA_CA<4>")
	)
	(gr_poly
		(pts
			(xy 381.905002 -254.002286) (xy 381.905002 -253.957836) (xy 381.70485 -253.957836) (xy 381.70485 -254.002286)
			(xy 381.804926 -254.102362)
		)
		(stroke
			(width 0)
			(type solid)
		)
		(fill yes)
		(layer "In4.Cu")
		(net "M_J_CPU0_SA_CA<3>")
	)
	(gr_poly
		(pts
			(xy 381.905002 -252.786134) (xy 381.804926 -252.686058) (xy 381.70485 -252.786134) (xy 381.70485 -252.830584)
			(xy 381.905002 -252.830584)
		)
		(stroke
			(width 0)
			(type solid)
		)
		(fill yes)
		(layer "In4.Cu")
		(net "M_J_CPU0_SA_CA<0>")
	)
	(gr_poly
		(pts
			(xy 381.905002 -251.166122) (xy 381.804926 -251.066046) (xy 381.70485 -251.166122) (xy 381.70485 -251.210572)
			(xy 381.905002 -251.210572)
		)
		(stroke
			(width 0)
			(type solid)
		)
		(fill yes)
		(layer "In4.Cu")
		(net "M_J_CPU0_SA_CS_N<0>")
	)
	(gr_poly
		(pts
			(xy 381.905002 -250.762262) (xy 381.905002 -250.717812) (xy 381.70485 -250.717812) (xy 381.70485 -250.762262)
			(xy 381.804926 -250.862338)
		)
		(stroke
			(width 0)
			(type solid)
		)
		(fill yes)
		(layer "In4.Cu")
		(net "M_J_CPU0_RESET_N")
	)
	(gr_poly
		(pts
			(xy 381.905002 -249.14225) (xy 381.905002 -249.0978) (xy 381.70485 -249.0978) (xy 381.70485 -249.14225)
			(xy 381.804926 -249.242326)
		)
		(stroke
			(width 0)
			(type solid)
		)
		(fill yes)
		(layer "In4.Cu")
		(net "M_J_CPU0_SA_CB<7>")
	)
	(gr_poly
		(pts
			(xy 381.905002 -247.926098) (xy 381.804926 -247.826022) (xy 381.70485 -247.926098) (xy 381.70485 -247.970548)
			(xy 381.905002 -247.970548)
		)
		(stroke
			(width 0)
			(type solid)
		)
		(fill yes)
		(layer "In4.Cu")
		(net "M_J_CPU0_SA_CB<4>")
	)
	(gr_poly
		(pts
			(xy 381.905002 -247.522492) (xy 381.905002 -247.47474) (xy 381.70485 -247.47474) (xy 381.70485 -247.522492)
			(xy 381.804926 -247.622314)
		)
		(stroke
			(width 0)
			(type solid)
		)
		(fill yes)
		(layer "In4.Cu")
		(net "M_J_CPU0_SA_DQS_DP<9>")
	)
	(gr_poly
		(pts
			(xy 381.905002 -246.305832) (xy 381.804926 -246.20601) (xy 381.70485 -246.305832) (xy 381.70485 -246.353584)
			(xy 381.905002 -246.353584)
		)
		(stroke
			(width 0)
			(type solid)
		)
		(fill yes)
		(layer "In4.Cu")
		(net "M_J_CPU0_SA_DQS_DP<4>")
	)
	(gr_poly
		(pts
			(xy 381.905002 -245.902226) (xy 381.905002 -245.857776) (xy 381.70485 -245.857776) (xy 381.70485 -245.902226)
			(xy 381.804926 -246.002302)
		)
		(stroke
			(width 0)
			(type solid)
		)
		(fill yes)
		(layer "In4.Cu")
		(net "M_J_CPU0_SA_CB<3>")
	)
	(gr_poly
		(pts
			(xy 381.905002 -244.686074) (xy 381.804926 -244.585998) (xy 381.70485 -244.686074) (xy 381.70485 -244.730524)
			(xy 381.905002 -244.730524)
		)
		(stroke
			(width 0)
			(type solid)
		)
		(fill yes)
		(layer "In4.Cu")
		(net "M_J_CPU0_SA_CB<0>")
	)
	(gr_poly
		(pts
			(xy 381.905002 -244.282214) (xy 381.905002 -244.237764) (xy 381.70485 -244.237764) (xy 381.70485 -244.282214)
			(xy 381.804926 -244.38229)
		)
		(stroke
			(width 0)
			(type solid)
		)
		(fill yes)
		(layer "In4.Cu")
		(net "M_J_CPU0_SA_DQ<31>")
	)
	(gr_poly
		(pts
			(xy 381.905002 -243.066062) (xy 381.804926 -242.965986) (xy 381.70485 -243.066062) (xy 381.70485 -243.110512)
			(xy 381.905002 -243.110512)
		)
		(stroke
			(width 0)
			(type solid)
		)
		(fill yes)
		(layer "In4.Cu")
		(net "M_J_CPU0_SA_DQ<28>")
	)
	(gr_poly
		(pts
			(xy 381.905002 -242.662456) (xy 381.905002 -242.614704) (xy 381.70485 -242.614704) (xy 381.70485 -242.662456)
			(xy 381.804926 -242.762278)
		)
		(stroke
			(width 0)
			(type solid)
		)
		(fill yes)
		(layer "In4.Cu")
		(net "M_J_CPU0_SA_DQS_DP<8>")
	)
	(gr_poly
		(pts
			(xy 381.905002 -241.445796) (xy 381.804926 -241.345974) (xy 381.70485 -241.445796) (xy 381.70485 -241.493548)
			(xy 381.905002 -241.493548)
		)
		(stroke
			(width 0)
			(type solid)
		)
		(fill yes)
		(layer "In4.Cu")
		(net "M_J_CPU0_SA_DQS_DP<3>")
	)
	(gr_poly
		(pts
			(xy 381.905002 -241.04219) (xy 381.905002 -240.99774) (xy 381.70485 -240.99774) (xy 381.70485 -241.04219)
			(xy 381.804926 -241.142266)
		)
		(stroke
			(width 0)
			(type solid)
		)
		(fill yes)
		(layer "In4.Cu")
		(net "M_J_CPU0_SA_DQ<27>")
	)
	(gr_poly
		(pts
			(xy 381.905002 -239.826038) (xy 381.804926 -239.725962) (xy 381.70485 -239.826038) (xy 381.70485 -239.870488)
			(xy 381.905002 -239.870488)
		)
		(stroke
			(width 0)
			(type solid)
		)
		(fill yes)
		(layer "In4.Cu")
		(net "M_J_CPU0_SA_DQ<24>")
	)
	(gr_poly
		(pts
			(xy 381.905002 -239.422178) (xy 381.905002 -239.377728) (xy 381.70485 -239.377728) (xy 381.70485 -239.422178)
			(xy 381.804926 -239.522254)
		)
		(stroke
			(width 0)
			(type solid)
		)
		(fill yes)
		(layer "In4.Cu")
		(net "M_J_CPU0_SA_DQ<23>")
	)
	(gr_poly
		(pts
			(xy 381.905002 -238.206026) (xy 381.804926 -238.10595) (xy 381.70485 -238.206026) (xy 381.70485 -238.250476)
			(xy 381.905002 -238.250476)
		)
		(stroke
			(width 0)
			(type solid)
		)
		(fill yes)
		(layer "In4.Cu")
		(net "M_J_CPU0_SA_DQ<20>")
	)
	(gr_poly
		(pts
			(xy 381.905002 -237.80242) (xy 381.905002 -237.754668) (xy 381.70485 -237.754668) (xy 381.70485 -237.80242)
			(xy 381.804926 -237.902242)
		)
		(stroke
			(width 0)
			(type solid)
		)
		(fill yes)
		(layer "In4.Cu")
		(net "M_J_CPU0_SA_DQS_DP<7>")
	)
	(gr_poly
		(pts
			(xy 381.905002 -236.58576) (xy 381.804926 -236.485938) (xy 381.70485 -236.58576) (xy 381.70485 -236.633512)
			(xy 381.905002 -236.633512)
		)
		(stroke
			(width 0)
			(type solid)
		)
		(fill yes)
		(layer "In4.Cu")
		(net "M_J_CPU0_SA_DQS_DP<2>")
	)
	(gr_poly
		(pts
			(xy 381.905002 -236.182154) (xy 381.905002 -236.137704) (xy 381.70485 -236.137704) (xy 381.70485 -236.182154)
			(xy 381.804926 -236.28223)
		)
		(stroke
			(width 0)
			(type solid)
		)
		(fill yes)
		(layer "In4.Cu")
		(net "M_J_CPU0_SA_DQ<19>")
	)
	(gr_poly
		(pts
			(xy 381.905002 -234.966002) (xy 381.804926 -234.865926) (xy 381.70485 -234.966002) (xy 381.70485 -235.010452)
			(xy 381.905002 -235.010452)
		)
		(stroke
			(width 0)
			(type solid)
		)
		(fill yes)
		(layer "In4.Cu")
		(net "M_J_CPU0_SA_DQ<16>")
	)
	(gr_poly
		(pts
			(xy 381.905002 -234.562142) (xy 381.905002 -234.517692) (xy 381.70485 -234.517692) (xy 381.70485 -234.562142)
			(xy 381.804926 -234.662218)
		)
		(stroke
			(width 0)
			(type solid)
		)
		(fill yes)
		(layer "In4.Cu")
		(net "M_J_CPU0_SA_DQ<15>")
	)
	(gr_poly
		(pts
			(xy 381.905002 -233.34599) (xy 381.804926 -233.245914) (xy 381.70485 -233.34599) (xy 381.70485 -233.39044)
			(xy 381.905002 -233.39044)
		)
		(stroke
			(width 0)
			(type solid)
		)
		(fill yes)
		(layer "In4.Cu")
		(net "M_J_CPU0_SA_DQ<12>")
	)
	(gr_poly
		(pts
			(xy 381.905002 -232.942384) (xy 381.905002 -232.894632) (xy 381.70485 -232.894632) (xy 381.70485 -232.942384)
			(xy 381.804926 -233.042206)
		)
		(stroke
			(width 0)
			(type solid)
		)
		(fill yes)
		(layer "In4.Cu")
		(net "M_J_CPU0_SA_DQS_DP<6>")
	)
	(gr_poly
		(pts
			(xy 381.905002 -231.725724) (xy 381.804926 -231.625902) (xy 381.70485 -231.725724) (xy 381.70485 -231.773476)
			(xy 381.905002 -231.773476)
		)
		(stroke
			(width 0)
			(type solid)
		)
		(fill yes)
		(layer "In4.Cu")
		(net "M_J_CPU0_SA_DQS_DP<1>")
	)
	(gr_poly
		(pts
			(xy 381.905002 -231.322372) (xy 381.905002 -231.277922) (xy 381.70485 -231.277922) (xy 381.70485 -231.322372)
			(xy 381.804926 -231.422448)
		)
		(stroke
			(width 0)
			(type solid)
		)
		(fill yes)
		(layer "In4.Cu")
		(net "M_J_CPU0_SA_DQ<11>")
	)
	(gr_poly
		(pts
			(xy 381.905002 -230.105966) (xy 381.804926 -230.006144) (xy 381.70485 -230.105966) (xy 381.70485 -230.150416)
			(xy 381.905002 -230.150416)
		)
		(stroke
			(width 0)
			(type solid)
		)
		(fill yes)
		(layer "In4.Cu")
		(net "M_J_CPU0_SA_DQ<8>")
	)
	(gr_poly
		(pts
			(xy 381.905002 -229.70236) (xy 381.905002 -229.65791) (xy 381.70485 -229.65791) (xy 381.70485 -229.70236)
			(xy 381.804926 -229.802436)
		)
		(stroke
			(width 0)
			(type solid)
		)
		(fill yes)
		(layer "In4.Cu")
		(net "M_J_CPU0_SA_DQ<7>")
	)
	(gr_poly
		(pts
			(xy 381.905002 -228.486208) (xy 381.804926 -228.386132) (xy 381.70485 -228.486208) (xy 381.70485 -228.530658)
			(xy 381.905002 -228.530658)
		)
		(stroke
			(width 0)
			(type solid)
		)
		(fill yes)
		(layer "In4.Cu")
		(net "M_J_CPU0_SA_DQ<4>")
	)
	(gr_poly
		(pts
			(xy 381.905002 -228.082602) (xy 381.905002 -228.03485) (xy 381.70485 -228.03485) (xy 381.70485 -228.082602)
			(xy 381.804926 -228.182424)
		)
		(stroke
			(width 0)
			(type solid)
		)
		(fill yes)
		(layer "In4.Cu")
		(net "M_J_CPU0_SA_DQS_DP<5>")
	)
	(gr_poly
		(pts
			(xy 381.905002 -226.865942) (xy 381.804926 -226.76612) (xy 381.70485 -226.865942) (xy 381.70485 -226.913694)
			(xy 381.905002 -226.913694)
		)
		(stroke
			(width 0)
			(type solid)
		)
		(fill yes)
		(layer "In4.Cu")
		(net "M_J_CPU0_SA_DQS_DP<0>")
	)
	(gr_poly
		(pts
			(xy 381.905002 -226.462336) (xy 381.905002 -226.417886) (xy 381.70485 -226.417886) (xy 381.70485 -226.462336)
			(xy 381.804926 -226.562412)
		)
		(stroke
			(width 0)
			(type solid)
		)
		(fill yes)
		(layer "In4.Cu")
		(net "M_J_CPU0_SA_DQ<3>")
	)
	(gr_poly
		(pts
			(xy 381.905002 -225.246184) (xy 381.804926 -225.146108) (xy 381.70485 -225.246184) (xy 381.70485 -225.290634)
			(xy 381.905002 -225.290634)
		)
		(stroke
			(width 0)
			(type solid)
		)
		(fill yes)
		(layer "In4.Cu")
		(net "M_J_CPU0_SA_DQ<0>")
	)
	(gr_poly
		(pts
			(xy 382.204976 -292.91788) (xy 382.1049 -292.817804) (xy 382.004824 -292.91788) (xy 382.004824 -292.96233)
			(xy 382.204976 -292.96233)
		)
		(stroke
			(width 0)
			(type solid)
		)
		(fill yes)
		(layer "In4.Cu")
		(net "M_J_CPU0_SB_DQ<29>")
	)
	(gr_poly
		(pts
			(xy 382.204976 -292.51402) (xy 382.204976 -292.46957) (xy 382.004824 -292.46957) (xy 382.004824 -292.51402)
			(xy 382.1049 -292.614096)
		)
		(stroke
			(width 0)
			(type solid)
		)
		(fill yes)
		(layer "In4.Cu")
		(net "M_J_CPU0_SB_DQ<30>")
	)
	(gr_poly
		(pts
			(xy 382.204976 -291.297614) (xy 382.1049 -291.197792) (xy 382.004824 -291.297614) (xy 382.004824 -291.345366)
			(xy 382.204976 -291.345366)
		)
		(stroke
			(width 0)
			(type solid)
		)
		(fill yes)
		(layer "In4.Cu")
		(net "M_J_CPU0_SB_DQS_DN<8>")
	)
	(gr_poly
		(pts
			(xy 382.204976 -290.894262) (xy 382.204976 -290.84651) (xy 382.004824 -290.84651) (xy 382.004824 -290.894262)
			(xy 382.1049 -290.994084)
		)
		(stroke
			(width 0)
			(type solid)
		)
		(fill yes)
		(layer "In4.Cu")
		(net "M_J_CPU0_SB_DQS_DN<3>")
	)
	(gr_poly
		(pts
			(xy 382.204976 -289.677856) (xy 382.1049 -289.57778) (xy 382.004824 -289.677856) (xy 382.004824 -289.722306)
			(xy 382.204976 -289.722306)
		)
		(stroke
			(width 0)
			(type solid)
		)
		(fill yes)
		(layer "In4.Cu")
		(net "M_J_CPU0_SB_DQ<25>")
	)
	(gr_poly
		(pts
			(xy 382.204976 -289.273996) (xy 382.204976 -289.229546) (xy 382.004824 -289.229546) (xy 382.004824 -289.273996)
			(xy 382.1049 -289.374072)
		)
		(stroke
			(width 0)
			(type solid)
		)
		(fill yes)
		(layer "In4.Cu")
		(net "M_J_CPU0_SB_DQ<26>")
	)
	(gr_poly
		(pts
			(xy 382.204976 -288.057844) (xy 382.1049 -287.957768) (xy 382.004824 -288.057844) (xy 382.004824 -288.102294)
			(xy 382.204976 -288.102294)
		)
		(stroke
			(width 0)
			(type solid)
		)
		(fill yes)
		(layer "In4.Cu")
		(net "M_J_CPU0_SB_DQ<21>")
	)
	(gr_poly
		(pts
			(xy 382.204976 -287.654238) (xy 382.204976 -287.609788) (xy 382.004824 -287.609788) (xy 382.004824 -287.654238)
			(xy 382.1049 -287.75406)
		)
		(stroke
			(width 0)
			(type solid)
		)
		(fill yes)
		(layer "In4.Cu")
		(net "M_J_CPU0_SB_DQ<22>")
	)
	(gr_poly
		(pts
			(xy 382.204976 -286.437832) (xy 382.1049 -286.337756) (xy 382.004824 -286.437832) (xy 382.004824 -286.485584)
			(xy 382.204976 -286.485584)
		)
		(stroke
			(width 0)
			(type solid)
		)
		(fill yes)
		(layer "In4.Cu")
		(net "M_J_CPU0_SB_DQS_DN<7>")
	)
	(gr_poly
		(pts
			(xy 382.204976 -286.03448) (xy 382.204976 -285.986728) (xy 382.004824 -285.986728) (xy 382.004824 -286.03448)
			(xy 382.1049 -286.134302)
		)
		(stroke
			(width 0)
			(type solid)
		)
		(fill yes)
		(layer "In4.Cu")
		(net "M_J_CPU0_SB_DQS_DN<2>")
	)
	(gr_poly
		(pts
			(xy 382.204976 -284.818074) (xy 382.1049 -284.717998) (xy 382.004824 -284.818074) (xy 382.004824 -284.862524)
			(xy 382.204976 -284.862524)
		)
		(stroke
			(width 0)
			(type solid)
		)
		(fill yes)
		(layer "In4.Cu")
		(net "M_J_CPU0_SB_DQ<17>")
	)
	(gr_poly
		(pts
			(xy 382.204976 -284.414214) (xy 382.204976 -284.369764) (xy 382.004824 -284.369764) (xy 382.004824 -284.414214)
			(xy 382.1049 -284.51429)
		)
		(stroke
			(width 0)
			(type solid)
		)
		(fill yes)
		(layer "In4.Cu")
		(net "M_J_CPU0_SB_DQ<18>")
	)
	(gr_poly
		(pts
			(xy 382.204976 -283.198062) (xy 382.1049 -283.097986) (xy 382.004824 -283.198062) (xy 382.004824 -283.242512)
			(xy 382.204976 -283.242512)
		)
		(stroke
			(width 0)
			(type solid)
		)
		(fill yes)
		(layer "In4.Cu")
		(net "M_J_CPU0_SB_DQ<13>")
	)
	(gr_poly
		(pts
			(xy 382.204976 -282.794202) (xy 382.204976 -282.749752) (xy 382.004824 -282.749752) (xy 382.004824 -282.794202)
			(xy 382.1049 -282.894278)
		)
		(stroke
			(width 0)
			(type solid)
		)
		(fill yes)
		(layer "In4.Cu")
		(net "M_J_CPU0_SB_DQ<14>")
	)
	(gr_poly
		(pts
			(xy 382.204976 -281.577796) (xy 382.1049 -281.477974) (xy 382.004824 -281.577796) (xy 382.004824 -281.625548)
			(xy 382.204976 -281.625548)
		)
		(stroke
			(width 0)
			(type solid)
		)
		(fill yes)
		(layer "In4.Cu")
		(net "M_J_CPU0_SB_DQS_DN<6>")
	)
	(gr_poly
		(pts
			(xy 382.204976 -281.174444) (xy 382.204976 -281.126692) (xy 382.004824 -281.126692) (xy 382.004824 -281.174444)
			(xy 382.1049 -281.274266)
		)
		(stroke
			(width 0)
			(type solid)
		)
		(fill yes)
		(layer "In4.Cu")
		(net "M_J_CPU0_SB_DQS_DN<1>")
	)
	(gr_poly
		(pts
			(xy 382.204976 -279.958038) (xy 382.1049 -279.857962) (xy 382.004824 -279.958038) (xy 382.004824 -280.002488)
			(xy 382.204976 -280.002488)
		)
		(stroke
			(width 0)
			(type solid)
		)
		(fill yes)
		(layer "In4.Cu")
		(net "M_J_CPU0_SB_DQ<9>")
	)
	(gr_poly
		(pts
			(xy 382.204976 -279.554178) (xy 382.204976 -279.509728) (xy 382.004824 -279.509728) (xy 382.004824 -279.554178)
			(xy 382.1049 -279.654254)
		)
		(stroke
			(width 0)
			(type solid)
		)
		(fill yes)
		(layer "In4.Cu")
		(net "M_J_CPU0_SB_DQ<10>")
	)
	(gr_poly
		(pts
			(xy 382.204976 -278.338026) (xy 382.1049 -278.23795) (xy 382.004824 -278.338026) (xy 382.004824 -278.382476)
			(xy 382.204976 -278.382476)
		)
		(stroke
			(width 0)
			(type solid)
		)
		(fill yes)
		(layer "In4.Cu")
		(net "M_J_CPU0_SB_DQ<5>")
	)
	(gr_poly
		(pts
			(xy 382.204976 -277.934166) (xy 382.204976 -277.889716) (xy 382.004824 -277.889716) (xy 382.004824 -277.934166)
			(xy 382.1049 -278.034242)
		)
		(stroke
			(width 0)
			(type solid)
		)
		(fill yes)
		(layer "In4.Cu")
		(net "M_J_CPU0_SB_DQ<6>")
	)
	(gr_poly
		(pts
			(xy 382.204976 -276.71776) (xy 382.1049 -276.617938) (xy 382.004824 -276.71776) (xy 382.004824 -276.765512)
			(xy 382.204976 -276.765512)
		)
		(stroke
			(width 0)
			(type solid)
		)
		(fill yes)
		(layer "In4.Cu")
		(net "M_J_CPU0_SB_DQS_DN<5>")
	)
	(gr_poly
		(pts
			(xy 382.204976 -276.314408) (xy 382.204976 -276.266656) (xy 382.004824 -276.266656) (xy 382.004824 -276.314408)
			(xy 382.1049 -276.41423)
		)
		(stroke
			(width 0)
			(type solid)
		)
		(fill yes)
		(layer "In4.Cu")
		(net "M_J_CPU0_SB_DQS_DN<0>")
	)
	(gr_poly
		(pts
			(xy 382.204976 -275.098002) (xy 382.1049 -274.997926) (xy 382.004824 -275.098002) (xy 382.004824 -275.142452)
			(xy 382.204976 -275.142452)
		)
		(stroke
			(width 0)
			(type solid)
		)
		(fill yes)
		(layer "In4.Cu")
		(net "M_J_CPU0_SB_DQ<1>")
	)
	(gr_poly
		(pts
			(xy 382.204976 -274.694142) (xy 382.204976 -274.649692) (xy 382.004824 -274.649692) (xy 382.004824 -274.694142)
			(xy 382.1049 -274.794218)
		)
		(stroke
			(width 0)
			(type solid)
		)
		(fill yes)
		(layer "In4.Cu")
		(net "M_J_CPU0_SB_DQ<2>")
	)
	(gr_poly
		(pts
			(xy 382.204976 -273.47799) (xy 382.1049 -273.377914) (xy 382.004824 -273.47799) (xy 382.004824 -273.52244)
			(xy 382.204976 -273.52244)
		)
		(stroke
			(width 0)
			(type solid)
		)
		(fill yes)
		(layer "In4.Cu")
		(net "M_J_CPU0_SB_CB<1>")
	)
	(gr_poly
		(pts
			(xy 382.204976 -273.07413) (xy 382.204976 -273.02968) (xy 382.004824 -273.02968) (xy 382.004824 -273.07413)
			(xy 382.1049 -273.174206)
		)
		(stroke
			(width 0)
			(type solid)
		)
		(fill yes)
		(layer "In4.Cu")
		(net "M_J_CPU0_SB_CB<2>")
	)
	(gr_poly
		(pts
			(xy 382.204976 -271.857724) (xy 382.1049 -271.757902) (xy 382.004824 -271.857724) (xy 382.004824 -271.905476)
			(xy 382.204976 -271.905476)
		)
		(stroke
			(width 0)
			(type solid)
		)
		(fill yes)
		(layer "In4.Cu")
		(net "M_J_CPU0_SB_DQS_DN<4>")
	)
	(gr_poly
		(pts
			(xy 382.204976 -271.454372) (xy 382.204976 -271.40662) (xy 382.004824 -271.40662) (xy 382.004824 -271.454372)
			(xy 382.1049 -271.554194)
		)
		(stroke
			(width 0)
			(type solid)
		)
		(fill yes)
		(layer "In4.Cu")
		(net "M_J_CPU0_SB_DQS_DN<9>")
	)
	(gr_poly
		(pts
			(xy 382.204976 -270.237966) (xy 382.1049 -270.13789) (xy 382.004824 -270.237966) (xy 382.004824 -270.282416)
			(xy 382.204976 -270.282416)
		)
		(stroke
			(width 0)
			(type solid)
		)
		(fill yes)
		(layer "In4.Cu")
		(net "M_J_CPU0_SB_CB<5>")
	)
	(gr_poly
		(pts
			(xy 382.204976 -269.834106) (xy 382.204976 -269.789656) (xy 382.004824 -269.789656) (xy 382.004824 -269.834106)
			(xy 382.1049 -269.934182)
		)
		(stroke
			(width 0)
			(type solid)
		)
		(fill yes)
		(layer "In4.Cu")
		(net "M_J_CPU0_SB_CB<6>")
	)
	(gr_poly
		(pts
			(xy 382.204976 -266.997942) (xy 382.1049 -266.897866) (xy 382.004824 -266.997942) (xy 382.004824 -267.042392)
			(xy 382.204976 -267.042392)
		)
		(stroke
			(width 0)
			(type solid)
		)
		(fill yes)
		(layer "In4.Cu")
		(net "M_J_CPU0_SA_RSP<0>")
	)
	(gr_poly
		(pts
			(xy 382.204976 -266.594082) (xy 382.204976 -266.549632) (xy 382.004824 -266.549632) (xy 382.004824 -266.594082)
			(xy 382.1049 -266.694158)
		)
		(stroke
			(width 0)
			(type solid)
		)
		(fill yes)
		(layer "In4.Cu")
		(net "M_J_CPU0_SB_CS_N<1>")
	)
	(gr_poly
		(pts
			(xy 382.204976 -265.37793) (xy 382.1049 -265.277854) (xy 382.004824 -265.37793) (xy 382.004824 -265.42238)
			(xy 382.204976 -265.42238)
		)
		(stroke
			(width 0)
			(type solid)
		)
		(fill yes)
		(layer "In4.Cu")
		(net "M_J_CPU0_SB_PAR")
	)
	(gr_poly
		(pts
			(xy 382.204976 -263.757918) (xy 382.1049 -263.657842) (xy 382.004824 -263.757918) (xy 382.004824 -263.802368)
			(xy 382.204976 -263.802368)
		)
		(stroke
			(width 0)
			(type solid)
		)
		(fill yes)
		(layer "In4.Cu")
		(net "M_J_CPU0_SB_CA<4>")
	)
	(gr_poly
		(pts
			(xy 382.204976 -263.354058) (xy 382.204976 -263.309608) (xy 382.004824 -263.309608) (xy 382.004824 -263.354058)
			(xy 382.1049 -263.454134)
		)
		(stroke
			(width 0)
			(type solid)
		)
		(fill yes)
		(layer "In4.Cu")
		(net "M_J_CPU0_SB_CA<3>")
	)
	(gr_poly
		(pts
			(xy 382.204976 -262.137906) (xy 382.1049 -262.03783) (xy 382.004824 -262.137906) (xy 382.004824 -262.182356)
			(xy 382.204976 -262.182356)
		)
		(stroke
			(width 0)
			(type solid)
		)
		(fill yes)
		(layer "In4.Cu")
		(net "M_J_CPU0_SB_CA<0>")
	)
	(gr_poly
		(pts
			(xy 382.374902 -256.432558) (xy 382.374902 -256.384806) (xy 382.17475 -256.384806) (xy 382.17475 -256.432558)
			(xy 382.274826 -256.53238)
		)
		(stroke
			(width 0)
			(type solid)
		)
		(fill yes)
		(layer "In4.Cu")
		(net "M_J_CPU0_CLK_DN<0>")
	)
	(gr_poly
		(pts
			(xy 382.374902 -255.216152) (xy 382.274826 -255.116076) (xy 382.17475 -255.216152) (xy 382.17475 -255.260602)
			(xy 382.374902 -255.260602)
		)
		(stroke
			(width 0)
			(type solid)
		)
		(fill yes)
		(layer "In4.Cu")
		(net "M_J_CPU0_SA_CA<6>")
	)
	(gr_poly
		(pts
			(xy 382.374902 -254.812292) (xy 382.374902 -254.767842) (xy 382.17475 -254.767842) (xy 382.17475 -254.812292)
			(xy 382.274826 -254.912368)
		)
		(stroke
			(width 0)
			(type solid)
		)
		(fill yes)
		(layer "In4.Cu")
		(net "M_J_CPU0_SA_CA<5>")
	)
	(gr_poly
		(pts
			(xy 382.374902 -253.59614) (xy 382.274826 -253.496064) (xy 382.17475 -253.59614) (xy 382.17475 -253.64059)
			(xy 382.374902 -253.64059)
		)
		(stroke
			(width 0)
			(type solid)
		)
		(fill yes)
		(layer "In4.Cu")
		(net "M_J_CPU0_SA_CA<2>")
	)
	(gr_poly
		(pts
			(xy 382.374902 -253.19228) (xy 382.374902 -253.14783) (xy 382.17475 -253.14783) (xy 382.17475 -253.19228)
			(xy 382.274826 -253.292356)
		)
		(stroke
			(width 0)
			(type solid)
		)
		(fill yes)
		(layer "In4.Cu")
		(net "M_J_CPU0_SA_CA<1>")
	)
	(gr_poly
		(pts
			(xy 382.374902 -251.976128) (xy 382.274826 -251.876052) (xy 382.17475 -251.976128) (xy 382.17475 -252.020578)
			(xy 382.374902 -252.020578)
		)
		(stroke
			(width 0)
			(type solid)
		)
		(fill yes)
		(layer "In4.Cu")
		(net "M_J_CPU0_SA_CS_N<1>")
	)
	(gr_poly
		(pts
			(xy 382.374902 -250.356116) (xy 382.274826 -250.25604) (xy 382.17475 -250.356116) (xy 382.17475 -250.400566)
			(xy 382.374902 -250.400566)
		)
		(stroke
			(width 0)
			(type solid)
		)
		(fill yes)
		(layer "In4.Cu")
		(net "M_J_CPU0_ALERT_R_N")
	)
	(gr_poly
		(pts
			(xy 382.374902 -248.736104) (xy 382.274826 -248.636028) (xy 382.17475 -248.736104) (xy 382.17475 -248.780554)
			(xy 382.374902 -248.780554)
		)
		(stroke
			(width 0)
			(type solid)
		)
		(fill yes)
		(layer "In4.Cu")
		(net "M_J_CPU0_SA_CB<5>")
	)
	(gr_poly
		(pts
			(xy 382.374902 -248.332244) (xy 382.374902 -248.287794) (xy 382.17475 -248.287794) (xy 382.17475 -248.332244)
			(xy 382.274826 -248.43232)
		)
		(stroke
			(width 0)
			(type solid)
		)
		(fill yes)
		(layer "In4.Cu")
		(net "M_J_CPU0_SA_CB<6>")
	)
	(gr_poly
		(pts
			(xy 382.374902 -247.115838) (xy 382.274826 -247.016016) (xy 382.17475 -247.115838) (xy 382.17475 -247.16359)
			(xy 382.374902 -247.16359)
		)
		(stroke
			(width 0)
			(type solid)
		)
		(fill yes)
		(layer "In4.Cu")
		(net "M_J_CPU0_SA_DQS_DN<9>")
	)
	(gr_poly
		(pts
			(xy 382.374902 -246.712486) (xy 382.374902 -246.664734) (xy 382.17475 -246.664734) (xy 382.17475 -246.712486)
			(xy 382.274826 -246.812308)
		)
		(stroke
			(width 0)
			(type solid)
		)
		(fill yes)
		(layer "In4.Cu")
		(net "M_J_CPU0_SA_DQS_DN<4>")
	)
	(gr_poly
		(pts
			(xy 382.374902 -245.49608) (xy 382.274826 -245.396004) (xy 382.17475 -245.49608) (xy 382.17475 -245.54053)
			(xy 382.374902 -245.54053)
		)
		(stroke
			(width 0)
			(type solid)
		)
		(fill yes)
		(layer "In4.Cu")
		(net "M_J_CPU0_SA_CB<1>")
	)
	(gr_poly
		(pts
			(xy 382.374902 -245.09222) (xy 382.374902 -245.04777) (xy 382.17475 -245.04777) (xy 382.17475 -245.09222)
			(xy 382.274826 -245.192296)
		)
		(stroke
			(width 0)
			(type solid)
		)
		(fill yes)
		(layer "In4.Cu")
		(net "M_J_CPU0_SA_CB<2>")
	)
	(gr_poly
		(pts
			(xy 382.374902 -243.876068) (xy 382.274826 -243.775992) (xy 382.17475 -243.876068) (xy 382.17475 -243.920518)
			(xy 382.374902 -243.920518)
		)
		(stroke
			(width 0)
			(type solid)
		)
		(fill yes)
		(layer "In4.Cu")
		(net "M_J_CPU0_SA_DQ<29>")
	)
	(gr_poly
		(pts
			(xy 382.374902 -243.472208) (xy 382.374902 -243.427758) (xy 382.17475 -243.427758) (xy 382.17475 -243.472208)
			(xy 382.274826 -243.572284)
		)
		(stroke
			(width 0)
			(type solid)
		)
		(fill yes)
		(layer "In4.Cu")
		(net "M_J_CPU0_SA_DQ<30>")
	)
	(gr_poly
		(pts
			(xy 382.374902 -242.255802) (xy 382.274826 -242.15598) (xy 382.17475 -242.255802) (xy 382.17475 -242.303554)
			(xy 382.374902 -242.303554)
		)
		(stroke
			(width 0)
			(type solid)
		)
		(fill yes)
		(layer "In4.Cu")
		(net "M_J_CPU0_SA_DQS_DN<8>")
	)
	(gr_poly
		(pts
			(xy 382.374902 -241.85245) (xy 382.374902 -241.804698) (xy 382.17475 -241.804698) (xy 382.17475 -241.85245)
			(xy 382.274826 -241.952272)
		)
		(stroke
			(width 0)
			(type solid)
		)
		(fill yes)
		(layer "In4.Cu")
		(net "M_J_CPU0_SA_DQS_DN<3>")
	)
	(gr_poly
		(pts
			(xy 382.374902 -240.636044) (xy 382.274826 -240.535968) (xy 382.17475 -240.636044) (xy 382.17475 -240.680494)
			(xy 382.374902 -240.680494)
		)
		(stroke
			(width 0)
			(type solid)
		)
		(fill yes)
		(layer "In4.Cu")
		(net "M_J_CPU0_SA_DQ<25>")
	)
	(gr_poly
		(pts
			(xy 382.374902 -240.232184) (xy 382.374902 -240.187734) (xy 382.17475 -240.187734) (xy 382.17475 -240.232184)
			(xy 382.274826 -240.33226)
		)
		(stroke
			(width 0)
			(type solid)
		)
		(fill yes)
		(layer "In4.Cu")
		(net "M_J_CPU0_SA_DQ<26>")
	)
	(gr_poly
		(pts
			(xy 382.374902 -239.016032) (xy 382.274826 -238.915956) (xy 382.17475 -239.016032) (xy 382.17475 -239.060482)
			(xy 382.374902 -239.060482)
		)
		(stroke
			(width 0)
			(type solid)
		)
		(fill yes)
		(layer "In4.Cu")
		(net "M_J_CPU0_SA_DQ<21>")
	)
	(gr_poly
		(pts
			(xy 382.374902 -238.612172) (xy 382.374902 -238.567722) (xy 382.17475 -238.567722) (xy 382.17475 -238.612172)
			(xy 382.274826 -238.712248)
		)
		(stroke
			(width 0)
			(type solid)
		)
		(fill yes)
		(layer "In4.Cu")
		(net "M_J_CPU0_SA_DQ<22>")
	)
	(gr_poly
		(pts
			(xy 382.374902 -237.395766) (xy 382.274826 -237.295944) (xy 382.17475 -237.395766) (xy 382.17475 -237.443518)
			(xy 382.374902 -237.443518)
		)
		(stroke
			(width 0)
			(type solid)
		)
		(fill yes)
		(layer "In4.Cu")
		(net "M_J_CPU0_SA_DQS_DN<7>")
	)
	(gr_poly
		(pts
			(xy 382.374902 -236.992414) (xy 382.374902 -236.944662) (xy 382.17475 -236.944662) (xy 382.17475 -236.992414)
			(xy 382.274826 -237.092236)
		)
		(stroke
			(width 0)
			(type solid)
		)
		(fill yes)
		(layer "In4.Cu")
		(net "M_J_CPU0_SA_DQS_DN<2>")
	)
	(gr_poly
		(pts
			(xy 382.374902 -235.776008) (xy 382.274826 -235.675932) (xy 382.17475 -235.776008) (xy 382.17475 -235.820458)
			(xy 382.374902 -235.820458)
		)
		(stroke
			(width 0)
			(type solid)
		)
		(fill yes)
		(layer "In4.Cu")
		(net "M_J_CPU0_SA_DQ<17>")
	)
	(gr_poly
		(pts
			(xy 382.374902 -235.372148) (xy 382.374902 -235.327698) (xy 382.17475 -235.327698) (xy 382.17475 -235.372148)
			(xy 382.274826 -235.472224)
		)
		(stroke
			(width 0)
			(type solid)
		)
		(fill yes)
		(layer "In4.Cu")
		(net "M_J_CPU0_SA_DQ<18>")
	)
	(gr_poly
		(pts
			(xy 382.374902 -234.155996) (xy 382.274826 -234.05592) (xy 382.17475 -234.155996) (xy 382.17475 -234.200446)
			(xy 382.374902 -234.200446)
		)
		(stroke
			(width 0)
			(type solid)
		)
		(fill yes)
		(layer "In4.Cu")
		(net "M_J_CPU0_SA_DQ<13>")
	)
	(gr_poly
		(pts
			(xy 382.374902 -233.752136) (xy 382.374902 -233.707686) (xy 382.17475 -233.707686) (xy 382.17475 -233.752136)
			(xy 382.274826 -233.852212)
		)
		(stroke
			(width 0)
			(type solid)
		)
		(fill yes)
		(layer "In4.Cu")
		(net "M_J_CPU0_SA_DQ<14>")
	)
	(gr_poly
		(pts
			(xy 382.374902 -232.53573) (xy 382.274826 -232.435908) (xy 382.17475 -232.53573) (xy 382.17475 -232.583482)
			(xy 382.374902 -232.583482)
		)
		(stroke
			(width 0)
			(type solid)
		)
		(fill yes)
		(layer "In4.Cu")
		(net "M_J_CPU0_SA_DQS_DN<6>")
	)
	(gr_poly
		(pts
			(xy 382.374902 -232.132378) (xy 382.374902 -232.084626) (xy 382.17475 -232.084626) (xy 382.17475 -232.132378)
			(xy 382.274826 -232.2322)
		)
		(stroke
			(width 0)
			(type solid)
		)
		(fill yes)
		(layer "In4.Cu")
		(net "M_J_CPU0_SA_DQS_DN<1>")
	)
	(gr_poly
		(pts
			(xy 382.374902 -230.915972) (xy 382.274826 -230.815896) (xy 382.17475 -230.915972) (xy 382.17475 -230.960422)
			(xy 382.374902 -230.960422)
		)
		(stroke
			(width 0)
			(type solid)
		)
		(fill yes)
		(layer "In4.Cu")
		(net "M_J_CPU0_SA_DQ<9>")
	)
	(gr_poly
		(pts
			(xy 382.374902 -230.512366) (xy 382.374902 -230.467916) (xy 382.17475 -230.467916) (xy 382.17475 -230.512366)
			(xy 382.274826 -230.612188)
		)
		(stroke
			(width 0)
			(type solid)
		)
		(fill yes)
		(layer "In4.Cu")
		(net "M_J_CPU0_SA_DQ<10>")
	)
	(gr_poly
		(pts
			(xy 382.374902 -229.29596) (xy 382.274826 -229.195884) (xy 382.17475 -229.29596) (xy 382.17475 -229.34041)
			(xy 382.374902 -229.34041)
		)
		(stroke
			(width 0)
			(type solid)
		)
		(fill yes)
		(layer "In4.Cu")
		(net "M_J_CPU0_SA_DQ<5>")
	)
	(gr_poly
		(pts
			(xy 382.374902 -228.892354) (xy 382.374902 -228.847904) (xy 382.17475 -228.847904) (xy 382.17475 -228.892354)
			(xy 382.274826 -228.99243)
		)
		(stroke
			(width 0)
			(type solid)
		)
		(fill yes)
		(layer "In4.Cu")
		(net "M_J_CPU0_SA_DQ<6>")
	)
	(gr_poly
		(pts
			(xy 382.374902 -227.675948) (xy 382.274826 -227.576126) (xy 382.17475 -227.675948) (xy 382.17475 -227.7237)
			(xy 382.374902 -227.7237)
		)
		(stroke
			(width 0)
			(type solid)
		)
		(fill yes)
		(layer "In4.Cu")
		(net "M_J_CPU0_SA_DQS_DN<5>")
	)
	(gr_poly
		(pts
			(xy 382.374902 -227.272596) (xy 382.374902 -227.224844) (xy 382.17475 -227.224844) (xy 382.17475 -227.272596)
			(xy 382.274826 -227.372418)
		)
		(stroke
			(width 0)
			(type solid)
		)
		(fill yes)
		(layer "In4.Cu")
		(net "M_J_CPU0_SA_DQS_DN<0>")
	)
	(gr_poly
		(pts
			(xy 382.374902 -226.05619) (xy 382.274826 -225.956114) (xy 382.17475 -226.05619) (xy 382.17475 -226.10064)
			(xy 382.374902 -226.10064)
		)
		(stroke
			(width 0)
			(type solid)
		)
		(fill yes)
		(layer "In4.Cu")
		(net "M_J_CPU0_SA_DQ<1>")
	)
	(gr_poly
		(pts
			(xy 382.374902 -225.65233) (xy 382.374902 -225.60788) (xy 382.17475 -225.60788) (xy 382.17475 -225.65233)
			(xy 382.274826 -225.752406)
		)
		(stroke
			(width 0)
			(type solid)
		)
		(fill yes)
		(layer "In4.Cu")
		(net "M_J_CPU0_SA_DQ<2>")
	)
	(gr_poly
		(pts
			(xy 382.674876 -293.324026) (xy 382.674876 -293.279576) (xy 382.474724 -293.279576) (xy 382.474724 -293.324026)
			(xy 382.5748 -293.424102)
		)
		(stroke
			(width 0)
			(type solid)
		)
		(fill yes)
		(layer "In4.Cu")
		(net "M_J_CPU0_SB_DQ<31>")
	)
	(gr_poly
		(pts
			(xy 382.674876 -292.107874) (xy 382.5748 -292.007798) (xy 382.474724 -292.107874) (xy 382.474724 -292.152324)
			(xy 382.674876 -292.152324)
		)
		(stroke
			(width 0)
			(type solid)
		)
		(fill yes)
		(layer "In4.Cu")
		(net "M_J_CPU0_SB_DQ<28>")
	)
	(gr_poly
		(pts
			(xy 382.674876 -291.704268) (xy 382.674876 -291.656516) (xy 382.474724 -291.656516) (xy 382.474724 -291.704268)
			(xy 382.5748 -291.80409)
		)
		(stroke
			(width 0)
			(type solid)
		)
		(fill yes)
		(layer "In4.Cu")
		(net "M_J_CPU0_SB_DQS_DP<8>")
	)
	(gr_poly
		(pts
			(xy 382.674876 -290.487608) (xy 382.5748 -290.387786) (xy 382.474724 -290.487608) (xy 382.474724 -290.53536)
			(xy 382.674876 -290.53536)
		)
		(stroke
			(width 0)
			(type solid)
		)
		(fill yes)
		(layer "In4.Cu")
		(net "M_J_CPU0_SB_DQS_DP<3>")
	)
	(gr_poly
		(pts
			(xy 382.674876 -290.084002) (xy 382.674876 -290.039552) (xy 382.474724 -290.039552) (xy 382.474724 -290.084002)
			(xy 382.5748 -290.184078)
		)
		(stroke
			(width 0)
			(type solid)
		)
		(fill yes)
		(layer "In4.Cu")
		(net "M_J_CPU0_SB_DQ<27>")
	)
	(gr_poly
		(pts
			(xy 382.674876 -288.86785) (xy 382.5748 -288.767774) (xy 382.474724 -288.86785) (xy 382.474724 -288.9123)
			(xy 382.674876 -288.9123)
		)
		(stroke
			(width 0)
			(type solid)
		)
		(fill yes)
		(layer "In4.Cu")
		(net "M_J_CPU0_SB_DQ<24>")
	)
	(gr_poly
		(pts
			(xy 382.674876 -288.464244) (xy 382.674876 -288.419794) (xy 382.474724 -288.419794) (xy 382.474724 -288.464244)
			(xy 382.5748 -288.56432)
		)
		(stroke
			(width 0)
			(type solid)
		)
		(fill yes)
		(layer "In4.Cu")
		(net "M_J_CPU0_SB_DQ<23>")
	)
	(gr_poly
		(pts
			(xy 382.674876 -287.247838) (xy 382.5748 -287.148016) (xy 382.474724 -287.247838) (xy 382.474724 -287.292288)
			(xy 382.674876 -287.292288)
		)
		(stroke
			(width 0)
			(type solid)
		)
		(fill yes)
		(layer "In4.Cu")
		(net "M_J_CPU0_SB_DQ<20>")
	)
	(gr_poly
		(pts
			(xy 382.674876 -286.844232) (xy 382.674876 -286.79648) (xy 382.474724 -286.79648) (xy 382.474724 -286.844232)
			(xy 382.5748 -286.944308)
		)
		(stroke
			(width 0)
			(type solid)
		)
		(fill yes)
		(layer "In4.Cu")
		(net "M_J_CPU0_SB_DQS_DP<7>")
	)
	(gr_poly
		(pts
			(xy 382.674876 -285.627826) (xy 382.5748 -285.528004) (xy 382.474724 -285.627826) (xy 382.474724 -285.675578)
			(xy 382.674876 -285.675578)
		)
		(stroke
			(width 0)
			(type solid)
		)
		(fill yes)
		(layer "In4.Cu")
		(net "M_J_CPU0_SB_DQS_DP<2>")
	)
	(gr_poly
		(pts
			(xy 382.674876 -285.22422) (xy 382.674876 -285.17977) (xy 382.474724 -285.17977) (xy 382.474724 -285.22422)
			(xy 382.5748 -285.324296)
		)
		(stroke
			(width 0)
			(type solid)
		)
		(fill yes)
		(layer "In4.Cu")
		(net "M_J_CPU0_SB_DQ<19>")
	)
	(gr_poly
		(pts
			(xy 382.674876 -284.008068) (xy 382.5748 -283.907992) (xy 382.474724 -284.008068) (xy 382.474724 -284.052518)
			(xy 382.674876 -284.052518)
		)
		(stroke
			(width 0)
			(type solid)
		)
		(fill yes)
		(layer "In4.Cu")
		(net "M_J_CPU0_SB_DQ<16>")
	)
	(gr_poly
		(pts
			(xy 382.674876 -283.604208) (xy 382.674876 -283.559758) (xy 382.474724 -283.559758) (xy 382.474724 -283.604208)
			(xy 382.5748 -283.704284)
		)
		(stroke
			(width 0)
			(type solid)
		)
		(fill yes)
		(layer "In4.Cu")
		(net "M_J_CPU0_SB_DQ<15>")
	)
	(gr_poly
		(pts
			(xy 382.674876 -282.388056) (xy 382.5748 -282.28798) (xy 382.474724 -282.388056) (xy 382.474724 -282.432506)
			(xy 382.674876 -282.432506)
		)
		(stroke
			(width 0)
			(type solid)
		)
		(fill yes)
		(layer "In4.Cu")
		(net "M_J_CPU0_SB_DQ<12>")
	)
	(gr_poly
		(pts
			(xy 382.674876 -281.98445) (xy 382.674876 -281.936698) (xy 382.474724 -281.936698) (xy 382.474724 -281.98445)
			(xy 382.5748 -282.084272)
		)
		(stroke
			(width 0)
			(type solid)
		)
		(fill yes)
		(layer "In4.Cu")
		(net "M_J_CPU0_SB_DQS_DP<6>")
	)
	(gr_poly
		(pts
			(xy 382.674876 -280.76779) (xy 382.5748 -280.667968) (xy 382.474724 -280.76779) (xy 382.474724 -280.815542)
			(xy 382.674876 -280.815542)
		)
		(stroke
			(width 0)
			(type solid)
		)
		(fill yes)
		(layer "In4.Cu")
		(net "M_J_CPU0_SB_DQS_DP<1>")
	)
	(gr_poly
		(pts
			(xy 382.674876 -280.364184) (xy 382.674876 -280.319734) (xy 382.474724 -280.319734) (xy 382.474724 -280.364184)
			(xy 382.5748 -280.46426)
		)
		(stroke
			(width 0)
			(type solid)
		)
		(fill yes)
		(layer "In4.Cu")
		(net "M_J_CPU0_SB_DQ<11>")
	)
	(gr_poly
		(pts
			(xy 382.674876 -279.148032) (xy 382.5748 -279.047956) (xy 382.474724 -279.148032) (xy 382.474724 -279.192482)
			(xy 382.674876 -279.192482)
		)
		(stroke
			(width 0)
			(type solid)
		)
		(fill yes)
		(layer "In4.Cu")
		(net "M_J_CPU0_SB_DQ<8>")
	)
	(gr_poly
		(pts
			(xy 382.674876 -278.744172) (xy 382.674876 -278.699722) (xy 382.474724 -278.699722) (xy 382.474724 -278.744172)
			(xy 382.5748 -278.844248)
		)
		(stroke
			(width 0)
			(type solid)
		)
		(fill yes)
		(layer "In4.Cu")
		(net "M_J_CPU0_SB_DQ<7>")
	)
	(gr_poly
		(pts
			(xy 382.674876 -277.52802) (xy 382.5748 -277.427944) (xy 382.474724 -277.52802) (xy 382.474724 -277.57247)
			(xy 382.674876 -277.57247)
		)
		(stroke
			(width 0)
			(type solid)
		)
		(fill yes)
		(layer "In4.Cu")
		(net "M_J_CPU0_SB_DQ<4>")
	)
	(gr_poly
		(pts
			(xy 382.674876 -277.124414) (xy 382.674876 -277.076662) (xy 382.474724 -277.076662) (xy 382.474724 -277.124414)
			(xy 382.5748 -277.224236)
		)
		(stroke
			(width 0)
			(type solid)
		)
		(fill yes)
		(layer "In4.Cu")
		(net "M_J_CPU0_SB_DQS_DP<5>")
	)
	(gr_poly
		(pts
			(xy 382.674876 -275.907754) (xy 382.5748 -275.807932) (xy 382.474724 -275.907754) (xy 382.474724 -275.955506)
			(xy 382.674876 -275.955506)
		)
		(stroke
			(width 0)
			(type solid)
		)
		(fill yes)
		(layer "In4.Cu")
		(net "M_J_CPU0_SB_DQS_DP<0>")
	)
	(gr_poly
		(pts
			(xy 382.674876 -275.504148) (xy 382.674876 -275.459698) (xy 382.474724 -275.459698) (xy 382.474724 -275.504148)
			(xy 382.5748 -275.604224)
		)
		(stroke
			(width 0)
			(type solid)
		)
		(fill yes)
		(layer "In4.Cu")
		(net "M_J_CPU0_SB_DQ<3>")
	)
	(gr_poly
		(pts
			(xy 382.674876 -274.287996) (xy 382.5748 -274.18792) (xy 382.474724 -274.287996) (xy 382.474724 -274.332446)
			(xy 382.674876 -274.332446)
		)
		(stroke
			(width 0)
			(type solid)
		)
		(fill yes)
		(layer "In4.Cu")
		(net "M_J_CPU0_SB_DQ<0>")
	)
	(gr_poly
		(pts
			(xy 382.674876 -273.884136) (xy 382.674876 -273.839686) (xy 382.474724 -273.839686) (xy 382.474724 -273.884136)
			(xy 382.5748 -273.984212)
		)
		(stroke
			(width 0)
			(type solid)
		)
		(fill yes)
		(layer "In4.Cu")
		(net "M_J_CPU0_SB_CB<3>")
	)
	(gr_poly
		(pts
			(xy 382.674876 -272.667984) (xy 382.5748 -272.567908) (xy 382.474724 -272.667984) (xy 382.474724 -272.712434)
			(xy 382.674876 -272.712434)
		)
		(stroke
			(width 0)
			(type solid)
		)
		(fill yes)
		(layer "In4.Cu")
		(net "M_J_CPU0_SB_CB<0>")
	)
	(gr_poly
		(pts
			(xy 382.674876 -272.264378) (xy 382.674876 -272.216626) (xy 382.474724 -272.216626) (xy 382.474724 -272.264378)
			(xy 382.5748 -272.3642)
		)
		(stroke
			(width 0)
			(type solid)
		)
		(fill yes)
		(layer "In4.Cu")
		(net "M_J_CPU0_SB_DQS_DP<4>")
	)
	(gr_poly
		(pts
			(xy 382.674876 -271.047718) (xy 382.5748 -270.947896) (xy 382.474724 -271.047718) (xy 382.474724 -271.09547)
			(xy 382.674876 -271.09547)
		)
		(stroke
			(width 0)
			(type solid)
		)
		(fill yes)
		(layer "In4.Cu")
		(net "M_J_CPU0_SB_DQS_DP<9>")
	)
	(gr_poly
		(pts
			(xy 382.674876 -270.644112) (xy 382.674876 -270.599662) (xy 382.474724 -270.599662) (xy 382.474724 -270.644112)
			(xy 382.5748 -270.744188)
		)
		(stroke
			(width 0)
			(type solid)
		)
		(fill yes)
		(layer "In4.Cu")
		(net "M_J_CPU0_SB_CB<7>")
	)
	(gr_poly
		(pts
			(xy 382.674876 -269.42796) (xy 382.5748 -269.327884) (xy 382.474724 -269.42796) (xy 382.474724 -269.47241)
			(xy 382.674876 -269.47241)
		)
		(stroke
			(width 0)
			(type solid)
		)
		(fill yes)
		(layer "In4.Cu")
		(net "M_J_CPU0_SB_CB<4>")
	)
	(gr_poly
		(pts
			(xy 382.674876 -267.807948) (xy 382.5748 -267.707872) (xy 382.474724 -267.807948) (xy 382.474724 -267.852398)
			(xy 382.674876 -267.852398)
		)
		(stroke
			(width 0)
			(type solid)
		)
		(fill yes)
		(layer "In4.Cu")
		(net "M_J_CPU0_SB_RSP<0>")
	)
	(gr_poly
		(pts
			(xy 382.674876 -265.784076) (xy 382.674876 -265.739626) (xy 382.474724 -265.739626) (xy 382.474724 -265.784076)
			(xy 382.5748 -265.884152)
		)
		(stroke
			(width 0)
			(type solid)
		)
		(fill yes)
		(layer "In4.Cu")
		(net "M_J_CPU0_SB_CS_N<0>")
	)
	(gr_poly
		(pts
			(xy 382.674876 -264.567924) (xy 382.5748 -264.467848) (xy 382.474724 -264.567924) (xy 382.474724 -264.612374)
			(xy 382.674876 -264.612374)
		)
		(stroke
			(width 0)
			(type solid)
		)
		(fill yes)
		(layer "In4.Cu")
		(net "M_J_CPU0_SB_CA<6>")
	)
	(gr_poly
		(pts
			(xy 382.674876 -264.164064) (xy 382.674876 -264.119614) (xy 382.474724 -264.119614) (xy 382.474724 -264.164064)
			(xy 382.5748 -264.26414)
		)
		(stroke
			(width 0)
			(type solid)
		)
		(fill yes)
		(layer "In4.Cu")
		(net "M_J_CPU0_SB_CA<5>")
	)
	(gr_poly
		(pts
			(xy 382.674876 -262.947912) (xy 382.5748 -262.847836) (xy 382.474724 -262.947912) (xy 382.474724 -262.992362)
			(xy 382.674876 -262.992362)
		)
		(stroke
			(width 0)
			(type solid)
		)
		(fill yes)
		(layer "In4.Cu")
		(net "M_J_CPU0_SB_CA<2>")
	)
	(gr_poly
		(pts
			(xy 382.674876 -262.544052) (xy 382.674876 -262.499602) (xy 382.474724 -262.499602) (xy 382.474724 -262.544052)
			(xy 382.5748 -262.644128)
		)
		(stroke
			(width 0)
			(type solid)
		)
		(fill yes)
		(layer "In4.Cu")
		(net "M_J_CPU0_SB_CA<1>")
	)
	(gr_poly
		(pts
			(xy 382.844802 -256.025904) (xy 382.744726 -255.926082) (xy 382.64465 -256.025904) (xy 382.64465 -256.073656)
			(xy 382.844802 -256.073656)
		)
		(stroke
			(width 0)
			(type solid)
		)
		(fill yes)
		(layer "In4.Cu")
		(net "M_J_CPU0_CLK_DP<0>")
	)
	(gr_poly
		(pts
			(xy 382.844802 -255.622298) (xy 382.844802 -255.577848) (xy 382.64465 -255.577848) (xy 382.64465 -255.622298)
			(xy 382.744726 -255.722374)
		)
		(stroke
			(width 0)
			(type solid)
		)
		(fill yes)
		(layer "In4.Cu")
		(net "M_J_CPU0_SA_PAR")
	)
	(gr_poly
		(pts
			(xy 382.844802 -254.406146) (xy 382.744726 -254.30607) (xy 382.64465 -254.406146) (xy 382.64465 -254.450596)
			(xy 382.844802 -254.450596)
		)
		(stroke
			(width 0)
			(type solid)
		)
		(fill yes)
		(layer "In4.Cu")
		(net "M_J_CPU0_SA_CA<4>")
	)
	(gr_poly
		(pts
			(xy 382.844802 -254.002286) (xy 382.844802 -253.957836) (xy 382.64465 -253.957836) (xy 382.64465 -254.002286)
			(xy 382.744726 -254.102362)
		)
		(stroke
			(width 0)
			(type solid)
		)
		(fill yes)
		(layer "In4.Cu")
		(net "M_J_CPU0_SA_CA<3>")
	)
	(gr_poly
		(pts
			(xy 382.844802 -252.786134) (xy 382.744726 -252.686058) (xy 382.64465 -252.786134) (xy 382.64465 -252.830584)
			(xy 382.844802 -252.830584)
		)
		(stroke
			(width 0)
			(type solid)
		)
		(fill yes)
		(layer "In4.Cu")
		(net "M_J_CPU0_SA_CA<0>")
	)
	(gr_poly
		(pts
			(xy 382.844802 -251.166122) (xy 382.744726 -251.066046) (xy 382.64465 -251.166122) (xy 382.64465 -251.210572)
			(xy 382.844802 -251.210572)
		)
		(stroke
			(width 0)
			(type solid)
		)
		(fill yes)
		(layer "In4.Cu")
		(net "M_J_CPU0_SA_CS_N<0>")
	)
	(gr_poly
		(pts
			(xy 382.844802 -250.762262) (xy 382.844802 -250.717812) (xy 382.64465 -250.717812) (xy 382.64465 -250.762262)
			(xy 382.744726 -250.862338)
		)
		(stroke
			(width 0)
			(type solid)
		)
		(fill yes)
		(layer "In4.Cu")
		(net "M_J_CPU0_RESET_N")
	)
	(gr_poly
		(pts
			(xy 382.844802 -249.14225) (xy 382.844802 -249.0978) (xy 382.64465 -249.0978) (xy 382.64465 -249.14225)
			(xy 382.744726 -249.242326)
		)
		(stroke
			(width 0)
			(type solid)
		)
		(fill yes)
		(layer "In4.Cu")
		(net "M_J_CPU0_SA_CB<7>")
	)
	(gr_poly
		(pts
			(xy 382.844802 -247.926098) (xy 382.744726 -247.826022) (xy 382.64465 -247.926098) (xy 382.64465 -247.970548)
			(xy 382.844802 -247.970548)
		)
		(stroke
			(width 0)
			(type solid)
		)
		(fill yes)
		(layer "In4.Cu")
		(net "M_J_CPU0_SA_CB<4>")
	)
	(gr_poly
		(pts
			(xy 382.844802 -247.522492) (xy 382.844802 -247.47474) (xy 382.64465 -247.47474) (xy 382.64465 -247.522492)
			(xy 382.744726 -247.622314)
		)
		(stroke
			(width 0)
			(type solid)
		)
		(fill yes)
		(layer "In4.Cu")
		(net "M_J_CPU0_SA_DQS_DP<9>")
	)
	(gr_poly
		(pts
			(xy 382.844802 -246.305832) (xy 382.744726 -246.20601) (xy 382.64465 -246.305832) (xy 382.64465 -246.353584)
			(xy 382.844802 -246.353584)
		)
		(stroke
			(width 0)
			(type solid)
		)
		(fill yes)
		(layer "In4.Cu")
		(net "M_J_CPU0_SA_DQS_DP<4>")
	)
	(gr_poly
		(pts
			(xy 382.844802 -245.902226) (xy 382.844802 -245.857776) (xy 382.64465 -245.857776) (xy 382.64465 -245.902226)
			(xy 382.744726 -246.002302)
		)
		(stroke
			(width 0)
			(type solid)
		)
		(fill yes)
		(layer "In4.Cu")
		(net "M_J_CPU0_SA_CB<3>")
	)
	(gr_poly
		(pts
			(xy 382.844802 -244.686074) (xy 382.744726 -244.585998) (xy 382.64465 -244.686074) (xy 382.64465 -244.730524)
			(xy 382.844802 -244.730524)
		)
		(stroke
			(width 0)
			(type solid)
		)
		(fill yes)
		(layer "In4.Cu")
		(net "M_J_CPU0_SA_CB<0>")
	)
	(gr_poly
		(pts
			(xy 382.844802 -244.282214) (xy 382.844802 -244.237764) (xy 382.64465 -244.237764) (xy 382.64465 -244.282214)
			(xy 382.744726 -244.38229)
		)
		(stroke
			(width 0)
			(type solid)
		)
		(fill yes)
		(layer "In4.Cu")
		(net "M_J_CPU0_SA_DQ<31>")
	)
	(gr_poly
		(pts
			(xy 382.844802 -243.066062) (xy 382.744726 -242.965986) (xy 382.64465 -243.066062) (xy 382.64465 -243.110512)
			(xy 382.844802 -243.110512)
		)
		(stroke
			(width 0)
			(type solid)
		)
		(fill yes)
		(layer "In4.Cu")
		(net "M_J_CPU0_SA_DQ<28>")
	)
	(gr_poly
		(pts
			(xy 382.844802 -242.662456) (xy 382.844802 -242.614704) (xy 382.64465 -242.614704) (xy 382.64465 -242.662456)
			(xy 382.744726 -242.762278)
		)
		(stroke
			(width 0)
			(type solid)
		)
		(fill yes)
		(layer "In4.Cu")
		(net "M_J_CPU0_SA_DQS_DP<8>")
	)
	(gr_poly
		(pts
			(xy 382.844802 -241.445796) (xy 382.744726 -241.345974) (xy 382.64465 -241.445796) (xy 382.64465 -241.493548)
			(xy 382.844802 -241.493548)
		)
		(stroke
			(width 0)
			(type solid)
		)
		(fill yes)
		(layer "In4.Cu")
		(net "M_J_CPU0_SA_DQS_DP<3>")
	)
	(gr_poly
		(pts
			(xy 382.844802 -241.04219) (xy 382.844802 -240.99774) (xy 382.64465 -240.99774) (xy 382.64465 -241.04219)
			(xy 382.744726 -241.142266)
		)
		(stroke
			(width 0)
			(type solid)
		)
		(fill yes)
		(layer "In4.Cu")
		(net "M_J_CPU0_SA_DQ<27>")
	)
	(gr_poly
		(pts
			(xy 382.844802 -239.826038) (xy 382.744726 -239.725962) (xy 382.64465 -239.826038) (xy 382.64465 -239.870488)
			(xy 382.844802 -239.870488)
		)
		(stroke
			(width 0)
			(type solid)
		)
		(fill yes)
		(layer "In4.Cu")
		(net "M_J_CPU0_SA_DQ<24>")
	)
	(gr_poly
		(pts
			(xy 382.844802 -239.422178) (xy 382.844802 -239.377728) (xy 382.64465 -239.377728) (xy 382.64465 -239.422178)
			(xy 382.744726 -239.522254)
		)
		(stroke
			(width 0)
			(type solid)
		)
		(fill yes)
		(layer "In4.Cu")
		(net "M_J_CPU0_SA_DQ<23>")
	)
	(gr_poly
		(pts
			(xy 382.844802 -238.206026) (xy 382.744726 -238.10595) (xy 382.64465 -238.206026) (xy 382.64465 -238.250476)
			(xy 382.844802 -238.250476)
		)
		(stroke
			(width 0)
			(type solid)
		)
		(fill yes)
		(layer "In4.Cu")
		(net "M_J_CPU0_SA_DQ<20>")
	)
	(gr_poly
		(pts
			(xy 382.844802 -237.80242) (xy 382.844802 -237.754668) (xy 382.64465 -237.754668) (xy 382.64465 -237.80242)
			(xy 382.744726 -237.902242)
		)
		(stroke
			(width 0)
			(type solid)
		)
		(fill yes)
		(layer "In4.Cu")
		(net "M_J_CPU0_SA_DQS_DP<7>")
	)
	(gr_poly
		(pts
			(xy 382.844802 -236.58576) (xy 382.744726 -236.485938) (xy 382.64465 -236.58576) (xy 382.64465 -236.633512)
			(xy 382.844802 -236.633512)
		)
		(stroke
			(width 0)
			(type solid)
		)
		(fill yes)
		(layer "In4.Cu")
		(net "M_J_CPU0_SA_DQS_DP<2>")
	)
	(gr_poly
		(pts
			(xy 382.844802 -236.182154) (xy 382.844802 -236.137704) (xy 382.64465 -236.137704) (xy 382.64465 -236.182154)
			(xy 382.744726 -236.28223)
		)
		(stroke
			(width 0)
			(type solid)
		)
		(fill yes)
		(layer "In4.Cu")
		(net "M_J_CPU0_SA_DQ<19>")
	)
	(gr_poly
		(pts
			(xy 382.844802 -234.966002) (xy 382.744726 -234.865926) (xy 382.64465 -234.966002) (xy 382.64465 -235.010452)
			(xy 382.844802 -235.010452)
		)
		(stroke
			(width 0)
			(type solid)
		)
		(fill yes)
		(layer "In4.Cu")
		(net "M_J_CPU0_SA_DQ<16>")
	)
	(gr_poly
		(pts
			(xy 382.844802 -234.562142) (xy 382.844802 -234.517692) (xy 382.64465 -234.517692) (xy 382.64465 -234.562142)
			(xy 382.744726 -234.662218)
		)
		(stroke
			(width 0)
			(type solid)
		)
		(fill yes)
		(layer "In4.Cu")
		(net "M_J_CPU0_SA_DQ<15>")
	)
	(gr_poly
		(pts
			(xy 382.844802 -233.34599) (xy 382.744726 -233.245914) (xy 382.64465 -233.34599) (xy 382.64465 -233.39044)
			(xy 382.844802 -233.39044)
		)
		(stroke
			(width 0)
			(type solid)
		)
		(fill yes)
		(layer "In4.Cu")
		(net "M_J_CPU0_SA_DQ<12>")
	)
	(gr_poly
		(pts
			(xy 382.844802 -232.942384) (xy 382.844802 -232.894632) (xy 382.64465 -232.894632) (xy 382.64465 -232.942384)
			(xy 382.744726 -233.042206)
		)
		(stroke
			(width 0)
			(type solid)
		)
		(fill yes)
		(layer "In4.Cu")
		(net "M_J_CPU0_SA_DQS_DP<6>")
	)
	(gr_poly
		(pts
			(xy 382.844802 -231.725724) (xy 382.744726 -231.625902) (xy 382.64465 -231.725724) (xy 382.64465 -231.773476)
			(xy 382.844802 -231.773476)
		)
		(stroke
			(width 0)
			(type solid)
		)
		(fill yes)
		(layer "In4.Cu")
		(net "M_J_CPU0_SA_DQS_DP<1>")
	)
	(gr_poly
		(pts
			(xy 382.844802 -231.322372) (xy 382.844802 -231.277922) (xy 382.64465 -231.277922) (xy 382.64465 -231.322372)
			(xy 382.744726 -231.422448)
		)
		(stroke
			(width 0)
			(type solid)
		)
		(fill yes)
		(layer "In4.Cu")
		(net "M_J_CPU0_SA_DQ<11>")
	)
	(gr_poly
		(pts
			(xy 382.844802 -230.105966) (xy 382.744726 -230.006144) (xy 382.64465 -230.105966) (xy 382.64465 -230.150416)
			(xy 382.844802 -230.150416)
		)
		(stroke
			(width 0)
			(type solid)
		)
		(fill yes)
		(layer "In4.Cu")
		(net "M_J_CPU0_SA_DQ<8>")
	)
	(gr_poly
		(pts
			(xy 382.844802 -229.70236) (xy 382.844802 -229.65791) (xy 382.64465 -229.65791) (xy 382.64465 -229.70236)
			(xy 382.744726 -229.802436)
		)
		(stroke
			(width 0)
			(type solid)
		)
		(fill yes)
		(layer "In4.Cu")
		(net "M_J_CPU0_SA_DQ<7>")
	)
	(gr_poly
		(pts
			(xy 382.844802 -228.486208) (xy 382.744726 -228.386132) (xy 382.64465 -228.486208) (xy 382.64465 -228.530658)
			(xy 382.844802 -228.530658)
		)
		(stroke
			(width 0)
			(type solid)
		)
		(fill yes)
		(layer "In4.Cu")
		(net "M_J_CPU0_SA_DQ<4>")
	)
	(gr_poly
		(pts
			(xy 382.844802 -228.082602) (xy 382.844802 -228.03485) (xy 382.64465 -228.03485) (xy 382.64465 -228.082602)
			(xy 382.744726 -228.182424)
		)
		(stroke
			(width 0)
			(type solid)
		)
		(fill yes)
		(layer "In4.Cu")
		(net "M_J_CPU0_SA_DQS_DP<5>")
	)
	(gr_poly
		(pts
			(xy 382.844802 -226.865942) (xy 382.744726 -226.76612) (xy 382.64465 -226.865942) (xy 382.64465 -226.913694)
			(xy 382.844802 -226.913694)
		)
		(stroke
			(width 0)
			(type solid)
		)
		(fill yes)
		(layer "In4.Cu")
		(net "M_J_CPU0_SA_DQS_DP<0>")
	)
	(gr_poly
		(pts
			(xy 382.844802 -226.462336) (xy 382.844802 -226.417886) (xy 382.64465 -226.417886) (xy 382.64465 -226.462336)
			(xy 382.744726 -226.562412)
		)
		(stroke
			(width 0)
			(type solid)
		)
		(fill yes)
		(layer "In4.Cu")
		(net "M_J_CPU0_SA_DQ<3>")
	)
	(gr_poly
		(pts
			(xy 382.844802 -225.246184) (xy 382.744726 -225.146108) (xy 382.64465 -225.246184) (xy 382.64465 -225.290634)
			(xy 382.844802 -225.290634)
		)
		(stroke
			(width 0)
			(type solid)
		)
		(fill yes)
		(layer "In4.Cu")
		(net "M_J_CPU0_SA_DQ<0>")
	)
	(gr_poly
		(pts
			(xy 383.144776 -292.91788) (xy 383.0447 -292.817804) (xy 382.944624 -292.91788) (xy 382.944624 -292.96233)
			(xy 383.144776 -292.96233)
		)
		(stroke
			(width 0)
			(type solid)
		)
		(fill yes)
		(layer "In4.Cu")
		(net "M_J_CPU0_SB_DQ<29>")
	)
	(gr_poly
		(pts
			(xy 383.144776 -292.51402) (xy 383.144776 -292.46957) (xy 382.944624 -292.46957) (xy 382.944624 -292.51402)
			(xy 383.0447 -292.614096)
		)
		(stroke
			(width 0)
			(type solid)
		)
		(fill yes)
		(layer "In4.Cu")
		(net "M_J_CPU0_SB_DQ<30>")
	)
	(gr_poly
		(pts
			(xy 383.144776 -291.297614) (xy 383.0447 -291.197792) (xy 382.944624 -291.297614) (xy 382.944624 -291.345366)
			(xy 383.144776 -291.345366)
		)
		(stroke
			(width 0)
			(type solid)
		)
		(fill yes)
		(layer "In4.Cu")
		(net "M_J_CPU0_SB_DQS_DN<8>")
	)
	(gr_poly
		(pts
			(xy 383.144776 -290.894262) (xy 383.144776 -290.84651) (xy 382.944624 -290.84651) (xy 382.944624 -290.894262)
			(xy 383.0447 -290.994084)
		)
		(stroke
			(width 0)
			(type solid)
		)
		(fill yes)
		(layer "In4.Cu")
		(net "M_J_CPU0_SB_DQS_DN<3>")
	)
	(gr_poly
		(pts
			(xy 383.144776 -289.677856) (xy 383.0447 -289.57778) (xy 382.944624 -289.677856) (xy 382.944624 -289.722306)
			(xy 383.144776 -289.722306)
		)
		(stroke
			(width 0)
			(type solid)
		)
		(fill yes)
		(layer "In4.Cu")
		(net "M_J_CPU0_SB_DQ<25>")
	)
	(gr_poly
		(pts
			(xy 383.144776 -289.273996) (xy 383.144776 -289.229546) (xy 382.944624 -289.229546) (xy 382.944624 -289.273996)
			(xy 383.0447 -289.374072)
		)
		(stroke
			(width 0)
			(type solid)
		)
		(fill yes)
		(layer "In4.Cu")
		(net "M_J_CPU0_SB_DQ<26>")
	)
	(gr_poly
		(pts
			(xy 383.144776 -288.057844) (xy 383.0447 -287.957768) (xy 382.944624 -288.057844) (xy 382.944624 -288.102294)
			(xy 383.144776 -288.102294)
		)
		(stroke
			(width 0)
			(type solid)
		)
		(fill yes)
		(layer "In4.Cu")
		(net "M_J_CPU0_SB_DQ<21>")
	)
	(gr_poly
		(pts
			(xy 383.144776 -287.654238) (xy 383.144776 -287.609788) (xy 382.944624 -287.609788) (xy 382.944624 -287.654238)
			(xy 383.0447 -287.75406)
		)
		(stroke
			(width 0)
			(type solid)
		)
		(fill yes)
		(layer "In4.Cu")
		(net "M_J_CPU0_SB_DQ<22>")
	)
	(gr_poly
		(pts
			(xy 383.144776 -286.437832) (xy 383.0447 -286.337756) (xy 382.944624 -286.437832) (xy 382.944624 -286.485584)
			(xy 383.144776 -286.485584)
		)
		(stroke
			(width 0)
			(type solid)
		)
		(fill yes)
		(layer "In4.Cu")
		(net "M_J_CPU0_SB_DQS_DN<7>")
	)
	(gr_poly
		(pts
			(xy 383.144776 -286.03448) (xy 383.144776 -285.986728) (xy 382.944624 -285.986728) (xy 382.944624 -286.03448)
			(xy 383.0447 -286.134302)
		)
		(stroke
			(width 0)
			(type solid)
		)
		(fill yes)
		(layer "In4.Cu")
		(net "M_J_CPU0_SB_DQS_DN<2>")
	)
	(gr_poly
		(pts
			(xy 383.144776 -284.818074) (xy 383.0447 -284.717998) (xy 382.944624 -284.818074) (xy 382.944624 -284.862524)
			(xy 383.144776 -284.862524)
		)
		(stroke
			(width 0)
			(type solid)
		)
		(fill yes)
		(layer "In4.Cu")
		(net "M_J_CPU0_SB_DQ<17>")
	)
	(gr_poly
		(pts
			(xy 383.144776 -284.414214) (xy 383.144776 -284.369764) (xy 382.944624 -284.369764) (xy 382.944624 -284.414214)
			(xy 383.0447 -284.51429)
		)
		(stroke
			(width 0)
			(type solid)
		)
		(fill yes)
		(layer "In4.Cu")
		(net "M_J_CPU0_SB_DQ<18>")
	)
	(gr_poly
		(pts
			(xy 383.144776 -283.198062) (xy 383.0447 -283.097986) (xy 382.944624 -283.198062) (xy 382.944624 -283.242512)
			(xy 383.144776 -283.242512)
		)
		(stroke
			(width 0)
			(type solid)
		)
		(fill yes)
		(layer "In4.Cu")
		(net "M_J_CPU0_SB_DQ<13>")
	)
	(gr_poly
		(pts
			(xy 383.144776 -282.794202) (xy 383.144776 -282.749752) (xy 382.944624 -282.749752) (xy 382.944624 -282.794202)
			(xy 383.0447 -282.894278)
		)
		(stroke
			(width 0)
			(type solid)
		)
		(fill yes)
		(layer "In4.Cu")
		(net "M_J_CPU0_SB_DQ<14>")
	)
	(gr_poly
		(pts
			(xy 383.144776 -281.577796) (xy 383.0447 -281.477974) (xy 382.944624 -281.577796) (xy 382.944624 -281.625548)
			(xy 383.144776 -281.625548)
		)
		(stroke
			(width 0)
			(type solid)
		)
		(fill yes)
		(layer "In4.Cu")
		(net "M_J_CPU0_SB_DQS_DN<6>")
	)
	(gr_poly
		(pts
			(xy 383.144776 -281.174444) (xy 383.144776 -281.126692) (xy 382.944624 -281.126692) (xy 382.944624 -281.174444)
			(xy 383.0447 -281.274266)
		)
		(stroke
			(width 0)
			(type solid)
		)
		(fill yes)
		(layer "In4.Cu")
		(net "M_J_CPU0_SB_DQS_DN<1>")
	)
	(gr_poly
		(pts
			(xy 383.144776 -279.958038) (xy 383.0447 -279.857962) (xy 382.944624 -279.958038) (xy 382.944624 -280.002488)
			(xy 383.144776 -280.002488)
		)
		(stroke
			(width 0)
			(type solid)
		)
		(fill yes)
		(layer "In4.Cu")
		(net "M_J_CPU0_SB_DQ<9>")
	)
	(gr_poly
		(pts
			(xy 383.144776 -279.554178) (xy 383.144776 -279.509728) (xy 382.944624 -279.509728) (xy 382.944624 -279.554178)
			(xy 383.0447 -279.654254)
		)
		(stroke
			(width 0)
			(type solid)
		)
		(fill yes)
		(layer "In4.Cu")
		(net "M_J_CPU0_SB_DQ<10>")
	)
	(gr_poly
		(pts
			(xy 383.144776 -278.338026) (xy 383.0447 -278.23795) (xy 382.944624 -278.338026) (xy 382.944624 -278.382476)
			(xy 383.144776 -278.382476)
		)
		(stroke
			(width 0)
			(type solid)
		)
		(fill yes)
		(layer "In4.Cu")
		(net "M_J_CPU0_SB_DQ<5>")
	)
	(gr_poly
		(pts
			(xy 383.144776 -277.934166) (xy 383.144776 -277.889716) (xy 382.944624 -277.889716) (xy 382.944624 -277.934166)
			(xy 383.0447 -278.034242)
		)
		(stroke
			(width 0)
			(type solid)
		)
		(fill yes)
		(layer "In4.Cu")
		(net "M_J_CPU0_SB_DQ<6>")
	)
	(gr_poly
		(pts
			(xy 383.144776 -276.71776) (xy 383.0447 -276.617938) (xy 382.944624 -276.71776) (xy 382.944624 -276.765512)
			(xy 383.144776 -276.765512)
		)
		(stroke
			(width 0)
			(type solid)
		)
		(fill yes)
		(layer "In4.Cu")
		(net "M_J_CPU0_SB_DQS_DN<5>")
	)
	(gr_poly
		(pts
			(xy 383.144776 -276.314408) (xy 383.144776 -276.266656) (xy 382.944624 -276.266656) (xy 382.944624 -276.314408)
			(xy 383.0447 -276.41423)
		)
		(stroke
			(width 0)
			(type solid)
		)
		(fill yes)
		(layer "In4.Cu")
		(net "M_J_CPU0_SB_DQS_DN<0>")
	)
	(gr_poly
		(pts
			(xy 383.144776 -275.098002) (xy 383.0447 -274.997926) (xy 382.944624 -275.098002) (xy 382.944624 -275.142452)
			(xy 383.144776 -275.142452)
		)
		(stroke
			(width 0)
			(type solid)
		)
		(fill yes)
		(layer "In4.Cu")
		(net "M_J_CPU0_SB_DQ<1>")
	)
	(gr_poly
		(pts
			(xy 383.144776 -274.694142) (xy 383.144776 -274.649692) (xy 382.944624 -274.649692) (xy 382.944624 -274.694142)
			(xy 383.0447 -274.794218)
		)
		(stroke
			(width 0)
			(type solid)
		)
		(fill yes)
		(layer "In4.Cu")
		(net "M_J_CPU0_SB_DQ<2>")
	)
	(gr_poly
		(pts
			(xy 383.144776 -273.47799) (xy 383.0447 -273.377914) (xy 382.944624 -273.47799) (xy 382.944624 -273.52244)
			(xy 383.144776 -273.52244)
		)
		(stroke
			(width 0)
			(type solid)
		)
		(fill yes)
		(layer "In4.Cu")
		(net "M_J_CPU0_SB_CB<1>")
	)
	(gr_poly
		(pts
			(xy 383.144776 -273.07413) (xy 383.144776 -273.02968) (xy 382.944624 -273.02968) (xy 382.944624 -273.07413)
			(xy 383.0447 -273.174206)
		)
		(stroke
			(width 0)
			(type solid)
		)
		(fill yes)
		(layer "In4.Cu")
		(net "M_J_CPU0_SB_CB<2>")
	)
	(gr_poly
		(pts
			(xy 383.144776 -271.857724) (xy 383.0447 -271.757902) (xy 382.944624 -271.857724) (xy 382.944624 -271.905476)
			(xy 383.144776 -271.905476)
		)
		(stroke
			(width 0)
			(type solid)
		)
		(fill yes)
		(layer "In4.Cu")
		(net "M_J_CPU0_SB_DQS_DN<4>")
	)
	(gr_poly
		(pts
			(xy 383.144776 -271.454372) (xy 383.144776 -271.40662) (xy 382.944624 -271.40662) (xy 382.944624 -271.454372)
			(xy 383.0447 -271.554194)
		)
		(stroke
			(width 0)
			(type solid)
		)
		(fill yes)
		(layer "In4.Cu")
		(net "M_J_CPU0_SB_DQS_DN<9>")
	)
	(gr_poly
		(pts
			(xy 383.144776 -270.237966) (xy 383.0447 -270.13789) (xy 382.944624 -270.237966) (xy 382.944624 -270.282416)
			(xy 383.144776 -270.282416)
		)
		(stroke
			(width 0)
			(type solid)
		)
		(fill yes)
		(layer "In4.Cu")
		(net "M_J_CPU0_SB_CB<5>")
	)
	(gr_poly
		(pts
			(xy 383.144776 -269.834106) (xy 383.144776 -269.789656) (xy 382.944624 -269.789656) (xy 382.944624 -269.834106)
			(xy 383.0447 -269.934182)
		)
		(stroke
			(width 0)
			(type solid)
		)
		(fill yes)
		(layer "In4.Cu")
		(net "M_J_CPU0_SB_CB<6>")
	)
	(gr_poly
		(pts
			(xy 383.144776 -266.997942) (xy 383.0447 -266.897866) (xy 382.944624 -266.997942) (xy 382.944624 -267.042392)
			(xy 383.144776 -267.042392)
		)
		(stroke
			(width 0)
			(type solid)
		)
		(fill yes)
		(layer "In4.Cu")
		(net "M_J_CPU0_SA_RSP<0>")
	)
	(gr_poly
		(pts
			(xy 383.144776 -266.594082) (xy 383.144776 -266.549632) (xy 382.944624 -266.549632) (xy 382.944624 -266.594082)
			(xy 383.0447 -266.694158)
		)
		(stroke
			(width 0)
			(type solid)
		)
		(fill yes)
		(layer "In4.Cu")
		(net "M_J_CPU0_SB_CS_N<1>")
	)
	(gr_poly
		(pts
			(xy 383.144776 -265.37793) (xy 383.0447 -265.277854) (xy 382.944624 -265.37793) (xy 382.944624 -265.42238)
			(xy 383.144776 -265.42238)
		)
		(stroke
			(width 0)
			(type solid)
		)
		(fill yes)
		(layer "In4.Cu")
		(net "M_J_CPU0_SB_PAR")
	)
	(gr_poly
		(pts
			(xy 383.144776 -263.757918) (xy 383.0447 -263.657842) (xy 382.944624 -263.757918) (xy 382.944624 -263.802368)
			(xy 383.144776 -263.802368)
		)
		(stroke
			(width 0)
			(type solid)
		)
		(fill yes)
		(layer "In4.Cu")
		(net "M_J_CPU0_SB_CA<4>")
	)
	(gr_poly
		(pts
			(xy 383.144776 -263.354058) (xy 383.144776 -263.309608) (xy 382.944624 -263.309608) (xy 382.944624 -263.354058)
			(xy 383.0447 -263.454134)
		)
		(stroke
			(width 0)
			(type solid)
		)
		(fill yes)
		(layer "In4.Cu")
		(net "M_J_CPU0_SB_CA<3>")
	)
	(gr_poly
		(pts
			(xy 383.144776 -262.137906) (xy 383.0447 -262.03783) (xy 382.944624 -262.137906) (xy 382.944624 -262.182356)
			(xy 383.144776 -262.182356)
		)
		(stroke
			(width 0)
			(type solid)
		)
		(fill yes)
		(layer "In4.Cu")
		(net "M_J_CPU0_SB_CA<0>")
	)
	(gr_poly
		(pts
			(xy 383.314956 -256.432558) (xy 383.314956 -256.384806) (xy 383.114804 -256.384806) (xy 383.114804 -256.432558)
			(xy 383.21488 -256.53238)
		)
		(stroke
			(width 0)
			(type solid)
		)
		(fill yes)
		(layer "In4.Cu")
		(net "M_J_CPU0_CLK_DN<0>")
	)
	(gr_poly
		(pts
			(xy 383.314956 -255.216152) (xy 383.21488 -255.116076) (xy 383.114804 -255.216152) (xy 383.114804 -255.260602)
			(xy 383.314956 -255.260602)
		)
		(stroke
			(width 0)
			(type solid)
		)
		(fill yes)
		(layer "In4.Cu")
		(net "M_J_CPU0_SA_CA<6>")
	)
	(gr_poly
		(pts
			(xy 383.314956 -254.812292) (xy 383.314956 -254.767842) (xy 383.114804 -254.767842) (xy 383.114804 -254.812292)
			(xy 383.21488 -254.912368)
		)
		(stroke
			(width 0)
			(type solid)
		)
		(fill yes)
		(layer "In4.Cu")
		(net "M_J_CPU0_SA_CA<5>")
	)
	(gr_poly
		(pts
			(xy 383.314956 -253.59614) (xy 383.21488 -253.496064) (xy 383.114804 -253.59614) (xy 383.114804 -253.64059)
			(xy 383.314956 -253.64059)
		)
		(stroke
			(width 0)
			(type solid)
		)
		(fill yes)
		(layer "In4.Cu")
		(net "M_J_CPU0_SA_CA<2>")
	)
	(gr_poly
		(pts
			(xy 383.314956 -253.19228) (xy 383.314956 -253.14783) (xy 383.114804 -253.14783) (xy 383.114804 -253.19228)
			(xy 383.21488 -253.292356)
		)
		(stroke
			(width 0)
			(type solid)
		)
		(fill yes)
		(layer "In4.Cu")
		(net "M_J_CPU0_SA_CA<1>")
	)
	(gr_poly
		(pts
			(xy 383.314956 -251.976128) (xy 383.21488 -251.876052) (xy 383.114804 -251.976128) (xy 383.114804 -252.020578)
			(xy 383.314956 -252.020578)
		)
		(stroke
			(width 0)
			(type solid)
		)
		(fill yes)
		(layer "In4.Cu")
		(net "M_J_CPU0_SA_CS_N<1>")
	)
	(gr_poly
		(pts
			(xy 383.314956 -250.356116) (xy 383.21488 -250.25604) (xy 383.114804 -250.356116) (xy 383.114804 -250.400566)
			(xy 383.314956 -250.400566)
		)
		(stroke
			(width 0)
			(type solid)
		)
		(fill yes)
		(layer "In4.Cu")
		(net "M_J_CPU0_ALERT_R_N")
	)
	(gr_poly
		(pts
			(xy 383.314956 -248.736104) (xy 383.21488 -248.636028) (xy 383.114804 -248.736104) (xy 383.114804 -248.780554)
			(xy 383.314956 -248.780554)
		)
		(stroke
			(width 0)
			(type solid)
		)
		(fill yes)
		(layer "In4.Cu")
		(net "M_J_CPU0_SA_CB<5>")
	)
	(gr_poly
		(pts
			(xy 383.314956 -248.332244) (xy 383.314956 -248.287794) (xy 383.114804 -248.287794) (xy 383.114804 -248.332244)
			(xy 383.21488 -248.43232)
		)
		(stroke
			(width 0)
			(type solid)
		)
		(fill yes)
		(layer "In4.Cu")
		(net "M_J_CPU0_SA_CB<6>")
	)
	(gr_poly
		(pts
			(xy 383.314956 -247.115838) (xy 383.21488 -247.016016) (xy 383.114804 -247.115838) (xy 383.114804 -247.16359)
			(xy 383.314956 -247.16359)
		)
		(stroke
			(width 0)
			(type solid)
		)
		(fill yes)
		(layer "In4.Cu")
		(net "M_J_CPU0_SA_DQS_DN<9>")
	)
	(gr_poly
		(pts
			(xy 383.314956 -246.712486) (xy 383.314956 -246.664734) (xy 383.114804 -246.664734) (xy 383.114804 -246.712486)
			(xy 383.21488 -246.812308)
		)
		(stroke
			(width 0)
			(type solid)
		)
		(fill yes)
		(layer "In4.Cu")
		(net "M_J_CPU0_SA_DQS_DN<4>")
	)
	(gr_poly
		(pts
			(xy 383.314956 -245.49608) (xy 383.21488 -245.396004) (xy 383.114804 -245.49608) (xy 383.114804 -245.54053)
			(xy 383.314956 -245.54053)
		)
		(stroke
			(width 0)
			(type solid)
		)
		(fill yes)
		(layer "In4.Cu")
		(net "M_J_CPU0_SA_CB<1>")
	)
	(gr_poly
		(pts
			(xy 383.314956 -245.09222) (xy 383.314956 -245.04777) (xy 383.114804 -245.04777) (xy 383.114804 -245.09222)
			(xy 383.21488 -245.192296)
		)
		(stroke
			(width 0)
			(type solid)
		)
		(fill yes)
		(layer "In4.Cu")
		(net "M_J_CPU0_SA_CB<2>")
	)
	(gr_poly
		(pts
			(xy 383.314956 -243.876068) (xy 383.21488 -243.775992) (xy 383.114804 -243.876068) (xy 383.114804 -243.920518)
			(xy 383.314956 -243.920518)
		)
		(stroke
			(width 0)
			(type solid)
		)
		(fill yes)
		(layer "In4.Cu")
		(net "M_J_CPU0_SA_DQ<29>")
	)
	(gr_poly
		(pts
			(xy 383.314956 -243.472208) (xy 383.314956 -243.427758) (xy 383.114804 -243.427758) (xy 383.114804 -243.472208)
			(xy 383.21488 -243.572284)
		)
		(stroke
			(width 0)
			(type solid)
		)
		(fill yes)
		(layer "In4.Cu")
		(net "M_J_CPU0_SA_DQ<30>")
	)
	(gr_poly
		(pts
			(xy 383.314956 -242.255802) (xy 383.21488 -242.15598) (xy 383.114804 -242.255802) (xy 383.114804 -242.303554)
			(xy 383.314956 -242.303554)
		)
		(stroke
			(width 0)
			(type solid)
		)
		(fill yes)
		(layer "In4.Cu")
		(net "M_J_CPU0_SA_DQS_DN<8>")
	)
	(gr_poly
		(pts
			(xy 383.314956 -241.85245) (xy 383.314956 -241.804698) (xy 383.114804 -241.804698) (xy 383.114804 -241.85245)
			(xy 383.21488 -241.952272)
		)
		(stroke
			(width 0)
			(type solid)
		)
		(fill yes)
		(layer "In4.Cu")
		(net "M_J_CPU0_SA_DQS_DN<3>")
	)
	(gr_poly
		(pts
			(xy 383.314956 -240.636044) (xy 383.21488 -240.535968) (xy 383.114804 -240.636044) (xy 383.114804 -240.680494)
			(xy 383.314956 -240.680494)
		)
		(stroke
			(width 0)
			(type solid)
		)
		(fill yes)
		(layer "In4.Cu")
		(net "M_J_CPU0_SA_DQ<25>")
	)
	(gr_poly
		(pts
			(xy 383.314956 -240.232184) (xy 383.314956 -240.187734) (xy 383.114804 -240.187734) (xy 383.114804 -240.232184)
			(xy 383.21488 -240.33226)
		)
		(stroke
			(width 0)
			(type solid)
		)
		(fill yes)
		(layer "In4.Cu")
		(net "M_J_CPU0_SA_DQ<26>")
	)
	(gr_poly
		(pts
			(xy 383.314956 -239.016032) (xy 383.21488 -238.915956) (xy 383.114804 -239.016032) (xy 383.114804 -239.060482)
			(xy 383.314956 -239.060482)
		)
		(stroke
			(width 0)
			(type solid)
		)
		(fill yes)
		(layer "In4.Cu")
		(net "M_J_CPU0_SA_DQ<21>")
	)
	(gr_poly
		(pts
			(xy 383.314956 -238.612172) (xy 383.314956 -238.567722) (xy 383.114804 -238.567722) (xy 383.114804 -238.612172)
			(xy 383.21488 -238.712248)
		)
		(stroke
			(width 0)
			(type solid)
		)
		(fill yes)
		(layer "In4.Cu")
		(net "M_J_CPU0_SA_DQ<22>")
	)
	(gr_poly
		(pts
			(xy 383.314956 -237.395766) (xy 383.21488 -237.295944) (xy 383.114804 -237.395766) (xy 383.114804 -237.443518)
			(xy 383.314956 -237.443518)
		)
		(stroke
			(width 0)
			(type solid)
		)
		(fill yes)
		(layer "In4.Cu")
		(net "M_J_CPU0_SA_DQS_DN<7>")
	)
	(gr_poly
		(pts
			(xy 383.314956 -236.992414) (xy 383.314956 -236.944662) (xy 383.114804 -236.944662) (xy 383.114804 -236.992414)
			(xy 383.21488 -237.092236)
		)
		(stroke
			(width 0)
			(type solid)
		)
		(fill yes)
		(layer "In4.Cu")
		(net "M_J_CPU0_SA_DQS_DN<2>")
	)
	(gr_poly
		(pts
			(xy 383.314956 -235.776008) (xy 383.21488 -235.675932) (xy 383.114804 -235.776008) (xy 383.114804 -235.820458)
			(xy 383.314956 -235.820458)
		)
		(stroke
			(width 0)
			(type solid)
		)
		(fill yes)
		(layer "In4.Cu")
		(net "M_J_CPU0_SA_DQ<17>")
	)
	(gr_poly
		(pts
			(xy 383.314956 -235.372148) (xy 383.314956 -235.327698) (xy 383.114804 -235.327698) (xy 383.114804 -235.372148)
			(xy 383.21488 -235.472224)
		)
		(stroke
			(width 0)
			(type solid)
		)
		(fill yes)
		(layer "In4.Cu")
		(net "M_J_CPU0_SA_DQ<18>")
	)
	(gr_poly
		(pts
			(xy 383.314956 -234.155996) (xy 383.21488 -234.05592) (xy 383.114804 -234.155996) (xy 383.114804 -234.200446)
			(xy 383.314956 -234.200446)
		)
		(stroke
			(width 0)
			(type solid)
		)
		(fill yes)
		(layer "In4.Cu")
		(net "M_J_CPU0_SA_DQ<13>")
	)
	(gr_poly
		(pts
			(xy 383.314956 -233.752136) (xy 383.314956 -233.707686) (xy 383.114804 -233.707686) (xy 383.114804 -233.752136)
			(xy 383.21488 -233.852212)
		)
		(stroke
			(width 0)
			(type solid)
		)
		(fill yes)
		(layer "In4.Cu")
		(net "M_J_CPU0_SA_DQ<14>")
	)
	(gr_poly
		(pts
			(xy 383.314956 -232.53573) (xy 383.21488 -232.435908) (xy 383.114804 -232.53573) (xy 383.114804 -232.583482)
			(xy 383.314956 -232.583482)
		)
		(stroke
			(width 0)
			(type solid)
		)
		(fill yes)
		(layer "In4.Cu")
		(net "M_J_CPU0_SA_DQS_DN<6>")
	)
	(gr_poly
		(pts
			(xy 383.314956 -232.132378) (xy 383.314956 -232.084626) (xy 383.114804 -232.084626) (xy 383.114804 -232.132378)
			(xy 383.21488 -232.2322)
		)
		(stroke
			(width 0)
			(type solid)
		)
		(fill yes)
		(layer "In4.Cu")
		(net "M_J_CPU0_SA_DQS_DN<1>")
	)
	(gr_poly
		(pts
			(xy 383.314956 -230.915972) (xy 383.21488 -230.815896) (xy 383.114804 -230.915972) (xy 383.114804 -230.960422)
			(xy 383.314956 -230.960422)
		)
		(stroke
			(width 0)
			(type solid)
		)
		(fill yes)
		(layer "In4.Cu")
		(net "M_J_CPU0_SA_DQ<9>")
	)
	(gr_poly
		(pts
			(xy 383.314956 -230.512366) (xy 383.314956 -230.467916) (xy 383.114804 -230.467916) (xy 383.114804 -230.512366)
			(xy 383.21488 -230.612188)
		)
		(stroke
			(width 0)
			(type solid)
		)
		(fill yes)
		(layer "In4.Cu")
		(net "M_J_CPU0_SA_DQ<10>")
	)
	(gr_poly
		(pts
			(xy 383.314956 -229.29596) (xy 383.21488 -229.195884) (xy 383.114804 -229.29596) (xy 383.114804 -229.34041)
			(xy 383.314956 -229.34041)
		)
		(stroke
			(width 0)
			(type solid)
		)
		(fill yes)
		(layer "In4.Cu")
		(net "M_J_CPU0_SA_DQ<5>")
	)
	(gr_poly
		(pts
			(xy 383.314956 -228.892354) (xy 383.314956 -228.847904) (xy 383.114804 -228.847904) (xy 383.114804 -228.892354)
			(xy 383.21488 -228.99243)
		)
		(stroke
			(width 0)
			(type solid)
		)
		(fill yes)
		(layer "In4.Cu")
		(net "M_J_CPU0_SA_DQ<6>")
	)
	(gr_poly
		(pts
			(xy 383.314956 -227.675948) (xy 383.21488 -227.576126) (xy 383.114804 -227.675948) (xy 383.114804 -227.7237)
			(xy 383.314956 -227.7237)
		)
		(stroke
			(width 0)
			(type solid)
		)
		(fill yes)
		(layer "In4.Cu")
		(net "M_J_CPU0_SA_DQS_DN<5>")
	)
	(gr_poly
		(pts
			(xy 383.314956 -227.272596) (xy 383.314956 -227.224844) (xy 383.114804 -227.224844) (xy 383.114804 -227.272596)
			(xy 383.21488 -227.372418)
		)
		(stroke
			(width 0)
			(type solid)
		)
		(fill yes)
		(layer "In4.Cu")
		(net "M_J_CPU0_SA_DQS_DN<0>")
	)
	(gr_poly
		(pts
			(xy 383.314956 -226.05619) (xy 383.21488 -225.956114) (xy 383.114804 -226.05619) (xy 383.114804 -226.10064)
			(xy 383.314956 -226.10064)
		)
		(stroke
			(width 0)
			(type solid)
		)
		(fill yes)
		(layer "In4.Cu")
		(net "M_J_CPU0_SA_DQ<1>")
	)
	(gr_poly
		(pts
			(xy 383.314956 -225.65233) (xy 383.314956 -225.60788) (xy 383.114804 -225.60788) (xy 383.114804 -225.65233)
			(xy 383.21488 -225.752406)
		)
		(stroke
			(width 0)
			(type solid)
		)
		(fill yes)
		(layer "In4.Cu")
		(net "M_J_CPU0_SA_DQ<2>")
	)
	(gr_poly
		(pts
			(xy 383.61493 -293.324026) (xy 383.61493 -293.279576) (xy 383.414778 -293.279576) (xy 383.414778 -293.324026)
			(xy 383.514854 -293.424102)
		)
		(stroke
			(width 0)
			(type solid)
		)
		(fill yes)
		(layer "In4.Cu")
		(net "M_J_CPU0_SB_DQ<31>")
	)
	(gr_poly
		(pts
			(xy 383.61493 -292.107874) (xy 383.514854 -292.007798) (xy 383.414778 -292.107874) (xy 383.414778 -292.152324)
			(xy 383.61493 -292.152324)
		)
		(stroke
			(width 0)
			(type solid)
		)
		(fill yes)
		(layer "In4.Cu")
		(net "M_J_CPU0_SB_DQ<28>")
	)
	(gr_poly
		(pts
			(xy 383.61493 -291.704268) (xy 383.61493 -291.656516) (xy 383.414778 -291.656516) (xy 383.414778 -291.704268)
			(xy 383.514854 -291.80409)
		)
		(stroke
			(width 0)
			(type solid)
		)
		(fill yes)
		(layer "In4.Cu")
		(net "M_J_CPU0_SB_DQS_DP<8>")
	)
	(gr_poly
		(pts
			(xy 383.61493 -290.487608) (xy 383.514854 -290.387786) (xy 383.414778 -290.487608) (xy 383.414778 -290.53536)
			(xy 383.61493 -290.53536)
		)
		(stroke
			(width 0)
			(type solid)
		)
		(fill yes)
		(layer "In4.Cu")
		(net "M_J_CPU0_SB_DQS_DP<3>")
	)
	(gr_poly
		(pts
			(xy 383.61493 -290.084002) (xy 383.61493 -290.039552) (xy 383.414778 -290.039552) (xy 383.414778 -290.084002)
			(xy 383.514854 -290.184078)
		)
		(stroke
			(width 0)
			(type solid)
		)
		(fill yes)
		(layer "In4.Cu")
		(net "M_J_CPU0_SB_DQ<27>")
	)
	(gr_poly
		(pts
			(xy 383.61493 -288.86785) (xy 383.514854 -288.767774) (xy 383.414778 -288.86785) (xy 383.414778 -288.9123)
			(xy 383.61493 -288.9123)
		)
		(stroke
			(width 0)
			(type solid)
		)
		(fill yes)
		(layer "In4.Cu")
		(net "M_J_CPU0_SB_DQ<24>")
	)
	(gr_poly
		(pts
			(xy 383.61493 -288.464244) (xy 383.61493 -288.419794) (xy 383.414778 -288.419794) (xy 383.414778 -288.464244)
			(xy 383.514854 -288.56432)
		)
		(stroke
			(width 0)
			(type solid)
		)
		(fill yes)
		(layer "In4.Cu")
		(net "M_J_CPU0_SB_DQ<23>")
	)
	(gr_poly
		(pts
			(xy 383.61493 -287.247838) (xy 383.514854 -287.148016) (xy 383.414778 -287.247838) (xy 383.414778 -287.292288)
			(xy 383.61493 -287.292288)
		)
		(stroke
			(width 0)
			(type solid)
		)
		(fill yes)
		(layer "In4.Cu")
		(net "M_J_CPU0_SB_DQ<20>")
	)
	(gr_poly
		(pts
			(xy 383.61493 -286.844232) (xy 383.61493 -286.79648) (xy 383.414778 -286.79648) (xy 383.414778 -286.844232)
			(xy 383.514854 -286.944308)
		)
		(stroke
			(width 0)
			(type solid)
		)
		(fill yes)
		(layer "In4.Cu")
		(net "M_J_CPU0_SB_DQS_DP<7>")
	)
	(gr_poly
		(pts
			(xy 383.61493 -285.627826) (xy 383.514854 -285.528004) (xy 383.414778 -285.627826) (xy 383.414778 -285.675578)
			(xy 383.61493 -285.675578)
		)
		(stroke
			(width 0)
			(type solid)
		)
		(fill yes)
		(layer "In4.Cu")
		(net "M_J_CPU0_SB_DQS_DP<2>")
	)
	(gr_poly
		(pts
			(xy 383.61493 -285.22422) (xy 383.61493 -285.17977) (xy 383.414778 -285.17977) (xy 383.414778 -285.22422)
			(xy 383.514854 -285.324296)
		)
		(stroke
			(width 0)
			(type solid)
		)
		(fill yes)
		(layer "In4.Cu")
		(net "M_J_CPU0_SB_DQ<19>")
	)
	(gr_poly
		(pts
			(xy 383.61493 -284.008068) (xy 383.514854 -283.907992) (xy 383.414778 -284.008068) (xy 383.414778 -284.052518)
			(xy 383.61493 -284.052518)
		)
		(stroke
			(width 0)
			(type solid)
		)
		(fill yes)
		(layer "In4.Cu")
		(net "M_J_CPU0_SB_DQ<16>")
	)
	(gr_poly
		(pts
			(xy 383.61493 -283.604208) (xy 383.61493 -283.559758) (xy 383.414778 -283.559758) (xy 383.414778 -283.604208)
			(xy 383.514854 -283.704284)
		)
		(stroke
			(width 0)
			(type solid)
		)
		(fill yes)
		(layer "In4.Cu")
		(net "M_J_CPU0_SB_DQ<15>")
	)
	(gr_poly
		(pts
			(xy 383.61493 -282.388056) (xy 383.514854 -282.28798) (xy 383.414778 -282.388056) (xy 383.414778 -282.432506)
			(xy 383.61493 -282.432506)
		)
		(stroke
			(width 0)
			(type solid)
		)
		(fill yes)
		(layer "In4.Cu")
		(net "M_J_CPU0_SB_DQ<12>")
	)
	(gr_poly
		(pts
			(xy 383.61493 -281.98445) (xy 383.61493 -281.936698) (xy 383.414778 -281.936698) (xy 383.414778 -281.98445)
			(xy 383.514854 -282.084272)
		)
		(stroke
			(width 0)
			(type solid)
		)
		(fill yes)
		(layer "In4.Cu")
		(net "M_J_CPU0_SB_DQS_DP<6>")
	)
	(gr_poly
		(pts
			(xy 383.61493 -280.76779) (xy 383.514854 -280.667968) (xy 383.414778 -280.76779) (xy 383.414778 -280.815542)
			(xy 383.61493 -280.815542)
		)
		(stroke
			(width 0)
			(type solid)
		)
		(fill yes)
		(layer "In4.Cu")
		(net "M_J_CPU0_SB_DQS_DP<1>")
	)
	(gr_poly
		(pts
			(xy 383.61493 -280.364184) (xy 383.61493 -280.319734) (xy 383.414778 -280.319734) (xy 383.414778 -280.364184)
			(xy 383.514854 -280.46426)
		)
		(stroke
			(width 0)
			(type solid)
		)
		(fill yes)
		(layer "In4.Cu")
		(net "M_J_CPU0_SB_DQ<11>")
	)
	(gr_poly
		(pts
			(xy 383.61493 -279.148032) (xy 383.514854 -279.047956) (xy 383.414778 -279.148032) (xy 383.414778 -279.192482)
			(xy 383.61493 -279.192482)
		)
		(stroke
			(width 0)
			(type solid)
		)
		(fill yes)
		(layer "In4.Cu")
		(net "M_J_CPU0_SB_DQ<8>")
	)
	(gr_poly
		(pts
			(xy 383.61493 -278.744172) (xy 383.61493 -278.699722) (xy 383.414778 -278.699722) (xy 383.414778 -278.744172)
			(xy 383.514854 -278.844248)
		)
		(stroke
			(width 0)
			(type solid)
		)
		(fill yes)
		(layer "In4.Cu")
		(net "M_J_CPU0_SB_DQ<7>")
	)
	(gr_poly
		(pts
			(xy 383.61493 -277.52802) (xy 383.514854 -277.427944) (xy 383.414778 -277.52802) (xy 383.414778 -277.57247)
			(xy 383.61493 -277.57247)
		)
		(stroke
			(width 0)
			(type solid)
		)
		(fill yes)
		(layer "In4.Cu")
		(net "M_J_CPU0_SB_DQ<4>")
	)
	(gr_poly
		(pts
			(xy 383.61493 -277.124414) (xy 383.61493 -277.076662) (xy 383.414778 -277.076662) (xy 383.414778 -277.124414)
			(xy 383.514854 -277.224236)
		)
		(stroke
			(width 0)
			(type solid)
		)
		(fill yes)
		(layer "In4.Cu")
		(net "M_J_CPU0_SB_DQS_DP<5>")
	)
	(gr_poly
		(pts
			(xy 383.61493 -275.907754) (xy 383.514854 -275.807932) (xy 383.414778 -275.907754) (xy 383.414778 -275.955506)
			(xy 383.61493 -275.955506)
		)
		(stroke
			(width 0)
			(type solid)
		)
		(fill yes)
		(layer "In4.Cu")
		(net "M_J_CPU0_SB_DQS_DP<0>")
	)
	(gr_poly
		(pts
			(xy 383.61493 -275.504148) (xy 383.61493 -275.459698) (xy 383.414778 -275.459698) (xy 383.414778 -275.504148)
			(xy 383.514854 -275.604224)
		)
		(stroke
			(width 0)
			(type solid)
		)
		(fill yes)
		(layer "In4.Cu")
		(net "M_J_CPU0_SB_DQ<3>")
	)
	(gr_poly
		(pts
			(xy 383.61493 -274.287996) (xy 383.514854 -274.18792) (xy 383.414778 -274.287996) (xy 383.414778 -274.332446)
			(xy 383.61493 -274.332446)
		)
		(stroke
			(width 0)
			(type solid)
		)
		(fill yes)
		(layer "In4.Cu")
		(net "M_J_CPU0_SB_DQ<0>")
	)
	(gr_poly
		(pts
			(xy 383.61493 -273.884136) (xy 383.61493 -273.839686) (xy 383.414778 -273.839686) (xy 383.414778 -273.884136)
			(xy 383.514854 -273.984212)
		)
		(stroke
			(width 0)
			(type solid)
		)
		(fill yes)
		(layer "In4.Cu")
		(net "M_J_CPU0_SB_CB<3>")
	)
	(gr_poly
		(pts
			(xy 383.61493 -272.667984) (xy 383.514854 -272.567908) (xy 383.414778 -272.667984) (xy 383.414778 -272.712434)
			(xy 383.61493 -272.712434)
		)
		(stroke
			(width 0)
			(type solid)
		)
		(fill yes)
		(layer "In4.Cu")
		(net "M_J_CPU0_SB_CB<0>")
	)
	(gr_poly
		(pts
			(xy 383.61493 -272.264378) (xy 383.61493 -272.216626) (xy 383.414778 -272.216626) (xy 383.414778 -272.264378)
			(xy 383.514854 -272.3642)
		)
		(stroke
			(width 0)
			(type solid)
		)
		(fill yes)
		(layer "In4.Cu")
		(net "M_J_CPU0_SB_DQS_DP<4>")
	)
	(gr_poly
		(pts
			(xy 383.61493 -271.047718) (xy 383.514854 -270.947896) (xy 383.414778 -271.047718) (xy 383.414778 -271.09547)
			(xy 383.61493 -271.09547)
		)
		(stroke
			(width 0)
			(type solid)
		)
		(fill yes)
		(layer "In4.Cu")
		(net "M_J_CPU0_SB_DQS_DP<9>")
	)
	(gr_poly
		(pts
			(xy 383.61493 -270.644112) (xy 383.61493 -270.599662) (xy 383.414778 -270.599662) (xy 383.414778 -270.644112)
			(xy 383.514854 -270.744188)
		)
		(stroke
			(width 0)
			(type solid)
		)
		(fill yes)
		(layer "In4.Cu")
		(net "M_J_CPU0_SB_CB<7>")
	)
	(gr_poly
		(pts
			(xy 383.61493 -269.42796) (xy 383.514854 -269.327884) (xy 383.414778 -269.42796) (xy 383.414778 -269.47241)
			(xy 383.61493 -269.47241)
		)
		(stroke
			(width 0)
			(type solid)
		)
		(fill yes)
		(layer "In4.Cu")
		(net "M_J_CPU0_SB_CB<4>")
	)
	(gr_poly
		(pts
			(xy 383.61493 -267.807948) (xy 383.514854 -267.707872) (xy 383.414778 -267.807948) (xy 383.414778 -267.852398)
			(xy 383.61493 -267.852398)
		)
		(stroke
			(width 0)
			(type solid)
		)
		(fill yes)
		(layer "In4.Cu")
		(net "M_J_CPU0_SB_RSP<0>")
	)
	(gr_poly
		(pts
			(xy 383.61493 -265.784076) (xy 383.61493 -265.739626) (xy 383.414778 -265.739626) (xy 383.414778 -265.784076)
			(xy 383.514854 -265.884152)
		)
		(stroke
			(width 0)
			(type solid)
		)
		(fill yes)
		(layer "In4.Cu")
		(net "M_J_CPU0_SB_CS_N<0>")
	)
	(gr_poly
		(pts
			(xy 383.61493 -264.567924) (xy 383.514854 -264.467848) (xy 383.414778 -264.567924) (xy 383.414778 -264.612374)
			(xy 383.61493 -264.612374)
		)
		(stroke
			(width 0)
			(type solid)
		)
		(fill yes)
		(layer "In4.Cu")
		(net "M_J_CPU0_SB_CA<6>")
	)
	(gr_poly
		(pts
			(xy 383.61493 -264.164064) (xy 383.61493 -264.119614) (xy 383.414778 -264.119614) (xy 383.414778 -264.164064)
			(xy 383.514854 -264.26414)
		)
		(stroke
			(width 0)
			(type solid)
		)
		(fill yes)
		(layer "In4.Cu")
		(net "M_J_CPU0_SB_CA<5>")
	)
	(gr_poly
		(pts
			(xy 383.61493 -262.947912) (xy 383.514854 -262.847836) (xy 383.414778 -262.947912) (xy 383.414778 -262.992362)
			(xy 383.61493 -262.992362)
		)
		(stroke
			(width 0)
			(type solid)
		)
		(fill yes)
		(layer "In4.Cu")
		(net "M_J_CPU0_SB_CA<2>")
	)
	(gr_poly
		(pts
			(xy 383.61493 -262.544052) (xy 383.61493 -262.499602) (xy 383.414778 -262.499602) (xy 383.414778 -262.544052)
			(xy 383.514854 -262.644128)
		)
		(stroke
			(width 0)
			(type solid)
		)
		(fill yes)
		(layer "In4.Cu")
		(net "M_J_CPU0_SB_CA<1>")
	)
	(gr_poly
		(pts
			(xy 383.784856 -256.025904) (xy 383.68478 -255.926082) (xy 383.584704 -256.025904) (xy 383.584704 -256.073656)
			(xy 383.784856 -256.073656)
		)
		(stroke
			(width 0)
			(type solid)
		)
		(fill yes)
		(layer "In4.Cu")
		(net "M_J_CPU0_CLK_DP<0>")
	)
	(gr_poly
		(pts
			(xy 383.784856 -255.622298) (xy 383.784856 -255.577848) (xy 383.584704 -255.577848) (xy 383.584704 -255.622298)
			(xy 383.68478 -255.722374)
		)
		(stroke
			(width 0)
			(type solid)
		)
		(fill yes)
		(layer "In4.Cu")
		(net "M_J_CPU0_SA_PAR")
	)
	(gr_poly
		(pts
			(xy 383.784856 -254.406146) (xy 383.68478 -254.30607) (xy 383.584704 -254.406146) (xy 383.584704 -254.450596)
			(xy 383.784856 -254.450596)
		)
		(stroke
			(width 0)
			(type solid)
		)
		(fill yes)
		(layer "In4.Cu")
		(net "M_J_CPU0_SA_CA<4>")
	)
	(gr_poly
		(pts
			(xy 383.784856 -254.002286) (xy 383.784856 -253.957836) (xy 383.584704 -253.957836) (xy 383.584704 -254.002286)
			(xy 383.68478 -254.102362)
		)
		(stroke
			(width 0)
			(type solid)
		)
		(fill yes)
		(layer "In4.Cu")
		(net "M_J_CPU0_SA_CA<3>")
	)
	(gr_poly
		(pts
			(xy 383.784856 -252.786134) (xy 383.68478 -252.686058) (xy 383.584704 -252.786134) (xy 383.584704 -252.830584)
			(xy 383.784856 -252.830584)
		)
		(stroke
			(width 0)
			(type solid)
		)
		(fill yes)
		(layer "In4.Cu")
		(net "M_J_CPU0_SA_CA<0>")
	)
	(gr_poly
		(pts
			(xy 383.784856 -251.166122) (xy 383.68478 -251.066046) (xy 383.584704 -251.166122) (xy 383.584704 -251.210572)
			(xy 383.784856 -251.210572)
		)
		(stroke
			(width 0)
			(type solid)
		)
		(fill yes)
		(layer "In4.Cu")
		(net "M_J_CPU0_SA_CS_N<0>")
	)
	(gr_poly
		(pts
			(xy 383.784856 -250.762262) (xy 383.784856 -250.717812) (xy 383.584704 -250.717812) (xy 383.584704 -250.762262)
			(xy 383.68478 -250.862338)
		)
		(stroke
			(width 0)
			(type solid)
		)
		(fill yes)
		(layer "In4.Cu")
		(net "M_J_CPU0_RESET_N")
	)
	(gr_poly
		(pts
			(xy 383.784856 -249.14225) (xy 383.784856 -249.0978) (xy 383.584704 -249.0978) (xy 383.584704 -249.14225)
			(xy 383.68478 -249.242326)
		)
		(stroke
			(width 0)
			(type solid)
		)
		(fill yes)
		(layer "In4.Cu")
		(net "M_J_CPU0_SA_CB<7>")
	)
	(gr_poly
		(pts
			(xy 383.784856 -247.926098) (xy 383.68478 -247.826022) (xy 383.584704 -247.926098) (xy 383.584704 -247.970548)
			(xy 383.784856 -247.970548)
		)
		(stroke
			(width 0)
			(type solid)
		)
		(fill yes)
		(layer "In4.Cu")
		(net "M_J_CPU0_SA_CB<4>")
	)
	(gr_poly
		(pts
			(xy 383.784856 -247.522492) (xy 383.784856 -247.47474) (xy 383.584704 -247.47474) (xy 383.584704 -247.522492)
			(xy 383.68478 -247.622314)
		)
		(stroke
			(width 0)
			(type solid)
		)
		(fill yes)
		(layer "In4.Cu")
		(net "M_J_CPU0_SA_DQS_DP<9>")
	)
	(gr_poly
		(pts
			(xy 383.784856 -246.305832) (xy 383.68478 -246.20601) (xy 383.584704 -246.305832) (xy 383.584704 -246.353584)
			(xy 383.784856 -246.353584)
		)
		(stroke
			(width 0)
			(type solid)
		)
		(fill yes)
		(layer "In4.Cu")
		(net "M_J_CPU0_SA_DQS_DP<4>")
	)
	(gr_poly
		(pts
			(xy 383.784856 -245.902226) (xy 383.784856 -245.857776) (xy 383.584704 -245.857776) (xy 383.584704 -245.902226)
			(xy 383.68478 -246.002302)
		)
		(stroke
			(width 0)
			(type solid)
		)
		(fill yes)
		(layer "In4.Cu")
		(net "M_J_CPU0_SA_CB<3>")
	)
	(gr_poly
		(pts
			(xy 383.784856 -244.686074) (xy 383.68478 -244.585998) (xy 383.584704 -244.686074) (xy 383.584704 -244.730524)
			(xy 383.784856 -244.730524)
		)
		(stroke
			(width 0)
			(type solid)
		)
		(fill yes)
		(layer "In4.Cu")
		(net "M_J_CPU0_SA_CB<0>")
	)
	(gr_poly
		(pts
			(xy 383.784856 -244.282214) (xy 383.784856 -244.237764) (xy 383.584704 -244.237764) (xy 383.584704 -244.282214)
			(xy 383.68478 -244.38229)
		)
		(stroke
			(width 0)
			(type solid)
		)
		(fill yes)
		(layer "In4.Cu")
		(net "M_J_CPU0_SA_DQ<31>")
	)
	(gr_poly
		(pts
			(xy 383.784856 -243.066062) (xy 383.68478 -242.965986) (xy 383.584704 -243.066062) (xy 383.584704 -243.110512)
			(xy 383.784856 -243.110512)
		)
		(stroke
			(width 0)
			(type solid)
		)
		(fill yes)
		(layer "In4.Cu")
		(net "M_J_CPU0_SA_DQ<28>")
	)
	(gr_poly
		(pts
			(xy 383.784856 -242.662456) (xy 383.784856 -242.614704) (xy 383.584704 -242.614704) (xy 383.584704 -242.662456)
			(xy 383.68478 -242.762278)
		)
		(stroke
			(width 0)
			(type solid)
		)
		(fill yes)
		(layer "In4.Cu")
		(net "M_J_CPU0_SA_DQS_DP<8>")
	)
	(gr_poly
		(pts
			(xy 383.784856 -241.445796) (xy 383.68478 -241.345974) (xy 383.584704 -241.445796) (xy 383.584704 -241.493548)
			(xy 383.784856 -241.493548)
		)
		(stroke
			(width 0)
			(type solid)
		)
		(fill yes)
		(layer "In4.Cu")
		(net "M_J_CPU0_SA_DQS_DP<3>")
	)
	(gr_poly
		(pts
			(xy 383.784856 -241.04219) (xy 383.784856 -240.99774) (xy 383.584704 -240.99774) (xy 383.584704 -241.04219)
			(xy 383.68478 -241.142266)
		)
		(stroke
			(width 0)
			(type solid)
		)
		(fill yes)
		(layer "In4.Cu")
		(net "M_J_CPU0_SA_DQ<27>")
	)
	(gr_poly
		(pts
			(xy 383.784856 -239.826038) (xy 383.68478 -239.725962) (xy 383.584704 -239.826038) (xy 383.584704 -239.870488)
			(xy 383.784856 -239.870488)
		)
		(stroke
			(width 0)
			(type solid)
		)
		(fill yes)
		(layer "In4.Cu")
		(net "M_J_CPU0_SA_DQ<24>")
	)
	(gr_poly
		(pts
			(xy 383.784856 -239.422178) (xy 383.784856 -239.377728) (xy 383.584704 -239.377728) (xy 383.584704 -239.422178)
			(xy 383.68478 -239.522254)
		)
		(stroke
			(width 0)
			(type solid)
		)
		(fill yes)
		(layer "In4.Cu")
		(net "M_J_CPU0_SA_DQ<23>")
	)
	(gr_poly
		(pts
			(xy 383.784856 -238.206026) (xy 383.68478 -238.10595) (xy 383.584704 -238.206026) (xy 383.584704 -238.250476)
			(xy 383.784856 -238.250476)
		)
		(stroke
			(width 0)
			(type solid)
		)
		(fill yes)
		(layer "In4.Cu")
		(net "M_J_CPU0_SA_DQ<20>")
	)
	(gr_poly
		(pts
			(xy 383.784856 -237.80242) (xy 383.784856 -237.754668) (xy 383.584704 -237.754668) (xy 383.584704 -237.80242)
			(xy 383.68478 -237.902242)
		)
		(stroke
			(width 0)
			(type solid)
		)
		(fill yes)
		(layer "In4.Cu")
		(net "M_J_CPU0_SA_DQS_DP<7>")
	)
	(gr_poly
		(pts
			(xy 383.784856 -236.58576) (xy 383.68478 -236.485938) (xy 383.584704 -236.58576) (xy 383.584704 -236.633512)
			(xy 383.784856 -236.633512)
		)
		(stroke
			(width 0)
			(type solid)
		)
		(fill yes)
		(layer "In4.Cu")
		(net "M_J_CPU0_SA_DQS_DP<2>")
	)
	(gr_poly
		(pts
			(xy 383.784856 -236.182154) (xy 383.784856 -236.137704) (xy 383.584704 -236.137704) (xy 383.584704 -236.182154)
			(xy 383.68478 -236.28223)
		)
		(stroke
			(width 0)
			(type solid)
		)
		(fill yes)
		(layer "In4.Cu")
		(net "M_J_CPU0_SA_DQ<19>")
	)
	(gr_poly
		(pts
			(xy 383.784856 -234.966002) (xy 383.68478 -234.865926) (xy 383.584704 -234.966002) (xy 383.584704 -235.010452)
			(xy 383.784856 -235.010452)
		)
		(stroke
			(width 0)
			(type solid)
		)
		(fill yes)
		(layer "In4.Cu")
		(net "M_J_CPU0_SA_DQ<16>")
	)
	(gr_poly
		(pts
			(xy 383.784856 -234.562142) (xy 383.784856 -234.517692) (xy 383.584704 -234.517692) (xy 383.584704 -234.562142)
			(xy 383.68478 -234.662218)
		)
		(stroke
			(width 0)
			(type solid)
		)
		(fill yes)
		(layer "In4.Cu")
		(net "M_J_CPU0_SA_DQ<15>")
	)
	(gr_poly
		(pts
			(xy 383.784856 -233.34599) (xy 383.68478 -233.245914) (xy 383.584704 -233.34599) (xy 383.584704 -233.39044)
			(xy 383.784856 -233.39044)
		)
		(stroke
			(width 0)
			(type solid)
		)
		(fill yes)
		(layer "In4.Cu")
		(net "M_J_CPU0_SA_DQ<12>")
	)
	(gr_poly
		(pts
			(xy 383.784856 -232.942384) (xy 383.784856 -232.894632) (xy 383.584704 -232.894632) (xy 383.584704 -232.942384)
			(xy 383.68478 -233.042206)
		)
		(stroke
			(width 0)
			(type solid)
		)
		(fill yes)
		(layer "In4.Cu")
		(net "M_J_CPU0_SA_DQS_DP<6>")
	)
	(gr_poly
		(pts
			(xy 383.784856 -231.725724) (xy 383.68478 -231.625902) (xy 383.584704 -231.725724) (xy 383.584704 -231.773476)
			(xy 383.784856 -231.773476)
		)
		(stroke
			(width 0)
			(type solid)
		)
		(fill yes)
		(layer "In4.Cu")
		(net "M_J_CPU0_SA_DQS_DP<1>")
	)
	(gr_poly
		(pts
			(xy 383.784856 -231.322372) (xy 383.784856 -231.277922) (xy 383.584704 -231.277922) (xy 383.584704 -231.322372)
			(xy 383.68478 -231.422448)
		)
		(stroke
			(width 0)
			(type solid)
		)
		(fill yes)
		(layer "In4.Cu")
		(net "M_J_CPU0_SA_DQ<11>")
	)
	(gr_poly
		(pts
			(xy 383.784856 -230.105966) (xy 383.68478 -230.006144) (xy 383.584704 -230.105966) (xy 383.584704 -230.150416)
			(xy 383.784856 -230.150416)
		)
		(stroke
			(width 0)
			(type solid)
		)
		(fill yes)
		(layer "In4.Cu")
		(net "M_J_CPU0_SA_DQ<8>")
	)
	(gr_poly
		(pts
			(xy 383.784856 -229.70236) (xy 383.784856 -229.65791) (xy 383.584704 -229.65791) (xy 383.584704 -229.70236)
			(xy 383.68478 -229.802436)
		)
		(stroke
			(width 0)
			(type solid)
		)
		(fill yes)
		(layer "In4.Cu")
		(net "M_J_CPU0_SA_DQ<7>")
	)
	(gr_poly
		(pts
			(xy 383.784856 -228.486208) (xy 383.68478 -228.386132) (xy 383.584704 -228.486208) (xy 383.584704 -228.530658)
			(xy 383.784856 -228.530658)
		)
		(stroke
			(width 0)
			(type solid)
		)
		(fill yes)
		(layer "In4.Cu")
		(net "M_J_CPU0_SA_DQ<4>")
	)
	(gr_poly
		(pts
			(xy 383.784856 -228.082602) (xy 383.784856 -228.03485) (xy 383.584704 -228.03485) (xy 383.584704 -228.082602)
			(xy 383.68478 -228.182424)
		)
		(stroke
			(width 0)
			(type solid)
		)
		(fill yes)
		(layer "In4.Cu")
		(net "M_J_CPU0_SA_DQS_DP<5>")
	)
	(gr_poly
		(pts
			(xy 383.784856 -226.865942) (xy 383.68478 -226.76612) (xy 383.584704 -226.865942) (xy 383.584704 -226.913694)
			(xy 383.784856 -226.913694)
		)
		(stroke
			(width 0)
			(type solid)
		)
		(fill yes)
		(layer "In4.Cu")
		(net "M_J_CPU0_SA_DQS_DP<0>")
	)
	(gr_poly
		(pts
			(xy 383.784856 -226.462336) (xy 383.784856 -226.417886) (xy 383.584704 -226.417886) (xy 383.584704 -226.462336)
			(xy 383.68478 -226.562412)
		)
		(stroke
			(width 0)
			(type solid)
		)
		(fill yes)
		(layer "In4.Cu")
		(net "M_J_CPU0_SA_DQ<3>")
	)
	(gr_poly
		(pts
			(xy 383.784856 -225.246184) (xy 383.68478 -225.146108) (xy 383.584704 -225.246184) (xy 383.584704 -225.290634)
			(xy 383.784856 -225.290634)
		)
		(stroke
			(width 0)
			(type solid)
		)
		(fill yes)
		(layer "In4.Cu")
		(net "M_J_CPU0_SA_DQ<0>")
	)
	(gr_poly
		(pts
			(xy 384.08483 -292.91788) (xy 383.984754 -292.817804) (xy 383.884678 -292.91788) (xy 383.884678 -292.96233)
			(xy 384.08483 -292.96233)
		)
		(stroke
			(width 0)
			(type solid)
		)
		(fill yes)
		(layer "In4.Cu")
		(net "M_J_CPU0_SB_DQ<29>")
	)
	(gr_poly
		(pts
			(xy 384.08483 -292.51402) (xy 384.08483 -292.46957) (xy 383.884678 -292.46957) (xy 383.884678 -292.51402)
			(xy 383.984754 -292.614096)
		)
		(stroke
			(width 0)
			(type solid)
		)
		(fill yes)
		(layer "In4.Cu")
		(net "M_J_CPU0_SB_DQ<30>")
	)
	(gr_poly
		(pts
			(xy 384.08483 -291.297614) (xy 383.984754 -291.197792) (xy 383.884678 -291.297614) (xy 383.884678 -291.345366)
			(xy 384.08483 -291.345366)
		)
		(stroke
			(width 0)
			(type solid)
		)
		(fill yes)
		(layer "In4.Cu")
		(net "M_J_CPU0_SB_DQS_DN<8>")
	)
	(gr_poly
		(pts
			(xy 384.08483 -290.894262) (xy 384.08483 -290.84651) (xy 383.884678 -290.84651) (xy 383.884678 -290.894262)
			(xy 383.984754 -290.994084)
		)
		(stroke
			(width 0)
			(type solid)
		)
		(fill yes)
		(layer "In4.Cu")
		(net "M_J_CPU0_SB_DQS_DN<3>")
	)
	(gr_poly
		(pts
			(xy 384.08483 -289.677856) (xy 383.984754 -289.57778) (xy 383.884678 -289.677856) (xy 383.884678 -289.722306)
			(xy 384.08483 -289.722306)
		)
		(stroke
			(width 0)
			(type solid)
		)
		(fill yes)
		(layer "In4.Cu")
		(net "M_J_CPU0_SB_DQ<25>")
	)
	(gr_poly
		(pts
			(xy 384.08483 -289.273996) (xy 384.08483 -289.229546) (xy 383.884678 -289.229546) (xy 383.884678 -289.273996)
			(xy 383.984754 -289.374072)
		)
		(stroke
			(width 0)
			(type solid)
		)
		(fill yes)
		(layer "In4.Cu")
		(net "M_J_CPU0_SB_DQ<26>")
	)
	(gr_poly
		(pts
			(xy 384.08483 -288.057844) (xy 383.984754 -287.957768) (xy 383.884678 -288.057844) (xy 383.884678 -288.102294)
			(xy 384.08483 -288.102294)
		)
		(stroke
			(width 0)
			(type solid)
		)
		(fill yes)
		(layer "In4.Cu")
		(net "M_J_CPU0_SB_DQ<21>")
	)
	(gr_poly
		(pts
			(xy 384.08483 -287.654238) (xy 384.08483 -287.609788) (xy 383.884678 -287.609788) (xy 383.884678 -287.654238)
			(xy 383.984754 -287.75406)
		)
		(stroke
			(width 0)
			(type solid)
		)
		(fill yes)
		(layer "In4.Cu")
		(net "M_J_CPU0_SB_DQ<22>")
	)
	(gr_poly
		(pts
			(xy 384.08483 -286.437832) (xy 383.984754 -286.337756) (xy 383.884678 -286.437832) (xy 383.884678 -286.485584)
			(xy 384.08483 -286.485584)
		)
		(stroke
			(width 0)
			(type solid)
		)
		(fill yes)
		(layer "In4.Cu")
		(net "M_J_CPU0_SB_DQS_DN<7>")
	)
	(gr_poly
		(pts
			(xy 384.08483 -286.03448) (xy 384.08483 -285.986728) (xy 383.884678 -285.986728) (xy 383.884678 -286.03448)
			(xy 383.984754 -286.134302)
		)
		(stroke
			(width 0)
			(type solid)
		)
		(fill yes)
		(layer "In4.Cu")
		(net "M_J_CPU0_SB_DQS_DN<2>")
	)
	(gr_poly
		(pts
			(xy 384.08483 -284.818074) (xy 383.984754 -284.717998) (xy 383.884678 -284.818074) (xy 383.884678 -284.862524)
			(xy 384.08483 -284.862524)
		)
		(stroke
			(width 0)
			(type solid)
		)
		(fill yes)
		(layer "In4.Cu")
		(net "M_J_CPU0_SB_DQ<17>")
	)
	(gr_poly
		(pts
			(xy 384.08483 -284.414214) (xy 384.08483 -284.369764) (xy 383.884678 -284.369764) (xy 383.884678 -284.414214)
			(xy 383.984754 -284.51429)
		)
		(stroke
			(width 0)
			(type solid)
		)
		(fill yes)
		(layer "In4.Cu")
		(net "M_J_CPU0_SB_DQ<18>")
	)
	(gr_poly
		(pts
			(xy 384.08483 -283.198062) (xy 383.984754 -283.097986) (xy 383.884678 -283.198062) (xy 383.884678 -283.242512)
			(xy 384.08483 -283.242512)
		)
		(stroke
			(width 0)
			(type solid)
		)
		(fill yes)
		(layer "In4.Cu")
		(net "M_J_CPU0_SB_DQ<13>")
	)
	(gr_poly
		(pts
			(xy 384.08483 -282.794202) (xy 384.08483 -282.749752) (xy 383.884678 -282.749752) (xy 383.884678 -282.794202)
			(xy 383.984754 -282.894278)
		)
		(stroke
			(width 0)
			(type solid)
		)
		(fill yes)
		(layer "In4.Cu")
		(net "M_J_CPU0_SB_DQ<14>")
	)
	(gr_poly
		(pts
			(xy 384.08483 -281.577796) (xy 383.984754 -281.477974) (xy 383.884678 -281.577796) (xy 383.884678 -281.625548)
			(xy 384.08483 -281.625548)
		)
		(stroke
			(width 0)
			(type solid)
		)
		(fill yes)
		(layer "In4.Cu")
		(net "M_J_CPU0_SB_DQS_DN<6>")
	)
	(gr_poly
		(pts
			(xy 384.08483 -281.174444) (xy 384.08483 -281.126692) (xy 383.884678 -281.126692) (xy 383.884678 -281.174444)
			(xy 383.984754 -281.274266)
		)
		(stroke
			(width 0)
			(type solid)
		)
		(fill yes)
		(layer "In4.Cu")
		(net "M_J_CPU0_SB_DQS_DN<1>")
	)
	(gr_poly
		(pts
			(xy 384.08483 -279.958038) (xy 383.984754 -279.857962) (xy 383.884678 -279.958038) (xy 383.884678 -280.002488)
			(xy 384.08483 -280.002488)
		)
		(stroke
			(width 0)
			(type solid)
		)
		(fill yes)
		(layer "In4.Cu")
		(net "M_J_CPU0_SB_DQ<9>")
	)
	(gr_poly
		(pts
			(xy 384.08483 -279.554178) (xy 384.08483 -279.509728) (xy 383.884678 -279.509728) (xy 383.884678 -279.554178)
			(xy 383.984754 -279.654254)
		)
		(stroke
			(width 0)
			(type solid)
		)
		(fill yes)
		(layer "In4.Cu")
		(net "M_J_CPU0_SB_DQ<10>")
	)
	(gr_poly
		(pts
			(xy 384.08483 -278.338026) (xy 383.984754 -278.23795) (xy 383.884678 -278.338026) (xy 383.884678 -278.382476)
			(xy 384.08483 -278.382476)
		)
		(stroke
			(width 0)
			(type solid)
		)
		(fill yes)
		(layer "In4.Cu")
		(net "M_J_CPU0_SB_DQ<5>")
	)
	(gr_poly
		(pts
			(xy 384.08483 -277.934166) (xy 384.08483 -277.889716) (xy 383.884678 -277.889716) (xy 383.884678 -277.934166)
			(xy 383.984754 -278.034242)
		)
		(stroke
			(width 0)
			(type solid)
		)
		(fill yes)
		(layer "In4.Cu")
		(net "M_J_CPU0_SB_DQ<6>")
	)
	(gr_poly
		(pts
			(xy 384.08483 -276.71776) (xy 383.984754 -276.617938) (xy 383.884678 -276.71776) (xy 383.884678 -276.765512)
			(xy 384.08483 -276.765512)
		)
		(stroke
			(width 0)
			(type solid)
		)
		(fill yes)
		(layer "In4.Cu")
		(net "M_J_CPU0_SB_DQS_DN<5>")
	)
	(gr_poly
		(pts
			(xy 384.08483 -276.314408) (xy 384.08483 -276.266656) (xy 383.884678 -276.266656) (xy 383.884678 -276.314408)
			(xy 383.984754 -276.41423)
		)
		(stroke
			(width 0)
			(type solid)
		)
		(fill yes)
		(layer "In4.Cu")
		(net "M_J_CPU0_SB_DQS_DN<0>")
	)
	(gr_poly
		(pts
			(xy 384.08483 -275.098002) (xy 383.984754 -274.997926) (xy 383.884678 -275.098002) (xy 383.884678 -275.142452)
			(xy 384.08483 -275.142452)
		)
		(stroke
			(width 0)
			(type solid)
		)
		(fill yes)
		(layer "In4.Cu")
		(net "M_J_CPU0_SB_DQ<1>")
	)
	(gr_poly
		(pts
			(xy 384.08483 -274.694142) (xy 384.08483 -274.649692) (xy 383.884678 -274.649692) (xy 383.884678 -274.694142)
			(xy 383.984754 -274.794218)
		)
		(stroke
			(width 0)
			(type solid)
		)
		(fill yes)
		(layer "In4.Cu")
		(net "M_J_CPU0_SB_DQ<2>")
	)
	(gr_poly
		(pts
			(xy 384.08483 -273.47799) (xy 383.984754 -273.377914) (xy 383.884678 -273.47799) (xy 383.884678 -273.52244)
			(xy 384.08483 -273.52244)
		)
		(stroke
			(width 0)
			(type solid)
		)
		(fill yes)
		(layer "In4.Cu")
		(net "M_J_CPU0_SB_CB<1>")
	)
	(gr_poly
		(pts
			(xy 384.08483 -273.07413) (xy 384.08483 -273.02968) (xy 383.884678 -273.02968) (xy 383.884678 -273.07413)
			(xy 383.984754 -273.174206)
		)
		(stroke
			(width 0)
			(type solid)
		)
		(fill yes)
		(layer "In4.Cu")
		(net "M_J_CPU0_SB_CB<2>")
	)
	(gr_poly
		(pts
			(xy 384.08483 -271.857724) (xy 383.984754 -271.757902) (xy 383.884678 -271.857724) (xy 383.884678 -271.905476)
			(xy 384.08483 -271.905476)
		)
		(stroke
			(width 0)
			(type solid)
		)
		(fill yes)
		(layer "In4.Cu")
		(net "M_J_CPU0_SB_DQS_DN<4>")
	)
	(gr_poly
		(pts
			(xy 384.08483 -271.454372) (xy 384.08483 -271.40662) (xy 383.884678 -271.40662) (xy 383.884678 -271.454372)
			(xy 383.984754 -271.554194)
		)
		(stroke
			(width 0)
			(type solid)
		)
		(fill yes)
		(layer "In4.Cu")
		(net "M_J_CPU0_SB_DQS_DN<9>")
	)
	(gr_poly
		(pts
			(xy 384.08483 -270.237966) (xy 383.984754 -270.13789) (xy 383.884678 -270.237966) (xy 383.884678 -270.282416)
			(xy 384.08483 -270.282416)
		)
		(stroke
			(width 0)
			(type solid)
		)
		(fill yes)
		(layer "In4.Cu")
		(net "M_J_CPU0_SB_CB<5>")
	)
	(gr_poly
		(pts
			(xy 384.08483 -269.834106) (xy 384.08483 -269.789656) (xy 383.884678 -269.789656) (xy 383.884678 -269.834106)
			(xy 383.984754 -269.934182)
		)
		(stroke
			(width 0)
			(type solid)
		)
		(fill yes)
		(layer "In4.Cu")
		(net "M_J_CPU0_SB_CB<6>")
	)
	(gr_poly
		(pts
			(xy 384.08483 -266.997942) (xy 383.984754 -266.897866) (xy 383.884678 -266.997942) (xy 383.884678 -267.042392)
			(xy 384.08483 -267.042392)
		)
		(stroke
			(width 0)
			(type solid)
		)
		(fill yes)
		(layer "In4.Cu")
		(net "M_J_CPU0_SA_RSP<0>")
	)
	(gr_poly
		(pts
			(xy 384.08483 -266.594082) (xy 384.08483 -266.549632) (xy 383.884678 -266.549632) (xy 383.884678 -266.594082)
			(xy 383.984754 -266.694158)
		)
		(stroke
			(width 0)
			(type solid)
		)
		(fill yes)
		(layer "In4.Cu")
		(net "M_J_CPU0_SB_CS_N<1>")
	)
	(gr_poly
		(pts
			(xy 384.08483 -265.37793) (xy 383.984754 -265.277854) (xy 383.884678 -265.37793) (xy 383.884678 -265.42238)
			(xy 384.08483 -265.42238)
		)
		(stroke
			(width 0)
			(type solid)
		)
		(fill yes)
		(layer "In4.Cu")
		(net "M_J_CPU0_SB_PAR")
	)
	(gr_poly
		(pts
			(xy 384.08483 -263.757918) (xy 383.984754 -263.657842) (xy 383.884678 -263.757918) (xy 383.884678 -263.802368)
			(xy 384.08483 -263.802368)
		)
		(stroke
			(width 0)
			(type solid)
		)
		(fill yes)
		(layer "In4.Cu")
		(net "M_J_CPU0_SB_CA<4>")
	)
	(gr_poly
		(pts
			(xy 384.08483 -263.354058) (xy 384.08483 -263.309608) (xy 383.884678 -263.309608) (xy 383.884678 -263.354058)
			(xy 383.984754 -263.454134)
		)
		(stroke
			(width 0)
			(type solid)
		)
		(fill yes)
		(layer "In4.Cu")
		(net "M_J_CPU0_SB_CA<3>")
	)
	(gr_poly
		(pts
			(xy 384.08483 -262.137906) (xy 383.984754 -262.03783) (xy 383.884678 -262.137906) (xy 383.884678 -262.182356)
			(xy 384.08483 -262.182356)
		)
		(stroke
			(width 0)
			(type solid)
		)
		(fill yes)
		(layer "In4.Cu")
		(net "M_J_CPU0_SB_CA<0>")
	)
	(gr_poly
		(pts
			(xy 384.25501 -256.432558) (xy 384.25501 -256.384806) (xy 384.054858 -256.384806) (xy 384.054858 -256.432558)
			(xy 384.154934 -256.53238)
		)
		(stroke
			(width 0)
			(type solid)
		)
		(fill yes)
		(layer "In4.Cu")
		(net "M_J_CPU0_CLK_DN<0>")
	)
	(gr_poly
		(pts
			(xy 384.25501 -255.216152) (xy 384.154934 -255.116076) (xy 384.054858 -255.216152) (xy 384.054858 -255.260602)
			(xy 384.25501 -255.260602)
		)
		(stroke
			(width 0)
			(type solid)
		)
		(fill yes)
		(layer "In4.Cu")
		(net "M_J_CPU0_SA_CA<6>")
	)
	(gr_poly
		(pts
			(xy 384.25501 -254.812292) (xy 384.25501 -254.767842) (xy 384.054858 -254.767842) (xy 384.054858 -254.812292)
			(xy 384.154934 -254.912368)
		)
		(stroke
			(width 0)
			(type solid)
		)
		(fill yes)
		(layer "In4.Cu")
		(net "M_J_CPU0_SA_CA<5>")
	)
	(gr_poly
		(pts
			(xy 384.25501 -253.59614) (xy 384.154934 -253.496064) (xy 384.054858 -253.59614) (xy 384.054858 -253.64059)
			(xy 384.25501 -253.64059)
		)
		(stroke
			(width 0)
			(type solid)
		)
		(fill yes)
		(layer "In4.Cu")
		(net "M_J_CPU0_SA_CA<2>")
	)
	(gr_poly
		(pts
			(xy 384.25501 -253.19228) (xy 384.25501 -253.14783) (xy 384.054858 -253.14783) (xy 384.054858 -253.19228)
			(xy 384.154934 -253.292356)
		)
		(stroke
			(width 0)
			(type solid)
		)
		(fill yes)
		(layer "In4.Cu")
		(net "M_J_CPU0_SA_CA<1>")
	)
	(gr_poly
		(pts
			(xy 384.25501 -251.976128) (xy 384.154934 -251.876052) (xy 384.054858 -251.976128) (xy 384.054858 -252.020578)
			(xy 384.25501 -252.020578)
		)
		(stroke
			(width 0)
			(type solid)
		)
		(fill yes)
		(layer "In4.Cu")
		(net "M_J_CPU0_SA_CS_N<1>")
	)
	(gr_poly
		(pts
			(xy 384.25501 -250.356116) (xy 384.154934 -250.25604) (xy 384.054858 -250.356116) (xy 384.054858 -250.400566)
			(xy 384.25501 -250.400566)
		)
		(stroke
			(width 0)
			(type solid)
		)
		(fill yes)
		(layer "In4.Cu")
		(net "M_J_CPU0_ALERT_R_N")
	)
	(gr_poly
		(pts
			(xy 384.25501 -248.736104) (xy 384.154934 -248.636028) (xy 384.054858 -248.736104) (xy 384.054858 -248.780554)
			(xy 384.25501 -248.780554)
		)
		(stroke
			(width 0)
			(type solid)
		)
		(fill yes)
		(layer "In4.Cu")
		(net "M_J_CPU0_SA_CB<5>")
	)
	(gr_poly
		(pts
			(xy 384.25501 -248.332244) (xy 384.25501 -248.287794) (xy 384.054858 -248.287794) (xy 384.054858 -248.332244)
			(xy 384.154934 -248.43232)
		)
		(stroke
			(width 0)
			(type solid)
		)
		(fill yes)
		(layer "In4.Cu")
		(net "M_J_CPU0_SA_CB<6>")
	)
	(gr_poly
		(pts
			(xy 384.25501 -247.115838) (xy 384.154934 -247.016016) (xy 384.054858 -247.115838) (xy 384.054858 -247.16359)
			(xy 384.25501 -247.16359)
		)
		(stroke
			(width 0)
			(type solid)
		)
		(fill yes)
		(layer "In4.Cu")
		(net "M_J_CPU0_SA_DQS_DN<9>")
	)
	(gr_poly
		(pts
			(xy 384.25501 -246.712486) (xy 384.25501 -246.664734) (xy 384.054858 -246.664734) (xy 384.054858 -246.712486)
			(xy 384.154934 -246.812308)
		)
		(stroke
			(width 0)
			(type solid)
		)
		(fill yes)
		(layer "In4.Cu")
		(net "M_J_CPU0_SA_DQS_DN<4>")
	)
	(gr_poly
		(pts
			(xy 384.25501 -245.49608) (xy 384.154934 -245.396004) (xy 384.054858 -245.49608) (xy 384.054858 -245.54053)
			(xy 384.25501 -245.54053)
		)
		(stroke
			(width 0)
			(type solid)
		)
		(fill yes)
		(layer "In4.Cu")
		(net "M_J_CPU0_SA_CB<1>")
	)
	(gr_poly
		(pts
			(xy 384.25501 -245.09222) (xy 384.25501 -245.04777) (xy 384.054858 -245.04777) (xy 384.054858 -245.09222)
			(xy 384.154934 -245.192296)
		)
		(stroke
			(width 0)
			(type solid)
		)
		(fill yes)
		(layer "In4.Cu")
		(net "M_J_CPU0_SA_CB<2>")
	)
	(gr_poly
		(pts
			(xy 384.25501 -243.876068) (xy 384.154934 -243.775992) (xy 384.054858 -243.876068) (xy 384.054858 -243.920518)
			(xy 384.25501 -243.920518)
		)
		(stroke
			(width 0)
			(type solid)
		)
		(fill yes)
		(layer "In4.Cu")
		(net "M_J_CPU0_SA_DQ<29>")
	)
	(gr_poly
		(pts
			(xy 384.25501 -243.472208) (xy 384.25501 -243.427758) (xy 384.054858 -243.427758) (xy 384.054858 -243.472208)
			(xy 384.154934 -243.572284)
		)
		(stroke
			(width 0)
			(type solid)
		)
		(fill yes)
		(layer "In4.Cu")
		(net "M_J_CPU0_SA_DQ<30>")
	)
	(gr_poly
		(pts
			(xy 384.25501 -242.255802) (xy 384.154934 -242.15598) (xy 384.054858 -242.255802) (xy 384.054858 -242.303554)
			(xy 384.25501 -242.303554)
		)
		(stroke
			(width 0)
			(type solid)
		)
		(fill yes)
		(layer "In4.Cu")
		(net "M_J_CPU0_SA_DQS_DN<8>")
	)
	(gr_poly
		(pts
			(xy 384.25501 -241.85245) (xy 384.25501 -241.804698) (xy 384.054858 -241.804698) (xy 384.054858 -241.85245)
			(xy 384.154934 -241.952272)
		)
		(stroke
			(width 0)
			(type solid)
		)
		(fill yes)
		(layer "In4.Cu")
		(net "M_J_CPU0_SA_DQS_DN<3>")
	)
	(gr_poly
		(pts
			(xy 384.25501 -240.636044) (xy 384.154934 -240.535968) (xy 384.054858 -240.636044) (xy 384.054858 -240.680494)
			(xy 384.25501 -240.680494)
		)
		(stroke
			(width 0)
			(type solid)
		)
		(fill yes)
		(layer "In4.Cu")
		(net "M_J_CPU0_SA_DQ<25>")
	)
	(gr_poly
		(pts
			(xy 384.25501 -240.232184) (xy 384.25501 -240.187734) (xy 384.054858 -240.187734) (xy 384.054858 -240.232184)
			(xy 384.154934 -240.33226)
		)
		(stroke
			(width 0)
			(type solid)
		)
		(fill yes)
		(layer "In4.Cu")
		(net "M_J_CPU0_SA_DQ<26>")
	)
	(gr_poly
		(pts
			(xy 384.25501 -239.016032) (xy 384.154934 -238.915956) (xy 384.054858 -239.016032) (xy 384.054858 -239.060482)
			(xy 384.25501 -239.060482)
		)
		(stroke
			(width 0)
			(type solid)
		)
		(fill yes)
		(layer "In4.Cu")
		(net "M_J_CPU0_SA_DQ<21>")
	)
	(gr_poly
		(pts
			(xy 384.25501 -238.612172) (xy 384.25501 -238.567722) (xy 384.054858 -238.567722) (xy 384.054858 -238.612172)
			(xy 384.154934 -238.712248)
		)
		(stroke
			(width 0)
			(type solid)
		)
		(fill yes)
		(layer "In4.Cu")
		(net "M_J_CPU0_SA_DQ<22>")
	)
	(gr_poly
		(pts
			(xy 384.25501 -237.395766) (xy 384.154934 -237.295944) (xy 384.054858 -237.395766) (xy 384.054858 -237.443518)
			(xy 384.25501 -237.443518)
		)
		(stroke
			(width 0)
			(type solid)
		)
		(fill yes)
		(layer "In4.Cu")
		(net "M_J_CPU0_SA_DQS_DN<7>")
	)
	(gr_poly
		(pts
			(xy 384.25501 -236.992414) (xy 384.25501 -236.944662) (xy 384.054858 -236.944662) (xy 384.054858 -236.992414)
			(xy 384.154934 -237.092236)
		)
		(stroke
			(width 0)
			(type solid)
		)
		(fill yes)
		(layer "In4.Cu")
		(net "M_J_CPU0_SA_DQS_DN<2>")
	)
	(gr_poly
		(pts
			(xy 384.25501 -235.776008) (xy 384.154934 -235.675932) (xy 384.054858 -235.776008) (xy 384.054858 -235.820458)
			(xy 384.25501 -235.820458)
		)
		(stroke
			(width 0)
			(type solid)
		)
		(fill yes)
		(layer "In4.Cu")
		(net "M_J_CPU0_SA_DQ<17>")
	)
	(gr_poly
		(pts
			(xy 384.25501 -235.372148) (xy 384.25501 -235.327698) (xy 384.054858 -235.327698) (xy 384.054858 -235.372148)
			(xy 384.154934 -235.472224)
		)
		(stroke
			(width 0)
			(type solid)
		)
		(fill yes)
		(layer "In4.Cu")
		(net "M_J_CPU0_SA_DQ<18>")
	)
	(gr_poly
		(pts
			(xy 384.25501 -234.155996) (xy 384.154934 -234.05592) (xy 384.054858 -234.155996) (xy 384.054858 -234.200446)
			(xy 384.25501 -234.200446)
		)
		(stroke
			(width 0)
			(type solid)
		)
		(fill yes)
		(layer "In4.Cu")
		(net "M_J_CPU0_SA_DQ<13>")
	)
	(gr_poly
		(pts
			(xy 384.25501 -233.752136) (xy 384.25501 -233.707686) (xy 384.054858 -233.707686) (xy 384.054858 -233.752136)
			(xy 384.154934 -233.852212)
		)
		(stroke
			(width 0)
			(type solid)
		)
		(fill yes)
		(layer "In4.Cu")
		(net "M_J_CPU0_SA_DQ<14>")
	)
	(gr_poly
		(pts
			(xy 384.25501 -232.53573) (xy 384.154934 -232.435908) (xy 384.054858 -232.53573) (xy 384.054858 -232.583482)
			(xy 384.25501 -232.583482)
		)
		(stroke
			(width 0)
			(type solid)
		)
		(fill yes)
		(layer "In4.Cu")
		(net "M_J_CPU0_SA_DQS_DN<6>")
	)
	(gr_poly
		(pts
			(xy 384.25501 -232.132378) (xy 384.25501 -232.084626) (xy 384.054858 -232.084626) (xy 384.054858 -232.132378)
			(xy 384.154934 -232.2322)
		)
		(stroke
			(width 0)
			(type solid)
		)
		(fill yes)
		(layer "In4.Cu")
		(net "M_J_CPU0_SA_DQS_DN<1>")
	)
	(gr_poly
		(pts
			(xy 384.25501 -230.915972) (xy 384.154934 -230.815896) (xy 384.054858 -230.915972) (xy 384.054858 -230.960422)
			(xy 384.25501 -230.960422)
		)
		(stroke
			(width 0)
			(type solid)
		)
		(fill yes)
		(layer "In4.Cu")
		(net "M_J_CPU0_SA_DQ<9>")
	)
	(gr_poly
		(pts
			(xy 384.25501 -230.512366) (xy 384.25501 -230.467916) (xy 384.054858 -230.467916) (xy 384.054858 -230.512366)
			(xy 384.154934 -230.612188)
		)
		(stroke
			(width 0)
			(type solid)
		)
		(fill yes)
		(layer "In4.Cu")
		(net "M_J_CPU0_SA_DQ<10>")
	)
	(gr_poly
		(pts
			(xy 384.25501 -229.29596) (xy 384.154934 -229.195884) (xy 384.054858 -229.29596) (xy 384.054858 -229.34041)
			(xy 384.25501 -229.34041)
		)
		(stroke
			(width 0)
			(type solid)
		)
		(fill yes)
		(layer "In4.Cu")
		(net "M_J_CPU0_SA_DQ<5>")
	)
	(gr_poly
		(pts
			(xy 384.25501 -228.892354) (xy 384.25501 -228.847904) (xy 384.054858 -228.847904) (xy 384.054858 -228.892354)
			(xy 384.154934 -228.99243)
		)
		(stroke
			(width 0)
			(type solid)
		)
		(fill yes)
		(layer "In4.Cu")
		(net "M_J_CPU0_SA_DQ<6>")
	)
	(gr_poly
		(pts
			(xy 384.25501 -227.675948) (xy 384.154934 -227.576126) (xy 384.054858 -227.675948) (xy 384.054858 -227.7237)
			(xy 384.25501 -227.7237)
		)
		(stroke
			(width 0)
			(type solid)
		)
		(fill yes)
		(layer "In4.Cu")
		(net "M_J_CPU0_SA_DQS_DN<5>")
	)
	(gr_poly
		(pts
			(xy 384.25501 -227.272596) (xy 384.25501 -227.224844) (xy 384.054858 -227.224844) (xy 384.054858 -227.272596)
			(xy 384.154934 -227.372418)
		)
		(stroke
			(width 0)
			(type solid)
		)
		(fill yes)
		(layer "In4.Cu")
		(net "M_J_CPU0_SA_DQS_DN<0>")
	)
	(gr_poly
		(pts
			(xy 384.25501 -226.05619) (xy 384.154934 -225.956114) (xy 384.054858 -226.05619) (xy 384.054858 -226.10064)
			(xy 384.25501 -226.10064)
		)
		(stroke
			(width 0)
			(type solid)
		)
		(fill yes)
		(layer "In4.Cu")
		(net "M_J_CPU0_SA_DQ<1>")
	)
	(gr_poly
		(pts
			(xy 384.25501 -225.65233) (xy 384.25501 -225.60788) (xy 384.054858 -225.60788) (xy 384.054858 -225.65233)
			(xy 384.154934 -225.752406)
		)
		(stroke
			(width 0)
			(type solid)
		)
		(fill yes)
		(layer "In4.Cu")
		(net "M_J_CPU0_SA_DQ<2>")
	)
	(gr_poly
		(pts
			(xy 384.554984 -293.324026) (xy 384.554984 -293.279576) (xy 384.354832 -293.279576) (xy 384.354832 -293.324026)
			(xy 384.454908 -293.424102)
		)
		(stroke
			(width 0)
			(type solid)
		)
		(fill yes)
		(layer "In4.Cu")
		(net "M_J_CPU0_SB_DQ<31>")
	)
	(gr_poly
		(pts
			(xy 384.554984 -292.107874) (xy 384.454908 -292.007798) (xy 384.354832 -292.107874) (xy 384.354832 -292.152324)
			(xy 384.554984 -292.152324)
		)
		(stroke
			(width 0)
			(type solid)
		)
		(fill yes)
		(layer "In4.Cu")
		(net "M_J_CPU0_SB_DQ<28>")
	)
	(gr_poly
		(pts
			(xy 384.554984 -291.704268) (xy 384.554984 -291.656516) (xy 384.354832 -291.656516) (xy 384.354832 -291.704268)
			(xy 384.454908 -291.80409)
		)
		(stroke
			(width 0)
			(type solid)
		)
		(fill yes)
		(layer "In4.Cu")
		(net "M_J_CPU0_SB_DQS_DP<8>")
	)
	(gr_poly
		(pts
			(xy 384.554984 -290.487608) (xy 384.454908 -290.387786) (xy 384.354832 -290.487608) (xy 384.354832 -290.53536)
			(xy 384.554984 -290.53536)
		)
		(stroke
			(width 0)
			(type solid)
		)
		(fill yes)
		(layer "In4.Cu")
		(net "M_J_CPU0_SB_DQS_DP<3>")
	)
	(gr_poly
		(pts
			(xy 384.554984 -290.084002) (xy 384.554984 -290.039552) (xy 384.354832 -290.039552) (xy 384.354832 -290.084002)
			(xy 384.454908 -290.184078)
		)
		(stroke
			(width 0)
			(type solid)
		)
		(fill yes)
		(layer "In4.Cu")
		(net "M_J_CPU0_SB_DQ<27>")
	)
	(gr_poly
		(pts
			(xy 384.554984 -288.86785) (xy 384.454908 -288.767774) (xy 384.354832 -288.86785) (xy 384.354832 -288.9123)
			(xy 384.554984 -288.9123)
		)
		(stroke
			(width 0)
			(type solid)
		)
		(fill yes)
		(layer "In4.Cu")
		(net "M_J_CPU0_SB_DQ<24>")
	)
	(gr_poly
		(pts
			(xy 384.554984 -288.464244) (xy 384.554984 -288.419794) (xy 384.354832 -288.419794) (xy 384.354832 -288.464244)
			(xy 384.454908 -288.56432)
		)
		(stroke
			(width 0)
			(type solid)
		)
		(fill yes)
		(layer "In4.Cu")
		(net "M_J_CPU0_SB_DQ<23>")
	)
	(gr_poly
		(pts
			(xy 384.554984 -287.247838) (xy 384.454908 -287.148016) (xy 384.354832 -287.247838) (xy 384.354832 -287.292288)
			(xy 384.554984 -287.292288)
		)
		(stroke
			(width 0)
			(type solid)
		)
		(fill yes)
		(layer "In4.Cu")
		(net "M_J_CPU0_SB_DQ<20>")
	)
	(gr_poly
		(pts
			(xy 384.554984 -286.844232) (xy 384.554984 -286.79648) (xy 384.354832 -286.79648) (xy 384.354832 -286.844232)
			(xy 384.454908 -286.944308)
		)
		(stroke
			(width 0)
			(type solid)
		)
		(fill yes)
		(layer "In4.Cu")
		(net "M_J_CPU0_SB_DQS_DP<7>")
	)
	(gr_poly
		(pts
			(xy 384.554984 -285.627826) (xy 384.454908 -285.528004) (xy 384.354832 -285.627826) (xy 384.354832 -285.675578)
			(xy 384.554984 -285.675578)
		)
		(stroke
			(width 0)
			(type solid)
		)
		(fill yes)
		(layer "In4.Cu")
		(net "M_J_CPU0_SB_DQS_DP<2>")
	)
	(gr_poly
		(pts
			(xy 384.554984 -285.22422) (xy 384.554984 -285.17977) (xy 384.354832 -285.17977) (xy 384.354832 -285.22422)
			(xy 384.454908 -285.324296)
		)
		(stroke
			(width 0)
			(type solid)
		)
		(fill yes)
		(layer "In4.Cu")
		(net "M_J_CPU0_SB_DQ<19>")
	)
	(gr_poly
		(pts
			(xy 384.554984 -284.008068) (xy 384.454908 -283.907992) (xy 384.354832 -284.008068) (xy 384.354832 -284.052518)
			(xy 384.554984 -284.052518)
		)
		(stroke
			(width 0)
			(type solid)
		)
		(fill yes)
		(layer "In4.Cu")
		(net "M_J_CPU0_SB_DQ<16>")
	)
	(gr_poly
		(pts
			(xy 384.554984 -283.604208) (xy 384.554984 -283.559758) (xy 384.354832 -283.559758) (xy 384.354832 -283.604208)
			(xy 384.454908 -283.704284)
		)
		(stroke
			(width 0)
			(type solid)
		)
		(fill yes)
		(layer "In4.Cu")
		(net "M_J_CPU0_SB_DQ<15>")
	)
	(gr_poly
		(pts
			(xy 384.554984 -282.388056) (xy 384.454908 -282.28798) (xy 384.354832 -282.388056) (xy 384.354832 -282.432506)
			(xy 384.554984 -282.432506)
		)
		(stroke
			(width 0)
			(type solid)
		)
		(fill yes)
		(layer "In4.Cu")
		(net "M_J_CPU0_SB_DQ<12>")
	)
	(gr_poly
		(pts
			(xy 384.554984 -281.98445) (xy 384.554984 -281.936698) (xy 384.354832 -281.936698) (xy 384.354832 -281.98445)
			(xy 384.454908 -282.084272)
		)
		(stroke
			(width 0)
			(type solid)
		)
		(fill yes)
		(layer "In4.Cu")
		(net "M_J_CPU0_SB_DQS_DP<6>")
	)
	(gr_poly
		(pts
			(xy 384.554984 -280.76779) (xy 384.454908 -280.667968) (xy 384.354832 -280.76779) (xy 384.354832 -280.815542)
			(xy 384.554984 -280.815542)
		)
		(stroke
			(width 0)
			(type solid)
		)
		(fill yes)
		(layer "In4.Cu")
		(net "M_J_CPU0_SB_DQS_DP<1>")
	)
	(gr_poly
		(pts
			(xy 384.554984 -280.364184) (xy 384.554984 -280.319734) (xy 384.354832 -280.319734) (xy 384.354832 -280.364184)
			(xy 384.454908 -280.46426)
		)
		(stroke
			(width 0)
			(type solid)
		)
		(fill yes)
		(layer "In4.Cu")
		(net "M_J_CPU0_SB_DQ<11>")
	)
	(gr_poly
		(pts
			(xy 384.554984 -279.148032) (xy 384.454908 -279.047956) (xy 384.354832 -279.148032) (xy 384.354832 -279.192482)
			(xy 384.554984 -279.192482)
		)
		(stroke
			(width 0)
			(type solid)
		)
		(fill yes)
		(layer "In4.Cu")
		(net "M_J_CPU0_SB_DQ<8>")
	)
	(gr_poly
		(pts
			(xy 384.554984 -278.744172) (xy 384.554984 -278.699722) (xy 384.354832 -278.699722) (xy 384.354832 -278.744172)
			(xy 384.454908 -278.844248)
		)
		(stroke
			(width 0)
			(type solid)
		)
		(fill yes)
		(layer "In4.Cu")
		(net "M_J_CPU0_SB_DQ<7>")
	)
	(gr_poly
		(pts
			(xy 384.554984 -277.52802) (xy 384.454908 -277.427944) (xy 384.354832 -277.52802) (xy 384.354832 -277.57247)
			(xy 384.554984 -277.57247)
		)
		(stroke
			(width 0)
			(type solid)
		)
		(fill yes)
		(layer "In4.Cu")
		(net "M_J_CPU0_SB_DQ<4>")
	)
	(gr_poly
		(pts
			(xy 384.554984 -277.124414) (xy 384.554984 -277.076662) (xy 384.354832 -277.076662) (xy 384.354832 -277.124414)
			(xy 384.454908 -277.224236)
		)
		(stroke
			(width 0)
			(type solid)
		)
		(fill yes)
		(layer "In4.Cu")
		(net "M_J_CPU0_SB_DQS_DP<5>")
	)
	(gr_poly
		(pts
			(xy 384.554984 -275.907754) (xy 384.454908 -275.807932) (xy 384.354832 -275.907754) (xy 384.354832 -275.955506)
			(xy 384.554984 -275.955506)
		)
		(stroke
			(width 0)
			(type solid)
		)
		(fill yes)
		(layer "In4.Cu")
		(net "M_J_CPU0_SB_DQS_DP<0>")
	)
	(gr_poly
		(pts
			(xy 384.554984 -275.504148) (xy 384.554984 -275.459698) (xy 384.354832 -275.459698) (xy 384.354832 -275.504148)
			(xy 384.454908 -275.604224)
		)
		(stroke
			(width 0)
			(type solid)
		)
		(fill yes)
		(layer "In4.Cu")
		(net "M_J_CPU0_SB_DQ<3>")
	)
	(gr_poly
		(pts
			(xy 384.554984 -274.287996) (xy 384.454908 -274.18792) (xy 384.354832 -274.287996) (xy 384.354832 -274.332446)
			(xy 384.554984 -274.332446)
		)
		(stroke
			(width 0)
			(type solid)
		)
		(fill yes)
		(layer "In4.Cu")
		(net "M_J_CPU0_SB_DQ<0>")
	)
	(gr_poly
		(pts
			(xy 384.554984 -273.884136) (xy 384.554984 -273.839686) (xy 384.354832 -273.839686) (xy 384.354832 -273.884136)
			(xy 384.454908 -273.984212)
		)
		(stroke
			(width 0)
			(type solid)
		)
		(fill yes)
		(layer "In4.Cu")
		(net "M_J_CPU0_SB_CB<3>")
	)
	(gr_poly
		(pts
			(xy 384.554984 -272.667984) (xy 384.454908 -272.567908) (xy 384.354832 -272.667984) (xy 384.354832 -272.712434)
			(xy 384.554984 -272.712434)
		)
		(stroke
			(width 0)
			(type solid)
		)
		(fill yes)
		(layer "In4.Cu")
		(net "M_J_CPU0_SB_CB<0>")
	)
	(gr_poly
		(pts
			(xy 384.554984 -272.264378) (xy 384.554984 -272.216626) (xy 384.354832 -272.216626) (xy 384.354832 -272.264378)
			(xy 384.454908 -272.3642)
		)
		(stroke
			(width 0)
			(type solid)
		)
		(fill yes)
		(layer "In4.Cu")
		(net "M_J_CPU0_SB_DQS_DP<4>")
	)
	(gr_poly
		(pts
			(xy 384.554984 -271.047718) (xy 384.454908 -270.947896) (xy 384.354832 -271.047718) (xy 384.354832 -271.09547)
			(xy 384.554984 -271.09547)
		)
		(stroke
			(width 0)
			(type solid)
		)
		(fill yes)
		(layer "In4.Cu")
		(net "M_J_CPU0_SB_DQS_DP<9>")
	)
	(gr_poly
		(pts
			(xy 384.554984 -270.644112) (xy 384.554984 -270.599662) (xy 384.354832 -270.599662) (xy 384.354832 -270.644112)
			(xy 384.454908 -270.744188)
		)
		(stroke
			(width 0)
			(type solid)
		)
		(fill yes)
		(layer "In4.Cu")
		(net "M_J_CPU0_SB_CB<7>")
	)
	(gr_poly
		(pts
			(xy 384.554984 -269.42796) (xy 384.454908 -269.327884) (xy 384.354832 -269.42796) (xy 384.354832 -269.47241)
			(xy 384.554984 -269.47241)
		)
		(stroke
			(width 0)
			(type solid)
		)
		(fill yes)
		(layer "In4.Cu")
		(net "M_J_CPU0_SB_CB<4>")
	)
	(gr_poly
		(pts
			(xy 384.554984 -267.807948) (xy 384.454908 -267.707872) (xy 384.354832 -267.807948) (xy 384.354832 -267.852398)
			(xy 384.554984 -267.852398)
		)
		(stroke
			(width 0)
			(type solid)
		)
		(fill yes)
		(layer "In4.Cu")
		(net "M_J_CPU0_SB_RSP<0>")
	)
	(gr_poly
		(pts
			(xy 384.554984 -265.784076) (xy 384.554984 -265.739626) (xy 384.354832 -265.739626) (xy 384.354832 -265.784076)
			(xy 384.454908 -265.884152)
		)
		(stroke
			(width 0)
			(type solid)
		)
		(fill yes)
		(layer "In4.Cu")
		(net "M_J_CPU0_SB_CS_N<0>")
	)
	(gr_poly
		(pts
			(xy 384.554984 -264.567924) (xy 384.454908 -264.467848) (xy 384.354832 -264.567924) (xy 384.354832 -264.612374)
			(xy 384.554984 -264.612374)
		)
		(stroke
			(width 0)
			(type solid)
		)
		(fill yes)
		(layer "In4.Cu")
		(net "M_J_CPU0_SB_CA<6>")
	)
	(gr_poly
		(pts
			(xy 384.554984 -264.164064) (xy 384.554984 -264.119614) (xy 384.354832 -264.119614) (xy 384.354832 -264.164064)
			(xy 384.454908 -264.26414)
		)
		(stroke
			(width 0)
			(type solid)
		)
		(fill yes)
		(layer "In4.Cu")
		(net "M_J_CPU0_SB_CA<5>")
	)
	(gr_poly
		(pts
			(xy 384.554984 -262.947912) (xy 384.454908 -262.847836) (xy 384.354832 -262.947912) (xy 384.354832 -262.992362)
			(xy 384.554984 -262.992362)
		)
		(stroke
			(width 0)
			(type solid)
		)
		(fill yes)
		(layer "In4.Cu")
		(net "M_J_CPU0_SB_CA<2>")
	)
	(gr_poly
		(pts
			(xy 384.554984 -262.544052) (xy 384.554984 -262.499602) (xy 384.354832 -262.499602) (xy 384.354832 -262.544052)
			(xy 384.454908 -262.644128)
		)
		(stroke
			(width 0)
			(type solid)
		)
		(fill yes)
		(layer "In4.Cu")
		(net "M_J_CPU0_SB_CA<1>")
	)
	(gr_poly
		(pts
			(xy 384.72491 -256.025904) (xy 384.624834 -255.926082) (xy 384.524758 -256.025904) (xy 384.524758 -256.073656)
			(xy 384.72491 -256.073656)
		)
		(stroke
			(width 0)
			(type solid)
		)
		(fill yes)
		(layer "In4.Cu")
		(net "M_J_CPU0_CLK_DP<0>")
	)
	(gr_poly
		(pts
			(xy 384.72491 -255.622298) (xy 384.72491 -255.577848) (xy 384.524758 -255.577848) (xy 384.524758 -255.622298)
			(xy 384.624834 -255.722374)
		)
		(stroke
			(width 0)
			(type solid)
		)
		(fill yes)
		(layer "In4.Cu")
		(net "M_J_CPU0_SA_PAR")
	)
	(gr_poly
		(pts
			(xy 384.72491 -254.406146) (xy 384.624834 -254.30607) (xy 384.524758 -254.406146) (xy 384.524758 -254.450596)
			(xy 384.72491 -254.450596)
		)
		(stroke
			(width 0)
			(type solid)
		)
		(fill yes)
		(layer "In4.Cu")
		(net "M_J_CPU0_SA_CA<4>")
	)
	(gr_poly
		(pts
			(xy 384.72491 -254.002286) (xy 384.72491 -253.957836) (xy 384.524758 -253.957836) (xy 384.524758 -254.002286)
			(xy 384.624834 -254.102362)
		)
		(stroke
			(width 0)
			(type solid)
		)
		(fill yes)
		(layer "In4.Cu")
		(net "M_J_CPU0_SA_CA<3>")
	)
	(gr_poly
		(pts
			(xy 384.72491 -252.786134) (xy 384.624834 -252.686058) (xy 384.524758 -252.786134) (xy 384.524758 -252.830584)
			(xy 384.72491 -252.830584)
		)
		(stroke
			(width 0)
			(type solid)
		)
		(fill yes)
		(layer "In4.Cu")
		(net "M_J_CPU0_SA_CA<0>")
	)
	(gr_poly
		(pts
			(xy 384.72491 -251.166122) (xy 384.624834 -251.066046) (xy 384.524758 -251.166122) (xy 384.524758 -251.210572)
			(xy 384.72491 -251.210572)
		)
		(stroke
			(width 0)
			(type solid)
		)
		(fill yes)
		(layer "In4.Cu")
		(net "M_J_CPU0_SA_CS_N<0>")
	)
	(gr_poly
		(pts
			(xy 384.72491 -250.762262) (xy 384.72491 -250.717812) (xy 384.524758 -250.717812) (xy 384.524758 -250.762262)
			(xy 384.624834 -250.862338)
		)
		(stroke
			(width 0)
			(type solid)
		)
		(fill yes)
		(layer "In4.Cu")
		(net "M_J_CPU0_RESET_N")
	)
	(gr_poly
		(pts
			(xy 384.72491 -249.14225) (xy 384.72491 -249.0978) (xy 384.524758 -249.0978) (xy 384.524758 -249.14225)
			(xy 384.624834 -249.242326)
		)
		(stroke
			(width 0)
			(type solid)
		)
		(fill yes)
		(layer "In4.Cu")
		(net "M_J_CPU0_SA_CB<7>")
	)
	(gr_poly
		(pts
			(xy 384.72491 -247.926098) (xy 384.624834 -247.826022) (xy 384.524758 -247.926098) (xy 384.524758 -247.970548)
			(xy 384.72491 -247.970548)
		)
		(stroke
			(width 0)
			(type solid)
		)
		(fill yes)
		(layer "In4.Cu")
		(net "M_J_CPU0_SA_CB<4>")
	)
	(gr_poly
		(pts
			(xy 384.72491 -247.522492) (xy 384.72491 -247.47474) (xy 384.524758 -247.47474) (xy 384.524758 -247.522492)
			(xy 384.624834 -247.622314)
		)
		(stroke
			(width 0)
			(type solid)
		)
		(fill yes)
		(layer "In4.Cu")
		(net "M_J_CPU0_SA_DQS_DP<9>")
	)
	(gr_poly
		(pts
			(xy 384.72491 -246.305832) (xy 384.624834 -246.20601) (xy 384.524758 -246.305832) (xy 384.524758 -246.353584)
			(xy 384.72491 -246.353584)
		)
		(stroke
			(width 0)
			(type solid)
		)
		(fill yes)
		(layer "In4.Cu")
		(net "M_J_CPU0_SA_DQS_DP<4>")
	)
	(gr_poly
		(pts
			(xy 384.72491 -245.902226) (xy 384.72491 -245.857776) (xy 384.524758 -245.857776) (xy 384.524758 -245.902226)
			(xy 384.624834 -246.002302)
		)
		(stroke
			(width 0)
			(type solid)
		)
		(fill yes)
		(layer "In4.Cu")
		(net "M_J_CPU0_SA_CB<3>")
	)
	(gr_poly
		(pts
			(xy 384.72491 -244.686074) (xy 384.624834 -244.585998) (xy 384.524758 -244.686074) (xy 384.524758 -244.730524)
			(xy 384.72491 -244.730524)
		)
		(stroke
			(width 0)
			(type solid)
		)
		(fill yes)
		(layer "In4.Cu")
		(net "M_J_CPU0_SA_CB<0>")
	)
	(gr_poly
		(pts
			(xy 384.72491 -244.282214) (xy 384.72491 -244.237764) (xy 384.524758 -244.237764) (xy 384.524758 -244.282214)
			(xy 384.624834 -244.38229)
		)
		(stroke
			(width 0)
			(type solid)
		)
		(fill yes)
		(layer "In4.Cu")
		(net "M_J_CPU0_SA_DQ<31>")
	)
	(gr_poly
		(pts
			(xy 384.72491 -243.066062) (xy 384.624834 -242.965986) (xy 384.524758 -243.066062) (xy 384.524758 -243.110512)
			(xy 384.72491 -243.110512)
		)
		(stroke
			(width 0)
			(type solid)
		)
		(fill yes)
		(layer "In4.Cu")
		(net "M_J_CPU0_SA_DQ<28>")
	)
	(gr_poly
		(pts
			(xy 384.72491 -242.662456) (xy 384.72491 -242.614704) (xy 384.524758 -242.614704) (xy 384.524758 -242.662456)
			(xy 384.624834 -242.762278)
		)
		(stroke
			(width 0)
			(type solid)
		)
		(fill yes)
		(layer "In4.Cu")
		(net "M_J_CPU0_SA_DQS_DP<8>")
	)
	(gr_poly
		(pts
			(xy 384.72491 -241.445796) (xy 384.624834 -241.345974) (xy 384.524758 -241.445796) (xy 384.524758 -241.493548)
			(xy 384.72491 -241.493548)
		)
		(stroke
			(width 0)
			(type solid)
		)
		(fill yes)
		(layer "In4.Cu")
		(net "M_J_CPU0_SA_DQS_DP<3>")
	)
	(gr_poly
		(pts
			(xy 384.72491 -241.04219) (xy 384.72491 -240.99774) (xy 384.524758 -240.99774) (xy 384.524758 -241.04219)
			(xy 384.624834 -241.142266)
		)
		(stroke
			(width 0)
			(type solid)
		)
		(fill yes)
		(layer "In4.Cu")
		(net "M_J_CPU0_SA_DQ<27>")
	)
	(gr_poly
		(pts
			(xy 384.72491 -239.826038) (xy 384.624834 -239.725962) (xy 384.524758 -239.826038) (xy 384.524758 -239.870488)
			(xy 384.72491 -239.870488)
		)
		(stroke
			(width 0)
			(type solid)
		)
		(fill yes)
		(layer "In4.Cu")
		(net "M_J_CPU0_SA_DQ<24>")
	)
	(gr_poly
		(pts
			(xy 384.72491 -239.422178) (xy 384.72491 -239.377728) (xy 384.524758 -239.377728) (xy 384.524758 -239.422178)
			(xy 384.624834 -239.522254)
		)
		(stroke
			(width 0)
			(type solid)
		)
		(fill yes)
		(layer "In4.Cu")
		(net "M_J_CPU0_SA_DQ<23>")
	)
	(gr_poly
		(pts
			(xy 384.72491 -238.206026) (xy 384.624834 -238.10595) (xy 384.524758 -238.206026) (xy 384.524758 -238.250476)
			(xy 384.72491 -238.250476)
		)
		(stroke
			(width 0)
			(type solid)
		)
		(fill yes)
		(layer "In4.Cu")
		(net "M_J_CPU0_SA_DQ<20>")
	)
	(gr_poly
		(pts
			(xy 384.72491 -237.80242) (xy 384.72491 -237.754668) (xy 384.524758 -237.754668) (xy 384.524758 -237.80242)
			(xy 384.624834 -237.902242)
		)
		(stroke
			(width 0)
			(type solid)
		)
		(fill yes)
		(layer "In4.Cu")
		(net "M_J_CPU0_SA_DQS_DP<7>")
	)
	(gr_poly
		(pts
			(xy 384.72491 -236.58576) (xy 384.624834 -236.485938) (xy 384.524758 -236.58576) (xy 384.524758 -236.633512)
			(xy 384.72491 -236.633512)
		)
		(stroke
			(width 0)
			(type solid)
		)
		(fill yes)
		(layer "In4.Cu")
		(net "M_J_CPU0_SA_DQS_DP<2>")
	)
	(gr_poly
		(pts
			(xy 384.72491 -236.182154) (xy 384.72491 -236.137704) (xy 384.524758 -236.137704) (xy 384.524758 -236.182154)
			(xy 384.624834 -236.28223)
		)
		(stroke
			(width 0)
			(type solid)
		)
		(fill yes)
		(layer "In4.Cu")
		(net "M_J_CPU0_SA_DQ<19>")
	)
	(gr_poly
		(pts
			(xy 384.72491 -234.966002) (xy 384.624834 -234.865926) (xy 384.524758 -234.966002) (xy 384.524758 -235.010452)
			(xy 384.72491 -235.010452)
		)
		(stroke
			(width 0)
			(type solid)
		)
		(fill yes)
		(layer "In4.Cu")
		(net "M_J_CPU0_SA_DQ<16>")
	)
	(gr_poly
		(pts
			(xy 384.72491 -234.562142) (xy 384.72491 -234.517692) (xy 384.524758 -234.517692) (xy 384.524758 -234.562142)
			(xy 384.624834 -234.662218)
		)
		(stroke
			(width 0)
			(type solid)
		)
		(fill yes)
		(layer "In4.Cu")
		(net "M_J_CPU0_SA_DQ<15>")
	)
	(gr_poly
		(pts
			(xy 384.72491 -233.34599) (xy 384.624834 -233.245914) (xy 384.524758 -233.34599) (xy 384.524758 -233.39044)
			(xy 384.72491 -233.39044)
		)
		(stroke
			(width 0)
			(type solid)
		)
		(fill yes)
		(layer "In4.Cu")
		(net "M_J_CPU0_SA_DQ<12>")
	)
	(gr_poly
		(pts
			(xy 384.72491 -232.942384) (xy 384.72491 -232.894632) (xy 384.524758 -232.894632) (xy 384.524758 -232.942384)
			(xy 384.624834 -233.042206)
		)
		(stroke
			(width 0)
			(type solid)
		)
		(fill yes)
		(layer "In4.Cu")
		(net "M_J_CPU0_SA_DQS_DP<6>")
	)
	(gr_poly
		(pts
			(xy 384.72491 -231.725724) (xy 384.624834 -231.625902) (xy 384.524758 -231.725724) (xy 384.524758 -231.773476)
			(xy 384.72491 -231.773476)
		)
		(stroke
			(width 0)
			(type solid)
		)
		(fill yes)
		(layer "In4.Cu")
		(net "M_J_CPU0_SA_DQS_DP<1>")
	)
	(gr_poly
		(pts
			(xy 384.72491 -231.322372) (xy 384.72491 -231.277922) (xy 384.524758 -231.277922) (xy 384.524758 -231.322372)
			(xy 384.624834 -231.422448)
		)
		(stroke
			(width 0)
			(type solid)
		)
		(fill yes)
		(layer "In4.Cu")
		(net "M_J_CPU0_SA_DQ<11>")
	)
	(gr_poly
		(pts
			(xy 384.72491 -230.105966) (xy 384.624834 -230.006144) (xy 384.524758 -230.105966) (xy 384.524758 -230.150416)
			(xy 384.72491 -230.150416)
		)
		(stroke
			(width 0)
			(type solid)
		)
		(fill yes)
		(layer "In4.Cu")
		(net "M_J_CPU0_SA_DQ<8>")
	)
	(gr_poly
		(pts
			(xy 384.72491 -229.70236) (xy 384.72491 -229.65791) (xy 384.524758 -229.65791) (xy 384.524758 -229.70236)
			(xy 384.624834 -229.802436)
		)
		(stroke
			(width 0)
			(type solid)
		)
		(fill yes)
		(layer "In4.Cu")
		(net "M_J_CPU0_SA_DQ<7>")
	)
	(gr_poly
		(pts
			(xy 384.72491 -228.486208) (xy 384.624834 -228.386132) (xy 384.524758 -228.486208) (xy 384.524758 -228.530658)
			(xy 384.72491 -228.530658)
		)
		(stroke
			(width 0)
			(type solid)
		)
		(fill yes)
		(layer "In4.Cu")
		(net "M_J_CPU0_SA_DQ<4>")
	)
	(gr_poly
		(pts
			(xy 384.72491 -228.082602) (xy 384.72491 -228.03485) (xy 384.524758 -228.03485) (xy 384.524758 -228.082602)
			(xy 384.624834 -228.182424)
		)
		(stroke
			(width 0)
			(type solid)
		)
		(fill yes)
		(layer "In4.Cu")
		(net "M_J_CPU0_SA_DQS_DP<5>")
	)
	(gr_poly
		(pts
			(xy 384.72491 -226.865942) (xy 384.624834 -226.76612) (xy 384.524758 -226.865942) (xy 384.524758 -226.913694)
			(xy 384.72491 -226.913694)
		)
		(stroke
			(width 0)
			(type solid)
		)
		(fill yes)
		(layer "In4.Cu")
		(net "M_J_CPU0_SA_DQS_DP<0>")
	)
	(gr_poly
		(pts
			(xy 384.72491 -226.462336) (xy 384.72491 -226.417886) (xy 384.524758 -226.417886) (xy 384.524758 -226.462336)
			(xy 384.624834 -226.562412)
		)
		(stroke
			(width 0)
			(type solid)
		)
		(fill yes)
		(layer "In4.Cu")
		(net "M_J_CPU0_SA_DQ<3>")
	)
	(gr_poly
		(pts
			(xy 384.72491 -225.246184) (xy 384.624834 -225.146108) (xy 384.524758 -225.246184) (xy 384.524758 -225.290634)
			(xy 384.72491 -225.290634)
		)
		(stroke
			(width 0)
			(type solid)
		)
		(fill yes)
		(layer "In4.Cu")
		(net "M_J_CPU0_SA_DQ<0>")
	)
	(gr_poly
		(pts
			(xy 385.024884 -292.91788) (xy 384.924808 -292.817804) (xy 384.824732 -292.91788) (xy 384.824732 -292.96233)
			(xy 385.024884 -292.96233)
		)
		(stroke
			(width 0)
			(type solid)
		)
		(fill yes)
		(layer "In4.Cu")
		(net "M_J_CPU0_SB_DQ<29>")
	)
	(gr_poly
		(pts
			(xy 385.024884 -292.51402) (xy 385.024884 -292.46957) (xy 384.824732 -292.46957) (xy 384.824732 -292.51402)
			(xy 384.924808 -292.614096)
		)
		(stroke
			(width 0)
			(type solid)
		)
		(fill yes)
		(layer "In4.Cu")
		(net "M_J_CPU0_SB_DQ<30>")
	)
	(gr_poly
		(pts
			(xy 385.024884 -291.297614) (xy 384.924808 -291.197792) (xy 384.824732 -291.297614) (xy 384.824732 -291.345366)
			(xy 385.024884 -291.345366)
		)
		(stroke
			(width 0)
			(type solid)
		)
		(fill yes)
		(layer "In4.Cu")
		(net "M_J_CPU0_SB_DQS_DN<8>")
	)
	(gr_poly
		(pts
			(xy 385.024884 -290.894262) (xy 385.024884 -290.84651) (xy 384.824732 -290.84651) (xy 384.824732 -290.894262)
			(xy 384.924808 -290.994084)
		)
		(stroke
			(width 0)
			(type solid)
		)
		(fill yes)
		(layer "In4.Cu")
		(net "M_J_CPU0_SB_DQS_DN<3>")
	)
	(gr_poly
		(pts
			(xy 385.024884 -289.677856) (xy 384.924808 -289.57778) (xy 384.824732 -289.677856) (xy 384.824732 -289.722306)
			(xy 385.024884 -289.722306)
		)
		(stroke
			(width 0)
			(type solid)
		)
		(fill yes)
		(layer "In4.Cu")
		(net "M_J_CPU0_SB_DQ<25>")
	)
	(gr_poly
		(pts
			(xy 385.024884 -289.273996) (xy 385.024884 -289.229546) (xy 384.824732 -289.229546) (xy 384.824732 -289.273996)
			(xy 384.924808 -289.374072)
		)
		(stroke
			(width 0)
			(type solid)
		)
		(fill yes)
		(layer "In4.Cu")
		(net "M_J_CPU0_SB_DQ<26>")
	)
	(gr_poly
		(pts
			(xy 385.024884 -288.057844) (xy 384.924808 -287.957768) (xy 384.824732 -288.057844) (xy 384.824732 -288.102294)
			(xy 385.024884 -288.102294)
		)
		(stroke
			(width 0)
			(type solid)
		)
		(fill yes)
		(layer "In4.Cu")
		(net "M_J_CPU0_SB_DQ<21>")
	)
	(gr_poly
		(pts
			(xy 385.024884 -287.654238) (xy 385.024884 -287.609788) (xy 384.824732 -287.609788) (xy 384.824732 -287.654238)
			(xy 384.924808 -287.75406)
		)
		(stroke
			(width 0)
			(type solid)
		)
		(fill yes)
		(layer "In4.Cu")
		(net "M_J_CPU0_SB_DQ<22>")
	)
	(gr_poly
		(pts
			(xy 385.024884 -286.437832) (xy 384.924808 -286.337756) (xy 384.824732 -286.437832) (xy 384.824732 -286.485584)
			(xy 385.024884 -286.485584)
		)
		(stroke
			(width 0)
			(type solid)
		)
		(fill yes)
		(layer "In4.Cu")
		(net "M_J_CPU0_SB_DQS_DN<7>")
	)
	(gr_poly
		(pts
			(xy 385.024884 -286.03448) (xy 385.024884 -285.986728) (xy 384.824732 -285.986728) (xy 384.824732 -286.03448)
			(xy 384.924808 -286.134302)
		)
		(stroke
			(width 0)
			(type solid)
		)
		(fill yes)
		(layer "In4.Cu")
		(net "M_J_CPU0_SB_DQS_DN<2>")
	)
	(gr_poly
		(pts
			(xy 385.024884 -284.818074) (xy 384.924808 -284.717998) (xy 384.824732 -284.818074) (xy 384.824732 -284.862524)
			(xy 385.024884 -284.862524)
		)
		(stroke
			(width 0)
			(type solid)
		)
		(fill yes)
		(layer "In4.Cu")
		(net "M_J_CPU0_SB_DQ<17>")
	)
	(gr_poly
		(pts
			(xy 385.024884 -284.414214) (xy 385.024884 -284.369764) (xy 384.824732 -284.369764) (xy 384.824732 -284.414214)
			(xy 384.924808 -284.51429)
		)
		(stroke
			(width 0)
			(type solid)
		)
		(fill yes)
		(layer "In4.Cu")
		(net "M_J_CPU0_SB_DQ<18>")
	)
	(gr_poly
		(pts
			(xy 385.024884 -283.198062) (xy 384.924808 -283.097986) (xy 384.824732 -283.198062) (xy 384.824732 -283.242512)
			(xy 385.024884 -283.242512)
		)
		(stroke
			(width 0)
			(type solid)
		)
		(fill yes)
		(layer "In4.Cu")
		(net "M_J_CPU0_SB_DQ<13>")
	)
	(gr_poly
		(pts
			(xy 385.024884 -282.794202) (xy 385.024884 -282.749752) (xy 384.824732 -282.749752) (xy 384.824732 -282.794202)
			(xy 384.924808 -282.894278)
		)
		(stroke
			(width 0)
			(type solid)
		)
		(fill yes)
		(layer "In4.Cu")
		(net "M_J_CPU0_SB_DQ<14>")
	)
	(gr_poly
		(pts
			(xy 385.024884 -281.577796) (xy 384.924808 -281.477974) (xy 384.824732 -281.577796) (xy 384.824732 -281.625548)
			(xy 385.024884 -281.625548)
		)
		(stroke
			(width 0)
			(type solid)
		)
		(fill yes)
		(layer "In4.Cu")
		(net "M_J_CPU0_SB_DQS_DN<6>")
	)
	(gr_poly
		(pts
			(xy 385.024884 -281.174444) (xy 385.024884 -281.126692) (xy 384.824732 -281.126692) (xy 384.824732 -281.174444)
			(xy 384.924808 -281.274266)
		)
		(stroke
			(width 0)
			(type solid)
		)
		(fill yes)
		(layer "In4.Cu")
		(net "M_J_CPU0_SB_DQS_DN<1>")
	)
	(gr_poly
		(pts
			(xy 385.024884 -279.958038) (xy 384.924808 -279.857962) (xy 384.824732 -279.958038) (xy 384.824732 -280.002488)
			(xy 385.024884 -280.002488)
		)
		(stroke
			(width 0)
			(type solid)
		)
		(fill yes)
		(layer "In4.Cu")
		(net "M_J_CPU0_SB_DQ<9>")
	)
	(gr_poly
		(pts
			(xy 385.024884 -279.554178) (xy 385.024884 -279.509728) (xy 384.824732 -279.509728) (xy 384.824732 -279.554178)
			(xy 384.924808 -279.654254)
		)
		(stroke
			(width 0)
			(type solid)
		)
		(fill yes)
		(layer "In4.Cu")
		(net "M_J_CPU0_SB_DQ<10>")
	)
	(gr_poly
		(pts
			(xy 385.024884 -278.338026) (xy 384.924808 -278.23795) (xy 384.824732 -278.338026) (xy 384.824732 -278.382476)
			(xy 385.024884 -278.382476)
		)
		(stroke
			(width 0)
			(type solid)
		)
		(fill yes)
		(layer "In4.Cu")
		(net "M_J_CPU0_SB_DQ<5>")
	)
	(gr_poly
		(pts
			(xy 385.024884 -277.934166) (xy 385.024884 -277.889716) (xy 384.824732 -277.889716) (xy 384.824732 -277.934166)
			(xy 384.924808 -278.034242)
		)
		(stroke
			(width 0)
			(type solid)
		)
		(fill yes)
		(layer "In4.Cu")
		(net "M_J_CPU0_SB_DQ<6>")
	)
	(gr_poly
		(pts
			(xy 385.024884 -276.71776) (xy 384.924808 -276.617938) (xy 384.824732 -276.71776) (xy 384.824732 -276.765512)
			(xy 385.024884 -276.765512)
		)
		(stroke
			(width 0)
			(type solid)
		)
		(fill yes)
		(layer "In4.Cu")
		(net "M_J_CPU0_SB_DQS_DN<5>")
	)
	(gr_poly
		(pts
			(xy 385.024884 -276.314408) (xy 385.024884 -276.266656) (xy 384.824732 -276.266656) (xy 384.824732 -276.314408)
			(xy 384.924808 -276.41423)
		)
		(stroke
			(width 0)
			(type solid)
		)
		(fill yes)
		(layer "In4.Cu")
		(net "M_J_CPU0_SB_DQS_DN<0>")
	)
	(gr_poly
		(pts
			(xy 385.024884 -275.098002) (xy 384.924808 -274.997926) (xy 384.824732 -275.098002) (xy 384.824732 -275.142452)
			(xy 385.024884 -275.142452)
		)
		(stroke
			(width 0)
			(type solid)
		)
		(fill yes)
		(layer "In4.Cu")
		(net "M_J_CPU0_SB_DQ<1>")
	)
	(gr_poly
		(pts
			(xy 385.024884 -274.694142) (xy 385.024884 -274.649692) (xy 384.824732 -274.649692) (xy 384.824732 -274.694142)
			(xy 384.924808 -274.794218)
		)
		(stroke
			(width 0)
			(type solid)
		)
		(fill yes)
		(layer "In4.Cu")
		(net "M_J_CPU0_SB_DQ<2>")
	)
	(gr_poly
		(pts
			(xy 385.024884 -273.47799) (xy 384.924808 -273.377914) (xy 384.824732 -273.47799) (xy 384.824732 -273.52244)
			(xy 385.024884 -273.52244)
		)
		(stroke
			(width 0)
			(type solid)
		)
		(fill yes)
		(layer "In4.Cu")
		(net "M_J_CPU0_SB_CB<1>")
	)
	(gr_poly
		(pts
			(xy 385.024884 -273.07413) (xy 385.024884 -273.02968) (xy 384.824732 -273.02968) (xy 384.824732 -273.07413)
			(xy 384.924808 -273.174206)
		)
		(stroke
			(width 0)
			(type solid)
		)
		(fill yes)
		(layer "In4.Cu")
		(net "M_J_CPU0_SB_CB<2>")
	)
	(gr_poly
		(pts
			(xy 385.024884 -271.857724) (xy 384.924808 -271.757902) (xy 384.824732 -271.857724) (xy 384.824732 -271.905476)
			(xy 385.024884 -271.905476)
		)
		(stroke
			(width 0)
			(type solid)
		)
		(fill yes)
		(layer "In4.Cu")
		(net "M_J_CPU0_SB_DQS_DN<4>")
	)
	(gr_poly
		(pts
			(xy 385.024884 -271.454372) (xy 385.024884 -271.40662) (xy 384.824732 -271.40662) (xy 384.824732 -271.454372)
			(xy 384.924808 -271.554194)
		)
		(stroke
			(width 0)
			(type solid)
		)
		(fill yes)
		(layer "In4.Cu")
		(net "M_J_CPU0_SB_DQS_DN<9>")
	)
	(gr_poly
		(pts
			(xy 385.024884 -270.237966) (xy 384.924808 -270.13789) (xy 384.824732 -270.237966) (xy 384.824732 -270.282416)
			(xy 385.024884 -270.282416)
		)
		(stroke
			(width 0)
			(type solid)
		)
		(fill yes)
		(layer "In4.Cu")
		(net "M_J_CPU0_SB_CB<5>")
	)
	(gr_poly
		(pts
			(xy 385.024884 -269.834106) (xy 385.024884 -269.789656) (xy 384.824732 -269.789656) (xy 384.824732 -269.834106)
			(xy 384.924808 -269.934182)
		)
		(stroke
			(width 0)
			(type solid)
		)
		(fill yes)
		(layer "In4.Cu")
		(net "M_J_CPU0_SB_CB<6>")
	)
	(gr_poly
		(pts
			(xy 385.024884 -266.997942) (xy 384.924808 -266.897866) (xy 384.824732 -266.997942) (xy 384.824732 -267.042392)
			(xy 385.024884 -267.042392)
		)
		(stroke
			(width 0)
			(type solid)
		)
		(fill yes)
		(layer "In4.Cu")
		(net "M_J_CPU0_SA_RSP<0>")
	)
	(gr_poly
		(pts
			(xy 385.024884 -266.594082) (xy 385.024884 -266.549632) (xy 384.824732 -266.549632) (xy 384.824732 -266.594082)
			(xy 384.924808 -266.694158)
		)
		(stroke
			(width 0)
			(type solid)
		)
		(fill yes)
		(layer "In4.Cu")
		(net "M_J_CPU0_SB_CS_N<1>")
	)
	(gr_poly
		(pts
			(xy 385.024884 -265.37793) (xy 384.924808 -265.277854) (xy 384.824732 -265.37793) (xy 384.824732 -265.42238)
			(xy 385.024884 -265.42238)
		)
		(stroke
			(width 0)
			(type solid)
		)
		(fill yes)
		(layer "In4.Cu")
		(net "M_J_CPU0_SB_PAR")
	)
	(gr_poly
		(pts
			(xy 385.024884 -263.757918) (xy 384.924808 -263.657842) (xy 384.824732 -263.757918) (xy 384.824732 -263.802368)
			(xy 385.024884 -263.802368)
		)
		(stroke
			(width 0)
			(type solid)
		)
		(fill yes)
		(layer "In4.Cu")
		(net "M_J_CPU0_SB_CA<4>")
	)
	(gr_poly
		(pts
			(xy 385.024884 -263.354058) (xy 385.024884 -263.309608) (xy 384.824732 -263.309608) (xy 384.824732 -263.354058)
			(xy 384.924808 -263.454134)
		)
		(stroke
			(width 0)
			(type solid)
		)
		(fill yes)
		(layer "In4.Cu")
		(net "M_J_CPU0_SB_CA<3>")
	)
	(gr_poly
		(pts
			(xy 385.024884 -262.137906) (xy 384.924808 -262.03783) (xy 384.824732 -262.137906) (xy 384.824732 -262.182356)
			(xy 385.024884 -262.182356)
		)
		(stroke
			(width 0)
			(type solid)
		)
		(fill yes)
		(layer "In4.Cu")
		(net "M_J_CPU0_SB_CA<0>")
	)
	(gr_poly
		(pts
			(xy 385.19481 -256.432558) (xy 385.19481 -256.384806) (xy 384.994658 -256.384806) (xy 384.994658 -256.432558)
			(xy 385.094734 -256.53238)
		)
		(stroke
			(width 0)
			(type solid)
		)
		(fill yes)
		(layer "In4.Cu")
		(net "M_J_CPU0_CLK_DN<0>")
	)
	(gr_poly
		(pts
			(xy 385.19481 -255.216152) (xy 385.094734 -255.116076) (xy 384.994658 -255.216152) (xy 384.994658 -255.260602)
			(xy 385.19481 -255.260602)
		)
		(stroke
			(width 0)
			(type solid)
		)
		(fill yes)
		(layer "In4.Cu")
		(net "M_J_CPU0_SA_CA<6>")
	)
	(gr_poly
		(pts
			(xy 385.19481 -254.812292) (xy 385.19481 -254.767842) (xy 384.994658 -254.767842) (xy 384.994658 -254.812292)
			(xy 385.094734 -254.912368)
		)
		(stroke
			(width 0)
			(type solid)
		)
		(fill yes)
		(layer "In4.Cu")
		(net "M_J_CPU0_SA_CA<5>")
	)
	(gr_poly
		(pts
			(xy 385.19481 -253.59614) (xy 385.094734 -253.496064) (xy 384.994658 -253.59614) (xy 384.994658 -253.64059)
			(xy 385.19481 -253.64059)
		)
		(stroke
			(width 0)
			(type solid)
		)
		(fill yes)
		(layer "In4.Cu")
		(net "M_J_CPU0_SA_CA<2>")
	)
	(gr_poly
		(pts
			(xy 385.19481 -253.19228) (xy 385.19481 -253.14783) (xy 384.994658 -253.14783) (xy 384.994658 -253.19228)
			(xy 385.094734 -253.292356)
		)
		(stroke
			(width 0)
			(type solid)
		)
		(fill yes)
		(layer "In4.Cu")
		(net "M_J_CPU0_SA_CA<1>")
	)
	(gr_poly
		(pts
			(xy 385.19481 -251.976128) (xy 385.094734 -251.876052) (xy 384.994658 -251.976128) (xy 384.994658 -252.020578)
			(xy 385.19481 -252.020578)
		)
		(stroke
			(width 0)
			(type solid)
		)
		(fill yes)
		(layer "In4.Cu")
		(net "M_J_CPU0_SA_CS_N<1>")
	)
	(gr_poly
		(pts
			(xy 385.19481 -250.356116) (xy 385.094734 -250.25604) (xy 384.994658 -250.356116) (xy 384.994658 -250.400566)
			(xy 385.19481 -250.400566)
		)
		(stroke
			(width 0)
			(type solid)
		)
		(fill yes)
		(layer "In4.Cu")
		(net "M_J_CPU0_ALERT_R_N")
	)
	(gr_poly
		(pts
			(xy 385.19481 -248.736104) (xy 385.094734 -248.636028) (xy 384.994658 -248.736104) (xy 384.994658 -248.780554)
			(xy 385.19481 -248.780554)
		)
		(stroke
			(width 0)
			(type solid)
		)
		(fill yes)
		(layer "In4.Cu")
		(net "M_J_CPU0_SA_CB<5>")
	)
	(gr_poly
		(pts
			(xy 385.19481 -248.332244) (xy 385.19481 -248.287794) (xy 384.994658 -248.287794) (xy 384.994658 -248.332244)
			(xy 385.094734 -248.43232)
		)
		(stroke
			(width 0)
			(type solid)
		)
		(fill yes)
		(layer "In4.Cu")
		(net "M_J_CPU0_SA_CB<6>")
	)
	(gr_poly
		(pts
			(xy 385.19481 -247.115838) (xy 385.094734 -247.016016) (xy 384.994658 -247.115838) (xy 384.994658 -247.16359)
			(xy 385.19481 -247.16359)
		)
		(stroke
			(width 0)
			(type solid)
		)
		(fill yes)
		(layer "In4.Cu")
		(net "M_J_CPU0_SA_DQS_DN<9>")
	)
	(gr_poly
		(pts
			(xy 385.19481 -246.712486) (xy 385.19481 -246.664734) (xy 384.994658 -246.664734) (xy 384.994658 -246.712486)
			(xy 385.094734 -246.812308)
		)
		(stroke
			(width 0)
			(type solid)
		)
		(fill yes)
		(layer "In4.Cu")
		(net "M_J_CPU0_SA_DQS_DN<4>")
	)
	(gr_poly
		(pts
			(xy 385.19481 -245.49608) (xy 385.094734 -245.396004) (xy 384.994658 -245.49608) (xy 384.994658 -245.54053)
			(xy 385.19481 -245.54053)
		)
		(stroke
			(width 0)
			(type solid)
		)
		(fill yes)
		(layer "In4.Cu")
		(net "M_J_CPU0_SA_CB<1>")
	)
	(gr_poly
		(pts
			(xy 385.19481 -245.09222) (xy 385.19481 -245.04777) (xy 384.994658 -245.04777) (xy 384.994658 -245.09222)
			(xy 385.094734 -245.192296)
		)
		(stroke
			(width 0)
			(type solid)
		)
		(fill yes)
		(layer "In4.Cu")
		(net "M_J_CPU0_SA_CB<2>")
	)
	(gr_poly
		(pts
			(xy 385.19481 -243.876068) (xy 385.094734 -243.775992) (xy 384.994658 -243.876068) (xy 384.994658 -243.920518)
			(xy 385.19481 -243.920518)
		)
		(stroke
			(width 0)
			(type solid)
		)
		(fill yes)
		(layer "In4.Cu")
		(net "M_J_CPU0_SA_DQ<29>")
	)
	(gr_poly
		(pts
			(xy 385.19481 -243.472208) (xy 385.19481 -243.427758) (xy 384.994658 -243.427758) (xy 384.994658 -243.472208)
			(xy 385.094734 -243.572284)
		)
		(stroke
			(width 0)
			(type solid)
		)
		(fill yes)
		(layer "In4.Cu")
		(net "M_J_CPU0_SA_DQ<30>")
	)
	(gr_poly
		(pts
			(xy 385.19481 -242.255802) (xy 385.094734 -242.15598) (xy 384.994658 -242.255802) (xy 384.994658 -242.303554)
			(xy 385.19481 -242.303554)
		)
		(stroke
			(width 0)
			(type solid)
		)
		(fill yes)
		(layer "In4.Cu")
		(net "M_J_CPU0_SA_DQS_DN<8>")
	)
	(gr_poly
		(pts
			(xy 385.19481 -241.85245) (xy 385.19481 -241.804698) (xy 384.994658 -241.804698) (xy 384.994658 -241.85245)
			(xy 385.094734 -241.952272)
		)
		(stroke
			(width 0)
			(type solid)
		)
		(fill yes)
		(layer "In4.Cu")
		(net "M_J_CPU0_SA_DQS_DN<3>")
	)
	(gr_poly
		(pts
			(xy 385.19481 -240.636044) (xy 385.094734 -240.535968) (xy 384.994658 -240.636044) (xy 384.994658 -240.680494)
			(xy 385.19481 -240.680494)
		)
		(stroke
			(width 0)
			(type solid)
		)
		(fill yes)
		(layer "In4.Cu")
		(net "M_J_CPU0_SA_DQ<25>")
	)
	(gr_poly
		(pts
			(xy 385.19481 -240.232184) (xy 385.19481 -240.187734) (xy 384.994658 -240.187734) (xy 384.994658 -240.232184)
			(xy 385.094734 -240.33226)
		)
		(stroke
			(width 0)
			(type solid)
		)
		(fill yes)
		(layer "In4.Cu")
		(net "M_J_CPU0_SA_DQ<26>")
	)
	(gr_poly
		(pts
			(xy 385.19481 -239.016032) (xy 385.094734 -238.915956) (xy 384.994658 -239.016032) (xy 384.994658 -239.060482)
			(xy 385.19481 -239.060482)
		)
		(stroke
			(width 0)
			(type solid)
		)
		(fill yes)
		(layer "In4.Cu")
		(net "M_J_CPU0_SA_DQ<21>")
	)
	(gr_poly
		(pts
			(xy 385.19481 -238.612172) (xy 385.19481 -238.567722) (xy 384.994658 -238.567722) (xy 384.994658 -238.612172)
			(xy 385.094734 -238.712248)
		)
		(stroke
			(width 0)
			(type solid)
		)
		(fill yes)
		(layer "In4.Cu")
		(net "M_J_CPU0_SA_DQ<22>")
	)
	(gr_poly
		(pts
			(xy 385.19481 -237.395766) (xy 385.094734 -237.295944) (xy 384.994658 -237.395766) (xy 384.994658 -237.443518)
			(xy 385.19481 -237.443518)
		)
		(stroke
			(width 0)
			(type solid)
		)
		(fill yes)
		(layer "In4.Cu")
		(net "M_J_CPU0_SA_DQS_DN<7>")
	)
	(gr_poly
		(pts
			(xy 385.19481 -236.992414) (xy 385.19481 -236.944662) (xy 384.994658 -236.944662) (xy 384.994658 -236.992414)
			(xy 385.094734 -237.092236)
		)
		(stroke
			(width 0)
			(type solid)
		)
		(fill yes)
		(layer "In4.Cu")
		(net "M_J_CPU0_SA_DQS_DN<2>")
	)
	(gr_poly
		(pts
			(xy 385.19481 -235.776008) (xy 385.094734 -235.675932) (xy 384.994658 -235.776008) (xy 384.994658 -235.820458)
			(xy 385.19481 -235.820458)
		)
		(stroke
			(width 0)
			(type solid)
		)
		(fill yes)
		(layer "In4.Cu")
		(net "M_J_CPU0_SA_DQ<17>")
	)
	(gr_poly
		(pts
			(xy 385.19481 -235.372148) (xy 385.19481 -235.327698) (xy 384.994658 -235.327698) (xy 384.994658 -235.372148)
			(xy 385.094734 -235.472224)
		)
		(stroke
			(width 0)
			(type solid)
		)
		(fill yes)
		(layer "In4.Cu")
		(net "M_J_CPU0_SA_DQ<18>")
	)
	(gr_poly
		(pts
			(xy 385.19481 -234.155996) (xy 385.094734 -234.05592) (xy 384.994658 -234.155996) (xy 384.994658 -234.200446)
			(xy 385.19481 -234.200446)
		)
		(stroke
			(width 0)
			(type solid)
		)
		(fill yes)
		(layer "In4.Cu")
		(net "M_J_CPU0_SA_DQ<13>")
	)
	(gr_poly
		(pts
			(xy 385.19481 -233.752136) (xy 385.19481 -233.707686) (xy 384.994658 -233.707686) (xy 384.994658 -233.752136)
			(xy 385.094734 -233.852212)
		)
		(stroke
			(width 0)
			(type solid)
		)
		(fill yes)
		(layer "In4.Cu")
		(net "M_J_CPU0_SA_DQ<14>")
	)
	(gr_poly
		(pts
			(xy 385.19481 -232.53573) (xy 385.094734 -232.435908) (xy 384.994658 -232.53573) (xy 384.994658 -232.583482)
			(xy 385.19481 -232.583482)
		)
		(stroke
			(width 0)
			(type solid)
		)
		(fill yes)
		(layer "In4.Cu")
		(net "M_J_CPU0_SA_DQS_DN<6>")
	)
	(gr_poly
		(pts
			(xy 385.19481 -232.132378) (xy 385.19481 -232.084626) (xy 384.994658 -232.084626) (xy 384.994658 -232.132378)
			(xy 385.094734 -232.2322)
		)
		(stroke
			(width 0)
			(type solid)
		)
		(fill yes)
		(layer "In4.Cu")
		(net "M_J_CPU0_SA_DQS_DN<1>")
	)
	(gr_poly
		(pts
			(xy 385.19481 -230.915972) (xy 385.094734 -230.815896) (xy 384.994658 -230.915972) (xy 384.994658 -230.960422)
			(xy 385.19481 -230.960422)
		)
		(stroke
			(width 0)
			(type solid)
		)
		(fill yes)
		(layer "In4.Cu")
		(net "M_J_CPU0_SA_DQ<9>")
	)
	(gr_poly
		(pts
			(xy 385.19481 -230.512366) (xy 385.19481 -230.467916) (xy 384.994658 -230.467916) (xy 384.994658 -230.512366)
			(xy 385.094734 -230.612188)
		)
		(stroke
			(width 0)
			(type solid)
		)
		(fill yes)
		(layer "In4.Cu")
		(net "M_J_CPU0_SA_DQ<10>")
	)
	(gr_poly
		(pts
			(xy 385.19481 -229.29596) (xy 385.094734 -229.195884) (xy 384.994658 -229.29596) (xy 384.994658 -229.34041)
			(xy 385.19481 -229.34041)
		)
		(stroke
			(width 0)
			(type solid)
		)
		(fill yes)
		(layer "In4.Cu")
		(net "M_J_CPU0_SA_DQ<5>")
	)
	(gr_poly
		(pts
			(xy 385.19481 -228.892354) (xy 385.19481 -228.847904) (xy 384.994658 -228.847904) (xy 384.994658 -228.892354)
			(xy 385.094734 -228.99243)
		)
		(stroke
			(width 0)
			(type solid)
		)
		(fill yes)
		(layer "In4.Cu")
		(net "M_J_CPU0_SA_DQ<6>")
	)
	(gr_poly
		(pts
			(xy 385.19481 -227.675948) (xy 385.094734 -227.576126) (xy 384.994658 -227.675948) (xy 384.994658 -227.7237)
			(xy 385.19481 -227.7237)
		)
		(stroke
			(width 0)
			(type solid)
		)
		(fill yes)
		(layer "In4.Cu")
		(net "M_J_CPU0_SA_DQS_DN<5>")
	)
	(gr_poly
		(pts
			(xy 385.19481 -227.272596) (xy 385.19481 -227.224844) (xy 384.994658 -227.224844) (xy 384.994658 -227.272596)
			(xy 385.094734 -227.372418)
		)
		(stroke
			(width 0)
			(type solid)
		)
		(fill yes)
		(layer "In4.Cu")
		(net "M_J_CPU0_SA_DQS_DN<0>")
	)
	(gr_poly
		(pts
			(xy 385.19481 -226.05619) (xy 385.094734 -225.956114) (xy 384.994658 -226.05619) (xy 384.994658 -226.10064)
			(xy 385.19481 -226.10064)
		)
		(stroke
			(width 0)
			(type solid)
		)
		(fill yes)
		(layer "In4.Cu")
		(net "M_J_CPU0_SA_DQ<1>")
	)
	(gr_poly
		(pts
			(xy 385.19481 -225.65233) (xy 385.19481 -225.60788) (xy 384.994658 -225.60788) (xy 384.994658 -225.65233)
			(xy 385.094734 -225.752406)
		)
		(stroke
			(width 0)
			(type solid)
		)
		(fill yes)
		(layer "In4.Cu")
		(net "M_J_CPU0_SA_DQ<2>")
	)
	(gr_poly
		(pts
			(xy 385.494784 -293.324026) (xy 385.494784 -293.279576) (xy 385.294632 -293.279576) (xy 385.294632 -293.324026)
			(xy 385.394708 -293.424102)
		)
		(stroke
			(width 0)
			(type solid)
		)
		(fill yes)
		(layer "In4.Cu")
		(net "M_J_CPU0_SB_DQ<31>")
	)
	(gr_poly
		(pts
			(xy 385.494784 -292.107874) (xy 385.394708 -292.007798) (xy 385.294632 -292.107874) (xy 385.294632 -292.152324)
			(xy 385.494784 -292.152324)
		)
		(stroke
			(width 0)
			(type solid)
		)
		(fill yes)
		(layer "In4.Cu")
		(net "M_J_CPU0_SB_DQ<28>")
	)
	(gr_poly
		(pts
			(xy 385.494784 -291.704268) (xy 385.494784 -291.656516) (xy 385.294632 -291.656516) (xy 385.294632 -291.704268)
			(xy 385.394708 -291.80409)
		)
		(stroke
			(width 0)
			(type solid)
		)
		(fill yes)
		(layer "In4.Cu")
		(net "M_J_CPU0_SB_DQS_DP<8>")
	)
	(gr_poly
		(pts
			(xy 385.494784 -290.487608) (xy 385.394708 -290.387786) (xy 385.294632 -290.487608) (xy 385.294632 -290.53536)
			(xy 385.494784 -290.53536)
		)
		(stroke
			(width 0)
			(type solid)
		)
		(fill yes)
		(layer "In4.Cu")
		(net "M_J_CPU0_SB_DQS_DP<3>")
	)
	(gr_poly
		(pts
			(xy 385.494784 -290.084002) (xy 385.494784 -290.039552) (xy 385.294632 -290.039552) (xy 385.294632 -290.084002)
			(xy 385.394708 -290.184078)
		)
		(stroke
			(width 0)
			(type solid)
		)
		(fill yes)
		(layer "In4.Cu")
		(net "M_J_CPU0_SB_DQ<27>")
	)
	(gr_poly
		(pts
			(xy 385.494784 -288.86785) (xy 385.394708 -288.767774) (xy 385.294632 -288.86785) (xy 385.294632 -288.9123)
			(xy 385.494784 -288.9123)
		)
		(stroke
			(width 0)
			(type solid)
		)
		(fill yes)
		(layer "In4.Cu")
		(net "M_J_CPU0_SB_DQ<24>")
	)
	(gr_poly
		(pts
			(xy 385.494784 -288.464244) (xy 385.494784 -288.419794) (xy 385.294632 -288.419794) (xy 385.294632 -288.464244)
			(xy 385.394708 -288.56432)
		)
		(stroke
			(width 0)
			(type solid)
		)
		(fill yes)
		(layer "In4.Cu")
		(net "M_J_CPU0_SB_DQ<23>")
	)
	(gr_poly
		(pts
			(xy 385.494784 -287.247838) (xy 385.394708 -287.148016) (xy 385.294632 -287.247838) (xy 385.294632 -287.292288)
			(xy 385.494784 -287.292288)
		)
		(stroke
			(width 0)
			(type solid)
		)
		(fill yes)
		(layer "In4.Cu")
		(net "M_J_CPU0_SB_DQ<20>")
	)
	(gr_poly
		(pts
			(xy 385.494784 -286.844232) (xy 385.494784 -286.79648) (xy 385.294632 -286.79648) (xy 385.294632 -286.844232)
			(xy 385.394708 -286.944308)
		)
		(stroke
			(width 0)
			(type solid)
		)
		(fill yes)
		(layer "In4.Cu")
		(net "M_J_CPU0_SB_DQS_DP<7>")
	)
	(gr_poly
		(pts
			(xy 385.494784 -285.627826) (xy 385.394708 -285.528004) (xy 385.294632 -285.627826) (xy 385.294632 -285.675578)
			(xy 385.494784 -285.675578)
		)
		(stroke
			(width 0)
			(type solid)
		)
		(fill yes)
		(layer "In4.Cu")
		(net "M_J_CPU0_SB_DQS_DP<2>")
	)
	(gr_poly
		(pts
			(xy 385.494784 -285.22422) (xy 385.494784 -285.17977) (xy 385.294632 -285.17977) (xy 385.294632 -285.22422)
			(xy 385.394708 -285.324296)
		)
		(stroke
			(width 0)
			(type solid)
		)
		(fill yes)
		(layer "In4.Cu")
		(net "M_J_CPU0_SB_DQ<19>")
	)
	(gr_poly
		(pts
			(xy 385.494784 -284.008068) (xy 385.394708 -283.907992) (xy 385.294632 -284.008068) (xy 385.294632 -284.052518)
			(xy 385.494784 -284.052518)
		)
		(stroke
			(width 0)
			(type solid)
		)
		(fill yes)
		(layer "In4.Cu")
		(net "M_J_CPU0_SB_DQ<16>")
	)
	(gr_poly
		(pts
			(xy 385.494784 -283.604208) (xy 385.494784 -283.559758) (xy 385.294632 -283.559758) (xy 385.294632 -283.604208)
			(xy 385.394708 -283.704284)
		)
		(stroke
			(width 0)
			(type solid)
		)
		(fill yes)
		(layer "In4.Cu")
		(net "M_J_CPU0_SB_DQ<15>")
	)
	(gr_poly
		(pts
			(xy 385.494784 -282.388056) (xy 385.394708 -282.28798) (xy 385.294632 -282.388056) (xy 385.294632 -282.432506)
			(xy 385.494784 -282.432506)
		)
		(stroke
			(width 0)
			(type solid)
		)
		(fill yes)
		(layer "In4.Cu")
		(net "M_J_CPU0_SB_DQ<12>")
	)
	(gr_poly
		(pts
			(xy 385.494784 -281.98445) (xy 385.494784 -281.936698) (xy 385.294632 -281.936698) (xy 385.294632 -281.98445)
			(xy 385.394708 -282.084272)
		)
		(stroke
			(width 0)
			(type solid)
		)
		(fill yes)
		(layer "In4.Cu")
		(net "M_J_CPU0_SB_DQS_DP<6>")
	)
	(gr_poly
		(pts
			(xy 385.494784 -280.76779) (xy 385.394708 -280.667968) (xy 385.294632 -280.76779) (xy 385.294632 -280.815542)
			(xy 385.494784 -280.815542)
		)
		(stroke
			(width 0)
			(type solid)
		)
		(fill yes)
		(layer "In4.Cu")
		(net "M_J_CPU0_SB_DQS_DP<1>")
	)
	(gr_poly
		(pts
			(xy 385.494784 -280.364184) (xy 385.494784 -280.319734) (xy 385.294632 -280.319734) (xy 385.294632 -280.364184)
			(xy 385.394708 -280.46426)
		)
		(stroke
			(width 0)
			(type solid)
		)
		(fill yes)
		(layer "In4.Cu")
		(net "M_J_CPU0_SB_DQ<11>")
	)
	(gr_poly
		(pts
			(xy 385.494784 -279.148032) (xy 385.394708 -279.047956) (xy 385.294632 -279.148032) (xy 385.294632 -279.192482)
			(xy 385.494784 -279.192482)
		)
		(stroke
			(width 0)
			(type solid)
		)
		(fill yes)
		(layer "In4.Cu")
		(net "M_J_CPU0_SB_DQ<8>")
	)
	(gr_poly
		(pts
			(xy 385.494784 -278.744172) (xy 385.494784 -278.699722) (xy 385.294632 -278.699722) (xy 385.294632 -278.744172)
			(xy 385.394708 -278.844248)
		)
		(stroke
			(width 0)
			(type solid)
		)
		(fill yes)
		(layer "In4.Cu")
		(net "M_J_CPU0_SB_DQ<7>")
	)
	(gr_poly
		(pts
			(xy 385.494784 -277.52802) (xy 385.394708 -277.427944) (xy 385.294632 -277.52802) (xy 385.294632 -277.57247)
			(xy 385.494784 -277.57247)
		)
		(stroke
			(width 0)
			(type solid)
		)
		(fill yes)
		(layer "In4.Cu")
		(net "M_J_CPU0_SB_DQ<4>")
	)
	(gr_poly
		(pts
			(xy 385.494784 -277.124414) (xy 385.494784 -277.076662) (xy 385.294632 -277.076662) (xy 385.294632 -277.124414)
			(xy 385.394708 -277.224236)
		)
		(stroke
			(width 0)
			(type solid)
		)
		(fill yes)
		(layer "In4.Cu")
		(net "M_J_CPU0_SB_DQS_DP<5>")
	)
	(gr_poly
		(pts
			(xy 385.494784 -275.907754) (xy 385.394708 -275.807932) (xy 385.294632 -275.907754) (xy 385.294632 -275.955506)
			(xy 385.494784 -275.955506)
		)
		(stroke
			(width 0)
			(type solid)
		)
		(fill yes)
		(layer "In4.Cu")
		(net "M_J_CPU0_SB_DQS_DP<0>")
	)
	(gr_poly
		(pts
			(xy 385.494784 -275.504148) (xy 385.494784 -275.459698) (xy 385.294632 -275.459698) (xy 385.294632 -275.504148)
			(xy 385.394708 -275.604224)
		)
		(stroke
			(width 0)
			(type solid)
		)
		(fill yes)
		(layer "In4.Cu")
		(net "M_J_CPU0_SB_DQ<3>")
	)
	(gr_poly
		(pts
			(xy 385.494784 -274.287996) (xy 385.394708 -274.18792) (xy 385.294632 -274.287996) (xy 385.294632 -274.332446)
			(xy 385.494784 -274.332446)
		)
		(stroke
			(width 0)
			(type solid)
		)
		(fill yes)
		(layer "In4.Cu")
		(net "M_J_CPU0_SB_DQ<0>")
	)
	(gr_poly
		(pts
			(xy 385.494784 -273.884136) (xy 385.494784 -273.839686) (xy 385.294632 -273.839686) (xy 385.294632 -273.884136)
			(xy 385.394708 -273.984212)
		)
		(stroke
			(width 0)
			(type solid)
		)
		(fill yes)
		(layer "In4.Cu")
		(net "M_J_CPU0_SB_CB<3>")
	)
	(gr_poly
		(pts
			(xy 385.494784 -272.667984) (xy 385.394708 -272.567908) (xy 385.294632 -272.667984) (xy 385.294632 -272.712434)
			(xy 385.494784 -272.712434)
		)
		(stroke
			(width 0)
			(type solid)
		)
		(fill yes)
		(layer "In4.Cu")
		(net "M_J_CPU0_SB_CB<0>")
	)
	(gr_poly
		(pts
			(xy 385.494784 -272.264378) (xy 385.494784 -272.216626) (xy 385.294632 -272.216626) (xy 385.294632 -272.264378)
			(xy 385.394708 -272.3642)
		)
		(stroke
			(width 0)
			(type solid)
		)
		(fill yes)
		(layer "In4.Cu")
		(net "M_J_CPU0_SB_DQS_DP<4>")
	)
	(gr_poly
		(pts
			(xy 385.494784 -271.047718) (xy 385.394708 -270.947896) (xy 385.294632 -271.047718) (xy 385.294632 -271.09547)
			(xy 385.494784 -271.09547)
		)
		(stroke
			(width 0)
			(type solid)
		)
		(fill yes)
		(layer "In4.Cu")
		(net "M_J_CPU0_SB_DQS_DP<9>")
	)
	(gr_poly
		(pts
			(xy 385.494784 -270.644112) (xy 385.494784 -270.599662) (xy 385.294632 -270.599662) (xy 385.294632 -270.644112)
			(xy 385.394708 -270.744188)
		)
		(stroke
			(width 0)
			(type solid)
		)
		(fill yes)
		(layer "In4.Cu")
		(net "M_J_CPU0_SB_CB<7>")
	)
	(gr_poly
		(pts
			(xy 385.494784 -269.42796) (xy 385.394708 -269.327884) (xy 385.294632 -269.42796) (xy 385.294632 -269.47241)
			(xy 385.494784 -269.47241)
		)
		(stroke
			(width 0)
			(type solid)
		)
		(fill yes)
		(layer "In4.Cu")
		(net "M_J_CPU0_SB_CB<4>")
	)
	(gr_poly
		(pts
			(xy 385.494784 -267.807948) (xy 385.394708 -267.707872) (xy 385.294632 -267.807948) (xy 385.294632 -267.852398)
			(xy 385.494784 -267.852398)
		)
		(stroke
			(width 0)
			(type solid)
		)
		(fill yes)
		(layer "In4.Cu")
		(net "M_J_CPU0_SB_RSP<0>")
	)
	(gr_poly
		(pts
			(xy 385.494784 -265.784076) (xy 385.494784 -265.739626) (xy 385.294632 -265.739626) (xy 385.294632 -265.784076)
			(xy 385.394708 -265.884152)
		)
		(stroke
			(width 0)
			(type solid)
		)
		(fill yes)
		(layer "In4.Cu")
		(net "M_J_CPU0_SB_CS_N<0>")
	)
	(gr_poly
		(pts
			(xy 385.494784 -264.567924) (xy 385.394708 -264.467848) (xy 385.294632 -264.567924) (xy 385.294632 -264.612374)
			(xy 385.494784 -264.612374)
		)
		(stroke
			(width 0)
			(type solid)
		)
		(fill yes)
		(layer "In4.Cu")
		(net "M_J_CPU0_SB_CA<6>")
	)
	(gr_poly
		(pts
			(xy 385.494784 -264.164064) (xy 385.494784 -264.119614) (xy 385.294632 -264.119614) (xy 385.294632 -264.164064)
			(xy 385.394708 -264.26414)
		)
		(stroke
			(width 0)
			(type solid)
		)
		(fill yes)
		(layer "In4.Cu")
		(net "M_J_CPU0_SB_CA<5>")
	)
	(gr_poly
		(pts
			(xy 385.494784 -262.947912) (xy 385.394708 -262.847836) (xy 385.294632 -262.947912) (xy 385.294632 -262.992362)
			(xy 385.494784 -262.992362)
		)
		(stroke
			(width 0)
			(type solid)
		)
		(fill yes)
		(layer "In4.Cu")
		(net "M_J_CPU0_SB_CA<2>")
	)
	(gr_poly
		(pts
			(xy 385.494784 -262.544052) (xy 385.494784 -262.499602) (xy 385.294632 -262.499602) (xy 385.294632 -262.544052)
			(xy 385.394708 -262.644128)
		)
		(stroke
			(width 0)
			(type solid)
		)
		(fill yes)
		(layer "In4.Cu")
		(net "M_J_CPU0_SB_CA<1>")
	)
	(gr_poly
		(pts
			(xy 385.664964 -256.025904) (xy 385.564888 -255.926082) (xy 385.464812 -256.025904) (xy 385.464812 -256.073656)
			(xy 385.664964 -256.073656)
		)
		(stroke
			(width 0)
			(type solid)
		)
		(fill yes)
		(layer "In4.Cu")
		(net "M_J_CPU0_CLK_DP<0>")
	)
	(gr_poly
		(pts
			(xy 385.664964 -255.622298) (xy 385.664964 -255.577848) (xy 385.464812 -255.577848) (xy 385.464812 -255.622298)
			(xy 385.564888 -255.722374)
		)
		(stroke
			(width 0)
			(type solid)
		)
		(fill yes)
		(layer "In4.Cu")
		(net "M_J_CPU0_SA_PAR")
	)
	(gr_poly
		(pts
			(xy 385.664964 -254.406146) (xy 385.564888 -254.30607) (xy 385.464812 -254.406146) (xy 385.464812 -254.450596)
			(xy 385.664964 -254.450596)
		)
		(stroke
			(width 0)
			(type solid)
		)
		(fill yes)
		(layer "In4.Cu")
		(net "M_J_CPU0_SA_CA<4>")
	)
	(gr_poly
		(pts
			(xy 385.664964 -254.002286) (xy 385.664964 -253.957836) (xy 385.464812 -253.957836) (xy 385.464812 -254.002286)
			(xy 385.564888 -254.102362)
		)
		(stroke
			(width 0)
			(type solid)
		)
		(fill yes)
		(layer "In4.Cu")
		(net "M_J_CPU0_SA_CA<3>")
	)
	(gr_poly
		(pts
			(xy 385.664964 -252.786134) (xy 385.564888 -252.686058) (xy 385.464812 -252.786134) (xy 385.464812 -252.830584)
			(xy 385.664964 -252.830584)
		)
		(stroke
			(width 0)
			(type solid)
		)
		(fill yes)
		(layer "In4.Cu")
		(net "M_J_CPU0_SA_CA<0>")
	)
	(gr_poly
		(pts
			(xy 385.664964 -251.166122) (xy 385.564888 -251.066046) (xy 385.464812 -251.166122) (xy 385.464812 -251.210572)
			(xy 385.664964 -251.210572)
		)
		(stroke
			(width 0)
			(type solid)
		)
		(fill yes)
		(layer "In4.Cu")
		(net "M_J_CPU0_SA_CS_N<0>")
	)
	(gr_poly
		(pts
			(xy 385.664964 -250.762262) (xy 385.664964 -250.717812) (xy 385.464812 -250.717812) (xy 385.464812 -250.762262)
			(xy 385.564888 -250.862338)
		)
		(stroke
			(width 0)
			(type solid)
		)
		(fill yes)
		(layer "In4.Cu")
		(net "M_J_CPU0_RESET_N")
	)
	(gr_poly
		(pts
			(xy 385.664964 -249.14225) (xy 385.664964 -249.0978) (xy 385.464812 -249.0978) (xy 385.464812 -249.14225)
			(xy 385.564888 -249.242326)
		)
		(stroke
			(width 0)
			(type solid)
		)
		(fill yes)
		(layer "In4.Cu")
		(net "M_J_CPU0_SA_CB<7>")
	)
	(gr_poly
		(pts
			(xy 385.664964 -247.926098) (xy 385.564888 -247.826022) (xy 385.464812 -247.926098) (xy 385.464812 -247.970548)
			(xy 385.664964 -247.970548)
		)
		(stroke
			(width 0)
			(type solid)
		)
		(fill yes)
		(layer "In4.Cu")
		(net "M_J_CPU0_SA_CB<4>")
	)
	(gr_poly
		(pts
			(xy 385.664964 -247.522492) (xy 385.664964 -247.47474) (xy 385.464812 -247.47474) (xy 385.464812 -247.522492)
			(xy 385.564888 -247.622314)
		)
		(stroke
			(width 0)
			(type solid)
		)
		(fill yes)
		(layer "In4.Cu")
		(net "M_J_CPU0_SA_DQS_DP<9>")
	)
	(gr_poly
		(pts
			(xy 385.664964 -246.305832) (xy 385.564888 -246.20601) (xy 385.464812 -246.305832) (xy 385.464812 -246.353584)
			(xy 385.664964 -246.353584)
		)
		(stroke
			(width 0)
			(type solid)
		)
		(fill yes)
		(layer "In4.Cu")
		(net "M_J_CPU0_SA_DQS_DP<4>")
	)
	(gr_poly
		(pts
			(xy 385.664964 -245.902226) (xy 385.664964 -245.857776) (xy 385.464812 -245.857776) (xy 385.464812 -245.902226)
			(xy 385.564888 -246.002302)
		)
		(stroke
			(width 0)
			(type solid)
		)
		(fill yes)
		(layer "In4.Cu")
		(net "M_J_CPU0_SA_CB<3>")
	)
	(gr_poly
		(pts
			(xy 385.664964 -244.686074) (xy 385.564888 -244.585998) (xy 385.464812 -244.686074) (xy 385.464812 -244.730524)
			(xy 385.664964 -244.730524)
		)
		(stroke
			(width 0)
			(type solid)
		)
		(fill yes)
		(layer "In4.Cu")
		(net "M_J_CPU0_SA_CB<0>")
	)
	(gr_poly
		(pts
			(xy 385.664964 -244.282214) (xy 385.664964 -244.237764) (xy 385.464812 -244.237764) (xy 385.464812 -244.282214)
			(xy 385.564888 -244.38229)
		)
		(stroke
			(width 0)
			(type solid)
		)
		(fill yes)
		(layer "In4.Cu")
		(net "M_J_CPU0_SA_DQ<31>")
	)
	(gr_poly
		(pts
			(xy 385.664964 -243.066062) (xy 385.564888 -242.965986) (xy 385.464812 -243.066062) (xy 385.464812 -243.110512)
			(xy 385.664964 -243.110512)
		)
		(stroke
			(width 0)
			(type solid)
		)
		(fill yes)
		(layer "In4.Cu")
		(net "M_J_CPU0_SA_DQ<28>")
	)
	(gr_poly
		(pts
			(xy 385.664964 -242.662456) (xy 385.664964 -242.614704) (xy 385.464812 -242.614704) (xy 385.464812 -242.662456)
			(xy 385.564888 -242.762278)
		)
		(stroke
			(width 0)
			(type solid)
		)
		(fill yes)
		(layer "In4.Cu")
		(net "M_J_CPU0_SA_DQS_DP<8>")
	)
	(gr_poly
		(pts
			(xy 385.664964 -241.445796) (xy 385.564888 -241.345974) (xy 385.464812 -241.445796) (xy 385.464812 -241.493548)
			(xy 385.664964 -241.493548)
		)
		(stroke
			(width 0)
			(type solid)
		)
		(fill yes)
		(layer "In4.Cu")
		(net "M_J_CPU0_SA_DQS_DP<3>")
	)
	(gr_poly
		(pts
			(xy 385.664964 -241.04219) (xy 385.664964 -240.99774) (xy 385.464812 -240.99774) (xy 385.464812 -241.04219)
			(xy 385.564888 -241.142266)
		)
		(stroke
			(width 0)
			(type solid)
		)
		(fill yes)
		(layer "In4.Cu")
		(net "M_J_CPU0_SA_DQ<27>")
	)
	(gr_poly
		(pts
			(xy 385.664964 -239.826038) (xy 385.564888 -239.725962) (xy 385.464812 -239.826038) (xy 385.464812 -239.870488)
			(xy 385.664964 -239.870488)
		)
		(stroke
			(width 0)
			(type solid)
		)
		(fill yes)
		(layer "In4.Cu")
		(net "M_J_CPU0_SA_DQ<24>")
	)
	(gr_poly
		(pts
			(xy 385.664964 -239.422178) (xy 385.664964 -239.377728) (xy 385.464812 -239.377728) (xy 385.464812 -239.422178)
			(xy 385.564888 -239.522254)
		)
		(stroke
			(width 0)
			(type solid)
		)
		(fill yes)
		(layer "In4.Cu")
		(net "M_J_CPU0_SA_DQ<23>")
	)
	(gr_poly
		(pts
			(xy 385.664964 -238.206026) (xy 385.564888 -238.10595) (xy 385.464812 -238.206026) (xy 385.464812 -238.250476)
			(xy 385.664964 -238.250476)
		)
		(stroke
			(width 0)
			(type solid)
		)
		(fill yes)
		(layer "In4.Cu")
		(net "M_J_CPU0_SA_DQ<20>")
	)
	(gr_poly
		(pts
			(xy 385.664964 -237.80242) (xy 385.664964 -237.754668) (xy 385.464812 -237.754668) (xy 385.464812 -237.80242)
			(xy 385.564888 -237.902242)
		)
		(stroke
			(width 0)
			(type solid)
		)
		(fill yes)
		(layer "In4.Cu")
		(net "M_J_CPU0_SA_DQS_DP<7>")
	)
	(gr_poly
		(pts
			(xy 385.664964 -236.58576) (xy 385.564888 -236.485938) (xy 385.464812 -236.58576) (xy 385.464812 -236.633512)
			(xy 385.664964 -236.633512)
		)
		(stroke
			(width 0)
			(type solid)
		)
		(fill yes)
		(layer "In4.Cu")
		(net "M_J_CPU0_SA_DQS_DP<2>")
	)
	(gr_poly
		(pts
			(xy 385.664964 -236.182154) (xy 385.664964 -236.137704) (xy 385.464812 -236.137704) (xy 385.464812 -236.182154)
			(xy 385.564888 -236.28223)
		)
		(stroke
			(width 0)
			(type solid)
		)
		(fill yes)
		(layer "In4.Cu")
		(net "M_J_CPU0_SA_DQ<19>")
	)
	(gr_poly
		(pts
			(xy 385.664964 -234.966002) (xy 385.564888 -234.865926) (xy 385.464812 -234.966002) (xy 385.464812 -235.010452)
			(xy 385.664964 -235.010452)
		)
		(stroke
			(width 0)
			(type solid)
		)
		(fill yes)
		(layer "In4.Cu")
		(net "M_J_CPU0_SA_DQ<16>")
	)
	(gr_poly
		(pts
			(xy 385.664964 -234.562142) (xy 385.664964 -234.517692) (xy 385.464812 -234.517692) (xy 385.464812 -234.562142)
			(xy 385.564888 -234.662218)
		)
		(stroke
			(width 0)
			(type solid)
		)
		(fill yes)
		(layer "In4.Cu")
		(net "M_J_CPU0_SA_DQ<15>")
	)
	(gr_poly
		(pts
			(xy 385.664964 -233.34599) (xy 385.564888 -233.245914) (xy 385.464812 -233.34599) (xy 385.464812 -233.39044)
			(xy 385.664964 -233.39044)
		)
		(stroke
			(width 0)
			(type solid)
		)
		(fill yes)
		(layer "In4.Cu")
		(net "M_J_CPU0_SA_DQ<12>")
	)
	(gr_poly
		(pts
			(xy 385.664964 -232.942384) (xy 385.664964 -232.894632) (xy 385.464812 -232.894632) (xy 385.464812 -232.942384)
			(xy 385.564888 -233.042206)
		)
		(stroke
			(width 0)
			(type solid)
		)
		(fill yes)
		(layer "In4.Cu")
		(net "M_J_CPU0_SA_DQS_DP<6>")
	)
	(gr_poly
		(pts
			(xy 385.664964 -231.725724) (xy 385.564888 -231.625902) (xy 385.464812 -231.725724) (xy 385.464812 -231.773476)
			(xy 385.664964 -231.773476)
		)
		(stroke
			(width 0)
			(type solid)
		)
		(fill yes)
		(layer "In4.Cu")
		(net "M_J_CPU0_SA_DQS_DP<1>")
	)
	(gr_poly
		(pts
			(xy 385.664964 -231.322372) (xy 385.664964 -231.277922) (xy 385.464812 -231.277922) (xy 385.464812 -231.322372)
			(xy 385.564888 -231.422448)
		)
		(stroke
			(width 0)
			(type solid)
		)
		(fill yes)
		(layer "In4.Cu")
		(net "M_J_CPU0_SA_DQ<11>")
	)
	(gr_poly
		(pts
			(xy 385.664964 -230.105966) (xy 385.564888 -230.006144) (xy 385.464812 -230.105966) (xy 385.464812 -230.150416)
			(xy 385.664964 -230.150416)
		)
		(stroke
			(width 0)
			(type solid)
		)
		(fill yes)
		(layer "In4.Cu")
		(net "M_J_CPU0_SA_DQ<8>")
	)
	(gr_poly
		(pts
			(xy 385.664964 -229.70236) (xy 385.664964 -229.65791) (xy 385.464812 -229.65791) (xy 385.464812 -229.70236)
			(xy 385.564888 -229.802436)
		)
		(stroke
			(width 0)
			(type solid)
		)
		(fill yes)
		(layer "In4.Cu")
		(net "M_J_CPU0_SA_DQ<7>")
	)
	(gr_poly
		(pts
			(xy 385.664964 -228.486208) (xy 385.564888 -228.386132) (xy 385.464812 -228.486208) (xy 385.464812 -228.530658)
			(xy 385.664964 -228.530658)
		)
		(stroke
			(width 0)
			(type solid)
		)
		(fill yes)
		(layer "In4.Cu")
		(net "M_J_CPU0_SA_DQ<4>")
	)
	(gr_poly
		(pts
			(xy 385.664964 -228.082602) (xy 385.664964 -228.03485) (xy 385.464812 -228.03485) (xy 385.464812 -228.082602)
			(xy 385.564888 -228.182424)
		)
		(stroke
			(width 0)
			(type solid)
		)
		(fill yes)
		(layer "In4.Cu")
		(net "M_J_CPU0_SA_DQS_DP<5>")
	)
	(gr_poly
		(pts
			(xy 385.664964 -226.865942) (xy 385.564888 -226.76612) (xy 385.464812 -226.865942) (xy 385.464812 -226.913694)
			(xy 385.664964 -226.913694)
		)
		(stroke
			(width 0)
			(type solid)
		)
		(fill yes)
		(layer "In4.Cu")
		(net "M_J_CPU0_SA_DQS_DP<0>")
	)
	(gr_poly
		(pts
			(xy 385.664964 -226.462336) (xy 385.664964 -226.417886) (xy 385.464812 -226.417886) (xy 385.464812 -226.462336)
			(xy 385.564888 -226.562412)
		)
		(stroke
			(width 0)
			(type solid)
		)
		(fill yes)
		(layer "In4.Cu")
		(net "M_J_CPU0_SA_DQ<3>")
	)
	(gr_poly
		(pts
			(xy 385.664964 -225.246184) (xy 385.564888 -225.146108) (xy 385.464812 -225.246184) (xy 385.464812 -225.290634)
			(xy 385.664964 -225.290634)
		)
		(stroke
			(width 0)
			(type solid)
		)
		(fill yes)
		(layer "In4.Cu")
		(net "M_J_CPU0_SA_DQ<0>")
	)
	(gr_poly
		(pts
			(xy 385.964938 -292.91788) (xy 385.864862 -292.817804) (xy 385.764786 -292.91788) (xy 385.764786 -292.96233)
			(xy 385.964938 -292.96233)
		)
		(stroke
			(width 0)
			(type solid)
		)
		(fill yes)
		(layer "In4.Cu")
		(net "M_J_CPU0_SB_DQ<29>")
	)
	(gr_poly
		(pts
			(xy 385.964938 -292.51402) (xy 385.964938 -292.46957) (xy 385.764786 -292.46957) (xy 385.764786 -292.51402)
			(xy 385.864862 -292.614096)
		)
		(stroke
			(width 0)
			(type solid)
		)
		(fill yes)
		(layer "In4.Cu")
		(net "M_J_CPU0_SB_DQ<30>")
	)
	(gr_poly
		(pts
			(xy 385.964938 -291.297614) (xy 385.864862 -291.197792) (xy 385.764786 -291.297614) (xy 385.764786 -291.345366)
			(xy 385.964938 -291.345366)
		)
		(stroke
			(width 0)
			(type solid)
		)
		(fill yes)
		(layer "In4.Cu")
		(net "M_J_CPU0_SB_DQS_DN<8>")
	)
	(gr_poly
		(pts
			(xy 385.964938 -290.894262) (xy 385.964938 -290.84651) (xy 385.764786 -290.84651) (xy 385.764786 -290.894262)
			(xy 385.864862 -290.994084)
		)
		(stroke
			(width 0)
			(type solid)
		)
		(fill yes)
		(layer "In4.Cu")
		(net "M_J_CPU0_SB_DQS_DN<3>")
	)
	(gr_poly
		(pts
			(xy 385.964938 -289.677856) (xy 385.864862 -289.57778) (xy 385.764786 -289.677856) (xy 385.764786 -289.722306)
			(xy 385.964938 -289.722306)
		)
		(stroke
			(width 0)
			(type solid)
		)
		(fill yes)
		(layer "In4.Cu")
		(net "M_J_CPU0_SB_DQ<25>")
	)
	(gr_poly
		(pts
			(xy 385.964938 -289.273996) (xy 385.964938 -289.229546) (xy 385.764786 -289.229546) (xy 385.764786 -289.273996)
			(xy 385.864862 -289.374072)
		)
		(stroke
			(width 0)
			(type solid)
		)
		(fill yes)
		(layer "In4.Cu")
		(net "M_J_CPU0_SB_DQ<26>")
	)
	(gr_poly
		(pts
			(xy 385.964938 -288.057844) (xy 385.864862 -287.957768) (xy 385.764786 -288.057844) (xy 385.764786 -288.102294)
			(xy 385.964938 -288.102294)
		)
		(stroke
			(width 0)
			(type solid)
		)
		(fill yes)
		(layer "In4.Cu")
		(net "M_J_CPU0_SB_DQ<21>")
	)
	(gr_poly
		(pts
			(xy 385.964938 -287.654238) (xy 385.964938 -287.609788) (xy 385.764786 -287.609788) (xy 385.764786 -287.654238)
			(xy 385.864862 -287.75406)
		)
		(stroke
			(width 0)
			(type solid)
		)
		(fill yes)
		(layer "In4.Cu")
		(net "M_J_CPU0_SB_DQ<22>")
	)
	(gr_poly
		(pts
			(xy 385.964938 -286.437832) (xy 385.864862 -286.337756) (xy 385.764786 -286.437832) (xy 385.764786 -286.485584)
			(xy 385.964938 -286.485584)
		)
		(stroke
			(width 0)
			(type solid)
		)
		(fill yes)
		(layer "In4.Cu")
		(net "M_J_CPU0_SB_DQS_DN<7>")
	)
	(gr_poly
		(pts
			(xy 385.964938 -286.03448) (xy 385.964938 -285.986728) (xy 385.764786 -285.986728) (xy 385.764786 -286.03448)
			(xy 385.864862 -286.134302)
		)
		(stroke
			(width 0)
			(type solid)
		)
		(fill yes)
		(layer "In4.Cu")
		(net "M_J_CPU0_SB_DQS_DN<2>")
	)
	(gr_poly
		(pts
			(xy 385.964938 -284.818074) (xy 385.864862 -284.717998) (xy 385.764786 -284.818074) (xy 385.764786 -284.862524)
			(xy 385.964938 -284.862524)
		)
		(stroke
			(width 0)
			(type solid)
		)
		(fill yes)
		(layer "In4.Cu")
		(net "M_J_CPU0_SB_DQ<17>")
	)
	(gr_poly
		(pts
			(xy 385.964938 -284.414214) (xy 385.964938 -284.369764) (xy 385.764786 -284.369764) (xy 385.764786 -284.414214)
			(xy 385.864862 -284.51429)
		)
		(stroke
			(width 0)
			(type solid)
		)
		(fill yes)
		(layer "In4.Cu")
		(net "M_J_CPU0_SB_DQ<18>")
	)
	(gr_poly
		(pts
			(xy 385.964938 -283.198062) (xy 385.864862 -283.097986) (xy 385.764786 -283.198062) (xy 385.764786 -283.242512)
			(xy 385.964938 -283.242512)
		)
		(stroke
			(width 0)
			(type solid)
		)
		(fill yes)
		(layer "In4.Cu")
		(net "M_J_CPU0_SB_DQ<13>")
	)
	(gr_poly
		(pts
			(xy 385.964938 -282.794202) (xy 385.964938 -282.749752) (xy 385.764786 -282.749752) (xy 385.764786 -282.794202)
			(xy 385.864862 -282.894278)
		)
		(stroke
			(width 0)
			(type solid)
		)
		(fill yes)
		(layer "In4.Cu")
		(net "M_J_CPU0_SB_DQ<14>")
	)
	(gr_poly
		(pts
			(xy 385.964938 -281.577796) (xy 385.864862 -281.477974) (xy 385.764786 -281.577796) (xy 385.764786 -281.625548)
			(xy 385.964938 -281.625548)
		)
		(stroke
			(width 0)
			(type solid)
		)
		(fill yes)
		(layer "In4.Cu")
		(net "M_J_CPU0_SB_DQS_DN<6>")
	)
	(gr_poly
		(pts
			(xy 385.964938 -281.174444) (xy 385.964938 -281.126692) (xy 385.764786 -281.126692) (xy 385.764786 -281.174444)
			(xy 385.864862 -281.274266)
		)
		(stroke
			(width 0)
			(type solid)
		)
		(fill yes)
		(layer "In4.Cu")
		(net "M_J_CPU0_SB_DQS_DN<1>")
	)
	(gr_poly
		(pts
			(xy 385.964938 -279.958038) (xy 385.864862 -279.857962) (xy 385.764786 -279.958038) (xy 385.764786 -280.002488)
			(xy 385.964938 -280.002488)
		)
		(stroke
			(width 0)
			(type solid)
		)
		(fill yes)
		(layer "In4.Cu")
		(net "M_J_CPU0_SB_DQ<9>")
	)
	(gr_poly
		(pts
			(xy 385.964938 -279.554178) (xy 385.964938 -279.509728) (xy 385.764786 -279.509728) (xy 385.764786 -279.554178)
			(xy 385.864862 -279.654254)
		)
		(stroke
			(width 0)
			(type solid)
		)
		(fill yes)
		(layer "In4.Cu")
		(net "M_J_CPU0_SB_DQ<10>")
	)
	(gr_poly
		(pts
			(xy 385.964938 -278.338026) (xy 385.864862 -278.23795) (xy 385.764786 -278.338026) (xy 385.764786 -278.382476)
			(xy 385.964938 -278.382476)
		)
		(stroke
			(width 0)
			(type solid)
		)
		(fill yes)
		(layer "In4.Cu")
		(net "M_J_CPU0_SB_DQ<5>")
	)
	(gr_poly
		(pts
			(xy 385.964938 -277.934166) (xy 385.964938 -277.889716) (xy 385.764786 -277.889716) (xy 385.764786 -277.934166)
			(xy 385.864862 -278.034242)
		)
		(stroke
			(width 0)
			(type solid)
		)
		(fill yes)
		(layer "In4.Cu")
		(net "M_J_CPU0_SB_DQ<6>")
	)
	(gr_poly
		(pts
			(xy 385.964938 -276.71776) (xy 385.864862 -276.617938) (xy 385.764786 -276.71776) (xy 385.764786 -276.765512)
			(xy 385.964938 -276.765512)
		)
		(stroke
			(width 0)
			(type solid)
		)
		(fill yes)
		(layer "In4.Cu")
		(net "M_J_CPU0_SB_DQS_DN<5>")
	)
	(gr_poly
		(pts
			(xy 385.964938 -276.314408) (xy 385.964938 -276.266656) (xy 385.764786 -276.266656) (xy 385.764786 -276.314408)
			(xy 385.864862 -276.41423)
		)
		(stroke
			(width 0)
			(type solid)
		)
		(fill yes)
		(layer "In4.Cu")
		(net "M_J_CPU0_SB_DQS_DN<0>")
	)
	(gr_poly
		(pts
			(xy 385.964938 -275.098002) (xy 385.864862 -274.997926) (xy 385.764786 -275.098002) (xy 385.764786 -275.142452)
			(xy 385.964938 -275.142452)
		)
		(stroke
			(width 0)
			(type solid)
		)
		(fill yes)
		(layer "In4.Cu")
		(net "M_J_CPU0_SB_DQ<1>")
	)
	(gr_poly
		(pts
			(xy 385.964938 -274.694142) (xy 385.964938 -274.649692) (xy 385.764786 -274.649692) (xy 385.764786 -274.694142)
			(xy 385.864862 -274.794218)
		)
		(stroke
			(width 0)
			(type solid)
		)
		(fill yes)
		(layer "In4.Cu")
		(net "M_J_CPU0_SB_DQ<2>")
	)
	(gr_poly
		(pts
			(xy 385.964938 -273.47799) (xy 385.864862 -273.377914) (xy 385.764786 -273.47799) (xy 385.764786 -273.52244)
			(xy 385.964938 -273.52244)
		)
		(stroke
			(width 0)
			(type solid)
		)
		(fill yes)
		(layer "In4.Cu")
		(net "M_J_CPU0_SB_CB<1>")
	)
	(gr_poly
		(pts
			(xy 385.964938 -273.07413) (xy 385.964938 -273.02968) (xy 385.764786 -273.02968) (xy 385.764786 -273.07413)
			(xy 385.864862 -273.174206)
		)
		(stroke
			(width 0)
			(type solid)
		)
		(fill yes)
		(layer "In4.Cu")
		(net "M_J_CPU0_SB_CB<2>")
	)
	(gr_poly
		(pts
			(xy 385.964938 -271.857724) (xy 385.864862 -271.757902) (xy 385.764786 -271.857724) (xy 385.764786 -271.905476)
			(xy 385.964938 -271.905476)
		)
		(stroke
			(width 0)
			(type solid)
		)
		(fill yes)
		(layer "In4.Cu")
		(net "M_J_CPU0_SB_DQS_DN<4>")
	)
	(gr_poly
		(pts
			(xy 385.964938 -271.454372) (xy 385.964938 -271.40662) (xy 385.764786 -271.40662) (xy 385.764786 -271.454372)
			(xy 385.864862 -271.554194)
		)
		(stroke
			(width 0)
			(type solid)
		)
		(fill yes)
		(layer "In4.Cu")
		(net "M_J_CPU0_SB_DQS_DN<9>")
	)
	(gr_poly
		(pts
			(xy 385.964938 -270.237966) (xy 385.864862 -270.13789) (xy 385.764786 -270.237966) (xy 385.764786 -270.282416)
			(xy 385.964938 -270.282416)
		)
		(stroke
			(width 0)
			(type solid)
		)
		(fill yes)
		(layer "In4.Cu")
		(net "M_J_CPU0_SB_CB<5>")
	)
	(gr_poly
		(pts
			(xy 385.964938 -269.834106) (xy 385.964938 -269.789656) (xy 385.764786 -269.789656) (xy 385.764786 -269.834106)
			(xy 385.864862 -269.934182)
		)
		(stroke
			(width 0)
			(type solid)
		)
		(fill yes)
		(layer "In4.Cu")
		(net "M_J_CPU0_SB_CB<6>")
	)
	(gr_poly
		(pts
			(xy 385.964938 -266.997942) (xy 385.864862 -266.897866) (xy 385.764786 -266.997942) (xy 385.764786 -267.042392)
			(xy 385.964938 -267.042392)
		)
		(stroke
			(width 0)
			(type solid)
		)
		(fill yes)
		(layer "In4.Cu")
		(net "M_J_CPU0_SA_RSP<0>")
	)
	(gr_poly
		(pts
			(xy 385.964938 -266.594082) (xy 385.964938 -266.549632) (xy 385.764786 -266.549632) (xy 385.764786 -266.594082)
			(xy 385.864862 -266.694158)
		)
		(stroke
			(width 0)
			(type solid)
		)
		(fill yes)
		(layer "In4.Cu")
		(net "M_J_CPU0_SB_CS_N<1>")
	)
	(gr_poly
		(pts
			(xy 385.964938 -265.37793) (xy 385.864862 -265.277854) (xy 385.764786 -265.37793) (xy 385.764786 -265.42238)
			(xy 385.964938 -265.42238)
		)
		(stroke
			(width 0)
			(type solid)
		)
		(fill yes)
		(layer "In4.Cu")
		(net "M_J_CPU0_SB_PAR")
	)
	(gr_poly
		(pts
			(xy 385.964938 -263.757918) (xy 385.864862 -263.657842) (xy 385.764786 -263.757918) (xy 385.764786 -263.802368)
			(xy 385.964938 -263.802368)
		)
		(stroke
			(width 0)
			(type solid)
		)
		(fill yes)
		(layer "In4.Cu")
		(net "M_J_CPU0_SB_CA<4>")
	)
	(gr_poly
		(pts
			(xy 385.964938 -263.354058) (xy 385.964938 -263.309608) (xy 385.764786 -263.309608) (xy 385.764786 -263.354058)
			(xy 385.864862 -263.454134)
		)
		(stroke
			(width 0)
			(type solid)
		)
		(fill yes)
		(layer "In4.Cu")
		(net "M_J_CPU0_SB_CA<3>")
	)
	(gr_poly
		(pts
			(xy 385.964938 -262.137906) (xy 385.864862 -262.03783) (xy 385.764786 -262.137906) (xy 385.764786 -262.182356)
			(xy 385.964938 -262.182356)
		)
		(stroke
			(width 0)
			(type solid)
		)
		(fill yes)
		(layer "In4.Cu")
		(net "M_J_CPU0_SB_CA<0>")
	)
	(gr_poly
		(pts
			(xy 386.134864 -256.432558) (xy 386.134864 -256.384806) (xy 385.934712 -256.384806) (xy 385.934712 -256.432558)
			(xy 386.034788 -256.53238)
		)
		(stroke
			(width 0)
			(type solid)
		)
		(fill yes)
		(layer "In4.Cu")
		(net "M_J_CPU0_CLK_DN<0>")
	)
	(gr_poly
		(pts
			(xy 386.134864 -255.216152) (xy 386.034788 -255.116076) (xy 385.934712 -255.216152) (xy 385.934712 -255.260602)
			(xy 386.134864 -255.260602)
		)
		(stroke
			(width 0)
			(type solid)
		)
		(fill yes)
		(layer "In4.Cu")
		(net "M_J_CPU0_SA_CA<6>")
	)
	(gr_poly
		(pts
			(xy 386.134864 -254.812292) (xy 386.134864 -254.767842) (xy 385.934712 -254.767842) (xy 385.934712 -254.812292)
			(xy 386.034788 -254.912368)
		)
		(stroke
			(width 0)
			(type solid)
		)
		(fill yes)
		(layer "In4.Cu")
		(net "M_J_CPU0_SA_CA<5>")
	)
	(gr_poly
		(pts
			(xy 386.134864 -253.59614) (xy 386.034788 -253.496064) (xy 385.934712 -253.59614) (xy 385.934712 -253.64059)
			(xy 386.134864 -253.64059)
		)
		(stroke
			(width 0)
			(type solid)
		)
		(fill yes)
		(layer "In4.Cu")
		(net "M_J_CPU0_SA_CA<2>")
	)
	(gr_poly
		(pts
			(xy 386.134864 -253.19228) (xy 386.134864 -253.14783) (xy 385.934712 -253.14783) (xy 385.934712 -253.19228)
			(xy 386.034788 -253.292356)
		)
		(stroke
			(width 0)
			(type solid)
		)
		(fill yes)
		(layer "In4.Cu")
		(net "M_J_CPU0_SA_CA<1>")
	)
	(gr_poly
		(pts
			(xy 386.134864 -251.976128) (xy 386.034788 -251.876052) (xy 385.934712 -251.976128) (xy 385.934712 -252.020578)
			(xy 386.134864 -252.020578)
		)
		(stroke
			(width 0)
			(type solid)
		)
		(fill yes)
		(layer "In4.Cu")
		(net "M_J_CPU0_SA_CS_N<1>")
	)
	(gr_poly
		(pts
			(xy 386.134864 -250.356116) (xy 386.034788 -250.25604) (xy 385.934712 -250.356116) (xy 385.934712 -250.400566)
			(xy 386.134864 -250.400566)
		)
		(stroke
			(width 0)
			(type solid)
		)
		(fill yes)
		(layer "In4.Cu")
		(net "M_J_CPU0_ALERT_R_N")
	)
	(gr_poly
		(pts
			(xy 386.134864 -248.736104) (xy 386.034788 -248.636028) (xy 385.934712 -248.736104) (xy 385.934712 -248.780554)
			(xy 386.134864 -248.780554)
		)
		(stroke
			(width 0)
			(type solid)
		)
		(fill yes)
		(layer "In4.Cu")
		(net "M_J_CPU0_SA_CB<5>")
	)
	(gr_poly
		(pts
			(xy 386.134864 -248.332244) (xy 386.134864 -248.287794) (xy 385.934712 -248.287794) (xy 385.934712 -248.332244)
			(xy 386.034788 -248.43232)
		)
		(stroke
			(width 0)
			(type solid)
		)
		(fill yes)
		(layer "In4.Cu")
		(net "M_J_CPU0_SA_CB<6>")
	)
	(gr_poly
		(pts
			(xy 386.134864 -247.115838) (xy 386.034788 -247.016016) (xy 385.934712 -247.115838) (xy 385.934712 -247.16359)
			(xy 386.134864 -247.16359)
		)
		(stroke
			(width 0)
			(type solid)
		)
		(fill yes)
		(layer "In4.Cu")
		(net "M_J_CPU0_SA_DQS_DN<9>")
	)
	(gr_poly
		(pts
			(xy 386.134864 -246.712486) (xy 386.134864 -246.664734) (xy 385.934712 -246.664734) (xy 385.934712 -246.712486)
			(xy 386.034788 -246.812308)
		)
		(stroke
			(width 0)
			(type solid)
		)
		(fill yes)
		(layer "In4.Cu")
		(net "M_J_CPU0_SA_DQS_DN<4>")
	)
	(gr_poly
		(pts
			(xy 386.134864 -245.49608) (xy 386.034788 -245.396004) (xy 385.934712 -245.49608) (xy 385.934712 -245.54053)
			(xy 386.134864 -245.54053)
		)
		(stroke
			(width 0)
			(type solid)
		)
		(fill yes)
		(layer "In4.Cu")
		(net "M_J_CPU0_SA_CB<1>")
	)
	(gr_poly
		(pts
			(xy 386.134864 -245.09222) (xy 386.134864 -245.04777) (xy 385.934712 -245.04777) (xy 385.934712 -245.09222)
			(xy 386.034788 -245.192296)
		)
		(stroke
			(width 0)
			(type solid)
		)
		(fill yes)
		(layer "In4.Cu")
		(net "M_J_CPU0_SA_CB<2>")
	)
	(gr_poly
		(pts
			(xy 386.134864 -243.876068) (xy 386.034788 -243.775992) (xy 385.934712 -243.876068) (xy 385.934712 -243.920518)
			(xy 386.134864 -243.920518)
		)
		(stroke
			(width 0)
			(type solid)
		)
		(fill yes)
		(layer "In4.Cu")
		(net "M_J_CPU0_SA_DQ<29>")
	)
	(gr_poly
		(pts
			(xy 386.134864 -243.472208) (xy 386.134864 -243.427758) (xy 385.934712 -243.427758) (xy 385.934712 -243.472208)
			(xy 386.034788 -243.572284)
		)
		(stroke
			(width 0)
			(type solid)
		)
		(fill yes)
		(layer "In4.Cu")
		(net "M_J_CPU0_SA_DQ<30>")
	)
	(gr_poly
		(pts
			(xy 386.134864 -242.255802) (xy 386.034788 -242.15598) (xy 385.934712 -242.255802) (xy 385.934712 -242.303554)
			(xy 386.134864 -242.303554)
		)
		(stroke
			(width 0)
			(type solid)
		)
		(fill yes)
		(layer "In4.Cu")
		(net "M_J_CPU0_SA_DQS_DN<8>")
	)
	(gr_poly
		(pts
			(xy 386.134864 -241.85245) (xy 386.134864 -241.804698) (xy 385.934712 -241.804698) (xy 385.934712 -241.85245)
			(xy 386.034788 -241.952272)
		)
		(stroke
			(width 0)
			(type solid)
		)
		(fill yes)
		(layer "In4.Cu")
		(net "M_J_CPU0_SA_DQS_DN<3>")
	)
	(gr_poly
		(pts
			(xy 386.134864 -240.636044) (xy 386.034788 -240.535968) (xy 385.934712 -240.636044) (xy 385.934712 -240.680494)
			(xy 386.134864 -240.680494)
		)
		(stroke
			(width 0)
			(type solid)
		)
		(fill yes)
		(layer "In4.Cu")
		(net "M_J_CPU0_SA_DQ<25>")
	)
	(gr_poly
		(pts
			(xy 386.134864 -240.232184) (xy 386.134864 -240.187734) (xy 385.934712 -240.187734) (xy 385.934712 -240.232184)
			(xy 386.034788 -240.33226)
		)
		(stroke
			(width 0)
			(type solid)
		)
		(fill yes)
		(layer "In4.Cu")
		(net "M_J_CPU0_SA_DQ<26>")
	)
	(gr_poly
		(pts
			(xy 386.134864 -239.016032) (xy 386.034788 -238.915956) (xy 385.934712 -239.016032) (xy 385.934712 -239.060482)
			(xy 386.134864 -239.060482)
		)
		(stroke
			(width 0)
			(type solid)
		)
		(fill yes)
		(layer "In4.Cu")
		(net "M_J_CPU0_SA_DQ<21>")
	)
	(gr_poly
		(pts
			(xy 386.134864 -238.612172) (xy 386.134864 -238.567722) (xy 385.934712 -238.567722) (xy 385.934712 -238.612172)
			(xy 386.034788 -238.712248)
		)
		(stroke
			(width 0)
			(type solid)
		)
		(fill yes)
		(layer "In4.Cu")
		(net "M_J_CPU0_SA_DQ<22>")
	)
	(gr_poly
		(pts
			(xy 386.134864 -237.395766) (xy 386.034788 -237.295944) (xy 385.934712 -237.395766) (xy 385.934712 -237.443518)
			(xy 386.134864 -237.443518)
		)
		(stroke
			(width 0)
			(type solid)
		)
		(fill yes)
		(layer "In4.Cu")
		(net "M_J_CPU0_SA_DQS_DN<7>")
	)
	(gr_poly
		(pts
			(xy 386.134864 -236.992414) (xy 386.134864 -236.944662) (xy 385.934712 -236.944662) (xy 385.934712 -236.992414)
			(xy 386.034788 -237.092236)
		)
		(stroke
			(width 0)
			(type solid)
		)
		(fill yes)
		(layer "In4.Cu")
		(net "M_J_CPU0_SA_DQS_DN<2>")
	)
	(gr_poly
		(pts
			(xy 386.134864 -235.776008) (xy 386.034788 -235.675932) (xy 385.934712 -235.776008) (xy 385.934712 -235.820458)
			(xy 386.134864 -235.820458)
		)
		(stroke
			(width 0)
			(type solid)
		)
		(fill yes)
		(layer "In4.Cu")
		(net "M_J_CPU0_SA_DQ<17>")
	)
	(gr_poly
		(pts
			(xy 386.134864 -235.372148) (xy 386.134864 -235.327698) (xy 385.934712 -235.327698) (xy 385.934712 -235.372148)
			(xy 386.034788 -235.472224)
		)
		(stroke
			(width 0)
			(type solid)
		)
		(fill yes)
		(layer "In4.Cu")
		(net "M_J_CPU0_SA_DQ<18>")
	)
	(gr_poly
		(pts
			(xy 386.134864 -234.155996) (xy 386.034788 -234.05592) (xy 385.934712 -234.155996) (xy 385.934712 -234.200446)
			(xy 386.134864 -234.200446)
		)
		(stroke
			(width 0)
			(type solid)
		)
		(fill yes)
		(layer "In4.Cu")
		(net "M_J_CPU0_SA_DQ<13>")
	)
	(gr_poly
		(pts
			(xy 386.134864 -233.752136) (xy 386.134864 -233.707686) (xy 385.934712 -233.707686) (xy 385.934712 -233.752136)
			(xy 386.034788 -233.852212)
		)
		(stroke
			(width 0)
			(type solid)
		)
		(fill yes)
		(layer "In4.Cu")
		(net "M_J_CPU0_SA_DQ<14>")
	)
	(gr_poly
		(pts
			(xy 386.134864 -232.53573) (xy 386.034788 -232.435908) (xy 385.934712 -232.53573) (xy 385.934712 -232.583482)
			(xy 386.134864 -232.583482)
		)
		(stroke
			(width 0)
			(type solid)
		)
		(fill yes)
		(layer "In4.Cu")
		(net "M_J_CPU0_SA_DQS_DN<6>")
	)
	(gr_poly
		(pts
			(xy 386.134864 -232.132378) (xy 386.134864 -232.084626) (xy 385.934712 -232.084626) (xy 385.934712 -232.132378)
			(xy 386.034788 -232.2322)
		)
		(stroke
			(width 0)
			(type solid)
		)
		(fill yes)
		(layer "In4.Cu")
		(net "M_J_CPU0_SA_DQS_DN<1>")
	)
	(gr_poly
		(pts
			(xy 386.134864 -230.915972) (xy 386.034788 -230.815896) (xy 385.934712 -230.915972) (xy 385.934712 -230.960422)
			(xy 386.134864 -230.960422)
		)
		(stroke
			(width 0)
			(type solid)
		)
		(fill yes)
		(layer "In4.Cu")
		(net "M_J_CPU0_SA_DQ<9>")
	)
	(gr_poly
		(pts
			(xy 386.134864 -230.512366) (xy 386.134864 -230.467916) (xy 385.934712 -230.467916) (xy 385.934712 -230.512366)
			(xy 386.034788 -230.612188)
		)
		(stroke
			(width 0)
			(type solid)
		)
		(fill yes)
		(layer "In4.Cu")
		(net "M_J_CPU0_SA_DQ<10>")
	)
	(gr_poly
		(pts
			(xy 386.134864 -229.29596) (xy 386.034788 -229.195884) (xy 385.934712 -229.29596) (xy 385.934712 -229.34041)
			(xy 386.134864 -229.34041)
		)
		(stroke
			(width 0)
			(type solid)
		)
		(fill yes)
		(layer "In4.Cu")
		(net "M_J_CPU0_SA_DQ<5>")
	)
	(gr_poly
		(pts
			(xy 386.134864 -228.892354) (xy 386.134864 -228.847904) (xy 385.934712 -228.847904) (xy 385.934712 -228.892354)
			(xy 386.034788 -228.99243)
		)
		(stroke
			(width 0)
			(type solid)
		)
		(fill yes)
		(layer "In4.Cu")
		(net "M_J_CPU0_SA_DQ<6>")
	)
	(gr_poly
		(pts
			(xy 386.134864 -227.675948) (xy 386.034788 -227.576126) (xy 385.934712 -227.675948) (xy 385.934712 -227.7237)
			(xy 386.134864 -227.7237)
		)
		(stroke
			(width 0)
			(type solid)
		)
		(fill yes)
		(layer "In4.Cu")
		(net "M_J_CPU0_SA_DQS_DN<5>")
	)
	(gr_poly
		(pts
			(xy 386.134864 -227.272596) (xy 386.134864 -227.224844) (xy 385.934712 -227.224844) (xy 385.934712 -227.272596)
			(xy 386.034788 -227.372418)
		)
		(stroke
			(width 0)
			(type solid)
		)
		(fill yes)
		(layer "In4.Cu")
		(net "M_J_CPU0_SA_DQS_DN<0>")
	)
	(gr_poly
		(pts
			(xy 386.134864 -226.05619) (xy 386.034788 -225.956114) (xy 385.934712 -226.05619) (xy 385.934712 -226.10064)
			(xy 386.134864 -226.10064)
		)
		(stroke
			(width 0)
			(type solid)
		)
		(fill yes)
		(layer "In4.Cu")
		(net "M_J_CPU0_SA_DQ<1>")
	)
	(gr_poly
		(pts
			(xy 386.134864 -225.65233) (xy 386.134864 -225.60788) (xy 385.934712 -225.60788) (xy 385.934712 -225.65233)
			(xy 386.034788 -225.752406)
		)
		(stroke
			(width 0)
			(type solid)
		)
		(fill yes)
		(layer "In4.Cu")
		(net "M_J_CPU0_SA_DQ<2>")
	)
	(gr_poly
		(pts
			(xy 386.434838 -293.324026) (xy 386.434838 -293.279576) (xy 386.234686 -293.279576) (xy 386.234686 -293.324026)
			(xy 386.334762 -293.424102)
		)
		(stroke
			(width 0)
			(type solid)
		)
		(fill yes)
		(layer "In4.Cu")
		(net "M_J_CPU0_SB_DQ<31>")
	)
	(gr_poly
		(pts
			(xy 386.434838 -292.107874) (xy 386.334762 -292.007798) (xy 386.234686 -292.107874) (xy 386.234686 -292.152324)
			(xy 386.434838 -292.152324)
		)
		(stroke
			(width 0)
			(type solid)
		)
		(fill yes)
		(layer "In4.Cu")
		(net "M_J_CPU0_SB_DQ<28>")
	)
	(gr_poly
		(pts
			(xy 386.434838 -291.704268) (xy 386.434838 -291.656516) (xy 386.234686 -291.656516) (xy 386.234686 -291.704268)
			(xy 386.334762 -291.80409)
		)
		(stroke
			(width 0)
			(type solid)
		)
		(fill yes)
		(layer "In4.Cu")
		(net "M_J_CPU0_SB_DQS_DP<8>")
	)
	(gr_poly
		(pts
			(xy 386.434838 -290.487608) (xy 386.334762 -290.387786) (xy 386.234686 -290.487608) (xy 386.234686 -290.53536)
			(xy 386.434838 -290.53536)
		)
		(stroke
			(width 0)
			(type solid)
		)
		(fill yes)
		(layer "In4.Cu")
		(net "M_J_CPU0_SB_DQS_DP<3>")
	)
	(gr_poly
		(pts
			(xy 386.434838 -290.084002) (xy 386.434838 -290.039552) (xy 386.234686 -290.039552) (xy 386.234686 -290.084002)
			(xy 386.334762 -290.184078)
		)
		(stroke
			(width 0)
			(type solid)
		)
		(fill yes)
		(layer "In4.Cu")
		(net "M_J_CPU0_SB_DQ<27>")
	)
	(gr_poly
		(pts
			(xy 386.434838 -288.86785) (xy 386.334762 -288.767774) (xy 386.234686 -288.86785) (xy 386.234686 -288.9123)
			(xy 386.434838 -288.9123)
		)
		(stroke
			(width 0)
			(type solid)
		)
		(fill yes)
		(layer "In4.Cu")
		(net "M_J_CPU0_SB_DQ<24>")
	)
	(gr_poly
		(pts
			(xy 386.434838 -288.464244) (xy 386.434838 -288.419794) (xy 386.234686 -288.419794) (xy 386.234686 -288.464244)
			(xy 386.334762 -288.56432)
		)
		(stroke
			(width 0)
			(type solid)
		)
		(fill yes)
		(layer "In4.Cu")
		(net "M_J_CPU0_SB_DQ<23>")
	)
	(gr_poly
		(pts
			(xy 386.434838 -287.247838) (xy 386.334762 -287.148016) (xy 386.234686 -287.247838) (xy 386.234686 -287.292288)
			(xy 386.434838 -287.292288)
		)
		(stroke
			(width 0)
			(type solid)
		)
		(fill yes)
		(layer "In4.Cu")
		(net "M_J_CPU0_SB_DQ<20>")
	)
	(gr_poly
		(pts
			(xy 386.434838 -286.844232) (xy 386.434838 -286.79648) (xy 386.234686 -286.79648) (xy 386.234686 -286.844232)
			(xy 386.334762 -286.944308)
		)
		(stroke
			(width 0)
			(type solid)
		)
		(fill yes)
		(layer "In4.Cu")
		(net "M_J_CPU0_SB_DQS_DP<7>")
	)
	(gr_poly
		(pts
			(xy 386.434838 -285.627826) (xy 386.334762 -285.528004) (xy 386.234686 -285.627826) (xy 386.234686 -285.675578)
			(xy 386.434838 -285.675578)
		)
		(stroke
			(width 0)
			(type solid)
		)
		(fill yes)
		(layer "In4.Cu")
		(net "M_J_CPU0_SB_DQS_DP<2>")
	)
	(gr_poly
		(pts
			(xy 386.434838 -285.22422) (xy 386.434838 -285.17977) (xy 386.234686 -285.17977) (xy 386.234686 -285.22422)
			(xy 386.334762 -285.324296)
		)
		(stroke
			(width 0)
			(type solid)
		)
		(fill yes)
		(layer "In4.Cu")
		(net "M_J_CPU0_SB_DQ<19>")
	)
	(gr_poly
		(pts
			(xy 386.434838 -284.008068) (xy 386.334762 -283.907992) (xy 386.234686 -284.008068) (xy 386.234686 -284.052518)
			(xy 386.434838 -284.052518)
		)
		(stroke
			(width 0)
			(type solid)
		)
		(fill yes)
		(layer "In4.Cu")
		(net "M_J_CPU0_SB_DQ<16>")
	)
	(gr_poly
		(pts
			(xy 386.434838 -283.604208) (xy 386.434838 -283.559758) (xy 386.234686 -283.559758) (xy 386.234686 -283.604208)
			(xy 386.334762 -283.704284)
		)
		(stroke
			(width 0)
			(type solid)
		)
		(fill yes)
		(layer "In4.Cu")
		(net "M_J_CPU0_SB_DQ<15>")
	)
	(gr_poly
		(pts
			(xy 386.434838 -282.388056) (xy 386.334762 -282.28798) (xy 386.234686 -282.388056) (xy 386.234686 -282.432506)
			(xy 386.434838 -282.432506)
		)
		(stroke
			(width 0)
			(type solid)
		)
		(fill yes)
		(layer "In4.Cu")
		(net "M_J_CPU0_SB_DQ<12>")
	)
	(gr_poly
		(pts
			(xy 386.434838 -281.98445) (xy 386.434838 -281.936698) (xy 386.234686 -281.936698) (xy 386.234686 -281.98445)
			(xy 386.334762 -282.084272)
		)
		(stroke
			(width 0)
			(type solid)
		)
		(fill yes)
		(layer "In4.Cu")
		(net "M_J_CPU0_SB_DQS_DP<6>")
	)
	(gr_poly
		(pts
			(xy 386.434838 -280.76779) (xy 386.334762 -280.667968) (xy 386.234686 -280.76779) (xy 386.234686 -280.815542)
			(xy 386.434838 -280.815542)
		)
		(stroke
			(width 0)
			(type solid)
		)
		(fill yes)
		(layer "In4.Cu")
		(net "M_J_CPU0_SB_DQS_DP<1>")
	)
	(gr_poly
		(pts
			(xy 386.434838 -280.364184) (xy 386.434838 -280.319734) (xy 386.234686 -280.319734) (xy 386.234686 -280.364184)
			(xy 386.334762 -280.46426)
		)
		(stroke
			(width 0)
			(type solid)
		)
		(fill yes)
		(layer "In4.Cu")
		(net "M_J_CPU0_SB_DQ<11>")
	)
	(gr_poly
		(pts
			(xy 386.434838 -279.148032) (xy 386.334762 -279.047956) (xy 386.234686 -279.148032) (xy 386.234686 -279.192482)
			(xy 386.434838 -279.192482)
		)
		(stroke
			(width 0)
			(type solid)
		)
		(fill yes)
		(layer "In4.Cu")
		(net "M_J_CPU0_SB_DQ<8>")
	)
	(gr_poly
		(pts
			(xy 386.434838 -278.744172) (xy 386.434838 -278.699722) (xy 386.234686 -278.699722) (xy 386.234686 -278.744172)
			(xy 386.334762 -278.844248)
		)
		(stroke
			(width 0)
			(type solid)
		)
		(fill yes)
		(layer "In4.Cu")
		(net "M_J_CPU0_SB_DQ<7>")
	)
	(gr_poly
		(pts
			(xy 386.434838 -277.52802) (xy 386.334762 -277.427944) (xy 386.234686 -277.52802) (xy 386.234686 -277.57247)
			(xy 386.434838 -277.57247)
		)
		(stroke
			(width 0)
			(type solid)
		)
		(fill yes)
		(layer "In4.Cu")
		(net "M_J_CPU0_SB_DQ<4>")
	)
	(gr_poly
		(pts
			(xy 386.434838 -277.124414) (xy 386.434838 -277.076662) (xy 386.234686 -277.076662) (xy 386.234686 -277.124414)
			(xy 386.334762 -277.224236)
		)
		(stroke
			(width 0)
			(type solid)
		)
		(fill yes)
		(layer "In4.Cu")
		(net "M_J_CPU0_SB_DQS_DP<5>")
	)
	(gr_poly
		(pts
			(xy 386.434838 -275.907754) (xy 386.334762 -275.807932) (xy 386.234686 -275.907754) (xy 386.234686 -275.955506)
			(xy 386.434838 -275.955506)
		)
		(stroke
			(width 0)
			(type solid)
		)
		(fill yes)
		(layer "In4.Cu")
		(net "M_J_CPU0_SB_DQS_DP<0>")
	)
	(gr_poly
		(pts
			(xy 386.434838 -275.504148) (xy 386.434838 -275.459698) (xy 386.234686 -275.459698) (xy 386.234686 -275.504148)
			(xy 386.334762 -275.604224)
		)
		(stroke
			(width 0)
			(type solid)
		)
		(fill yes)
		(layer "In4.Cu")
		(net "M_J_CPU0_SB_DQ<3>")
	)
	(gr_poly
		(pts
			(xy 386.434838 -274.287996) (xy 386.334762 -274.18792) (xy 386.234686 -274.287996) (xy 386.234686 -274.332446)
			(xy 386.434838 -274.332446)
		)
		(stroke
			(width 0)
			(type solid)
		)
		(fill yes)
		(layer "In4.Cu")
		(net "M_J_CPU0_SB_DQ<0>")
	)
	(gr_poly
		(pts
			(xy 386.434838 -273.884136) (xy 386.434838 -273.839686) (xy 386.234686 -273.839686) (xy 386.234686 -273.884136)
			(xy 386.334762 -273.984212)
		)
		(stroke
			(width 0)
			(type solid)
		)
		(fill yes)
		(layer "In4.Cu")
		(net "M_J_CPU0_SB_CB<3>")
	)
	(gr_poly
		(pts
			(xy 386.434838 -272.667984) (xy 386.334762 -272.567908) (xy 386.234686 -272.667984) (xy 386.234686 -272.712434)
			(xy 386.434838 -272.712434)
		)
		(stroke
			(width 0)
			(type solid)
		)
		(fill yes)
		(layer "In4.Cu")
		(net "M_J_CPU0_SB_CB<0>")
	)
	(gr_poly
		(pts
			(xy 386.434838 -272.264378) (xy 386.434838 -272.216626) (xy 386.234686 -272.216626) (xy 386.234686 -272.264378)
			(xy 386.334762 -272.3642)
		)
		(stroke
			(width 0)
			(type solid)
		)
		(fill yes)
		(layer "In4.Cu")
		(net "M_J_CPU0_SB_DQS_DP<4>")
	)
	(gr_poly
		(pts
			(xy 386.434838 -271.047718) (xy 386.334762 -270.947896) (xy 386.234686 -271.047718) (xy 386.234686 -271.09547)
			(xy 386.434838 -271.09547)
		)
		(stroke
			(width 0)
			(type solid)
		)
		(fill yes)
		(layer "In4.Cu")
		(net "M_J_CPU0_SB_DQS_DP<9>")
	)
	(gr_poly
		(pts
			(xy 386.434838 -270.644112) (xy 386.434838 -270.599662) (xy 386.234686 -270.599662) (xy 386.234686 -270.644112)
			(xy 386.334762 -270.744188)
		)
		(stroke
			(width 0)
			(type solid)
		)
		(fill yes)
		(layer "In4.Cu")
		(net "M_J_CPU0_SB_CB<7>")
	)
	(gr_poly
		(pts
			(xy 386.434838 -269.42796) (xy 386.334762 -269.327884) (xy 386.234686 -269.42796) (xy 386.234686 -269.47241)
			(xy 386.434838 -269.47241)
		)
		(stroke
			(width 0)
			(type solid)
		)
		(fill yes)
		(layer "In4.Cu")
		(net "M_J_CPU0_SB_CB<4>")
	)
	(gr_poly
		(pts
			(xy 386.434838 -267.807948) (xy 386.334762 -267.707872) (xy 386.234686 -267.807948) (xy 386.234686 -267.852398)
			(xy 386.434838 -267.852398)
		)
		(stroke
			(width 0)
			(type solid)
		)
		(fill yes)
		(layer "In4.Cu")
		(net "M_J_CPU0_SB_RSP<0>")
	)
	(gr_poly
		(pts
			(xy 386.434838 -265.784076) (xy 386.434838 -265.739626) (xy 386.234686 -265.739626) (xy 386.234686 -265.784076)
			(xy 386.334762 -265.884152)
		)
		(stroke
			(width 0)
			(type solid)
		)
		(fill yes)
		(layer "In4.Cu")
		(net "M_J_CPU0_SB_CS_N<0>")
	)
	(gr_poly
		(pts
			(xy 386.434838 -264.567924) (xy 386.334762 -264.467848) (xy 386.234686 -264.567924) (xy 386.234686 -264.612374)
			(xy 386.434838 -264.612374)
		)
		(stroke
			(width 0)
			(type solid)
		)
		(fill yes)
		(layer "In4.Cu")
		(net "M_J_CPU0_SB_CA<6>")
	)
	(gr_poly
		(pts
			(xy 386.434838 -264.164064) (xy 386.434838 -264.119614) (xy 386.234686 -264.119614) (xy 386.234686 -264.164064)
			(xy 386.334762 -264.26414)
		)
		(stroke
			(width 0)
			(type solid)
		)
		(fill yes)
		(layer "In4.Cu")
		(net "M_J_CPU0_SB_CA<5>")
	)
	(gr_poly
		(pts
			(xy 386.434838 -262.947912) (xy 386.334762 -262.847836) (xy 386.234686 -262.947912) (xy 386.234686 -262.992362)
			(xy 386.434838 -262.992362)
		)
		(stroke
			(width 0)
			(type solid)
		)
		(fill yes)
		(layer "In4.Cu")
		(net "M_J_CPU0_SB_CA<2>")
	)
	(gr_poly
		(pts
			(xy 386.434838 -262.544052) (xy 386.434838 -262.499602) (xy 386.234686 -262.499602) (xy 386.234686 -262.544052)
			(xy 386.334762 -262.644128)
		)
		(stroke
			(width 0)
			(type solid)
		)
		(fill yes)
		(layer "In4.Cu")
		(net "M_J_CPU0_SB_CA<1>")
	)
	(gr_poly
		(pts
			(xy 386.605018 -256.025904) (xy 386.504942 -255.926082) (xy 386.404866 -256.025904) (xy 386.404866 -256.073656)
			(xy 386.605018 -256.073656)
		)
		(stroke
			(width 0)
			(type solid)
		)
		(fill yes)
		(layer "In4.Cu")
		(net "M_J_CPU0_CLK_DP<0>")
	)
	(gr_poly
		(pts
			(xy 386.605018 -255.622298) (xy 386.605018 -255.577848) (xy 386.404866 -255.577848) (xy 386.404866 -255.622298)
			(xy 386.504942 -255.722374)
		)
		(stroke
			(width 0)
			(type solid)
		)
		(fill yes)
		(layer "In4.Cu")
		(net "M_J_CPU0_SA_PAR")
	)
	(gr_poly
		(pts
			(xy 386.605018 -254.406146) (xy 386.504942 -254.30607) (xy 386.404866 -254.406146) (xy 386.404866 -254.450596)
			(xy 386.605018 -254.450596)
		)
		(stroke
			(width 0)
			(type solid)
		)
		(fill yes)
		(layer "In4.Cu")
		(net "M_J_CPU0_SA_CA<4>")
	)
	(gr_poly
		(pts
			(xy 386.605018 -254.002286) (xy 386.605018 -253.957836) (xy 386.404866 -253.957836) (xy 386.404866 -254.002286)
			(xy 386.504942 -254.102362)
		)
		(stroke
			(width 0)
			(type solid)
		)
		(fill yes)
		(layer "In4.Cu")
		(net "M_J_CPU0_SA_CA<3>")
	)
	(gr_poly
		(pts
			(xy 386.605018 -252.786134) (xy 386.504942 -252.686058) (xy 386.404866 -252.786134) (xy 386.404866 -252.830584)
			(xy 386.605018 -252.830584)
		)
		(stroke
			(width 0)
			(type solid)
		)
		(fill yes)
		(layer "In4.Cu")
		(net "M_J_CPU0_SA_CA<0>")
	)
	(gr_poly
		(pts
			(xy 386.605018 -251.166122) (xy 386.504942 -251.066046) (xy 386.404866 -251.166122) (xy 386.404866 -251.210572)
			(xy 386.605018 -251.210572)
		)
		(stroke
			(width 0)
			(type solid)
		)
		(fill yes)
		(layer "In4.Cu")
		(net "M_J_CPU0_SA_CS_N<0>")
	)
	(gr_poly
		(pts
			(xy 386.605018 -250.762262) (xy 386.605018 -250.717812) (xy 386.404866 -250.717812) (xy 386.404866 -250.762262)
			(xy 386.504942 -250.862338)
		)
		(stroke
			(width 0)
			(type solid)
		)
		(fill yes)
		(layer "In4.Cu")
		(net "M_J_CPU0_RESET_N")
	)
	(gr_poly
		(pts
			(xy 386.605018 -249.14225) (xy 386.605018 -249.0978) (xy 386.404866 -249.0978) (xy 386.404866 -249.14225)
			(xy 386.504942 -249.242326)
		)
		(stroke
			(width 0)
			(type solid)
		)
		(fill yes)
		(layer "In4.Cu")
		(net "M_J_CPU0_SA_CB<7>")
	)
	(gr_poly
		(pts
			(xy 386.605018 -247.926098) (xy 386.504942 -247.826022) (xy 386.404866 -247.926098) (xy 386.404866 -247.970548)
			(xy 386.605018 -247.970548)
		)
		(stroke
			(width 0)
			(type solid)
		)
		(fill yes)
		(layer "In4.Cu")
		(net "M_J_CPU0_SA_CB<4>")
	)
	(gr_poly
		(pts
			(xy 386.605018 -247.522492) (xy 386.605018 -247.47474) (xy 386.404866 -247.47474) (xy 386.404866 -247.522492)
			(xy 386.504942 -247.622314)
		)
		(stroke
			(width 0)
			(type solid)
		)
		(fill yes)
		(layer "In4.Cu")
		(net "M_J_CPU0_SA_DQS_DP<9>")
	)
	(gr_poly
		(pts
			(xy 386.605018 -246.305832) (xy 386.504942 -246.20601) (xy 386.404866 -246.305832) (xy 386.404866 -246.353584)
			(xy 386.605018 -246.353584)
		)
		(stroke
			(width 0)
			(type solid)
		)
		(fill yes)
		(layer "In4.Cu")
		(net "M_J_CPU0_SA_DQS_DP<4>")
	)
	(gr_poly
		(pts
			(xy 386.605018 -245.902226) (xy 386.605018 -245.857776) (xy 386.404866 -245.857776) (xy 386.404866 -245.902226)
			(xy 386.504942 -246.002302)
		)
		(stroke
			(width 0)
			(type solid)
		)
		(fill yes)
		(layer "In4.Cu")
		(net "M_J_CPU0_SA_CB<3>")
	)
	(gr_poly
		(pts
			(xy 386.605018 -244.686074) (xy 386.504942 -244.585998) (xy 386.404866 -244.686074) (xy 386.404866 -244.730524)
			(xy 386.605018 -244.730524)
		)
		(stroke
			(width 0)
			(type solid)
		)
		(fill yes)
		(layer "In4.Cu")
		(net "M_J_CPU0_SA_CB<0>")
	)
	(gr_poly
		(pts
			(xy 386.605018 -244.282214) (xy 386.605018 -244.237764) (xy 386.404866 -244.237764) (xy 386.404866 -244.282214)
			(xy 386.504942 -244.38229)
		)
		(stroke
			(width 0)
			(type solid)
		)
		(fill yes)
		(layer "In4.Cu")
		(net "M_J_CPU0_SA_DQ<31>")
	)
	(gr_poly
		(pts
			(xy 386.605018 -243.066062) (xy 386.504942 -242.965986) (xy 386.404866 -243.066062) (xy 386.404866 -243.110512)
			(xy 386.605018 -243.110512)
		)
		(stroke
			(width 0)
			(type solid)
		)
		(fill yes)
		(layer "In4.Cu")
		(net "M_J_CPU0_SA_DQ<28>")
	)
	(gr_poly
		(pts
			(xy 386.605018 -242.662456) (xy 386.605018 -242.614704) (xy 386.404866 -242.614704) (xy 386.404866 -242.662456)
			(xy 386.504942 -242.762278)
		)
		(stroke
			(width 0)
			(type solid)
		)
		(fill yes)
		(layer "In4.Cu")
		(net "M_J_CPU0_SA_DQS_DP<8>")
	)
	(gr_poly
		(pts
			(xy 386.605018 -241.445796) (xy 386.504942 -241.345974) (xy 386.404866 -241.445796) (xy 386.404866 -241.493548)
			(xy 386.605018 -241.493548)
		)
		(stroke
			(width 0)
			(type solid)
		)
		(fill yes)
		(layer "In4.Cu")
		(net "M_J_CPU0_SA_DQS_DP<3>")
	)
	(gr_poly
		(pts
			(xy 386.605018 -241.04219) (xy 386.605018 -240.99774) (xy 386.404866 -240.99774) (xy 386.404866 -241.04219)
			(xy 386.504942 -241.142266)
		)
		(stroke
			(width 0)
			(type solid)
		)
		(fill yes)
		(layer "In4.Cu")
		(net "M_J_CPU0_SA_DQ<27>")
	)
	(gr_poly
		(pts
			(xy 386.605018 -239.826038) (xy 386.504942 -239.725962) (xy 386.404866 -239.826038) (xy 386.404866 -239.870488)
			(xy 386.605018 -239.870488)
		)
		(stroke
			(width 0)
			(type solid)
		)
		(fill yes)
		(layer "In4.Cu")
		(net "M_J_CPU0_SA_DQ<24>")
	)
	(gr_poly
		(pts
			(xy 386.605018 -239.422178) (xy 386.605018 -239.377728) (xy 386.404866 -239.377728) (xy 386.404866 -239.422178)
			(xy 386.504942 -239.522254)
		)
		(stroke
			(width 0)
			(type solid)
		)
		(fill yes)
		(layer "In4.Cu")
		(net "M_J_CPU0_SA_DQ<23>")
	)
	(gr_poly
		(pts
			(xy 386.605018 -238.206026) (xy 386.504942 -238.10595) (xy 386.404866 -238.206026) (xy 386.404866 -238.250476)
			(xy 386.605018 -238.250476)
		)
		(stroke
			(width 0)
			(type solid)
		)
		(fill yes)
		(layer "In4.Cu")
		(net "M_J_CPU0_SA_DQ<20>")
	)
	(gr_poly
		(pts
			(xy 386.605018 -237.80242) (xy 386.605018 -237.754668) (xy 386.404866 -237.754668) (xy 386.404866 -237.80242)
			(xy 386.504942 -237.902242)
		)
		(stroke
			(width 0)
			(type solid)
		)
		(fill yes)
		(layer "In4.Cu")
		(net "M_J_CPU0_SA_DQS_DP<7>")
	)
	(gr_poly
		(pts
			(xy 386.605018 -236.58576) (xy 386.504942 -236.485938) (xy 386.404866 -236.58576) (xy 386.404866 -236.633512)
			(xy 386.605018 -236.633512)
		)
		(stroke
			(width 0)
			(type solid)
		)
		(fill yes)
		(layer "In4.Cu")
		(net "M_J_CPU0_SA_DQS_DP<2>")
	)
	(gr_poly
		(pts
			(xy 386.605018 -236.182154) (xy 386.605018 -236.137704) (xy 386.404866 -236.137704) (xy 386.404866 -236.182154)
			(xy 386.504942 -236.28223)
		)
		(stroke
			(width 0)
			(type solid)
		)
		(fill yes)
		(layer "In4.Cu")
		(net "M_J_CPU0_SA_DQ<19>")
	)
	(gr_poly
		(pts
			(xy 386.605018 -234.966002) (xy 386.504942 -234.865926) (xy 386.404866 -234.966002) (xy 386.404866 -235.010452)
			(xy 386.605018 -235.010452)
		)
		(stroke
			(width 0)
			(type solid)
		)
		(fill yes)
		(layer "In4.Cu")
		(net "M_J_CPU0_SA_DQ<16>")
	)
	(gr_poly
		(pts
			(xy 386.605018 -234.562142) (xy 386.605018 -234.517692) (xy 386.404866 -234.517692) (xy 386.404866 -234.562142)
			(xy 386.504942 -234.662218)
		)
		(stroke
			(width 0)
			(type solid)
		)
		(fill yes)
		(layer "In4.Cu")
		(net "M_J_CPU0_SA_DQ<15>")
	)
	(gr_poly
		(pts
			(xy 386.605018 -233.34599) (xy 386.504942 -233.245914) (xy 386.404866 -233.34599) (xy 386.404866 -233.39044)
			(xy 386.605018 -233.39044)
		)
		(stroke
			(width 0)
			(type solid)
		)
		(fill yes)
		(layer "In4.Cu")
		(net "M_J_CPU0_SA_DQ<12>")
	)
	(gr_poly
		(pts
			(xy 386.605018 -232.942384) (xy 386.605018 -232.894632) (xy 386.404866 -232.894632) (xy 386.404866 -232.942384)
			(xy 386.504942 -233.042206)
		)
		(stroke
			(width 0)
			(type solid)
		)
		(fill yes)
		(layer "In4.Cu")
		(net "M_J_CPU0_SA_DQS_DP<6>")
	)
	(gr_poly
		(pts
			(xy 386.605018 -231.725724) (xy 386.504942 -231.625902) (xy 386.404866 -231.725724) (xy 386.404866 -231.773476)
			(xy 386.605018 -231.773476)
		)
		(stroke
			(width 0)
			(type solid)
		)
		(fill yes)
		(layer "In4.Cu")
		(net "M_J_CPU0_SA_DQS_DP<1>")
	)
	(gr_poly
		(pts
			(xy 386.605018 -231.322372) (xy 386.605018 -231.277922) (xy 386.404866 -231.277922) (xy 386.404866 -231.322372)
			(xy 386.504942 -231.422448)
		)
		(stroke
			(width 0)
			(type solid)
		)
		(fill yes)
		(layer "In4.Cu")
		(net "M_J_CPU0_SA_DQ<11>")
	)
	(gr_poly
		(pts
			(xy 386.605018 -230.105966) (xy 386.504942 -230.006144) (xy 386.404866 -230.105966) (xy 386.404866 -230.150416)
			(xy 386.605018 -230.150416)
		)
		(stroke
			(width 0)
			(type solid)
		)
		(fill yes)
		(layer "In4.Cu")
		(net "M_J_CPU0_SA_DQ<8>")
	)
	(gr_poly
		(pts
			(xy 386.605018 -229.70236) (xy 386.605018 -229.65791) (xy 386.404866 -229.65791) (xy 386.404866 -229.70236)
			(xy 386.504942 -229.802436)
		)
		(stroke
			(width 0)
			(type solid)
		)
		(fill yes)
		(layer "In4.Cu")
		(net "M_J_CPU0_SA_DQ<7>")
	)
	(gr_poly
		(pts
			(xy 386.605018 -228.486208) (xy 386.504942 -228.386132) (xy 386.404866 -228.486208) (xy 386.404866 -228.530658)
			(xy 386.605018 -228.530658)
		)
		(stroke
			(width 0)
			(type solid)
		)
		(fill yes)
		(layer "In4.Cu")
		(net "M_J_CPU0_SA_DQ<4>")
	)
	(gr_poly
		(pts
			(xy 386.605018 -228.082602) (xy 386.605018 -228.03485) (xy 386.404866 -228.03485) (xy 386.404866 -228.082602)
			(xy 386.504942 -228.182424)
		)
		(stroke
			(width 0)
			(type solid)
		)
		(fill yes)
		(layer "In4.Cu")
		(net "M_J_CPU0_SA_DQS_DP<5>")
	)
	(gr_poly
		(pts
			(xy 386.605018 -226.865942) (xy 386.504942 -226.76612) (xy 386.404866 -226.865942) (xy 386.404866 -226.913694)
			(xy 386.605018 -226.913694)
		)
		(stroke
			(width 0)
			(type solid)
		)
		(fill yes)
		(layer "In4.Cu")
		(net "M_J_CPU0_SA_DQS_DP<0>")
	)
	(gr_poly
		(pts
			(xy 386.605018 -226.462336) (xy 386.605018 -226.417886) (xy 386.404866 -226.417886) (xy 386.404866 -226.462336)
			(xy 386.504942 -226.562412)
		)
		(stroke
			(width 0)
			(type solid)
		)
		(fill yes)
		(layer "In4.Cu")
		(net "M_J_CPU0_SA_DQ<3>")
	)
	(gr_poly
		(pts
			(xy 386.605018 -225.246184) (xy 386.504942 -225.146108) (xy 386.404866 -225.246184) (xy 386.404866 -225.290634)
			(xy 386.605018 -225.290634)
		)
		(stroke
			(width 0)
			(type solid)
		)
		(fill yes)
		(layer "In4.Cu")
		(net "M_J_CPU0_SA_DQ<0>")
	)
	(gr_poly
		(pts
			(xy 386.904992 -292.91788) (xy 386.804916 -292.817804) (xy 386.70484 -292.91788) (xy 386.70484 -292.96233)
			(xy 386.904992 -292.96233)
		)
		(stroke
			(width 0)
			(type solid)
		)
		(fill yes)
		(layer "In4.Cu")
		(net "M_J_CPU0_SB_DQ<29>")
	)
	(gr_poly
		(pts
			(xy 386.904992 -292.51402) (xy 386.904992 -292.46957) (xy 386.70484 -292.46957) (xy 386.70484 -292.51402)
			(xy 386.804916 -292.614096)
		)
		(stroke
			(width 0)
			(type solid)
		)
		(fill yes)
		(layer "In4.Cu")
		(net "M_J_CPU0_SB_DQ<30>")
	)
	(gr_poly
		(pts
			(xy 386.904992 -291.297614) (xy 386.804916 -291.197792) (xy 386.70484 -291.297614) (xy 386.70484 -291.345366)
			(xy 386.904992 -291.345366)
		)
		(stroke
			(width 0)
			(type solid)
		)
		(fill yes)
		(layer "In4.Cu")
		(net "M_J_CPU0_SB_DQS_DN<8>")
	)
	(gr_poly
		(pts
			(xy 386.904992 -290.894262) (xy 386.904992 -290.84651) (xy 386.70484 -290.84651) (xy 386.70484 -290.894262)
			(xy 386.804916 -290.994084)
		)
		(stroke
			(width 0)
			(type solid)
		)
		(fill yes)
		(layer "In4.Cu")
		(net "M_J_CPU0_SB_DQS_DN<3>")
	)
	(gr_poly
		(pts
			(xy 386.904992 -289.677856) (xy 386.804916 -289.57778) (xy 386.70484 -289.677856) (xy 386.70484 -289.722306)
			(xy 386.904992 -289.722306)
		)
		(stroke
			(width 0)
			(type solid)
		)
		(fill yes)
		(layer "In4.Cu")
		(net "M_J_CPU0_SB_DQ<25>")
	)
	(gr_poly
		(pts
			(xy 386.904992 -289.273996) (xy 386.904992 -289.229546) (xy 386.70484 -289.229546) (xy 386.70484 -289.273996)
			(xy 386.804916 -289.374072)
		)
		(stroke
			(width 0)
			(type solid)
		)
		(fill yes)
		(layer "In4.Cu")
		(net "M_J_CPU0_SB_DQ<26>")
	)
	(gr_poly
		(pts
			(xy 386.904992 -288.057844) (xy 386.804916 -287.957768) (xy 386.70484 -288.057844) (xy 386.70484 -288.102294)
			(xy 386.904992 -288.102294)
		)
		(stroke
			(width 0)
			(type solid)
		)
		(fill yes)
		(layer "In4.Cu")
		(net "M_J_CPU0_SB_DQ<21>")
	)
	(gr_poly
		(pts
			(xy 386.904992 -287.654238) (xy 386.904992 -287.609788) (xy 386.70484 -287.609788) (xy 386.70484 -287.654238)
			(xy 386.804916 -287.75406)
		)
		(stroke
			(width 0)
			(type solid)
		)
		(fill yes)
		(layer "In4.Cu")
		(net "M_J_CPU0_SB_DQ<22>")
	)
	(gr_poly
		(pts
			(xy 386.904992 -286.437832) (xy 386.804916 -286.337756) (xy 386.70484 -286.437832) (xy 386.70484 -286.485584)
			(xy 386.904992 -286.485584)
		)
		(stroke
			(width 0)
			(type solid)
		)
		(fill yes)
		(layer "In4.Cu")
		(net "M_J_CPU0_SB_DQS_DN<7>")
	)
	(gr_poly
		(pts
			(xy 386.904992 -286.03448) (xy 386.904992 -285.986728) (xy 386.70484 -285.986728) (xy 386.70484 -286.03448)
			(xy 386.804916 -286.134302)
		)
		(stroke
			(width 0)
			(type solid)
		)
		(fill yes)
		(layer "In4.Cu")
		(net "M_J_CPU0_SB_DQS_DN<2>")
	)
	(gr_poly
		(pts
			(xy 386.904992 -284.818074) (xy 386.804916 -284.717998) (xy 386.70484 -284.818074) (xy 386.70484 -284.862524)
			(xy 386.904992 -284.862524)
		)
		(stroke
			(width 0)
			(type solid)
		)
		(fill yes)
		(layer "In4.Cu")
		(net "M_J_CPU0_SB_DQ<17>")
	)
	(gr_poly
		(pts
			(xy 386.904992 -284.414214) (xy 386.904992 -284.369764) (xy 386.70484 -284.369764) (xy 386.70484 -284.414214)
			(xy 386.804916 -284.51429)
		)
		(stroke
			(width 0)
			(type solid)
		)
		(fill yes)
		(layer "In4.Cu")
		(net "M_J_CPU0_SB_DQ<18>")
	)
	(gr_poly
		(pts
			(xy 386.904992 -283.198062) (xy 386.804916 -283.097986) (xy 386.70484 -283.198062) (xy 386.70484 -283.242512)
			(xy 386.904992 -283.242512)
		)
		(stroke
			(width 0)
			(type solid)
		)
		(fill yes)
		(layer "In4.Cu")
		(net "M_J_CPU0_SB_DQ<13>")
	)
	(gr_poly
		(pts
			(xy 386.904992 -282.794202) (xy 386.904992 -282.749752) (xy 386.70484 -282.749752) (xy 386.70484 -282.794202)
			(xy 386.804916 -282.894278)
		)
		(stroke
			(width 0)
			(type solid)
		)
		(fill yes)
		(layer "In4.Cu")
		(net "M_J_CPU0_SB_DQ<14>")
	)
	(gr_poly
		(pts
			(xy 386.904992 -281.577796) (xy 386.804916 -281.477974) (xy 386.70484 -281.577796) (xy 386.70484 -281.625548)
			(xy 386.904992 -281.625548)
		)
		(stroke
			(width 0)
			(type solid)
		)
		(fill yes)
		(layer "In4.Cu")
		(net "M_J_CPU0_SB_DQS_DN<6>")
	)
	(gr_poly
		(pts
			(xy 386.904992 -281.174444) (xy 386.904992 -281.126692) (xy 386.70484 -281.126692) (xy 386.70484 -281.174444)
			(xy 386.804916 -281.274266)
		)
		(stroke
			(width 0)
			(type solid)
		)
		(fill yes)
		(layer "In4.Cu")
		(net "M_J_CPU0_SB_DQS_DN<1>")
	)
	(gr_poly
		(pts
			(xy 386.904992 -279.958038) (xy 386.804916 -279.857962) (xy 386.70484 -279.958038) (xy 386.70484 -280.002488)
			(xy 386.904992 -280.002488)
		)
		(stroke
			(width 0)
			(type solid)
		)
		(fill yes)
		(layer "In4.Cu")
		(net "M_J_CPU0_SB_DQ<9>")
	)
	(gr_poly
		(pts
			(xy 386.904992 -279.554178) (xy 386.904992 -279.509728) (xy 386.70484 -279.509728) (xy 386.70484 -279.554178)
			(xy 386.804916 -279.654254)
		)
		(stroke
			(width 0)
			(type solid)
		)
		(fill yes)
		(layer "In4.Cu")
		(net "M_J_CPU0_SB_DQ<10>")
	)
	(gr_poly
		(pts
			(xy 386.904992 -278.338026) (xy 386.804916 -278.23795) (xy 386.70484 -278.338026) (xy 386.70484 -278.382476)
			(xy 386.904992 -278.382476)
		)
		(stroke
			(width 0)
			(type solid)
		)
		(fill yes)
		(layer "In4.Cu")
		(net "M_J_CPU0_SB_DQ<5>")
	)
	(gr_poly
		(pts
			(xy 386.904992 -277.934166) (xy 386.904992 -277.889716) (xy 386.70484 -277.889716) (xy 386.70484 -277.934166)
			(xy 386.804916 -278.034242)
		)
		(stroke
			(width 0)
			(type solid)
		)
		(fill yes)
		(layer "In4.Cu")
		(net "M_J_CPU0_SB_DQ<6>")
	)
	(gr_poly
		(pts
			(xy 386.904992 -276.71776) (xy 386.804916 -276.617938) (xy 386.70484 -276.71776) (xy 386.70484 -276.765512)
			(xy 386.904992 -276.765512)
		)
		(stroke
			(width 0)
			(type solid)
		)
		(fill yes)
		(layer "In4.Cu")
		(net "M_J_CPU0_SB_DQS_DN<5>")
	)
	(gr_poly
		(pts
			(xy 386.904992 -276.314408) (xy 386.904992 -276.266656) (xy 386.70484 -276.266656) (xy 386.70484 -276.314408)
			(xy 386.804916 -276.41423)
		)
		(stroke
			(width 0)
			(type solid)
		)
		(fill yes)
		(layer "In4.Cu")
		(net "M_J_CPU0_SB_DQS_DN<0>")
	)
	(gr_poly
		(pts
			(xy 386.904992 -275.098002) (xy 386.804916 -274.997926) (xy 386.70484 -275.098002) (xy 386.70484 -275.142452)
			(xy 386.904992 -275.142452)
		)
		(stroke
			(width 0)
			(type solid)
		)
		(fill yes)
		(layer "In4.Cu")
		(net "M_J_CPU0_SB_DQ<1>")
	)
	(gr_poly
		(pts
			(xy 386.904992 -274.694142) (xy 386.904992 -274.649692) (xy 386.70484 -274.649692) (xy 386.70484 -274.694142)
			(xy 386.804916 -274.794218)
		)
		(stroke
			(width 0)
			(type solid)
		)
		(fill yes)
		(layer "In4.Cu")
		(net "M_J_CPU0_SB_DQ<2>")
	)
	(gr_poly
		(pts
			(xy 386.904992 -273.47799) (xy 386.804916 -273.377914) (xy 386.70484 -273.47799) (xy 386.70484 -273.52244)
			(xy 386.904992 -273.52244)
		)
		(stroke
			(width 0)
			(type solid)
		)
		(fill yes)
		(layer "In4.Cu")
		(net "M_J_CPU0_SB_CB<1>")
	)
	(gr_poly
		(pts
			(xy 386.904992 -273.07413) (xy 386.904992 -273.02968) (xy 386.70484 -273.02968) (xy 386.70484 -273.07413)
			(xy 386.804916 -273.174206)
		)
		(stroke
			(width 0)
			(type solid)
		)
		(fill yes)
		(layer "In4.Cu")
		(net "M_J_CPU0_SB_CB<2>")
	)
	(gr_poly
		(pts
			(xy 386.904992 -271.857724) (xy 386.804916 -271.757902) (xy 386.70484 -271.857724) (xy 386.70484 -271.905476)
			(xy 386.904992 -271.905476)
		)
		(stroke
			(width 0)
			(type solid)
		)
		(fill yes)
		(layer "In4.Cu")
		(net "M_J_CPU0_SB_DQS_DN<4>")
	)
	(gr_poly
		(pts
			(xy 386.904992 -271.454372) (xy 386.904992 -271.40662) (xy 386.70484 -271.40662) (xy 386.70484 -271.454372)
			(xy 386.804916 -271.554194)
		)
		(stroke
			(width 0)
			(type solid)
		)
		(fill yes)
		(layer "In4.Cu")
		(net "M_J_CPU0_SB_DQS_DN<9>")
	)
	(gr_poly
		(pts
			(xy 386.904992 -270.237966) (xy 386.804916 -270.13789) (xy 386.70484 -270.237966) (xy 386.70484 -270.282416)
			(xy 386.904992 -270.282416)
		)
		(stroke
			(width 0)
			(type solid)
		)
		(fill yes)
		(layer "In4.Cu")
		(net "M_J_CPU0_SB_CB<5>")
	)
	(gr_poly
		(pts
			(xy 386.904992 -269.834106) (xy 386.904992 -269.789656) (xy 386.70484 -269.789656) (xy 386.70484 -269.834106)
			(xy 386.804916 -269.934182)
		)
		(stroke
			(width 0)
			(type solid)
		)
		(fill yes)
		(layer "In4.Cu")
		(net "M_J_CPU0_SB_CB<6>")
	)
	(gr_poly
		(pts
			(xy 386.904992 -266.997942) (xy 386.804916 -266.897866) (xy 386.70484 -266.997942) (xy 386.70484 -267.042392)
			(xy 386.904992 -267.042392)
		)
		(stroke
			(width 0)
			(type solid)
		)
		(fill yes)
		(layer "In4.Cu")
		(net "M_J_CPU0_SA_RSP<0>")
	)
	(gr_poly
		(pts
			(xy 386.904992 -266.594082) (xy 386.904992 -266.549632) (xy 386.70484 -266.549632) (xy 386.70484 -266.594082)
			(xy 386.804916 -266.694158)
		)
		(stroke
			(width 0)
			(type solid)
		)
		(fill yes)
		(layer "In4.Cu")
		(net "M_J_CPU0_SB_CS_N<1>")
	)
	(gr_poly
		(pts
			(xy 386.904992 -265.37793) (xy 386.804916 -265.277854) (xy 386.70484 -265.37793) (xy 386.70484 -265.42238)
			(xy 386.904992 -265.42238)
		)
		(stroke
			(width 0)
			(type solid)
		)
		(fill yes)
		(layer "In4.Cu")
		(net "M_J_CPU0_SB_PAR")
	)
	(gr_poly
		(pts
			(xy 386.904992 -263.757918) (xy 386.804916 -263.657842) (xy 386.70484 -263.757918) (xy 386.70484 -263.802368)
			(xy 386.904992 -263.802368)
		)
		(stroke
			(width 0)
			(type solid)
		)
		(fill yes)
		(layer "In4.Cu")
		(net "M_J_CPU0_SB_CA<4>")
	)
	(gr_poly
		(pts
			(xy 386.904992 -263.354058) (xy 386.904992 -263.309608) (xy 386.70484 -263.309608) (xy 386.70484 -263.354058)
			(xy 386.804916 -263.454134)
		)
		(stroke
			(width 0)
			(type solid)
		)
		(fill yes)
		(layer "In4.Cu")
		(net "M_J_CPU0_SB_CA<3>")
	)
	(gr_poly
		(pts
			(xy 386.904992 -262.137906) (xy 386.804916 -262.03783) (xy 386.70484 -262.137906) (xy 386.70484 -262.182356)
			(xy 386.904992 -262.182356)
		)
		(stroke
			(width 0)
			(type solid)
		)
		(fill yes)
		(layer "In4.Cu")
		(net "M_J_CPU0_SB_CA<0>")
	)
	(gr_poly
		(pts
			(xy 387.074918 -256.432558) (xy 387.074918 -256.384806) (xy 386.874766 -256.384806) (xy 386.874766 -256.432558)
			(xy 386.974842 -256.53238)
		)
		(stroke
			(width 0)
			(type solid)
		)
		(fill yes)
		(layer "In4.Cu")
		(net "M_J_CPU0_CLK_DN<0>")
	)
	(gr_poly
		(pts
			(xy 387.074918 -255.216152) (xy 386.974842 -255.116076) (xy 386.874766 -255.216152) (xy 386.874766 -255.260602)
			(xy 387.074918 -255.260602)
		)
		(stroke
			(width 0)
			(type solid)
		)
		(fill yes)
		(layer "In4.Cu")
		(net "M_J_CPU0_SA_CA<6>")
	)
	(gr_poly
		(pts
			(xy 387.074918 -254.812292) (xy 387.074918 -254.767842) (xy 386.874766 -254.767842) (xy 386.874766 -254.812292)
			(xy 386.974842 -254.912368)
		)
		(stroke
			(width 0)
			(type solid)
		)
		(fill yes)
		(layer "In4.Cu")
		(net "M_J_CPU0_SA_CA<5>")
	)
	(gr_poly
		(pts
			(xy 387.074918 -253.59614) (xy 386.974842 -253.496064) (xy 386.874766 -253.59614) (xy 386.874766 -253.64059)
			(xy 387.074918 -253.64059)
		)
		(stroke
			(width 0)
			(type solid)
		)
		(fill yes)
		(layer "In4.Cu")
		(net "M_J_CPU0_SA_CA<2>")
	)
	(gr_poly
		(pts
			(xy 387.074918 -253.19228) (xy 387.074918 -253.14783) (xy 386.874766 -253.14783) (xy 386.874766 -253.19228)
			(xy 386.974842 -253.292356)
		)
		(stroke
			(width 0)
			(type solid)
		)
		(fill yes)
		(layer "In4.Cu")
		(net "M_J_CPU0_SA_CA<1>")
	)
	(gr_poly
		(pts
			(xy 387.074918 -251.976128) (xy 386.974842 -251.876052) (xy 386.874766 -251.976128) (xy 386.874766 -252.020578)
			(xy 387.074918 -252.020578)
		)
		(stroke
			(width 0)
			(type solid)
		)
		(fill yes)
		(layer "In4.Cu")
		(net "M_J_CPU0_SA_CS_N<1>")
	)
	(gr_poly
		(pts
			(xy 387.074918 -250.356116) (xy 386.974842 -250.25604) (xy 386.874766 -250.356116) (xy 386.874766 -250.400566)
			(xy 387.074918 -250.400566)
		)
		(stroke
			(width 0)
			(type solid)
		)
		(fill yes)
		(layer "In4.Cu")
		(net "M_J_CPU0_ALERT_R_N")
	)
	(gr_poly
		(pts
			(xy 387.074918 -248.736104) (xy 386.974842 -248.636028) (xy 386.874766 -248.736104) (xy 386.874766 -248.780554)
			(xy 387.074918 -248.780554)
		)
		(stroke
			(width 0)
			(type solid)
		)
		(fill yes)
		(layer "In4.Cu")
		(net "M_J_CPU0_SA_CB<5>")
	)
	(gr_poly
		(pts
			(xy 387.074918 -248.332244) (xy 387.074918 -248.287794) (xy 386.874766 -248.287794) (xy 386.874766 -248.332244)
			(xy 386.974842 -248.43232)
		)
		(stroke
			(width 0)
			(type solid)
		)
		(fill yes)
		(layer "In4.Cu")
		(net "M_J_CPU0_SA_CB<6>")
	)
	(gr_poly
		(pts
			(xy 387.074918 -247.115838) (xy 386.974842 -247.016016) (xy 386.874766 -247.115838) (xy 386.874766 -247.16359)
			(xy 387.074918 -247.16359)
		)
		(stroke
			(width 0)
			(type solid)
		)
		(fill yes)
		(layer "In4.Cu")
		(net "M_J_CPU0_SA_DQS_DN<9>")
	)
	(gr_poly
		(pts
			(xy 387.074918 -246.712486) (xy 387.074918 -246.664734) (xy 386.874766 -246.664734) (xy 386.874766 -246.712486)
			(xy 386.974842 -246.812308)
		)
		(stroke
			(width 0)
			(type solid)
		)
		(fill yes)
		(layer "In4.Cu")
		(net "M_J_CPU0_SA_DQS_DN<4>")
	)
	(gr_poly
		(pts
			(xy 387.074918 -245.49608) (xy 386.974842 -245.396004) (xy 386.874766 -245.49608) (xy 386.874766 -245.54053)
			(xy 387.074918 -245.54053)
		)
		(stroke
			(width 0)
			(type solid)
		)
		(fill yes)
		(layer "In4.Cu")
		(net "M_J_CPU0_SA_CB<1>")
	)
	(gr_poly
		(pts
			(xy 387.074918 -245.09222) (xy 387.074918 -245.04777) (xy 386.874766 -245.04777) (xy 386.874766 -245.09222)
			(xy 386.974842 -245.192296)
		)
		(stroke
			(width 0)
			(type solid)
		)
		(fill yes)
		(layer "In4.Cu")
		(net "M_J_CPU0_SA_CB<2>")
	)
	(gr_poly
		(pts
			(xy 387.074918 -243.876068) (xy 386.974842 -243.775992) (xy 386.874766 -243.876068) (xy 386.874766 -243.920518)
			(xy 387.074918 -243.920518)
		)
		(stroke
			(width 0)
			(type solid)
		)
		(fill yes)
		(layer "In4.Cu")
		(net "M_J_CPU0_SA_DQ<29>")
	)
	(gr_poly
		(pts
			(xy 387.074918 -243.472208) (xy 387.074918 -243.427758) (xy 386.874766 -243.427758) (xy 386.874766 -243.472208)
			(xy 386.974842 -243.572284)
		)
		(stroke
			(width 0)
			(type solid)
		)
		(fill yes)
		(layer "In4.Cu")
		(net "M_J_CPU0_SA_DQ<30>")
	)
	(gr_poly
		(pts
			(xy 387.074918 -242.255802) (xy 386.974842 -242.15598) (xy 386.874766 -242.255802) (xy 386.874766 -242.303554)
			(xy 387.074918 -242.303554)
		)
		(stroke
			(width 0)
			(type solid)
		)
		(fill yes)
		(layer "In4.Cu")
		(net "M_J_CPU0_SA_DQS_DN<8>")
	)
	(gr_poly
		(pts
			(xy 387.074918 -241.85245) (xy 387.074918 -241.804698) (xy 386.874766 -241.804698) (xy 386.874766 -241.85245)
			(xy 386.974842 -241.952272)
		)
		(stroke
			(width 0)
			(type solid)
		)
		(fill yes)
		(layer "In4.Cu")
		(net "M_J_CPU0_SA_DQS_DN<3>")
	)
	(gr_poly
		(pts
			(xy 387.074918 -240.636044) (xy 386.974842 -240.535968) (xy 386.874766 -240.636044) (xy 386.874766 -240.680494)
			(xy 387.074918 -240.680494)
		)
		(stroke
			(width 0)
			(type solid)
		)
		(fill yes)
		(layer "In4.Cu")
		(net "M_J_CPU0_SA_DQ<25>")
	)
	(gr_poly
		(pts
			(xy 387.074918 -240.232184) (xy 387.074918 -240.187734) (xy 386.874766 -240.187734) (xy 386.874766 -240.232184)
			(xy 386.974842 -240.33226)
		)
		(stroke
			(width 0)
			(type solid)
		)
		(fill yes)
		(layer "In4.Cu")
		(net "M_J_CPU0_SA_DQ<26>")
	)
	(gr_poly
		(pts
			(xy 387.074918 -239.016032) (xy 386.974842 -238.915956) (xy 386.874766 -239.016032) (xy 386.874766 -239.060482)
			(xy 387.074918 -239.060482)
		)
		(stroke
			(width 0)
			(type solid)
		)
		(fill yes)
		(layer "In4.Cu")
		(net "M_J_CPU0_SA_DQ<21>")
	)
	(gr_poly
		(pts
			(xy 387.074918 -238.612172) (xy 387.074918 -238.567722) (xy 386.874766 -238.567722) (xy 386.874766 -238.612172)
			(xy 386.974842 -238.712248)
		)
		(stroke
			(width 0)
			(type solid)
		)
		(fill yes)
		(layer "In4.Cu")
		(net "M_J_CPU0_SA_DQ<22>")
	)
	(gr_poly
		(pts
			(xy 387.074918 -237.395766) (xy 386.974842 -237.295944) (xy 386.874766 -237.395766) (xy 386.874766 -237.443518)
			(xy 387.074918 -237.443518)
		)
		(stroke
			(width 0)
			(type solid)
		)
		(fill yes)
		(layer "In4.Cu")
		(net "M_J_CPU0_SA_DQS_DN<7>")
	)
	(gr_poly
		(pts
			(xy 387.074918 -236.992414) (xy 387.074918 -236.944662) (xy 386.874766 -236.944662) (xy 386.874766 -236.992414)
			(xy 386.974842 -237.092236)
		)
		(stroke
			(width 0)
			(type solid)
		)
		(fill yes)
		(layer "In4.Cu")
		(net "M_J_CPU0_SA_DQS_DN<2>")
	)
	(gr_poly
		(pts
			(xy 387.074918 -235.776008) (xy 386.974842 -235.675932) (xy 386.874766 -235.776008) (xy 386.874766 -235.820458)
			(xy 387.074918 -235.820458)
		)
		(stroke
			(width 0)
			(type solid)
		)
		(fill yes)
		(layer "In4.Cu")
		(net "M_J_CPU0_SA_DQ<17>")
	)
	(gr_poly
		(pts
			(xy 387.074918 -235.372148) (xy 387.074918 -235.327698) (xy 386.874766 -235.327698) (xy 386.874766 -235.372148)
			(xy 386.974842 -235.472224)
		)
		(stroke
			(width 0)
			(type solid)
		)
		(fill yes)
		(layer "In4.Cu")
		(net "M_J_CPU0_SA_DQ<18>")
	)
	(gr_poly
		(pts
			(xy 387.074918 -234.155996) (xy 386.974842 -234.05592) (xy 386.874766 -234.155996) (xy 386.874766 -234.200446)
			(xy 387.074918 -234.200446)
		)
		(stroke
			(width 0)
			(type solid)
		)
		(fill yes)
		(layer "In4.Cu")
		(net "M_J_CPU0_SA_DQ<13>")
	)
	(gr_poly
		(pts
			(xy 387.074918 -233.752136) (xy 387.074918 -233.707686) (xy 386.874766 -233.707686) (xy 386.874766 -233.752136)
			(xy 386.974842 -233.852212)
		)
		(stroke
			(width 0)
			(type solid)
		)
		(fill yes)
		(layer "In4.Cu")
		(net "M_J_CPU0_SA_DQ<14>")
	)
	(gr_poly
		(pts
			(xy 387.074918 -232.53573) (xy 386.974842 -232.435908) (xy 386.874766 -232.53573) (xy 386.874766 -232.583482)
			(xy 387.074918 -232.583482)
		)
		(stroke
			(width 0)
			(type solid)
		)
		(fill yes)
		(layer "In4.Cu")
		(net "M_J_CPU0_SA_DQS_DN<6>")
	)
	(gr_poly
		(pts
			(xy 387.074918 -232.132378) (xy 387.074918 -232.084626) (xy 386.874766 -232.084626) (xy 386.874766 -232.132378)
			(xy 386.974842 -232.2322)
		)
		(stroke
			(width 0)
			(type solid)
		)
		(fill yes)
		(layer "In4.Cu")
		(net "M_J_CPU0_SA_DQS_DN<1>")
	)
	(gr_poly
		(pts
			(xy 387.074918 -230.915972) (xy 386.974842 -230.815896) (xy 386.874766 -230.915972) (xy 386.874766 -230.960422)
			(xy 387.074918 -230.960422)
		)
		(stroke
			(width 0)
			(type solid)
		)
		(fill yes)
		(layer "In4.Cu")
		(net "M_J_CPU0_SA_DQ<9>")
	)
	(gr_poly
		(pts
			(xy 387.074918 -230.512366) (xy 387.074918 -230.467916) (xy 386.874766 -230.467916) (xy 386.874766 -230.512366)
			(xy 386.974842 -230.612188)
		)
		(stroke
			(width 0)
			(type solid)
		)
		(fill yes)
		(layer "In4.Cu")
		(net "M_J_CPU0_SA_DQ<10>")
	)
	(gr_poly
		(pts
			(xy 387.074918 -229.29596) (xy 386.974842 -229.195884) (xy 386.874766 -229.29596) (xy 386.874766 -229.34041)
			(xy 387.074918 -229.34041)
		)
		(stroke
			(width 0)
			(type solid)
		)
		(fill yes)
		(layer "In4.Cu")
		(net "M_J_CPU0_SA_DQ<5>")
	)
	(gr_poly
		(pts
			(xy 387.074918 -228.892354) (xy 387.074918 -228.847904) (xy 386.874766 -228.847904) (xy 386.874766 -228.892354)
			(xy 386.974842 -228.99243)
		)
		(stroke
			(width 0)
			(type solid)
		)
		(fill yes)
		(layer "In4.Cu")
		(net "M_J_CPU0_SA_DQ<6>")
	)
	(gr_poly
		(pts
			(xy 387.074918 -227.675948) (xy 386.974842 -227.576126) (xy 386.874766 -227.675948) (xy 386.874766 -227.7237)
			(xy 387.074918 -227.7237)
		)
		(stroke
			(width 0)
			(type solid)
		)
		(fill yes)
		(layer "In4.Cu")
		(net "M_J_CPU0_SA_DQS_DN<5>")
	)
	(gr_poly
		(pts
			(xy 387.074918 -227.272596) (xy 387.074918 -227.224844) (xy 386.874766 -227.224844) (xy 386.874766 -227.272596)
			(xy 386.974842 -227.372418)
		)
		(stroke
			(width 0)
			(type solid)
		)
		(fill yes)
		(layer "In4.Cu")
		(net "M_J_CPU0_SA_DQS_DN<0>")
	)
	(gr_poly
		(pts
			(xy 387.074918 -226.05619) (xy 386.974842 -225.956114) (xy 386.874766 -226.05619) (xy 386.874766 -226.10064)
			(xy 387.074918 -226.10064)
		)
		(stroke
			(width 0)
			(type solid)
		)
		(fill yes)
		(layer "In4.Cu")
		(net "M_J_CPU0_SA_DQ<1>")
	)
	(gr_poly
		(pts
			(xy 387.074918 -225.65233) (xy 387.074918 -225.60788) (xy 386.874766 -225.60788) (xy 386.874766 -225.65233)
			(xy 386.974842 -225.752406)
		)
		(stroke
			(width 0)
			(type solid)
		)
		(fill yes)
		(layer "In4.Cu")
		(net "M_J_CPU0_SA_DQ<2>")
	)
	(gr_poly
		(pts
			(xy 387.374892 -293.324026) (xy 387.374892 -293.279576) (xy 387.17474 -293.279576) (xy 387.17474 -293.324026)
			(xy 387.274816 -293.424102)
		)
		(stroke
			(width 0)
			(type solid)
		)
		(fill yes)
		(layer "In4.Cu")
		(net "M_J_CPU0_SB_DQ<31>")
	)
	(gr_poly
		(pts
			(xy 387.374892 -292.107874) (xy 387.274816 -292.007798) (xy 387.17474 -292.107874) (xy 387.17474 -292.152324)
			(xy 387.374892 -292.152324)
		)
		(stroke
			(width 0)
			(type solid)
		)
		(fill yes)
		(layer "In4.Cu")
		(net "M_J_CPU0_SB_DQ<28>")
	)
	(gr_poly
		(pts
			(xy 387.374892 -291.704268) (xy 387.374892 -291.656516) (xy 387.17474 -291.656516) (xy 387.17474 -291.704268)
			(xy 387.274816 -291.80409)
		)
		(stroke
			(width 0)
			(type solid)
		)
		(fill yes)
		(layer "In4.Cu")
		(net "M_J_CPU0_SB_DQS_DP<8>")
	)
	(gr_poly
		(pts
			(xy 387.374892 -290.487608) (xy 387.274816 -290.387786) (xy 387.17474 -290.487608) (xy 387.17474 -290.53536)
			(xy 387.374892 -290.53536)
		)
		(stroke
			(width 0)
			(type solid)
		)
		(fill yes)
		(layer "In4.Cu")
		(net "M_J_CPU0_SB_DQS_DP<3>")
	)
	(gr_poly
		(pts
			(xy 387.374892 -290.084002) (xy 387.374892 -290.039552) (xy 387.17474 -290.039552) (xy 387.17474 -290.084002)
			(xy 387.274816 -290.184078)
		)
		(stroke
			(width 0)
			(type solid)
		)
		(fill yes)
		(layer "In4.Cu")
		(net "M_J_CPU0_SB_DQ<27>")
	)
	(gr_poly
		(pts
			(xy 387.374892 -288.86785) (xy 387.274816 -288.767774) (xy 387.17474 -288.86785) (xy 387.17474 -288.9123)
			(xy 387.374892 -288.9123)
		)
		(stroke
			(width 0)
			(type solid)
		)
		(fill yes)
		(layer "In4.Cu")
		(net "M_J_CPU0_SB_DQ<24>")
	)
	(gr_poly
		(pts
			(xy 387.374892 -288.464244) (xy 387.374892 -288.419794) (xy 387.17474 -288.419794) (xy 387.17474 -288.464244)
			(xy 387.274816 -288.56432)
		)
		(stroke
			(width 0)
			(type solid)
		)
		(fill yes)
		(layer "In4.Cu")
		(net "M_J_CPU0_SB_DQ<23>")
	)
	(gr_poly
		(pts
			(xy 387.374892 -287.247838) (xy 387.274816 -287.148016) (xy 387.17474 -287.247838) (xy 387.17474 -287.292288)
			(xy 387.374892 -287.292288)
		)
		(stroke
			(width 0)
			(type solid)
		)
		(fill yes)
		(layer "In4.Cu")
		(net "M_J_CPU0_SB_DQ<20>")
	)
	(gr_poly
		(pts
			(xy 387.374892 -286.844232) (xy 387.374892 -286.79648) (xy 387.17474 -286.79648) (xy 387.17474 -286.844232)
			(xy 387.274816 -286.944308)
		)
		(stroke
			(width 0)
			(type solid)
		)
		(fill yes)
		(layer "In4.Cu")
		(net "M_J_CPU0_SB_DQS_DP<7>")
	)
	(gr_poly
		(pts
			(xy 387.374892 -285.627826) (xy 387.274816 -285.528004) (xy 387.17474 -285.627826) (xy 387.17474 -285.675578)
			(xy 387.374892 -285.675578)
		)
		(stroke
			(width 0)
			(type solid)
		)
		(fill yes)
		(layer "In4.Cu")
		(net "M_J_CPU0_SB_DQS_DP<2>")
	)
	(gr_poly
		(pts
			(xy 387.374892 -285.22422) (xy 387.374892 -285.17977) (xy 387.17474 -285.17977) (xy 387.17474 -285.22422)
			(xy 387.274816 -285.324296)
		)
		(stroke
			(width 0)
			(type solid)
		)
		(fill yes)
		(layer "In4.Cu")
		(net "M_J_CPU0_SB_DQ<19>")
	)
	(gr_poly
		(pts
			(xy 387.374892 -284.008068) (xy 387.274816 -283.907992) (xy 387.17474 -284.008068) (xy 387.17474 -284.052518)
			(xy 387.374892 -284.052518)
		)
		(stroke
			(width 0)
			(type solid)
		)
		(fill yes)
		(layer "In4.Cu")
		(net "M_J_CPU0_SB_DQ<16>")
	)
	(gr_poly
		(pts
			(xy 387.374892 -283.604208) (xy 387.374892 -283.559758) (xy 387.17474 -283.559758) (xy 387.17474 -283.604208)
			(xy 387.274816 -283.704284)
		)
		(stroke
			(width 0)
			(type solid)
		)
		(fill yes)
		(layer "In4.Cu")
		(net "M_J_CPU0_SB_DQ<15>")
	)
	(gr_poly
		(pts
			(xy 387.374892 -282.388056) (xy 387.274816 -282.28798) (xy 387.17474 -282.388056) (xy 387.17474 -282.432506)
			(xy 387.374892 -282.432506)
		)
		(stroke
			(width 0)
			(type solid)
		)
		(fill yes)
		(layer "In4.Cu")
		(net "M_J_CPU0_SB_DQ<12>")
	)
	(gr_poly
		(pts
			(xy 387.374892 -281.98445) (xy 387.374892 -281.936698) (xy 387.17474 -281.936698) (xy 387.17474 -281.98445)
			(xy 387.274816 -282.084272)
		)
		(stroke
			(width 0)
			(type solid)
		)
		(fill yes)
		(layer "In4.Cu")
		(net "M_J_CPU0_SB_DQS_DP<6>")
	)
	(gr_poly
		(pts
			(xy 387.374892 -280.76779) (xy 387.274816 -280.667968) (xy 387.17474 -280.76779) (xy 387.17474 -280.815542)
			(xy 387.374892 -280.815542)
		)
		(stroke
			(width 0)
			(type solid)
		)
		(fill yes)
		(layer "In4.Cu")
		(net "M_J_CPU0_SB_DQS_DP<1>")
	)
	(gr_poly
		(pts
			(xy 387.374892 -280.364184) (xy 387.374892 -280.319734) (xy 387.17474 -280.319734) (xy 387.17474 -280.364184)
			(xy 387.274816 -280.46426)
		)
		(stroke
			(width 0)
			(type solid)
		)
		(fill yes)
		(layer "In4.Cu")
		(net "M_J_CPU0_SB_DQ<11>")
	)
	(gr_poly
		(pts
			(xy 387.374892 -279.148032) (xy 387.274816 -279.047956) (xy 387.17474 -279.148032) (xy 387.17474 -279.192482)
			(xy 387.374892 -279.192482)
		)
		(stroke
			(width 0)
			(type solid)
		)
		(fill yes)
		(layer "In4.Cu")
		(net "M_J_CPU0_SB_DQ<8>")
	)
	(gr_poly
		(pts
			(xy 387.374892 -278.744172) (xy 387.374892 -278.699722) (xy 387.17474 -278.699722) (xy 387.17474 -278.744172)
			(xy 387.274816 -278.844248)
		)
		(stroke
			(width 0)
			(type solid)
		)
		(fill yes)
		(layer "In4.Cu")
		(net "M_J_CPU0_SB_DQ<7>")
	)
	(gr_poly
		(pts
			(xy 387.374892 -277.52802) (xy 387.274816 -277.427944) (xy 387.17474 -277.52802) (xy 387.17474 -277.57247)
			(xy 387.374892 -277.57247)
		)
		(stroke
			(width 0)
			(type solid)
		)
		(fill yes)
		(layer "In4.Cu")
		(net "M_J_CPU0_SB_DQ<4>")
	)
	(gr_poly
		(pts
			(xy 387.374892 -277.124414) (xy 387.374892 -277.076662) (xy 387.17474 -277.076662) (xy 387.17474 -277.124414)
			(xy 387.274816 -277.224236)
		)
		(stroke
			(width 0)
			(type solid)
		)
		(fill yes)
		(layer "In4.Cu")
		(net "M_J_CPU0_SB_DQS_DP<5>")
	)
	(gr_poly
		(pts
			(xy 387.374892 -275.907754) (xy 387.274816 -275.807932) (xy 387.17474 -275.907754) (xy 387.17474 -275.955506)
			(xy 387.374892 -275.955506)
		)
		(stroke
			(width 0)
			(type solid)
		)
		(fill yes)
		(layer "In4.Cu")
		(net "M_J_CPU0_SB_DQS_DP<0>")
	)
	(gr_poly
		(pts
			(xy 387.374892 -275.504148) (xy 387.374892 -275.459698) (xy 387.17474 -275.459698) (xy 387.17474 -275.504148)
			(xy 387.274816 -275.604224)
		)
		(stroke
			(width 0)
			(type solid)
		)
		(fill yes)
		(layer "In4.Cu")
		(net "M_J_CPU0_SB_DQ<3>")
	)
	(gr_poly
		(pts
			(xy 387.374892 -274.287996) (xy 387.274816 -274.18792) (xy 387.17474 -274.287996) (xy 387.17474 -274.332446)
			(xy 387.374892 -274.332446)
		)
		(stroke
			(width 0)
			(type solid)
		)
		(fill yes)
		(layer "In4.Cu")
		(net "M_J_CPU0_SB_DQ<0>")
	)
	(gr_poly
		(pts
			(xy 387.374892 -273.884136) (xy 387.374892 -273.839686) (xy 387.17474 -273.839686) (xy 387.17474 -273.884136)
			(xy 387.274816 -273.984212)
		)
		(stroke
			(width 0)
			(type solid)
		)
		(fill yes)
		(layer "In4.Cu")
		(net "M_J_CPU0_SB_CB<3>")
	)
	(gr_poly
		(pts
			(xy 387.374892 -272.667984) (xy 387.274816 -272.567908) (xy 387.17474 -272.667984) (xy 387.17474 -272.712434)
			(xy 387.374892 -272.712434)
		)
		(stroke
			(width 0)
			(type solid)
		)
		(fill yes)
		(layer "In4.Cu")
		(net "M_J_CPU0_SB_CB<0>")
	)
	(gr_poly
		(pts
			(xy 387.374892 -272.264378) (xy 387.374892 -272.216626) (xy 387.17474 -272.216626) (xy 387.17474 -272.264378)
			(xy 387.274816 -272.3642)
		)
		(stroke
			(width 0)
			(type solid)
		)
		(fill yes)
		(layer "In4.Cu")
		(net "M_J_CPU0_SB_DQS_DP<4>")
	)
	(gr_poly
		(pts
			(xy 387.374892 -271.047718) (xy 387.274816 -270.947896) (xy 387.17474 -271.047718) (xy 387.17474 -271.09547)
			(xy 387.374892 -271.09547)
		)
		(stroke
			(width 0)
			(type solid)
		)
		(fill yes)
		(layer "In4.Cu")
		(net "M_J_CPU0_SB_DQS_DP<9>")
	)
	(gr_poly
		(pts
			(xy 387.374892 -270.644112) (xy 387.374892 -270.599662) (xy 387.17474 -270.599662) (xy 387.17474 -270.644112)
			(xy 387.274816 -270.744188)
		)
		(stroke
			(width 0)
			(type solid)
		)
		(fill yes)
		(layer "In4.Cu")
		(net "M_J_CPU0_SB_CB<7>")
	)
	(gr_poly
		(pts
			(xy 387.374892 -269.42796) (xy 387.274816 -269.327884) (xy 387.17474 -269.42796) (xy 387.17474 -269.47241)
			(xy 387.374892 -269.47241)
		)
		(stroke
			(width 0)
			(type solid)
		)
		(fill yes)
		(layer "In4.Cu")
		(net "M_J_CPU0_SB_CB<4>")
	)
	(gr_poly
		(pts
			(xy 387.374892 -267.807948) (xy 387.274816 -267.707872) (xy 387.17474 -267.807948) (xy 387.17474 -267.852398)
			(xy 387.374892 -267.852398)
		)
		(stroke
			(width 0)
			(type solid)
		)
		(fill yes)
		(layer "In4.Cu")
		(net "M_J_CPU0_SB_RSP<0>")
	)
	(gr_poly
		(pts
			(xy 387.374892 -265.784076) (xy 387.374892 -265.739626) (xy 387.17474 -265.739626) (xy 387.17474 -265.784076)
			(xy 387.274816 -265.884152)
		)
		(stroke
			(width 0)
			(type solid)
		)
		(fill yes)
		(layer "In4.Cu")
		(net "M_J_CPU0_SB_CS_N<0>")
	)
	(gr_poly
		(pts
			(xy 387.374892 -264.567924) (xy 387.274816 -264.467848) (xy 387.17474 -264.567924) (xy 387.17474 -264.612374)
			(xy 387.374892 -264.612374)
		)
		(stroke
			(width 0)
			(type solid)
		)
		(fill yes)
		(layer "In4.Cu")
		(net "M_J_CPU0_SB_CA<6>")
	)
	(gr_poly
		(pts
			(xy 387.374892 -264.164064) (xy 387.374892 -264.119614) (xy 387.17474 -264.119614) (xy 387.17474 -264.164064)
			(xy 387.274816 -264.26414)
		)
		(stroke
			(width 0)
			(type solid)
		)
		(fill yes)
		(layer "In4.Cu")
		(net "M_J_CPU0_SB_CA<5>")
	)
	(gr_poly
		(pts
			(xy 387.374892 -262.947912) (xy 387.274816 -262.847836) (xy 387.17474 -262.947912) (xy 387.17474 -262.992362)
			(xy 387.374892 -262.992362)
		)
		(stroke
			(width 0)
			(type solid)
		)
		(fill yes)
		(layer "In4.Cu")
		(net "M_J_CPU0_SB_CA<2>")
	)
	(gr_poly
		(pts
			(xy 387.374892 -262.544052) (xy 387.374892 -262.499602) (xy 387.17474 -262.499602) (xy 387.17474 -262.544052)
			(xy 387.274816 -262.644128)
		)
		(stroke
			(width 0)
			(type solid)
		)
		(fill yes)
		(layer "In4.Cu")
		(net "M_J_CPU0_SB_CA<1>")
	)
	(gr_poly
		(pts
			(xy 387.544818 -256.025904) (xy 387.444742 -255.926082) (xy 387.344666 -256.025904) (xy 387.344666 -256.073656)
			(xy 387.544818 -256.073656)
		)
		(stroke
			(width 0)
			(type solid)
		)
		(fill yes)
		(layer "In4.Cu")
		(net "M_J_CPU0_CLK_DP<0>")
	)
	(gr_poly
		(pts
			(xy 387.544818 -255.622298) (xy 387.544818 -255.577848) (xy 387.344666 -255.577848) (xy 387.344666 -255.622298)
			(xy 387.444742 -255.722374)
		)
		(stroke
			(width 0)
			(type solid)
		)
		(fill yes)
		(layer "In4.Cu")
		(net "M_J_CPU0_SA_PAR")
	)
	(gr_poly
		(pts
			(xy 387.544818 -254.406146) (xy 387.444742 -254.30607) (xy 387.344666 -254.406146) (xy 387.344666 -254.450596)
			(xy 387.544818 -254.450596)
		)
		(stroke
			(width 0)
			(type solid)
		)
		(fill yes)
		(layer "In4.Cu")
		(net "M_J_CPU0_SA_CA<4>")
	)
	(gr_poly
		(pts
			(xy 387.544818 -254.002286) (xy 387.544818 -253.957836) (xy 387.344666 -253.957836) (xy 387.344666 -254.002286)
			(xy 387.444742 -254.102362)
		)
		(stroke
			(width 0)
			(type solid)
		)
		(fill yes)
		(layer "In4.Cu")
		(net "M_J_CPU0_SA_CA<3>")
	)
	(gr_poly
		(pts
			(xy 387.544818 -252.786134) (xy 387.444742 -252.686058) (xy 387.344666 -252.786134) (xy 387.344666 -252.830584)
			(xy 387.544818 -252.830584)
		)
		(stroke
			(width 0)
			(type solid)
		)
		(fill yes)
		(layer "In4.Cu")
		(net "M_J_CPU0_SA_CA<0>")
	)
	(gr_poly
		(pts
			(xy 387.544818 -251.166122) (xy 387.444742 -251.066046) (xy 387.344666 -251.166122) (xy 387.344666 -251.210572)
			(xy 387.544818 -251.210572)
		)
		(stroke
			(width 0)
			(type solid)
		)
		(fill yes)
		(layer "In4.Cu")
		(net "M_J_CPU0_SA_CS_N<0>")
	)
	(gr_poly
		(pts
			(xy 387.544818 -250.762262) (xy 387.544818 -250.717812) (xy 387.344666 -250.717812) (xy 387.344666 -250.762262)
			(xy 387.444742 -250.862338)
		)
		(stroke
			(width 0)
			(type solid)
		)
		(fill yes)
		(layer "In4.Cu")
		(net "M_J_CPU0_RESET_N")
	)
	(gr_poly
		(pts
			(xy 387.544818 -249.14225) (xy 387.544818 -249.0978) (xy 387.344666 -249.0978) (xy 387.344666 -249.14225)
			(xy 387.444742 -249.242326)
		)
		(stroke
			(width 0)
			(type solid)
		)
		(fill yes)
		(layer "In4.Cu")
		(net "M_J_CPU0_SA_CB<7>")
	)
	(gr_poly
		(pts
			(xy 387.544818 -247.926098) (xy 387.444742 -247.826022) (xy 387.344666 -247.926098) (xy 387.344666 -247.970548)
			(xy 387.544818 -247.970548)
		)
		(stroke
			(width 0)
			(type solid)
		)
		(fill yes)
		(layer "In4.Cu")
		(net "M_J_CPU0_SA_CB<4>")
	)
	(gr_poly
		(pts
			(xy 387.544818 -247.522492) (xy 387.544818 -247.47474) (xy 387.344666 -247.47474) (xy 387.344666 -247.522492)
			(xy 387.444742 -247.622314)
		)
		(stroke
			(width 0)
			(type solid)
		)
		(fill yes)
		(layer "In4.Cu")
		(net "M_J_CPU0_SA_DQS_DP<9>")
	)
	(gr_poly
		(pts
			(xy 387.544818 -246.305832) (xy 387.444742 -246.20601) (xy 387.344666 -246.305832) (xy 387.344666 -246.353584)
			(xy 387.544818 -246.353584)
		)
		(stroke
			(width 0)
			(type solid)
		)
		(fill yes)
		(layer "In4.Cu")
		(net "M_J_CPU0_SA_DQS_DP<4>")
	)
	(gr_poly
		(pts
			(xy 387.544818 -245.902226) (xy 387.544818 -245.857776) (xy 387.344666 -245.857776) (xy 387.344666 -245.902226)
			(xy 387.444742 -246.002302)
		)
		(stroke
			(width 0)
			(type solid)
		)
		(fill yes)
		(layer "In4.Cu")
		(net "M_J_CPU0_SA_CB<3>")
	)
	(gr_poly
		(pts
			(xy 387.544818 -244.686074) (xy 387.444742 -244.585998) (xy 387.344666 -244.686074) (xy 387.344666 -244.730524)
			(xy 387.544818 -244.730524)
		)
		(stroke
			(width 0)
			(type solid)
		)
		(fill yes)
		(layer "In4.Cu")
		(net "M_J_CPU0_SA_CB<0>")
	)
	(gr_poly
		(pts
			(xy 387.544818 -244.282214) (xy 387.544818 -244.237764) (xy 387.344666 -244.237764) (xy 387.344666 -244.282214)
			(xy 387.444742 -244.38229)
		)
		(stroke
			(width 0)
			(type solid)
		)
		(fill yes)
		(layer "In4.Cu")
		(net "M_J_CPU0_SA_DQ<31>")
	)
	(gr_poly
		(pts
			(xy 387.544818 -243.066062) (xy 387.444742 -242.965986) (xy 387.344666 -243.066062) (xy 387.344666 -243.110512)
			(xy 387.544818 -243.110512)
		)
		(stroke
			(width 0)
			(type solid)
		)
		(fill yes)
		(layer "In4.Cu")
		(net "M_J_CPU0_SA_DQ<28>")
	)
	(gr_poly
		(pts
			(xy 387.544818 -242.662456) (xy 387.544818 -242.614704) (xy 387.344666 -242.614704) (xy 387.344666 -242.662456)
			(xy 387.444742 -242.762278)
		)
		(stroke
			(width 0)
			(type solid)
		)
		(fill yes)
		(layer "In4.Cu")
		(net "M_J_CPU0_SA_DQS_DP<8>")
	)
	(gr_poly
		(pts
			(xy 387.544818 -241.445796) (xy 387.444742 -241.345974) (xy 387.344666 -241.445796) (xy 387.344666 -241.493548)
			(xy 387.544818 -241.493548)
		)
		(stroke
			(width 0)
			(type solid)
		)
		(fill yes)
		(layer "In4.Cu")
		(net "M_J_CPU0_SA_DQS_DP<3>")
	)
	(gr_poly
		(pts
			(xy 387.544818 -241.04219) (xy 387.544818 -240.99774) (xy 387.344666 -240.99774) (xy 387.344666 -241.04219)
			(xy 387.444742 -241.142266)
		)
		(stroke
			(width 0)
			(type solid)
		)
		(fill yes)
		(layer "In4.Cu")
		(net "M_J_CPU0_SA_DQ<27>")
	)
	(gr_poly
		(pts
			(xy 387.544818 -239.826038) (xy 387.444742 -239.725962) (xy 387.344666 -239.826038) (xy 387.344666 -239.870488)
			(xy 387.544818 -239.870488)
		)
		(stroke
			(width 0)
			(type solid)
		)
		(fill yes)
		(layer "In4.Cu")
		(net "M_J_CPU0_SA_DQ<24>")
	)
	(gr_poly
		(pts
			(xy 387.544818 -239.422178) (xy 387.544818 -239.377728) (xy 387.344666 -239.377728) (xy 387.344666 -239.422178)
			(xy 387.444742 -239.522254)
		)
		(stroke
			(width 0)
			(type solid)
		)
		(fill yes)
		(layer "In4.Cu")
		(net "M_J_CPU0_SA_DQ<23>")
	)
	(gr_poly
		(pts
			(xy 387.544818 -238.206026) (xy 387.444742 -238.10595) (xy 387.344666 -238.206026) (xy 387.344666 -238.250476)
			(xy 387.544818 -238.250476)
		)
		(stroke
			(width 0)
			(type solid)
		)
		(fill yes)
		(layer "In4.Cu")
		(net "M_J_CPU0_SA_DQ<20>")
	)
	(gr_poly
		(pts
			(xy 387.544818 -237.80242) (xy 387.544818 -237.754668) (xy 387.344666 -237.754668) (xy 387.344666 -237.80242)
			(xy 387.444742 -237.902242)
		)
		(stroke
			(width 0)
			(type solid)
		)
		(fill yes)
		(layer "In4.Cu")
		(net "M_J_CPU0_SA_DQS_DP<7>")
	)
	(gr_poly
		(pts
			(xy 387.544818 -236.58576) (xy 387.444742 -236.485938) (xy 387.344666 -236.58576) (xy 387.344666 -236.633512)
			(xy 387.544818 -236.633512)
		)
		(stroke
			(width 0)
			(type solid)
		)
		(fill yes)
		(layer "In4.Cu")
		(net "M_J_CPU0_SA_DQS_DP<2>")
	)
	(gr_poly
		(pts
			(xy 387.544818 -236.182154) (xy 387.544818 -236.137704) (xy 387.344666 -236.137704) (xy 387.344666 -236.182154)
			(xy 387.444742 -236.28223)
		)
		(stroke
			(width 0)
			(type solid)
		)
		(fill yes)
		(layer "In4.Cu")
		(net "M_J_CPU0_SA_DQ<19>")
	)
	(gr_poly
		(pts
			(xy 387.544818 -234.966002) (xy 387.444742 -234.865926) (xy 387.344666 -234.966002) (xy 387.344666 -235.010452)
			(xy 387.544818 -235.010452)
		)
		(stroke
			(width 0)
			(type solid)
		)
		(fill yes)
		(layer "In4.Cu")
		(net "M_J_CPU0_SA_DQ<16>")
	)
	(gr_poly
		(pts
			(xy 387.544818 -234.562142) (xy 387.544818 -234.517692) (xy 387.344666 -234.517692) (xy 387.344666 -234.562142)
			(xy 387.444742 -234.662218)
		)
		(stroke
			(width 0)
			(type solid)
		)
		(fill yes)
		(layer "In4.Cu")
		(net "M_J_CPU0_SA_DQ<15>")
	)
	(gr_poly
		(pts
			(xy 387.544818 -233.34599) (xy 387.444742 -233.245914) (xy 387.344666 -233.34599) (xy 387.344666 -233.39044)
			(xy 387.544818 -233.39044)
		)
		(stroke
			(width 0)
			(type solid)
		)
		(fill yes)
		(layer "In4.Cu")
		(net "M_J_CPU0_SA_DQ<12>")
	)
	(gr_poly
		(pts
			(xy 387.544818 -232.942384) (xy 387.544818 -232.894632) (xy 387.344666 -232.894632) (xy 387.344666 -232.942384)
			(xy 387.444742 -233.042206)
		)
		(stroke
			(width 0)
			(type solid)
		)
		(fill yes)
		(layer "In4.Cu")
		(net "M_J_CPU0_SA_DQS_DP<6>")
	)
	(gr_poly
		(pts
			(xy 387.544818 -231.725724) (xy 387.444742 -231.625902) (xy 387.344666 -231.725724) (xy 387.344666 -231.773476)
			(xy 387.544818 -231.773476)
		)
		(stroke
			(width 0)
			(type solid)
		)
		(fill yes)
		(layer "In4.Cu")
		(net "M_J_CPU0_SA_DQS_DP<1>")
	)
	(gr_poly
		(pts
			(xy 387.544818 -231.322372) (xy 387.544818 -231.277922) (xy 387.344666 -231.277922) (xy 387.344666 -231.322372)
			(xy 387.444742 -231.422448)
		)
		(stroke
			(width 0)
			(type solid)
		)
		(fill yes)
		(layer "In4.Cu")
		(net "M_J_CPU0_SA_DQ<11>")
	)
	(gr_poly
		(pts
			(xy 387.544818 -230.105966) (xy 387.444742 -230.006144) (xy 387.344666 -230.105966) (xy 387.344666 -230.150416)
			(xy 387.544818 -230.150416)
		)
		(stroke
			(width 0)
			(type solid)
		)
		(fill yes)
		(layer "In4.Cu")
		(net "M_J_CPU0_SA_DQ<8>")
	)
	(gr_poly
		(pts
			(xy 387.544818 -229.70236) (xy 387.544818 -229.65791) (xy 387.344666 -229.65791) (xy 387.344666 -229.70236)
			(xy 387.444742 -229.802436)
		)
		(stroke
			(width 0)
			(type solid)
		)
		(fill yes)
		(layer "In4.Cu")
		(net "M_J_CPU0_SA_DQ<7>")
	)
	(gr_poly
		(pts
			(xy 387.544818 -228.486208) (xy 387.444742 -228.386132) (xy 387.344666 -228.486208) (xy 387.344666 -228.530658)
			(xy 387.544818 -228.530658)
		)
		(stroke
			(width 0)
			(type solid)
		)
		(fill yes)
		(layer "In4.Cu")
		(net "M_J_CPU0_SA_DQ<4>")
	)
	(gr_poly
		(pts
			(xy 387.544818 -228.082602) (xy 387.544818 -228.03485) (xy 387.344666 -228.03485) (xy 387.344666 -228.082602)
			(xy 387.444742 -228.182424)
		)
		(stroke
			(width 0)
			(type solid)
		)
		(fill yes)
		(layer "In4.Cu")
		(net "M_J_CPU0_SA_DQS_DP<5>")
	)
	(gr_poly
		(pts
			(xy 387.544818 -226.865942) (xy 387.444742 -226.76612) (xy 387.344666 -226.865942) (xy 387.344666 -226.913694)
			(xy 387.544818 -226.913694)
		)
		(stroke
			(width 0)
			(type solid)
		)
		(fill yes)
		(layer "In4.Cu")
		(net "M_J_CPU0_SA_DQS_DP<0>")
	)
	(gr_poly
		(pts
			(xy 387.544818 -226.462336) (xy 387.544818 -226.417886) (xy 387.344666 -226.417886) (xy 387.344666 -226.462336)
			(xy 387.444742 -226.562412)
		)
		(stroke
			(width 0)
			(type solid)
		)
		(fill yes)
		(layer "In4.Cu")
		(net "M_J_CPU0_SA_DQ<3>")
	)
	(gr_poly
		(pts
			(xy 387.544818 -225.246184) (xy 387.444742 -225.146108) (xy 387.344666 -225.246184) (xy 387.344666 -225.290634)
			(xy 387.544818 -225.290634)
		)
		(stroke
			(width 0)
			(type solid)
		)
		(fill yes)
		(layer "In4.Cu")
		(net "M_J_CPU0_SA_DQ<0>")
	)
	(gr_poly
		(pts
			(xy 387.844792 -292.91788) (xy 387.744716 -292.817804) (xy 387.64464 -292.91788) (xy 387.64464 -292.96233)
			(xy 387.844792 -292.96233)
		)
		(stroke
			(width 0)
			(type solid)
		)
		(fill yes)
		(layer "In4.Cu")
		(net "M_J_CPU0_SB_DQ<29>")
	)
	(gr_poly
		(pts
			(xy 387.844792 -292.51402) (xy 387.844792 -292.46957) (xy 387.64464 -292.46957) (xy 387.64464 -292.51402)
			(xy 387.744716 -292.614096)
		)
		(stroke
			(width 0)
			(type solid)
		)
		(fill yes)
		(layer "In4.Cu")
		(net "M_J_CPU0_SB_DQ<30>")
	)
	(gr_poly
		(pts
			(xy 387.844792 -291.297614) (xy 387.744716 -291.197792) (xy 387.64464 -291.297614) (xy 387.64464 -291.345366)
			(xy 387.844792 -291.345366)
		)
		(stroke
			(width 0)
			(type solid)
		)
		(fill yes)
		(layer "In4.Cu")
		(net "M_J_CPU0_SB_DQS_DN<8>")
	)
	(gr_poly
		(pts
			(xy 387.844792 -290.894262) (xy 387.844792 -290.84651) (xy 387.64464 -290.84651) (xy 387.64464 -290.894262)
			(xy 387.744716 -290.994084)
		)
		(stroke
			(width 0)
			(type solid)
		)
		(fill yes)
		(layer "In4.Cu")
		(net "M_J_CPU0_SB_DQS_DN<3>")
	)
	(gr_poly
		(pts
			(xy 387.844792 -289.677856) (xy 387.744716 -289.57778) (xy 387.64464 -289.677856) (xy 387.64464 -289.722306)
			(xy 387.844792 -289.722306)
		)
		(stroke
			(width 0)
			(type solid)
		)
		(fill yes)
		(layer "In4.Cu")
		(net "M_J_CPU0_SB_DQ<25>")
	)
	(gr_poly
		(pts
			(xy 387.844792 -289.273996) (xy 387.844792 -289.229546) (xy 387.64464 -289.229546) (xy 387.64464 -289.273996)
			(xy 387.744716 -289.374072)
		)
		(stroke
			(width 0)
			(type solid)
		)
		(fill yes)
		(layer "In4.Cu")
		(net "M_J_CPU0_SB_DQ<26>")
	)
	(gr_poly
		(pts
			(xy 387.844792 -288.057844) (xy 387.744716 -287.957768) (xy 387.64464 -288.057844) (xy 387.64464 -288.102294)
			(xy 387.844792 -288.102294)
		)
		(stroke
			(width 0)
			(type solid)
		)
		(fill yes)
		(layer "In4.Cu")
		(net "M_J_CPU0_SB_DQ<21>")
	)
	(gr_poly
		(pts
			(xy 387.844792 -287.654238) (xy 387.844792 -287.609788) (xy 387.64464 -287.609788) (xy 387.64464 -287.654238)
			(xy 387.744716 -287.75406)
		)
		(stroke
			(width 0)
			(type solid)
		)
		(fill yes)
		(layer "In4.Cu")
		(net "M_J_CPU0_SB_DQ<22>")
	)
	(gr_poly
		(pts
			(xy 387.844792 -286.437832) (xy 387.744716 -286.337756) (xy 387.64464 -286.437832) (xy 387.64464 -286.485584)
			(xy 387.844792 -286.485584)
		)
		(stroke
			(width 0)
			(type solid)
		)
		(fill yes)
		(layer "In4.Cu")
		(net "M_J_CPU0_SB_DQS_DN<7>")
	)
	(gr_poly
		(pts
			(xy 387.844792 -286.03448) (xy 387.844792 -285.986728) (xy 387.64464 -285.986728) (xy 387.64464 -286.03448)
			(xy 387.744716 -286.134302)
		)
		(stroke
			(width 0)
			(type solid)
		)
		(fill yes)
		(layer "In4.Cu")
		(net "M_J_CPU0_SB_DQS_DN<2>")
	)
	(gr_poly
		(pts
			(xy 387.844792 -284.818074) (xy 387.744716 -284.717998) (xy 387.64464 -284.818074) (xy 387.64464 -284.862524)
			(xy 387.844792 -284.862524)
		)
		(stroke
			(width 0)
			(type solid)
		)
		(fill yes)
		(layer "In4.Cu")
		(net "M_J_CPU0_SB_DQ<17>")
	)
	(gr_poly
		(pts
			(xy 387.844792 -284.414214) (xy 387.844792 -284.369764) (xy 387.64464 -284.369764) (xy 387.64464 -284.414214)
			(xy 387.744716 -284.51429)
		)
		(stroke
			(width 0)
			(type solid)
		)
		(fill yes)
		(layer "In4.Cu")
		(net "M_J_CPU0_SB_DQ<18>")
	)
	(gr_poly
		(pts
			(xy 387.844792 -283.198062) (xy 387.744716 -283.097986) (xy 387.64464 -283.198062) (xy 387.64464 -283.242512)
			(xy 387.844792 -283.242512)
		)
		(stroke
			(width 0)
			(type solid)
		)
		(fill yes)
		(layer "In4.Cu")
		(net "M_J_CPU0_SB_DQ<13>")
	)
	(gr_poly
		(pts
			(xy 387.844792 -282.794202) (xy 387.844792 -282.749752) (xy 387.64464 -282.749752) (xy 387.64464 -282.794202)
			(xy 387.744716 -282.894278)
		)
		(stroke
			(width 0)
			(type solid)
		)
		(fill yes)
		(layer "In4.Cu")
		(net "M_J_CPU0_SB_DQ<14>")
	)
	(gr_poly
		(pts
			(xy 387.844792 -281.577796) (xy 387.744716 -281.477974) (xy 387.64464 -281.577796) (xy 387.64464 -281.625548)
			(xy 387.844792 -281.625548)
		)
		(stroke
			(width 0)
			(type solid)
		)
		(fill yes)
		(layer "In4.Cu")
		(net "M_J_CPU0_SB_DQS_DN<6>")
	)
	(gr_poly
		(pts
			(xy 387.844792 -281.174444) (xy 387.844792 -281.126692) (xy 387.64464 -281.126692) (xy 387.64464 -281.174444)
			(xy 387.744716 -281.274266)
		)
		(stroke
			(width 0)
			(type solid)
		)
		(fill yes)
		(layer "In4.Cu")
		(net "M_J_CPU0_SB_DQS_DN<1>")
	)
	(gr_poly
		(pts
			(xy 387.844792 -279.958038) (xy 387.744716 -279.857962) (xy 387.64464 -279.958038) (xy 387.64464 -280.002488)
			(xy 387.844792 -280.002488)
		)
		(stroke
			(width 0)
			(type solid)
		)
		(fill yes)
		(layer "In4.Cu")
		(net "M_J_CPU0_SB_DQ<9>")
	)
	(gr_poly
		(pts
			(xy 387.844792 -279.554178) (xy 387.844792 -279.509728) (xy 387.64464 -279.509728) (xy 387.64464 -279.554178)
			(xy 387.744716 -279.654254)
		)
		(stroke
			(width 0)
			(type solid)
		)
		(fill yes)
		(layer "In4.Cu")
		(net "M_J_CPU0_SB_DQ<10>")
	)
	(gr_poly
		(pts
			(xy 387.844792 -278.338026) (xy 387.744716 -278.23795) (xy 387.64464 -278.338026) (xy 387.64464 -278.382476)
			(xy 387.844792 -278.382476)
		)
		(stroke
			(width 0)
			(type solid)
		)
		(fill yes)
		(layer "In4.Cu")
		(net "M_J_CPU0_SB_DQ<5>")
	)
	(gr_poly
		(pts
			(xy 387.844792 -277.934166) (xy 387.844792 -277.889716) (xy 387.64464 -277.889716) (xy 387.64464 -277.934166)
			(xy 387.744716 -278.034242)
		)
		(stroke
			(width 0)
			(type solid)
		)
		(fill yes)
		(layer "In4.Cu")
		(net "M_J_CPU0_SB_DQ<6>")
	)
	(gr_poly
		(pts
			(xy 387.844792 -276.71776) (xy 387.744716 -276.617938) (xy 387.64464 -276.71776) (xy 387.64464 -276.765512)
			(xy 387.844792 -276.765512)
		)
		(stroke
			(width 0)
			(type solid)
		)
		(fill yes)
		(layer "In4.Cu")
		(net "M_J_CPU0_SB_DQS_DN<5>")
	)
	(gr_poly
		(pts
			(xy 387.844792 -276.314408) (xy 387.844792 -276.266656) (xy 387.64464 -276.266656) (xy 387.64464 -276.314408)
			(xy 387.744716 -276.41423)
		)
		(stroke
			(width 0)
			(type solid)
		)
		(fill yes)
		(layer "In4.Cu")
		(net "M_J_CPU0_SB_DQS_DN<0>")
	)
	(gr_poly
		(pts
			(xy 387.844792 -275.098002) (xy 387.744716 -274.997926) (xy 387.64464 -275.098002) (xy 387.64464 -275.142452)
			(xy 387.844792 -275.142452)
		)
		(stroke
			(width 0)
			(type solid)
		)
		(fill yes)
		(layer "In4.Cu")
		(net "M_J_CPU0_SB_DQ<1>")
	)
	(gr_poly
		(pts
			(xy 387.844792 -274.694142) (xy 387.844792 -274.649692) (xy 387.64464 -274.649692) (xy 387.64464 -274.694142)
			(xy 387.744716 -274.794218)
		)
		(stroke
			(width 0)
			(type solid)
		)
		(fill yes)
		(layer "In4.Cu")
		(net "M_J_CPU0_SB_DQ<2>")
	)
	(gr_poly
		(pts
			(xy 387.844792 -273.47799) (xy 387.744716 -273.377914) (xy 387.64464 -273.47799) (xy 387.64464 -273.52244)
			(xy 387.844792 -273.52244)
		)
		(stroke
			(width 0)
			(type solid)
		)
		(fill yes)
		(layer "In4.Cu")
		(net "M_J_CPU0_SB_CB<1>")
	)
	(gr_poly
		(pts
			(xy 387.844792 -273.07413) (xy 387.844792 -273.02968) (xy 387.64464 -273.02968) (xy 387.64464 -273.07413)
			(xy 387.744716 -273.174206)
		)
		(stroke
			(width 0)
			(type solid)
		)
		(fill yes)
		(layer "In4.Cu")
		(net "M_J_CPU0_SB_CB<2>")
	)
	(gr_poly
		(pts
			(xy 387.844792 -271.857724) (xy 387.744716 -271.757902) (xy 387.64464 -271.857724) (xy 387.64464 -271.905476)
			(xy 387.844792 -271.905476)
		)
		(stroke
			(width 0)
			(type solid)
		)
		(fill yes)
		(layer "In4.Cu")
		(net "M_J_CPU0_SB_DQS_DN<4>")
	)
	(gr_poly
		(pts
			(xy 387.844792 -271.454372) (xy 387.844792 -271.40662) (xy 387.64464 -271.40662) (xy 387.64464 -271.454372)
			(xy 387.744716 -271.554194)
		)
		(stroke
			(width 0)
			(type solid)
		)
		(fill yes)
		(layer "In4.Cu")
		(net "M_J_CPU0_SB_DQS_DN<9>")
	)
	(gr_poly
		(pts
			(xy 387.844792 -270.237966) (xy 387.744716 -270.13789) (xy 387.64464 -270.237966) (xy 387.64464 -270.282416)
			(xy 387.844792 -270.282416)
		)
		(stroke
			(width 0)
			(type solid)
		)
		(fill yes)
		(layer "In4.Cu")
		(net "M_J_CPU0_SB_CB<5>")
	)
	(gr_poly
		(pts
			(xy 387.844792 -269.834106) (xy 387.844792 -269.789656) (xy 387.64464 -269.789656) (xy 387.64464 -269.834106)
			(xy 387.744716 -269.934182)
		)
		(stroke
			(width 0)
			(type solid)
		)
		(fill yes)
		(layer "In4.Cu")
		(net "M_J_CPU0_SB_CB<6>")
	)
	(gr_poly
		(pts
			(xy 387.844792 -266.997942) (xy 387.744716 -266.897866) (xy 387.64464 -266.997942) (xy 387.64464 -267.042392)
			(xy 387.844792 -267.042392)
		)
		(stroke
			(width 0)
			(type solid)
		)
		(fill yes)
		(layer "In4.Cu")
		(net "M_J_CPU0_SA_RSP<0>")
	)
	(gr_poly
		(pts
			(xy 387.844792 -266.594082) (xy 387.844792 -266.549632) (xy 387.64464 -266.549632) (xy 387.64464 -266.594082)
			(xy 387.744716 -266.694158)
		)
		(stroke
			(width 0)
			(type solid)
		)
		(fill yes)
		(layer "In4.Cu")
		(net "M_J_CPU0_SB_CS_N<1>")
	)
	(gr_poly
		(pts
			(xy 387.844792 -265.37793) (xy 387.744716 -265.277854) (xy 387.64464 -265.37793) (xy 387.64464 -265.42238)
			(xy 387.844792 -265.42238)
		)
		(stroke
			(width 0)
			(type solid)
		)
		(fill yes)
		(layer "In4.Cu")
		(net "M_J_CPU0_SB_PAR")
	)
	(gr_poly
		(pts
			(xy 387.844792 -263.757918) (xy 387.744716 -263.657842) (xy 387.64464 -263.757918) (xy 387.64464 -263.802368)
			(xy 387.844792 -263.802368)
		)
		(stroke
			(width 0)
			(type solid)
		)
		(fill yes)
		(layer "In4.Cu")
		(net "M_J_CPU0_SB_CA<4>")
	)
	(gr_poly
		(pts
			(xy 387.844792 -263.354058) (xy 387.844792 -263.309608) (xy 387.64464 -263.309608) (xy 387.64464 -263.354058)
			(xy 387.744716 -263.454134)
		)
		(stroke
			(width 0)
			(type solid)
		)
		(fill yes)
		(layer "In4.Cu")
		(net "M_J_CPU0_SB_CA<3>")
	)
	(gr_poly
		(pts
			(xy 387.844792 -262.137906) (xy 387.744716 -262.03783) (xy 387.64464 -262.137906) (xy 387.64464 -262.182356)
			(xy 387.844792 -262.182356)
		)
		(stroke
			(width 0)
			(type solid)
		)
		(fill yes)
		(layer "In4.Cu")
		(net "M_J_CPU0_SB_CA<0>")
	)
	(gr_poly
		(pts
			(xy 388.014972 -256.432558) (xy 388.014972 -256.384806) (xy 387.81482 -256.384806) (xy 387.81482 -256.432558)
			(xy 387.914896 -256.53238)
		)
		(stroke
			(width 0)
			(type solid)
		)
		(fill yes)
		(layer "In4.Cu")
		(net "M_J_CPU0_CLK_DN<0>")
	)
	(gr_poly
		(pts
			(xy 388.014972 -255.216152) (xy 387.914896 -255.116076) (xy 387.81482 -255.216152) (xy 387.81482 -255.260602)
			(xy 388.014972 -255.260602)
		)
		(stroke
			(width 0)
			(type solid)
		)
		(fill yes)
		(layer "In4.Cu")
		(net "M_J_CPU0_SA_CA<6>")
	)
	(gr_poly
		(pts
			(xy 388.014972 -254.812292) (xy 388.014972 -254.767842) (xy 387.81482 -254.767842) (xy 387.81482 -254.812292)
			(xy 387.914896 -254.912368)
		)
		(stroke
			(width 0)
			(type solid)
		)
		(fill yes)
		(layer "In4.Cu")
		(net "M_J_CPU0_SA_CA<5>")
	)
	(gr_poly
		(pts
			(xy 388.014972 -253.59614) (xy 387.914896 -253.496064) (xy 387.81482 -253.59614) (xy 387.81482 -253.64059)
			(xy 388.014972 -253.64059)
		)
		(stroke
			(width 0)
			(type solid)
		)
		(fill yes)
		(layer "In4.Cu")
		(net "M_J_CPU0_SA_CA<2>")
	)
	(gr_poly
		(pts
			(xy 388.014972 -253.19228) (xy 388.014972 -253.14783) (xy 387.81482 -253.14783) (xy 387.81482 -253.19228)
			(xy 387.914896 -253.292356)
		)
		(stroke
			(width 0)
			(type solid)
		)
		(fill yes)
		(layer "In4.Cu")
		(net "M_J_CPU0_SA_CA<1>")
	)
	(gr_poly
		(pts
			(xy 388.014972 -251.976128) (xy 387.914896 -251.876052) (xy 387.81482 -251.976128) (xy 387.81482 -252.020578)
			(xy 388.014972 -252.020578)
		)
		(stroke
			(width 0)
			(type solid)
		)
		(fill yes)
		(layer "In4.Cu")
		(net "M_J_CPU0_SA_CS_N<1>")
	)
	(gr_poly
		(pts
			(xy 388.014972 -250.356116) (xy 387.914896 -250.25604) (xy 387.81482 -250.356116) (xy 387.81482 -250.400566)
			(xy 388.014972 -250.400566)
		)
		(stroke
			(width 0)
			(type solid)
		)
		(fill yes)
		(layer "In4.Cu")
		(net "M_J_CPU0_ALERT_R_N")
	)
	(gr_poly
		(pts
			(xy 388.014972 -248.736104) (xy 387.914896 -248.636028) (xy 387.81482 -248.736104) (xy 387.81482 -248.780554)
			(xy 388.014972 -248.780554)
		)
		(stroke
			(width 0)
			(type solid)
		)
		(fill yes)
		(layer "In4.Cu")
		(net "M_J_CPU0_SA_CB<5>")
	)
	(gr_poly
		(pts
			(xy 388.014972 -248.332244) (xy 388.014972 -248.287794) (xy 387.81482 -248.287794) (xy 387.81482 -248.332244)
			(xy 387.914896 -248.43232)
		)
		(stroke
			(width 0)
			(type solid)
		)
		(fill yes)
		(layer "In4.Cu")
		(net "M_J_CPU0_SA_CB<6>")
	)
	(gr_poly
		(pts
			(xy 388.014972 -247.115838) (xy 387.914896 -247.016016) (xy 387.81482 -247.115838) (xy 387.81482 -247.16359)
			(xy 388.014972 -247.16359)
		)
		(stroke
			(width 0)
			(type solid)
		)
		(fill yes)
		(layer "In4.Cu")
		(net "M_J_CPU0_SA_DQS_DN<9>")
	)
	(gr_poly
		(pts
			(xy 388.014972 -246.712486) (xy 388.014972 -246.664734) (xy 387.81482 -246.664734) (xy 387.81482 -246.712486)
			(xy 387.914896 -246.812308)
		)
		(stroke
			(width 0)
			(type solid)
		)
		(fill yes)
		(layer "In4.Cu")
		(net "M_J_CPU0_SA_DQS_DN<4>")
	)
	(gr_poly
		(pts
			(xy 388.014972 -245.49608) (xy 387.914896 -245.396004) (xy 387.81482 -245.49608) (xy 387.81482 -245.54053)
			(xy 388.014972 -245.54053)
		)
		(stroke
			(width 0)
			(type solid)
		)
		(fill yes)
		(layer "In4.Cu")
		(net "M_J_CPU0_SA_CB<1>")
	)
	(gr_poly
		(pts
			(xy 388.014972 -245.09222) (xy 388.014972 -245.04777) (xy 387.81482 -245.04777) (xy 387.81482 -245.09222)
			(xy 387.914896 -245.192296)
		)
		(stroke
			(width 0)
			(type solid)
		)
		(fill yes)
		(layer "In4.Cu")
		(net "M_J_CPU0_SA_CB<2>")
	)
	(gr_poly
		(pts
			(xy 388.014972 -243.876068) (xy 387.914896 -243.775992) (xy 387.81482 -243.876068) (xy 387.81482 -243.920518)
			(xy 388.014972 -243.920518)
		)
		(stroke
			(width 0)
			(type solid)
		)
		(fill yes)
		(layer "In4.Cu")
		(net "M_J_CPU0_SA_DQ<29>")
	)
	(gr_poly
		(pts
			(xy 388.014972 -243.472208) (xy 388.014972 -243.427758) (xy 387.81482 -243.427758) (xy 387.81482 -243.472208)
			(xy 387.914896 -243.572284)
		)
		(stroke
			(width 0)
			(type solid)
		)
		(fill yes)
		(layer "In4.Cu")
		(net "M_J_CPU0_SA_DQ<30>")
	)
	(gr_poly
		(pts
			(xy 388.014972 -242.255802) (xy 387.914896 -242.15598) (xy 387.81482 -242.255802) (xy 387.81482 -242.303554)
			(xy 388.014972 -242.303554)
		)
		(stroke
			(width 0)
			(type solid)
		)
		(fill yes)
		(layer "In4.Cu")
		(net "M_J_CPU0_SA_DQS_DN<8>")
	)
	(gr_poly
		(pts
			(xy 388.014972 -241.85245) (xy 388.014972 -241.804698) (xy 387.81482 -241.804698) (xy 387.81482 -241.85245)
			(xy 387.914896 -241.952272)
		)
		(stroke
			(width 0)
			(type solid)
		)
		(fill yes)
		(layer "In4.Cu")
		(net "M_J_CPU0_SA_DQS_DN<3>")
	)
	(gr_poly
		(pts
			(xy 388.014972 -240.636044) (xy 387.914896 -240.535968) (xy 387.81482 -240.636044) (xy 387.81482 -240.680494)
			(xy 388.014972 -240.680494)
		)
		(stroke
			(width 0)
			(type solid)
		)
		(fill yes)
		(layer "In4.Cu")
		(net "M_J_CPU0_SA_DQ<25>")
	)
	(gr_poly
		(pts
			(xy 388.014972 -240.232184) (xy 388.014972 -240.187734) (xy 387.81482 -240.187734) (xy 387.81482 -240.232184)
			(xy 387.914896 -240.33226)
		)
		(stroke
			(width 0)
			(type solid)
		)
		(fill yes)
		(layer "In4.Cu")
		(net "M_J_CPU0_SA_DQ<26>")
	)
	(gr_poly
		(pts
			(xy 388.014972 -239.016032) (xy 387.914896 -238.915956) (xy 387.81482 -239.016032) (xy 387.81482 -239.060482)
			(xy 388.014972 -239.060482)
		)
		(stroke
			(width 0)
			(type solid)
		)
		(fill yes)
		(layer "In4.Cu")
		(net "M_J_CPU0_SA_DQ<21>")
	)
	(gr_poly
		(pts
			(xy 388.014972 -238.612172) (xy 388.014972 -238.567722) (xy 387.81482 -238.567722) (xy 387.81482 -238.612172)
			(xy 387.914896 -238.712248)
		)
		(stroke
			(width 0)
			(type solid)
		)
		(fill yes)
		(layer "In4.Cu")
		(net "M_J_CPU0_SA_DQ<22>")
	)
	(gr_poly
		(pts
			(xy 388.014972 -237.395766) (xy 387.914896 -237.295944) (xy 387.81482 -237.395766) (xy 387.81482 -237.443518)
			(xy 388.014972 -237.443518)
		)
		(stroke
			(width 0)
			(type solid)
		)
		(fill yes)
		(layer "In4.Cu")
		(net "M_J_CPU0_SA_DQS_DN<7>")
	)
	(gr_poly
		(pts
			(xy 388.014972 -236.992414) (xy 388.014972 -236.944662) (xy 387.81482 -236.944662) (xy 387.81482 -236.992414)
			(xy 387.914896 -237.092236)
		)
		(stroke
			(width 0)
			(type solid)
		)
		(fill yes)
		(layer "In4.Cu")
		(net "M_J_CPU0_SA_DQS_DN<2>")
	)
	(gr_poly
		(pts
			(xy 388.014972 -235.776008) (xy 387.914896 -235.675932) (xy 387.81482 -235.776008) (xy 387.81482 -235.820458)
			(xy 388.014972 -235.820458)
		)
		(stroke
			(width 0)
			(type solid)
		)
		(fill yes)
		(layer "In4.Cu")
		(net "M_J_CPU0_SA_DQ<17>")
	)
	(gr_poly
		(pts
			(xy 388.014972 -235.372148) (xy 388.014972 -235.327698) (xy 387.81482 -235.327698) (xy 387.81482 -235.372148)
			(xy 387.914896 -235.472224)
		)
		(stroke
			(width 0)
			(type solid)
		)
		(fill yes)
		(layer "In4.Cu")
		(net "M_J_CPU0_SA_DQ<18>")
	)
	(gr_poly
		(pts
			(xy 388.014972 -234.155996) (xy 387.914896 -234.05592) (xy 387.81482 -234.155996) (xy 387.81482 -234.200446)
			(xy 388.014972 -234.200446)
		)
		(stroke
			(width 0)
			(type solid)
		)
		(fill yes)
		(layer "In4.Cu")
		(net "M_J_CPU0_SA_DQ<13>")
	)
	(gr_poly
		(pts
			(xy 388.014972 -233.752136) (xy 388.014972 -233.707686) (xy 387.81482 -233.707686) (xy 387.81482 -233.752136)
			(xy 387.914896 -233.852212)
		)
		(stroke
			(width 0)
			(type solid)
		)
		(fill yes)
		(layer "In4.Cu")
		(net "M_J_CPU0_SA_DQ<14>")
	)
	(gr_poly
		(pts
			(xy 388.014972 -232.53573) (xy 387.914896 -232.435908) (xy 387.81482 -232.53573) (xy 387.81482 -232.583482)
			(xy 388.014972 -232.583482)
		)
		(stroke
			(width 0)
			(type solid)
		)
		(fill yes)
		(layer "In4.Cu")
		(net "M_J_CPU0_SA_DQS_DN<6>")
	)
	(gr_poly
		(pts
			(xy 388.014972 -232.132378) (xy 388.014972 -232.084626) (xy 387.81482 -232.084626) (xy 387.81482 -232.132378)
			(xy 387.914896 -232.2322)
		)
		(stroke
			(width 0)
			(type solid)
		)
		(fill yes)
		(layer "In4.Cu")
		(net "M_J_CPU0_SA_DQS_DN<1>")
	)
	(gr_poly
		(pts
			(xy 388.014972 -230.915972) (xy 387.914896 -230.815896) (xy 387.81482 -230.915972) (xy 387.81482 -230.960422)
			(xy 388.014972 -230.960422)
		)
		(stroke
			(width 0)
			(type solid)
		)
		(fill yes)
		(layer "In4.Cu")
		(net "M_J_CPU0_SA_DQ<9>")
	)
	(gr_poly
		(pts
			(xy 388.014972 -230.512366) (xy 388.014972 -230.467916) (xy 387.81482 -230.467916) (xy 387.81482 -230.512366)
			(xy 387.914896 -230.612188)
		)
		(stroke
			(width 0)
			(type solid)
		)
		(fill yes)
		(layer "In4.Cu")
		(net "M_J_CPU0_SA_DQ<10>")
	)
	(gr_poly
		(pts
			(xy 388.014972 -229.29596) (xy 387.914896 -229.195884) (xy 387.81482 -229.29596) (xy 387.81482 -229.34041)
			(xy 388.014972 -229.34041)
		)
		(stroke
			(width 0)
			(type solid)
		)
		(fill yes)
		(layer "In4.Cu")
		(net "M_J_CPU0_SA_DQ<5>")
	)
	(gr_poly
		(pts
			(xy 388.014972 -228.892354) (xy 388.014972 -228.847904) (xy 387.81482 -228.847904) (xy 387.81482 -228.892354)
			(xy 387.914896 -228.99243)
		)
		(stroke
			(width 0)
			(type solid)
		)
		(fill yes)
		(layer "In4.Cu")
		(net "M_J_CPU0_SA_DQ<6>")
	)
	(gr_poly
		(pts
			(xy 388.014972 -227.675948) (xy 387.914896 -227.576126) (xy 387.81482 -227.675948) (xy 387.81482 -227.7237)
			(xy 388.014972 -227.7237)
		)
		(stroke
			(width 0)
			(type solid)
		)
		(fill yes)
		(layer "In4.Cu")
		(net "M_J_CPU0_SA_DQS_DN<5>")
	)
	(gr_poly
		(pts
			(xy 388.014972 -227.272596) (xy 388.014972 -227.224844) (xy 387.81482 -227.224844) (xy 387.81482 -227.272596)
			(xy 387.914896 -227.372418)
		)
		(stroke
			(width 0)
			(type solid)
		)
		(fill yes)
		(layer "In4.Cu")
		(net "M_J_CPU0_SA_DQS_DN<0>")
	)
	(gr_poly
		(pts
			(xy 388.014972 -226.05619) (xy 387.914896 -225.956114) (xy 387.81482 -226.05619) (xy 387.81482 -226.10064)
			(xy 388.014972 -226.10064)
		)
		(stroke
			(width 0)
			(type solid)
		)
		(fill yes)
		(layer "In4.Cu")
		(net "M_J_CPU0_SA_DQ<1>")
	)
	(gr_poly
		(pts
			(xy 388.014972 -225.65233) (xy 388.014972 -225.60788) (xy 387.81482 -225.60788) (xy 387.81482 -225.65233)
			(xy 387.914896 -225.752406)
		)
		(stroke
			(width 0)
			(type solid)
		)
		(fill yes)
		(layer "In4.Cu")
		(net "M_J_CPU0_SA_DQ<2>")
	)
	(gr_poly
		(pts
			(xy 388.314946 -293.324026) (xy 388.314946 -293.279576) (xy 388.114794 -293.279576) (xy 388.114794 -293.324026)
			(xy 388.21487 -293.424102)
		)
		(stroke
			(width 0)
			(type solid)
		)
		(fill yes)
		(layer "In4.Cu")
		(net "M_J_CPU0_SB_DQ<31>")
	)
	(gr_poly
		(pts
			(xy 388.314946 -292.107874) (xy 388.21487 -292.007798) (xy 388.114794 -292.107874) (xy 388.114794 -292.152324)
			(xy 388.314946 -292.152324)
		)
		(stroke
			(width 0)
			(type solid)
		)
		(fill yes)
		(layer "In4.Cu")
		(net "M_J_CPU0_SB_DQ<28>")
	)
	(gr_poly
		(pts
			(xy 388.314946 -291.704268) (xy 388.314946 -291.656516) (xy 388.114794 -291.656516) (xy 388.114794 -291.704268)
			(xy 388.21487 -291.80409)
		)
		(stroke
			(width 0)
			(type solid)
		)
		(fill yes)
		(layer "In4.Cu")
		(net "M_J_CPU0_SB_DQS_DP<8>")
	)
	(gr_poly
		(pts
			(xy 388.314946 -290.487608) (xy 388.21487 -290.387786) (xy 388.114794 -290.487608) (xy 388.114794 -290.53536)
			(xy 388.314946 -290.53536)
		)
		(stroke
			(width 0)
			(type solid)
		)
		(fill yes)
		(layer "In4.Cu")
		(net "M_J_CPU0_SB_DQS_DP<3>")
	)
	(gr_poly
		(pts
			(xy 388.314946 -290.084002) (xy 388.314946 -290.039552) (xy 388.114794 -290.039552) (xy 388.114794 -290.084002)
			(xy 388.21487 -290.184078)
		)
		(stroke
			(width 0)
			(type solid)
		)
		(fill yes)
		(layer "In4.Cu")
		(net "M_J_CPU0_SB_DQ<27>")
	)
	(gr_poly
		(pts
			(xy 388.314946 -288.86785) (xy 388.21487 -288.767774) (xy 388.114794 -288.86785) (xy 388.114794 -288.9123)
			(xy 388.314946 -288.9123)
		)
		(stroke
			(width 0)
			(type solid)
		)
		(fill yes)
		(layer "In4.Cu")
		(net "M_J_CPU0_SB_DQ<24>")
	)
	(gr_poly
		(pts
			(xy 388.314946 -288.464244) (xy 388.314946 -288.419794) (xy 388.114794 -288.419794) (xy 388.114794 -288.464244)
			(xy 388.21487 -288.56432)
		)
		(stroke
			(width 0)
			(type solid)
		)
		(fill yes)
		(layer "In4.Cu")
		(net "M_J_CPU0_SB_DQ<23>")
	)
	(gr_poly
		(pts
			(xy 388.314946 -287.247838) (xy 388.21487 -287.148016) (xy 388.114794 -287.247838) (xy 388.114794 -287.292288)
			(xy 388.314946 -287.292288)
		)
		(stroke
			(width 0)
			(type solid)
		)
		(fill yes)
		(layer "In4.Cu")
		(net "M_J_CPU0_SB_DQ<20>")
	)
	(gr_poly
		(pts
			(xy 388.314946 -286.844232) (xy 388.314946 -286.79648) (xy 388.114794 -286.79648) (xy 388.114794 -286.844232)
			(xy 388.21487 -286.944308)
		)
		(stroke
			(width 0)
			(type solid)
		)
		(fill yes)
		(layer "In4.Cu")
		(net "M_J_CPU0_SB_DQS_DP<7>")
	)
	(gr_poly
		(pts
			(xy 388.314946 -285.627826) (xy 388.21487 -285.528004) (xy 388.114794 -285.627826) (xy 388.114794 -285.675578)
			(xy 388.314946 -285.675578)
		)
		(stroke
			(width 0)
			(type solid)
		)
		(fill yes)
		(layer "In4.Cu")
		(net "M_J_CPU0_SB_DQS_DP<2>")
	)
	(gr_poly
		(pts
			(xy 388.314946 -285.22422) (xy 388.314946 -285.17977) (xy 388.114794 -285.17977) (xy 388.114794 -285.22422)
			(xy 388.21487 -285.324296)
		)
		(stroke
			(width 0)
			(type solid)
		)
		(fill yes)
		(layer "In4.Cu")
		(net "M_J_CPU0_SB_DQ<19>")
	)
	(gr_poly
		(pts
			(xy 388.314946 -284.008068) (xy 388.21487 -283.907992) (xy 388.114794 -284.008068) (xy 388.114794 -284.052518)
			(xy 388.314946 -284.052518)
		)
		(stroke
			(width 0)
			(type solid)
		)
		(fill yes)
		(layer "In4.Cu")
		(net "M_J_CPU0_SB_DQ<16>")
	)
	(gr_poly
		(pts
			(xy 388.314946 -283.604208) (xy 388.314946 -283.559758) (xy 388.114794 -283.559758) (xy 388.114794 -283.604208)
			(xy 388.21487 -283.704284)
		)
		(stroke
			(width 0)
			(type solid)
		)
		(fill yes)
		(layer "In4.Cu")
		(net "M_J_CPU0_SB_DQ<15>")
	)
	(gr_poly
		(pts
			(xy 388.314946 -282.388056) (xy 388.21487 -282.28798) (xy 388.114794 -282.388056) (xy 388.114794 -282.432506)
			(xy 388.314946 -282.432506)
		)
		(stroke
			(width 0)
			(type solid)
		)
		(fill yes)
		(layer "In4.Cu")
		(net "M_J_CPU0_SB_DQ<12>")
	)
	(gr_poly
		(pts
			(xy 388.314946 -281.98445) (xy 388.314946 -281.936698) (xy 388.114794 -281.936698) (xy 388.114794 -281.98445)
			(xy 388.21487 -282.084272)
		)
		(stroke
			(width 0)
			(type solid)
		)
		(fill yes)
		(layer "In4.Cu")
		(net "M_J_CPU0_SB_DQS_DP<6>")
	)
	(gr_poly
		(pts
			(xy 388.314946 -280.76779) (xy 388.21487 -280.667968) (xy 388.114794 -280.76779) (xy 388.114794 -280.815542)
			(xy 388.314946 -280.815542)
		)
		(stroke
			(width 0)
			(type solid)
		)
		(fill yes)
		(layer "In4.Cu")
		(net "M_J_CPU0_SB_DQS_DP<1>")
	)
	(gr_poly
		(pts
			(xy 388.314946 -280.364184) (xy 388.314946 -280.319734) (xy 388.114794 -280.319734) (xy 388.114794 -280.364184)
			(xy 388.21487 -280.46426)
		)
		(stroke
			(width 0)
			(type solid)
		)
		(fill yes)
		(layer "In4.Cu")
		(net "M_J_CPU0_SB_DQ<11>")
	)
	(gr_poly
		(pts
			(xy 388.314946 -279.148032) (xy 388.21487 -279.047956) (xy 388.114794 -279.148032) (xy 388.114794 -279.192482)
			(xy 388.314946 -279.192482)
		)
		(stroke
			(width 0)
			(type solid)
		)
		(fill yes)
		(layer "In4.Cu")
		(net "M_J_CPU0_SB_DQ<8>")
	)
	(gr_poly
		(pts
			(xy 388.314946 -278.744172) (xy 388.314946 -278.699722) (xy 388.114794 -278.699722) (xy 388.114794 -278.744172)
			(xy 388.21487 -278.844248)
		)
		(stroke
			(width 0)
			(type solid)
		)
		(fill yes)
		(layer "In4.Cu")
		(net "M_J_CPU0_SB_DQ<7>")
	)
	(gr_poly
		(pts
			(xy 388.314946 -277.52802) (xy 388.21487 -277.427944) (xy 388.114794 -277.52802) (xy 388.114794 -277.57247)
			(xy 388.314946 -277.57247)
		)
		(stroke
			(width 0)
			(type solid)
		)
		(fill yes)
		(layer "In4.Cu")
		(net "M_J_CPU0_SB_DQ<4>")
	)
	(gr_poly
		(pts
			(xy 388.314946 -277.124414) (xy 388.314946 -277.076662) (xy 388.114794 -277.076662) (xy 388.114794 -277.124414)
			(xy 388.21487 -277.224236)
		)
		(stroke
			(width 0)
			(type solid)
		)
		(fill yes)
		(layer "In4.Cu")
		(net "M_J_CPU0_SB_DQS_DP<5>")
	)
	(gr_poly
		(pts
			(xy 388.314946 -275.907754) (xy 388.21487 -275.807932) (xy 388.114794 -275.907754) (xy 388.114794 -275.955506)
			(xy 388.314946 -275.955506)
		)
		(stroke
			(width 0)
			(type solid)
		)
		(fill yes)
		(layer "In4.Cu")
		(net "M_J_CPU0_SB_DQS_DP<0>")
	)
	(gr_poly
		(pts
			(xy 388.314946 -275.504148) (xy 388.314946 -275.459698) (xy 388.114794 -275.459698) (xy 388.114794 -275.504148)
			(xy 388.21487 -275.604224)
		)
		(stroke
			(width 0)
			(type solid)
		)
		(fill yes)
		(layer "In4.Cu")
		(net "M_J_CPU0_SB_DQ<3>")
	)
	(gr_poly
		(pts
			(xy 388.314946 -274.287996) (xy 388.21487 -274.18792) (xy 388.114794 -274.287996) (xy 388.114794 -274.332446)
			(xy 388.314946 -274.332446)
		)
		(stroke
			(width 0)
			(type solid)
		)
		(fill yes)
		(layer "In4.Cu")
		(net "M_J_CPU0_SB_DQ<0>")
	)
	(gr_poly
		(pts
			(xy 388.314946 -273.884136) (xy 388.314946 -273.839686) (xy 388.114794 -273.839686) (xy 388.114794 -273.884136)
			(xy 388.21487 -273.984212)
		)
		(stroke
			(width 0)
			(type solid)
		)
		(fill yes)
		(layer "In4.Cu")
		(net "M_J_CPU0_SB_CB<3>")
	)
	(gr_poly
		(pts
			(xy 388.314946 -272.667984) (xy 388.21487 -272.567908) (xy 388.114794 -272.667984) (xy 388.114794 -272.712434)
			(xy 388.314946 -272.712434)
		)
		(stroke
			(width 0)
			(type solid)
		)
		(fill yes)
		(layer "In4.Cu")
		(net "M_J_CPU0_SB_CB<0>")
	)
	(gr_poly
		(pts
			(xy 388.314946 -272.264378) (xy 388.314946 -272.216626) (xy 388.114794 -272.216626) (xy 388.114794 -272.264378)
			(xy 388.21487 -272.3642)
		)
		(stroke
			(width 0)
			(type solid)
		)
		(fill yes)
		(layer "In4.Cu")
		(net "M_J_CPU0_SB_DQS_DP<4>")
	)
	(gr_poly
		(pts
			(xy 388.314946 -271.047718) (xy 388.21487 -270.947896) (xy 388.114794 -271.047718) (xy 388.114794 -271.09547)
			(xy 388.314946 -271.09547)
		)
		(stroke
			(width 0)
			(type solid)
		)
		(fill yes)
		(layer "In4.Cu")
		(net "M_J_CPU0_SB_DQS_DP<9>")
	)
	(gr_poly
		(pts
			(xy 388.314946 -270.644112) (xy 388.314946 -270.599662) (xy 388.114794 -270.599662) (xy 388.114794 -270.644112)
			(xy 388.21487 -270.744188)
		)
		(stroke
			(width 0)
			(type solid)
		)
		(fill yes)
		(layer "In4.Cu")
		(net "M_J_CPU0_SB_CB<7>")
	)
	(gr_poly
		(pts
			(xy 388.314946 -269.42796) (xy 388.21487 -269.327884) (xy 388.114794 -269.42796) (xy 388.114794 -269.47241)
			(xy 388.314946 -269.47241)
		)
		(stroke
			(width 0)
			(type solid)
		)
		(fill yes)
		(layer "In4.Cu")
		(net "M_J_CPU0_SB_CB<4>")
	)
	(gr_poly
		(pts
			(xy 388.314946 -267.807948) (xy 388.21487 -267.707872) (xy 388.114794 -267.807948) (xy 388.114794 -267.852398)
			(xy 388.314946 -267.852398)
		)
		(stroke
			(width 0)
			(type solid)
		)
		(fill yes)
		(layer "In4.Cu")
		(net "M_J_CPU0_SB_RSP<0>")
	)
	(gr_poly
		(pts
			(xy 388.314946 -265.784076) (xy 388.314946 -265.739626) (xy 388.114794 -265.739626) (xy 388.114794 -265.784076)
			(xy 388.21487 -265.884152)
		)
		(stroke
			(width 0)
			(type solid)
		)
		(fill yes)
		(layer "In4.Cu")
		(net "M_J_CPU0_SB_CS_N<0>")
	)
	(gr_poly
		(pts
			(xy 388.314946 -264.567924) (xy 388.21487 -264.467848) (xy 388.114794 -264.567924) (xy 388.114794 -264.612374)
			(xy 388.314946 -264.612374)
		)
		(stroke
			(width 0)
			(type solid)
		)
		(fill yes)
		(layer "In4.Cu")
		(net "M_J_CPU0_SB_CA<6>")
	)
	(gr_poly
		(pts
			(xy 388.314946 -264.164064) (xy 388.314946 -264.119614) (xy 388.114794 -264.119614) (xy 388.114794 -264.164064)
			(xy 388.21487 -264.26414)
		)
		(stroke
			(width 0)
			(type solid)
		)
		(fill yes)
		(layer "In4.Cu")
		(net "M_J_CPU0_SB_CA<5>")
	)
	(gr_poly
		(pts
			(xy 388.314946 -262.947912) (xy 388.21487 -262.847836) (xy 388.114794 -262.947912) (xy 388.114794 -262.992362)
			(xy 388.314946 -262.992362)
		)
		(stroke
			(width 0)
			(type solid)
		)
		(fill yes)
		(layer "In4.Cu")
		(net "M_J_CPU0_SB_CA<2>")
	)
	(gr_poly
		(pts
			(xy 388.314946 -262.544052) (xy 388.314946 -262.499602) (xy 388.114794 -262.499602) (xy 388.114794 -262.544052)
			(xy 388.21487 -262.644128)
		)
		(stroke
			(width 0)
			(type solid)
		)
		(fill yes)
		(layer "In4.Cu")
		(net "M_J_CPU0_SB_CA<1>")
	)
	(gr_poly
		(pts
			(xy 388.4041 -224.695512) (xy 388.365492 -224.67316) (xy 388.229094 -224.709736) (xy 388.26567 -224.846388)
			(xy 388.304024 -224.86874)
		)
		(stroke
			(width 0)
			(type solid)
		)
		(fill yes)
		(layer "In4.Cu")
		(net "M_J_CPU0_SA_DQ<0>")
	)
	(gr_poly
		(pts
			(xy 388.484872 -256.025904) (xy 388.384796 -255.926082) (xy 388.28472 -256.025904) (xy 388.28472 -256.073656)
			(xy 388.484872 -256.073656)
		)
		(stroke
			(width 0)
			(type solid)
		)
		(fill yes)
		(layer "In4.Cu")
		(net "M_J_CPU0_CLK_DP<0>")
	)
	(gr_poly
		(pts
			(xy 388.484872 -255.622298) (xy 388.484872 -255.577848) (xy 388.28472 -255.577848) (xy 388.28472 -255.622298)
			(xy 388.384796 -255.722374)
		)
		(stroke
			(width 0)
			(type solid)
		)
		(fill yes)
		(layer "In4.Cu")
		(net "M_J_CPU0_SA_PAR")
	)
	(gr_poly
		(pts
			(xy 388.484872 -254.406146) (xy 388.384796 -254.30607) (xy 388.28472 -254.406146) (xy 388.28472 -254.450596)
			(xy 388.484872 -254.450596)
		)
		(stroke
			(width 0)
			(type solid)
		)
		(fill yes)
		(layer "In4.Cu")
		(net "M_J_CPU0_SA_CA<4>")
	)
	(gr_poly
		(pts
			(xy 388.484872 -254.002286) (xy 388.484872 -253.957836) (xy 388.28472 -253.957836) (xy 388.28472 -254.002286)
			(xy 388.384796 -254.102362)
		)
		(stroke
			(width 0)
			(type solid)
		)
		(fill yes)
		(layer "In4.Cu")
		(net "M_J_CPU0_SA_CA<3>")
	)
	(gr_poly
		(pts
			(xy 388.484872 -252.786134) (xy 388.384796 -252.686058) (xy 388.28472 -252.786134) (xy 388.28472 -252.830584)
			(xy 388.484872 -252.830584)
		)
		(stroke
			(width 0)
			(type solid)
		)
		(fill yes)
		(layer "In4.Cu")
		(net "M_J_CPU0_SA_CA<0>")
	)
	(gr_poly
		(pts
			(xy 388.484872 -251.166122) (xy 388.384796 -251.066046) (xy 388.28472 -251.166122) (xy 388.28472 -251.210572)
			(xy 388.484872 -251.210572)
		)
		(stroke
			(width 0)
			(type solid)
		)
		(fill yes)
		(layer "In4.Cu")
		(net "M_J_CPU0_SA_CS_N<0>")
	)
	(gr_poly
		(pts
			(xy 388.484872 -250.762262) (xy 388.484872 -250.717812) (xy 388.28472 -250.717812) (xy 388.28472 -250.762262)
			(xy 388.384796 -250.862338)
		)
		(stroke
			(width 0)
			(type solid)
		)
		(fill yes)
		(layer "In4.Cu")
		(net "M_J_CPU0_RESET_N")
	)
	(gr_poly
		(pts
			(xy 388.484872 -249.14225) (xy 388.484872 -249.0978) (xy 388.28472 -249.0978) (xy 388.28472 -249.14225)
			(xy 388.384796 -249.242326)
		)
		(stroke
			(width 0)
			(type solid)
		)
		(fill yes)
		(layer "In4.Cu")
		(net "M_J_CPU0_SA_CB<7>")
	)
	(gr_poly
		(pts
			(xy 388.484872 -247.926098) (xy 388.384796 -247.826022) (xy 388.28472 -247.926098) (xy 388.28472 -247.970548)
			(xy 388.484872 -247.970548)
		)
		(stroke
			(width 0)
			(type solid)
		)
		(fill yes)
		(layer "In4.Cu")
		(net "M_J_CPU0_SA_CB<4>")
	)
	(gr_poly
		(pts
			(xy 388.484872 -247.522492) (xy 388.484872 -247.47474) (xy 388.28472 -247.47474) (xy 388.28472 -247.522492)
			(xy 388.384796 -247.622314)
		)
		(stroke
			(width 0)
			(type solid)
		)
		(fill yes)
		(layer "In4.Cu")
		(net "M_J_CPU0_SA_DQS_DP<9>")
	)
	(gr_poly
		(pts
			(xy 388.484872 -246.305832) (xy 388.384796 -246.20601) (xy 388.28472 -246.305832) (xy 388.28472 -246.353584)
			(xy 388.484872 -246.353584)
		)
		(stroke
			(width 0)
			(type solid)
		)
		(fill yes)
		(layer "In4.Cu")
		(net "M_J_CPU0_SA_DQS_DP<4>")
	)
	(gr_poly
		(pts
			(xy 388.484872 -245.902226) (xy 388.484872 -245.857776) (xy 388.28472 -245.857776) (xy 388.28472 -245.902226)
			(xy 388.384796 -246.002302)
		)
		(stroke
			(width 0)
			(type solid)
		)
		(fill yes)
		(layer "In4.Cu")
		(net "M_J_CPU0_SA_CB<3>")
	)
	(gr_poly
		(pts
			(xy 388.484872 -244.686074) (xy 388.384796 -244.585998) (xy 388.28472 -244.686074) (xy 388.28472 -244.730524)
			(xy 388.484872 -244.730524)
		)
		(stroke
			(width 0)
			(type solid)
		)
		(fill yes)
		(layer "In4.Cu")
		(net "M_J_CPU0_SA_CB<0>")
	)
	(gr_poly
		(pts
			(xy 388.484872 -244.282214) (xy 388.484872 -244.237764) (xy 388.28472 -244.237764) (xy 388.28472 -244.282214)
			(xy 388.384796 -244.38229)
		)
		(stroke
			(width 0)
			(type solid)
		)
		(fill yes)
		(layer "In4.Cu")
		(net "M_J_CPU0_SA_DQ<31>")
	)
	(gr_poly
		(pts
			(xy 388.484872 -243.066062) (xy 388.384796 -242.965986) (xy 388.28472 -243.066062) (xy 388.28472 -243.110512)
			(xy 388.484872 -243.110512)
		)
		(stroke
			(width 0)
			(type solid)
		)
		(fill yes)
		(layer "In4.Cu")
		(net "M_J_CPU0_SA_DQ<28>")
	)
	(gr_poly
		(pts
			(xy 388.484872 -242.662456) (xy 388.484872 -242.614704) (xy 388.28472 -242.614704) (xy 388.28472 -242.662456)
			(xy 388.384796 -242.762278)
		)
		(stroke
			(width 0)
			(type solid)
		)
		(fill yes)
		(layer "In4.Cu")
		(net "M_J_CPU0_SA_DQS_DP<8>")
	)
	(gr_poly
		(pts
			(xy 388.484872 -241.445796) (xy 388.384796 -241.345974) (xy 388.28472 -241.445796) (xy 388.28472 -241.493548)
			(xy 388.484872 -241.493548)
		)
		(stroke
			(width 0)
			(type solid)
		)
		(fill yes)
		(layer "In4.Cu")
		(net "M_J_CPU0_SA_DQS_DP<3>")
	)
	(gr_poly
		(pts
			(xy 388.484872 -241.04219) (xy 388.484872 -240.99774) (xy 388.28472 -240.99774) (xy 388.28472 -241.04219)
			(xy 388.384796 -241.142266)
		)
		(stroke
			(width 0)
			(type solid)
		)
		(fill yes)
		(layer "In4.Cu")
		(net "M_J_CPU0_SA_DQ<27>")
	)
	(gr_poly
		(pts
			(xy 388.484872 -239.826038) (xy 388.384796 -239.725962) (xy 388.28472 -239.826038) (xy 388.28472 -239.870488)
			(xy 388.484872 -239.870488)
		)
		(stroke
			(width 0)
			(type solid)
		)
		(fill yes)
		(layer "In4.Cu")
		(net "M_J_CPU0_SA_DQ<24>")
	)
	(gr_poly
		(pts
			(xy 388.484872 -239.422178) (xy 388.484872 -239.377728) (xy 388.28472 -239.377728) (xy 388.28472 -239.422178)
			(xy 388.384796 -239.522254)
		)
		(stroke
			(width 0)
			(type solid)
		)
		(fill yes)
		(layer "In4.Cu")
		(net "M_J_CPU0_SA_DQ<23>")
	)
	(gr_poly
		(pts
			(xy 388.484872 -238.206026) (xy 388.384796 -238.10595) (xy 388.28472 -238.206026) (xy 388.28472 -238.250476)
			(xy 388.484872 -238.250476)
		)
		(stroke
			(width 0)
			(type solid)
		)
		(fill yes)
		(layer "In4.Cu")
		(net "M_J_CPU0_SA_DQ<20>")
	)
	(gr_poly
		(pts
			(xy 388.484872 -237.80242) (xy 388.484872 -237.754668) (xy 388.28472 -237.754668) (xy 388.28472 -237.80242)
			(xy 388.384796 -237.902242)
		)
		(stroke
			(width 0)
			(type solid)
		)
		(fill yes)
		(layer "In4.Cu")
		(net "M_J_CPU0_SA_DQS_DP<7>")
	)
	(gr_poly
		(pts
			(xy 388.484872 -236.58576) (xy 388.384796 -236.485938) (xy 388.28472 -236.58576) (xy 388.28472 -236.633512)
			(xy 388.484872 -236.633512)
		)
		(stroke
			(width 0)
			(type solid)
		)
		(fill yes)
		(layer "In4.Cu")
		(net "M_J_CPU0_SA_DQS_DP<2>")
	)
	(gr_poly
		(pts
			(xy 388.484872 -236.182154) (xy 388.484872 -236.137704) (xy 388.28472 -236.137704) (xy 388.28472 -236.182154)
			(xy 388.384796 -236.28223)
		)
		(stroke
			(width 0)
			(type solid)
		)
		(fill yes)
		(layer "In4.Cu")
		(net "M_J_CPU0_SA_DQ<19>")
	)
	(gr_poly
		(pts
			(xy 388.484872 -234.966002) (xy 388.384796 -234.865926) (xy 388.28472 -234.966002) (xy 388.28472 -235.010452)
			(xy 388.484872 -235.010452)
		)
		(stroke
			(width 0)
			(type solid)
		)
		(fill yes)
		(layer "In4.Cu")
		(net "M_J_CPU0_SA_DQ<16>")
	)
	(gr_poly
		(pts
			(xy 388.484872 -234.562142) (xy 388.484872 -234.517692) (xy 388.28472 -234.517692) (xy 388.28472 -234.562142)
			(xy 388.384796 -234.662218)
		)
		(stroke
			(width 0)
			(type solid)
		)
		(fill yes)
		(layer "In4.Cu")
		(net "M_J_CPU0_SA_DQ<15>")
	)
	(gr_poly
		(pts
			(xy 388.484872 -233.34599) (xy 388.384796 -233.245914) (xy 388.28472 -233.34599) (xy 388.28472 -233.39044)
			(xy 388.484872 -233.39044)
		)
		(stroke
			(width 0)
			(type solid)
		)
		(fill yes)
		(layer "In4.Cu")
		(net "M_J_CPU0_SA_DQ<12>")
	)
	(gr_poly
		(pts
			(xy 388.484872 -232.942384) (xy 388.484872 -232.894632) (xy 388.28472 -232.894632) (xy 388.28472 -232.942384)
			(xy 388.384796 -233.042206)
		)
		(stroke
			(width 0)
			(type solid)
		)
		(fill yes)
		(layer "In4.Cu")
		(net "M_J_CPU0_SA_DQS_DP<6>")
	)
	(gr_poly
		(pts
			(xy 388.484872 -231.725724) (xy 388.384796 -231.625902) (xy 388.28472 -231.725724) (xy 388.28472 -231.773476)
			(xy 388.484872 -231.773476)
		)
		(stroke
			(width 0)
			(type solid)
		)
		(fill yes)
		(layer "In4.Cu")
		(net "M_J_CPU0_SA_DQS_DP<1>")
	)
	(gr_poly
		(pts
			(xy 388.484872 -231.322372) (xy 388.484872 -231.277922) (xy 388.28472 -231.277922) (xy 388.28472 -231.322372)
			(xy 388.384796 -231.422448)
		)
		(stroke
			(width 0)
			(type solid)
		)
		(fill yes)
		(layer "In4.Cu")
		(net "M_J_CPU0_SA_DQ<11>")
	)
	(gr_poly
		(pts
			(xy 388.484872 -230.105966) (xy 388.384796 -230.006144) (xy 388.28472 -230.105966) (xy 388.28472 -230.150416)
			(xy 388.484872 -230.150416)
		)
		(stroke
			(width 0)
			(type solid)
		)
		(fill yes)
		(layer "In4.Cu")
		(net "M_J_CPU0_SA_DQ<8>")
	)
	(gr_poly
		(pts
			(xy 388.484872 -229.70236) (xy 388.484872 -229.65791) (xy 388.28472 -229.65791) (xy 388.28472 -229.70236)
			(xy 388.384796 -229.802436)
		)
		(stroke
			(width 0)
			(type solid)
		)
		(fill yes)
		(layer "In4.Cu")
		(net "M_J_CPU0_SA_DQ<7>")
	)
	(gr_poly
		(pts
			(xy 388.484872 -228.486208) (xy 388.384796 -228.386132) (xy 388.28472 -228.486208) (xy 388.28472 -228.530658)
			(xy 388.484872 -228.530658)
		)
		(stroke
			(width 0)
			(type solid)
		)
		(fill yes)
		(layer "In4.Cu")
		(net "M_J_CPU0_SA_DQ<4>")
	)
	(gr_poly
		(pts
			(xy 388.484872 -228.082602) (xy 388.484872 -228.03485) (xy 388.28472 -228.03485) (xy 388.28472 -228.082602)
			(xy 388.384796 -228.182424)
		)
		(stroke
			(width 0)
			(type solid)
		)
		(fill yes)
		(layer "In4.Cu")
		(net "M_J_CPU0_SA_DQS_DP<5>")
	)
	(gr_poly
		(pts
			(xy 388.484872 -226.865942) (xy 388.384796 -226.76612) (xy 388.28472 -226.865942) (xy 388.28472 -226.913694)
			(xy 388.484872 -226.913694)
		)
		(stroke
			(width 0)
			(type solid)
		)
		(fill yes)
		(layer "In4.Cu")
		(net "M_J_CPU0_SA_DQS_DP<0>")
	)
	(gr_poly
		(pts
			(xy 388.484872 -226.462336) (xy 388.484872 -226.417886) (xy 388.28472 -226.417886) (xy 388.28472 -226.462336)
			(xy 388.384796 -226.562412)
		)
		(stroke
			(width 0)
			(type solid)
		)
		(fill yes)
		(layer "In4.Cu")
		(net "M_J_CPU0_SA_DQ<3>")
	)
	(gr_poly
		(pts
			(xy 388.541006 -225.378772) (xy 388.504176 -225.24212) (xy 388.465822 -225.219768) (xy 388.365746 -225.392996)
			(xy 388.404354 -225.415348)
		)
		(stroke
			(width 0)
			(type solid)
		)
		(fill yes)
		(layer "In4.Cu")
		(net "M_J_CPU0_SA_DQ<2>")
	)
	(gr_poly
		(pts
			(xy 388.784846 -292.91788) (xy 388.68477 -292.817804) (xy 388.584694 -292.91788) (xy 388.584694 -292.96233)
			(xy 388.784846 -292.96233)
		)
		(stroke
			(width 0)
			(type solid)
		)
		(fill yes)
		(layer "In4.Cu")
		(net "M_J_CPU0_SB_DQ<29>")
	)
	(gr_poly
		(pts
			(xy 388.784846 -292.51402) (xy 388.784846 -292.46957) (xy 388.584694 -292.46957) (xy 388.584694 -292.51402)
			(xy 388.68477 -292.614096)
		)
		(stroke
			(width 0)
			(type solid)
		)
		(fill yes)
		(layer "In4.Cu")
		(net "M_J_CPU0_SB_DQ<30>")
	)
	(gr_poly
		(pts
			(xy 388.784846 -291.297614) (xy 388.68477 -291.197792) (xy 388.584694 -291.297614) (xy 388.584694 -291.345366)
			(xy 388.784846 -291.345366)
		)
		(stroke
			(width 0)
			(type solid)
		)
		(fill yes)
		(layer "In4.Cu")
		(net "M_J_CPU0_SB_DQS_DN<8>")
	)
	(gr_poly
		(pts
			(xy 388.784846 -290.894262) (xy 388.784846 -290.84651) (xy 388.584694 -290.84651) (xy 388.584694 -290.894262)
			(xy 388.68477 -290.994084)
		)
		(stroke
			(width 0)
			(type solid)
		)
		(fill yes)
		(layer "In4.Cu")
		(net "M_J_CPU0_SB_DQS_DN<3>")
	)
	(gr_poly
		(pts
			(xy 388.784846 -289.677856) (xy 388.68477 -289.57778) (xy 388.584694 -289.677856) (xy 388.584694 -289.722306)
			(xy 388.784846 -289.722306)
		)
		(stroke
			(width 0)
			(type solid)
		)
		(fill yes)
		(layer "In4.Cu")
		(net "M_J_CPU0_SB_DQ<25>")
	)
	(gr_poly
		(pts
			(xy 388.784846 -289.273996) (xy 388.784846 -289.229546) (xy 388.584694 -289.229546) (xy 388.584694 -289.273996)
			(xy 388.68477 -289.374072)
		)
		(stroke
			(width 0)
			(type solid)
		)
		(fill yes)
		(layer "In4.Cu")
		(net "M_J_CPU0_SB_DQ<26>")
	)
	(gr_poly
		(pts
			(xy 388.784846 -288.057844) (xy 388.68477 -287.957768) (xy 388.584694 -288.057844) (xy 388.584694 -288.102294)
			(xy 388.784846 -288.102294)
		)
		(stroke
			(width 0)
			(type solid)
		)
		(fill yes)
		(layer "In4.Cu")
		(net "M_J_CPU0_SB_DQ<21>")
	)
	(gr_poly
		(pts
			(xy 388.784846 -287.654238) (xy 388.784846 -287.609788) (xy 388.584694 -287.609788) (xy 388.584694 -287.654238)
			(xy 388.68477 -287.75406)
		)
		(stroke
			(width 0)
			(type solid)
		)
		(fill yes)
		(layer "In4.Cu")
		(net "M_J_CPU0_SB_DQ<22>")
	)
	(gr_poly
		(pts
			(xy 388.784846 -286.437832) (xy 388.68477 -286.337756) (xy 388.584694 -286.437832) (xy 388.584694 -286.485584)
			(xy 388.784846 -286.485584)
		)
		(stroke
			(width 0)
			(type solid)
		)
		(fill yes)
		(layer "In4.Cu")
		(net "M_J_CPU0_SB_DQS_DN<7>")
	)
	(gr_poly
		(pts
			(xy 388.784846 -286.03448) (xy 388.784846 -285.986728) (xy 388.584694 -285.986728) (xy 388.584694 -286.03448)
			(xy 388.68477 -286.134302)
		)
		(stroke
			(width 0)
			(type solid)
		)
		(fill yes)
		(layer "In4.Cu")
		(net "M_J_CPU0_SB_DQS_DN<2>")
	)
	(gr_poly
		(pts
			(xy 388.784846 -284.818074) (xy 388.68477 -284.717998) (xy 388.584694 -284.818074) (xy 388.584694 -284.862524)
			(xy 388.784846 -284.862524)
		)
		(stroke
			(width 0)
			(type solid)
		)
		(fill yes)
		(layer "In4.Cu")
		(net "M_J_CPU0_SB_DQ<17>")
	)
	(gr_poly
		(pts
			(xy 388.784846 -284.414214) (xy 388.784846 -284.369764) (xy 388.584694 -284.369764) (xy 388.584694 -284.414214)
			(xy 388.68477 -284.51429)
		)
		(stroke
			(width 0)
			(type solid)
		)
		(fill yes)
		(layer "In4.Cu")
		(net "M_J_CPU0_SB_DQ<18>")
	)
	(gr_poly
		(pts
			(xy 388.784846 -283.198062) (xy 388.68477 -283.097986) (xy 388.584694 -283.198062) (xy 388.584694 -283.242512)
			(xy 388.784846 -283.242512)
		)
		(stroke
			(width 0)
			(type solid)
		)
		(fill yes)
		(layer "In4.Cu")
		(net "M_J_CPU0_SB_DQ<13>")
	)
	(gr_poly
		(pts
			(xy 388.784846 -282.794202) (xy 388.784846 -282.749752) (xy 388.584694 -282.749752) (xy 388.584694 -282.794202)
			(xy 388.68477 -282.894278)
		)
		(stroke
			(width 0)
			(type solid)
		)
		(fill yes)
		(layer "In4.Cu")
		(net "M_J_CPU0_SB_DQ<14>")
	)
	(gr_poly
		(pts
			(xy 388.784846 -281.577796) (xy 388.68477 -281.477974) (xy 388.584694 -281.577796) (xy 388.584694 -281.625548)
			(xy 388.784846 -281.625548)
		)
		(stroke
			(width 0)
			(type solid)
		)
		(fill yes)
		(layer "In4.Cu")
		(net "M_J_CPU0_SB_DQS_DN<6>")
	)
	(gr_poly
		(pts
			(xy 388.784846 -281.174444) (xy 388.784846 -281.126692) (xy 388.584694 -281.126692) (xy 388.584694 -281.174444)
			(xy 388.68477 -281.274266)
		)
		(stroke
			(width 0)
			(type solid)
		)
		(fill yes)
		(layer "In4.Cu")
		(net "M_J_CPU0_SB_DQS_DN<1>")
	)
	(gr_poly
		(pts
			(xy 388.784846 -279.958038) (xy 388.68477 -279.857962) (xy 388.584694 -279.958038) (xy 388.584694 -280.002488)
			(xy 388.784846 -280.002488)
		)
		(stroke
			(width 0)
			(type solid)
		)
		(fill yes)
		(layer "In4.Cu")
		(net "M_J_CPU0_SB_DQ<9>")
	)
	(gr_poly
		(pts
			(xy 388.784846 -279.554178) (xy 388.784846 -279.509728) (xy 388.584694 -279.509728) (xy 388.584694 -279.554178)
			(xy 388.68477 -279.654254)
		)
		(stroke
			(width 0)
			(type solid)
		)
		(fill yes)
		(layer "In4.Cu")
		(net "M_J_CPU0_SB_DQ<10>")
	)
	(gr_poly
		(pts
			(xy 388.784846 -278.338026) (xy 388.68477 -278.23795) (xy 388.584694 -278.338026) (xy 388.584694 -278.382476)
			(xy 388.784846 -278.382476)
		)
		(stroke
			(width 0)
			(type solid)
		)
		(fill yes)
		(layer "In4.Cu")
		(net "M_J_CPU0_SB_DQ<5>")
	)
	(gr_poly
		(pts
			(xy 388.784846 -277.934166) (xy 388.784846 -277.889716) (xy 388.584694 -277.889716) (xy 388.584694 -277.934166)
			(xy 388.68477 -278.034242)
		)
		(stroke
			(width 0)
			(type solid)
		)
		(fill yes)
		(layer "In4.Cu")
		(net "M_J_CPU0_SB_DQ<6>")
	)
	(gr_poly
		(pts
			(xy 388.784846 -276.71776) (xy 388.68477 -276.617938) (xy 388.584694 -276.71776) (xy 388.584694 -276.765512)
			(xy 388.784846 -276.765512)
		)
		(stroke
			(width 0)
			(type solid)
		)
		(fill yes)
		(layer "In4.Cu")
		(net "M_J_CPU0_SB_DQS_DN<5>")
	)
	(gr_poly
		(pts
			(xy 388.784846 -276.314408) (xy 388.784846 -276.266656) (xy 388.584694 -276.266656) (xy 388.584694 -276.314408)
			(xy 388.68477 -276.41423)
		)
		(stroke
			(width 0)
			(type solid)
		)
		(fill yes)
		(layer "In4.Cu")
		(net "M_J_CPU0_SB_DQS_DN<0>")
	)
	(gr_poly
		(pts
			(xy 388.784846 -275.098002) (xy 388.68477 -274.997926) (xy 388.584694 -275.098002) (xy 388.584694 -275.142452)
			(xy 388.784846 -275.142452)
		)
		(stroke
			(width 0)
			(type solid)
		)
		(fill yes)
		(layer "In4.Cu")
		(net "M_J_CPU0_SB_DQ<1>")
	)
	(gr_poly
		(pts
			(xy 388.784846 -274.694142) (xy 388.784846 -274.649692) (xy 388.584694 -274.649692) (xy 388.584694 -274.694142)
			(xy 388.68477 -274.794218)
		)
		(stroke
			(width 0)
			(type solid)
		)
		(fill yes)
		(layer "In4.Cu")
		(net "M_J_CPU0_SB_DQ<2>")
	)
	(gr_poly
		(pts
			(xy 388.784846 -273.47799) (xy 388.68477 -273.377914) (xy 388.584694 -273.47799) (xy 388.584694 -273.52244)
			(xy 388.784846 -273.52244)
		)
		(stroke
			(width 0)
			(type solid)
		)
		(fill yes)
		(layer "In4.Cu")
		(net "M_J_CPU0_SB_CB<1>")
	)
	(gr_poly
		(pts
			(xy 388.784846 -273.07413) (xy 388.784846 -273.02968) (xy 388.584694 -273.02968) (xy 388.584694 -273.07413)
			(xy 388.68477 -273.174206)
		)
		(stroke
			(width 0)
			(type solid)
		)
		(fill yes)
		(layer "In4.Cu")
		(net "M_J_CPU0_SB_CB<2>")
	)
	(gr_poly
		(pts
			(xy 388.784846 -271.857724) (xy 388.68477 -271.757902) (xy 388.584694 -271.857724) (xy 388.584694 -271.905476)
			(xy 388.784846 -271.905476)
		)
		(stroke
			(width 0)
			(type solid)
		)
		(fill yes)
		(layer "In4.Cu")
		(net "M_J_CPU0_SB_DQS_DN<4>")
	)
	(gr_poly
		(pts
			(xy 388.784846 -271.454372) (xy 388.784846 -271.40662) (xy 388.584694 -271.40662) (xy 388.584694 -271.454372)
			(xy 388.68477 -271.554194)
		)
		(stroke
			(width 0)
			(type solid)
		)
		(fill yes)
		(layer "In4.Cu")
		(net "M_J_CPU0_SB_DQS_DN<9>")
	)
	(gr_poly
		(pts
			(xy 388.784846 -270.237966) (xy 388.68477 -270.13789) (xy 388.584694 -270.237966) (xy 388.584694 -270.282416)
			(xy 388.784846 -270.282416)
		)
		(stroke
			(width 0)
			(type solid)
		)
		(fill yes)
		(layer "In4.Cu")
		(net "M_J_CPU0_SB_CB<5>")
	)
	(gr_poly
		(pts
			(xy 388.784846 -269.834106) (xy 388.784846 -269.789656) (xy 388.584694 -269.789656) (xy 388.584694 -269.834106)
			(xy 388.68477 -269.934182)
		)
		(stroke
			(width 0)
			(type solid)
		)
		(fill yes)
		(layer "In4.Cu")
		(net "M_J_CPU0_SB_CB<6>")
	)
	(gr_poly
		(pts
			(xy 388.784846 -266.997942) (xy 388.68477 -266.897866) (xy 388.584694 -266.997942) (xy 388.584694 -267.042392)
			(xy 388.784846 -267.042392)
		)
		(stroke
			(width 0)
			(type solid)
		)
		(fill yes)
		(layer "In4.Cu")
		(net "M_J_CPU0_SA_RSP<0>")
	)
	(gr_poly
		(pts
			(xy 388.784846 -266.594082) (xy 388.784846 -266.549632) (xy 388.584694 -266.549632) (xy 388.584694 -266.594082)
			(xy 388.68477 -266.694158)
		)
		(stroke
			(width 0)
			(type solid)
		)
		(fill yes)
		(layer "In4.Cu")
		(net "M_J_CPU0_SB_CS_N<1>")
	)
	(gr_poly
		(pts
			(xy 388.784846 -265.37793) (xy 388.68477 -265.277854) (xy 388.584694 -265.37793) (xy 388.584694 -265.42238)
			(xy 388.784846 -265.42238)
		)
		(stroke
			(width 0)
			(type solid)
		)
		(fill yes)
		(layer "In4.Cu")
		(net "M_J_CPU0_SB_PAR")
	)
	(gr_poly
		(pts
			(xy 388.784846 -263.757918) (xy 388.68477 -263.657842) (xy 388.584694 -263.757918) (xy 388.584694 -263.802368)
			(xy 388.784846 -263.802368)
		)
		(stroke
			(width 0)
			(type solid)
		)
		(fill yes)
		(layer "In4.Cu")
		(net "M_J_CPU0_SB_CA<4>")
	)
	(gr_poly
		(pts
			(xy 388.784846 -263.354058) (xy 388.784846 -263.309608) (xy 388.584694 -263.309608) (xy 388.584694 -263.354058)
			(xy 388.68477 -263.454134)
		)
		(stroke
			(width 0)
			(type solid)
		)
		(fill yes)
		(layer "In4.Cu")
		(net "M_J_CPU0_SB_CA<3>")
	)
	(gr_poly
		(pts
			(xy 388.784846 -262.137906) (xy 388.68477 -262.03783) (xy 388.584694 -262.137906) (xy 388.584694 -262.182356)
			(xy 388.784846 -262.182356)
		)
		(stroke
			(width 0)
			(type solid)
		)
		(fill yes)
		(layer "In4.Cu")
		(net "M_J_CPU0_SB_CA<0>")
	)
	(gr_poly
		(pts
			(xy 388.874 -225.505518) (xy 388.835392 -225.483166) (xy 388.698994 -225.519742) (xy 388.73557 -225.656394)
			(xy 388.773924 -225.678746)
		)
		(stroke
			(width 0)
			(type solid)
		)
		(fill yes)
		(layer "In4.Cu")
		(net "M_J_CPU0_SA_DQ<1>")
	)
	(gr_poly
		(pts
			(xy 388.874508 -223.884744) (xy 388.836154 -223.862392) (xy 388.699502 -223.898968) (xy 388.736078 -224.03562)
			(xy 388.774686 -224.057972)
		)
		(stroke
			(width 0)
			(type solid)
		)
		(fill yes)
		(layer "In4.Cu")
		(net "M_J_CPU0_SA_DQ<0>")
	)
	(gr_poly
		(pts
			(xy 388.955026 -256.432558) (xy 388.955026 -256.384806) (xy 388.754874 -256.384806) (xy 388.754874 -256.432558)
			(xy 388.85495 -256.53238)
		)
		(stroke
			(width 0)
			(type solid)
		)
		(fill yes)
		(layer "In4.Cu")
		(net "M_J_CPU0_CLK_DN<0>")
	)
	(gr_poly
		(pts
			(xy 388.955026 -255.216152) (xy 388.85495 -255.116076) (xy 388.754874 -255.216152) (xy 388.754874 -255.260602)
			(xy 388.955026 -255.260602)
		)
		(stroke
			(width 0)
			(type solid)
		)
		(fill yes)
		(layer "In4.Cu")
		(net "M_J_CPU0_SA_CA<6>")
	)
	(gr_poly
		(pts
			(xy 388.955026 -254.812292) (xy 388.955026 -254.767842) (xy 388.754874 -254.767842) (xy 388.754874 -254.812292)
			(xy 388.85495 -254.912368)
		)
		(stroke
			(width 0)
			(type solid)
		)
		(fill yes)
		(layer "In4.Cu")
		(net "M_J_CPU0_SA_CA<5>")
	)
	(gr_poly
		(pts
			(xy 388.955026 -253.59614) (xy 388.85495 -253.496064) (xy 388.754874 -253.59614) (xy 388.754874 -253.64059)
			(xy 388.955026 -253.64059)
		)
		(stroke
			(width 0)
			(type solid)
		)
		(fill yes)
		(layer "In4.Cu")
		(net "M_J_CPU0_SA_CA<2>")
	)
	(gr_poly
		(pts
			(xy 388.955026 -253.19228) (xy 388.955026 -253.14783) (xy 388.754874 -253.14783) (xy 388.754874 -253.19228)
			(xy 388.85495 -253.292356)
		)
		(stroke
			(width 0)
			(type solid)
		)
		(fill yes)
		(layer "In4.Cu")
		(net "M_J_CPU0_SA_CA<1>")
	)
	(gr_poly
		(pts
			(xy 388.955026 -251.976128) (xy 388.85495 -251.876052) (xy 388.754874 -251.976128) (xy 388.754874 -252.020578)
			(xy 388.955026 -252.020578)
		)
		(stroke
			(width 0)
			(type solid)
		)
		(fill yes)
		(layer "In4.Cu")
		(net "M_J_CPU0_SA_CS_N<1>")
	)
	(gr_poly
		(pts
			(xy 388.955026 -250.356116) (xy 388.85495 -250.25604) (xy 388.754874 -250.356116) (xy 388.754874 -250.400566)
			(xy 388.955026 -250.400566)
		)
		(stroke
			(width 0)
			(type solid)
		)
		(fill yes)
		(layer "In4.Cu")
		(net "M_J_CPU0_ALERT_R_N")
	)
	(gr_poly
		(pts
			(xy 388.955026 -248.736104) (xy 388.85495 -248.636028) (xy 388.754874 -248.736104) (xy 388.754874 -248.780554)
			(xy 388.955026 -248.780554)
		)
		(stroke
			(width 0)
			(type solid)
		)
		(fill yes)
		(layer "In4.Cu")
		(net "M_J_CPU0_SA_CB<5>")
	)
	(gr_poly
		(pts
			(xy 388.955026 -248.332244) (xy 388.955026 -248.287794) (xy 388.754874 -248.287794) (xy 388.754874 -248.332244)
			(xy 388.85495 -248.43232)
		)
		(stroke
			(width 0)
			(type solid)
		)
		(fill yes)
		(layer "In4.Cu")
		(net "M_J_CPU0_SA_CB<6>")
	)
	(gr_poly
		(pts
			(xy 388.955026 -247.115838) (xy 388.85495 -247.016016) (xy 388.754874 -247.115838) (xy 388.754874 -247.16359)
			(xy 388.955026 -247.16359)
		)
		(stroke
			(width 0)
			(type solid)
		)
		(fill yes)
		(layer "In4.Cu")
		(net "M_J_CPU0_SA_DQS_DN<9>")
	)
	(gr_poly
		(pts
			(xy 388.955026 -246.712486) (xy 388.955026 -246.664734) (xy 388.754874 -246.664734) (xy 388.754874 -246.712486)
			(xy 388.85495 -246.812308)
		)
		(stroke
			(width 0)
			(type solid)
		)
		(fill yes)
		(layer "In4.Cu")
		(net "M_J_CPU0_SA_DQS_DN<4>")
	)
	(gr_poly
		(pts
			(xy 388.955026 -245.49608) (xy 388.85495 -245.396004) (xy 388.754874 -245.49608) (xy 388.754874 -245.54053)
			(xy 388.955026 -245.54053)
		)
		(stroke
			(width 0)
			(type solid)
		)
		(fill yes)
		(layer "In4.Cu")
		(net "M_J_CPU0_SA_CB<1>")
	)
	(gr_poly
		(pts
			(xy 388.955026 -245.09222) (xy 388.955026 -245.04777) (xy 388.754874 -245.04777) (xy 388.754874 -245.09222)
			(xy 388.85495 -245.192296)
		)
		(stroke
			(width 0)
			(type solid)
		)
		(fill yes)
		(layer "In4.Cu")
		(net "M_J_CPU0_SA_CB<2>")
	)
	(gr_poly
		(pts
			(xy 388.955026 -243.876068) (xy 388.85495 -243.775992) (xy 388.754874 -243.876068) (xy 388.754874 -243.920518)
			(xy 388.955026 -243.920518)
		)
		(stroke
			(width 0)
			(type solid)
		)
		(fill yes)
		(layer "In4.Cu")
		(net "M_J_CPU0_SA_DQ<29>")
	)
	(gr_poly
		(pts
			(xy 388.955026 -243.472208) (xy 388.955026 -243.427758) (xy 388.754874 -243.427758) (xy 388.754874 -243.472208)
			(xy 388.85495 -243.572284)
		)
		(stroke
			(width 0)
			(type solid)
		)
		(fill yes)
		(layer "In4.Cu")
		(net "M_J_CPU0_SA_DQ<30>")
	)
	(gr_poly
		(pts
			(xy 388.955026 -242.255802) (xy 388.85495 -242.15598) (xy 388.754874 -242.255802) (xy 388.754874 -242.303554)
			(xy 388.955026 -242.303554)
		)
		(stroke
			(width 0)
			(type solid)
		)
		(fill yes)
		(layer "In4.Cu")
		(net "M_J_CPU0_SA_DQS_DN<8>")
	)
	(gr_poly
		(pts
			(xy 388.955026 -241.85245) (xy 388.955026 -241.804698) (xy 388.754874 -241.804698) (xy 388.754874 -241.85245)
			(xy 388.85495 -241.952272)
		)
		(stroke
			(width 0)
			(type solid)
		)
		(fill yes)
		(layer "In4.Cu")
		(net "M_J_CPU0_SA_DQS_DN<3>")
	)
	(gr_poly
		(pts
			(xy 388.955026 -240.636044) (xy 388.85495 -240.535968) (xy 388.754874 -240.636044) (xy 388.754874 -240.680494)
			(xy 388.955026 -240.680494)
		)
		(stroke
			(width 0)
			(type solid)
		)
		(fill yes)
		(layer "In4.Cu")
		(net "M_J_CPU0_SA_DQ<25>")
	)
	(gr_poly
		(pts
			(xy 388.955026 -240.232184) (xy 388.955026 -240.187734) (xy 388.754874 -240.187734) (xy 388.754874 -240.232184)
			(xy 388.85495 -240.33226)
		)
		(stroke
			(width 0)
			(type solid)
		)
		(fill yes)
		(layer "In4.Cu")
		(net "M_J_CPU0_SA_DQ<26>")
	)
	(gr_poly
		(pts
			(xy 388.955026 -239.016032) (xy 388.85495 -238.915956) (xy 388.754874 -239.016032) (xy 388.754874 -239.060482)
			(xy 388.955026 -239.060482)
		)
		(stroke
			(width 0)
			(type solid)
		)
		(fill yes)
		(layer "In4.Cu")
		(net "M_J_CPU0_SA_DQ<21>")
	)
	(gr_poly
		(pts
			(xy 388.955026 -238.612172) (xy 388.955026 -238.567722) (xy 388.754874 -238.567722) (xy 388.754874 -238.612172)
			(xy 388.85495 -238.712248)
		)
		(stroke
			(width 0)
			(type solid)
		)
		(fill yes)
		(layer "In4.Cu")
		(net "M_J_CPU0_SA_DQ<22>")
	)
	(gr_poly
		(pts
			(xy 388.955026 -237.395766) (xy 388.85495 -237.295944) (xy 388.754874 -237.395766) (xy 388.754874 -237.443518)
			(xy 388.955026 -237.443518)
		)
		(stroke
			(width 0)
			(type solid)
		)
		(fill yes)
		(layer "In4.Cu")
		(net "M_J_CPU0_SA_DQS_DN<7>")
	)
	(gr_poly
		(pts
			(xy 388.955026 -236.992414) (xy 388.955026 -236.944662) (xy 388.754874 -236.944662) (xy 388.754874 -236.992414)
			(xy 388.85495 -237.092236)
		)
		(stroke
			(width 0)
			(type solid)
		)
		(fill yes)
		(layer "In4.Cu")
		(net "M_J_CPU0_SA_DQS_DN<2>")
	)
	(gr_poly
		(pts
			(xy 388.955026 -235.776008) (xy 388.85495 -235.675932) (xy 388.754874 -235.776008) (xy 388.754874 -235.820458)
			(xy 388.955026 -235.820458)
		)
		(stroke
			(width 0)
			(type solid)
		)
		(fill yes)
		(layer "In4.Cu")
		(net "M_J_CPU0_SA_DQ<17>")
	)
	(gr_poly
		(pts
			(xy 388.955026 -235.372148) (xy 388.955026 -235.327698) (xy 388.754874 -235.327698) (xy 388.754874 -235.372148)
			(xy 388.85495 -235.472224)
		)
		(stroke
			(width 0)
			(type solid)
		)
		(fill yes)
		(layer "In4.Cu")
		(net "M_J_CPU0_SA_DQ<18>")
	)
	(gr_poly
		(pts
			(xy 388.955026 -234.155996) (xy 388.85495 -234.05592) (xy 388.754874 -234.155996) (xy 388.754874 -234.200446)
			(xy 388.955026 -234.200446)
		)
		(stroke
			(width 0)
			(type solid)
		)
		(fill yes)
		(layer "In4.Cu")
		(net "M_J_CPU0_SA_DQ<13>")
	)
	(gr_poly
		(pts
			(xy 388.955026 -233.752136) (xy 388.955026 -233.707686) (xy 388.754874 -233.707686) (xy 388.754874 -233.752136)
			(xy 388.85495 -233.852212)
		)
		(stroke
			(width 0)
			(type solid)
		)
		(fill yes)
		(layer "In4.Cu")
		(net "M_J_CPU0_SA_DQ<14>")
	)
	(gr_poly
		(pts
			(xy 388.955026 -232.53573) (xy 388.85495 -232.435908) (xy 388.754874 -232.53573) (xy 388.754874 -232.583482)
			(xy 388.955026 -232.583482)
		)
		(stroke
			(width 0)
			(type solid)
		)
		(fill yes)
		(layer "In4.Cu")
		(net "M_J_CPU0_SA_DQS_DN<6>")
	)
	(gr_poly
		(pts
			(xy 388.955026 -232.132378) (xy 388.955026 -232.084626) (xy 388.754874 -232.084626) (xy 388.754874 -232.132378)
			(xy 388.85495 -232.2322)
		)
		(stroke
			(width 0)
			(type solid)
		)
		(fill yes)
		(layer "In4.Cu")
		(net "M_J_CPU0_SA_DQS_DN<1>")
	)
	(gr_poly
		(pts
			(xy 388.955026 -230.915972) (xy 388.85495 -230.815896) (xy 388.754874 -230.915972) (xy 388.754874 -230.960422)
			(xy 388.955026 -230.960422)
		)
		(stroke
			(width 0)
			(type solid)
		)
		(fill yes)
		(layer "In4.Cu")
		(net "M_J_CPU0_SA_DQ<9>")
	)
	(gr_poly
		(pts
			(xy 388.955026 -230.512366) (xy 388.955026 -230.467916) (xy 388.754874 -230.467916) (xy 388.754874 -230.512366)
			(xy 388.85495 -230.612188)
		)
		(stroke
			(width 0)
			(type solid)
		)
		(fill yes)
		(layer "In4.Cu")
		(net "M_J_CPU0_SA_DQ<10>")
	)
	(gr_poly
		(pts
			(xy 388.955026 -229.29596) (xy 388.85495 -229.195884) (xy 388.754874 -229.29596) (xy 388.754874 -229.34041)
			(xy 388.955026 -229.34041)
		)
		(stroke
			(width 0)
			(type solid)
		)
		(fill yes)
		(layer "In4.Cu")
		(net "M_J_CPU0_SA_DQ<5>")
	)
	(gr_poly
		(pts
			(xy 388.955026 -228.892354) (xy 388.955026 -228.847904) (xy 388.754874 -228.847904) (xy 388.754874 -228.892354)
			(xy 388.85495 -228.99243)
		)
		(stroke
			(width 0)
			(type solid)
		)
		(fill yes)
		(layer "In4.Cu")
		(net "M_J_CPU0_SA_DQ<6>")
	)
	(gr_poly
		(pts
			(xy 388.955026 -227.675948) (xy 388.85495 -227.576126) (xy 388.754874 -227.675948) (xy 388.754874 -227.7237)
			(xy 388.955026 -227.7237)
		)
		(stroke
			(width 0)
			(type solid)
		)
		(fill yes)
		(layer "In4.Cu")
		(net "M_J_CPU0_SA_DQS_DN<5>")
	)
	(gr_poly
		(pts
			(xy 388.955026 -227.272596) (xy 388.955026 -227.224844) (xy 388.754874 -227.224844) (xy 388.754874 -227.272596)
			(xy 388.85495 -227.372418)
		)
		(stroke
			(width 0)
			(type solid)
		)
		(fill yes)
		(layer "In4.Cu")
		(net "M_J_CPU0_SA_DQS_DN<0>")
	)
	(gr_poly
		(pts
			(xy 389.010144 -224.570036) (xy 388.973568 -224.433384) (xy 388.93496 -224.411286) (xy 388.834884 -224.584514)
			(xy 388.873492 -224.606612)
		)
		(stroke
			(width 0)
			(type solid)
		)
		(fill yes)
		(layer "In4.Cu")
		(net "M_J_CPU0_SA_DQ<2>")
	)
	(gr_poly
		(pts
			(xy 389.010906 -226.188778) (xy 388.974076 -226.052126) (xy 388.935722 -226.029774) (xy 388.835646 -226.203002)
			(xy 388.874254 -226.225354)
		)
		(stroke
			(width 0)
			(type solid)
		)
		(fill yes)
		(layer "In4.Cu")
		(net "M_J_CPU0_SA_DQ<3>")
	)
	(gr_poly
		(pts
			(xy 389.255 -293.324026) (xy 389.255 -293.279576) (xy 389.054848 -293.279576) (xy 389.054848 -293.324026)
			(xy 389.154924 -293.424102)
		)
		(stroke
			(width 0)
			(type solid)
		)
		(fill yes)
		(layer "In4.Cu")
		(net "M_J_CPU0_SB_DQ<31>")
	)
	(gr_poly
		(pts
			(xy 389.255 -292.107874) (xy 389.154924 -292.007798) (xy 389.054848 -292.107874) (xy 389.054848 -292.152324)
			(xy 389.255 -292.152324)
		)
		(stroke
			(width 0)
			(type solid)
		)
		(fill yes)
		(layer "In4.Cu")
		(net "M_J_CPU0_SB_DQ<28>")
	)
	(gr_poly
		(pts
			(xy 389.255 -291.704268) (xy 389.255 -291.656516) (xy 389.054848 -291.656516) (xy 389.054848 -291.704268)
			(xy 389.154924 -291.80409)
		)
		(stroke
			(width 0)
			(type solid)
		)
		(fill yes)
		(layer "In4.Cu")
		(net "M_J_CPU0_SB_DQS_DP<8>")
	)
	(gr_poly
		(pts
			(xy 389.255 -290.487608) (xy 389.154924 -290.387786) (xy 389.054848 -290.487608) (xy 389.054848 -290.53536)
			(xy 389.255 -290.53536)
		)
		(stroke
			(width 0)
			(type solid)
		)
		(fill yes)
		(layer "In4.Cu")
		(net "M_J_CPU0_SB_DQS_DP<3>")
	)
	(gr_poly
		(pts
			(xy 389.255 -290.084002) (xy 389.255 -290.039552) (xy 389.054848 -290.039552) (xy 389.054848 -290.084002)
			(xy 389.154924 -290.184078)
		)
		(stroke
			(width 0)
			(type solid)
		)
		(fill yes)
		(layer "In4.Cu")
		(net "M_J_CPU0_SB_DQ<27>")
	)
	(gr_poly
		(pts
			(xy 389.255 -288.86785) (xy 389.154924 -288.767774) (xy 389.054848 -288.86785) (xy 389.054848 -288.9123)
			(xy 389.255 -288.9123)
		)
		(stroke
			(width 0)
			(type solid)
		)
		(fill yes)
		(layer "In4.Cu")
		(net "M_J_CPU0_SB_DQ<24>")
	)
	(gr_poly
		(pts
			(xy 389.255 -288.464244) (xy 389.255 -288.419794) (xy 389.054848 -288.419794) (xy 389.054848 -288.464244)
			(xy 389.154924 -288.56432)
		)
		(stroke
			(width 0)
			(type solid)
		)
		(fill yes)
		(layer "In4.Cu")
		(net "M_J_CPU0_SB_DQ<23>")
	)
	(gr_poly
		(pts
			(xy 389.255 -287.247838) (xy 389.154924 -287.148016) (xy 389.054848 -287.247838) (xy 389.054848 -287.292288)
			(xy 389.255 -287.292288)
		)
		(stroke
			(width 0)
			(type solid)
		)
		(fill yes)
		(layer "In4.Cu")
		(net "M_J_CPU0_SB_DQ<20>")
	)
	(gr_poly
		(pts
			(xy 389.255 -286.844232) (xy 389.255 -286.79648) (xy 389.054848 -286.79648) (xy 389.054848 -286.844232)
			(xy 389.154924 -286.944308)
		)
		(stroke
			(width 0)
			(type solid)
		)
		(fill yes)
		(layer "In4.Cu")
		(net "M_J_CPU0_SB_DQS_DP<7>")
	)
	(gr_poly
		(pts
			(xy 389.255 -285.627826) (xy 389.154924 -285.528004) (xy 389.054848 -285.627826) (xy 389.054848 -285.675578)
			(xy 389.255 -285.675578)
		)
		(stroke
			(width 0)
			(type solid)
		)
		(fill yes)
		(layer "In4.Cu")
		(net "M_J_CPU0_SB_DQS_DP<2>")
	)
	(gr_poly
		(pts
			(xy 389.255 -285.22422) (xy 389.255 -285.17977) (xy 389.054848 -285.17977) (xy 389.054848 -285.22422)
			(xy 389.154924 -285.324296)
		)
		(stroke
			(width 0)
			(type solid)
		)
		(fill yes)
		(layer "In4.Cu")
		(net "M_J_CPU0_SB_DQ<19>")
	)
	(gr_poly
		(pts
			(xy 389.255 -284.008068) (xy 389.154924 -283.907992) (xy 389.054848 -284.008068) (xy 389.054848 -284.052518)
			(xy 389.255 -284.052518)
		)
		(stroke
			(width 0)
			(type solid)
		)
		(fill yes)
		(layer "In4.Cu")
		(net "M_J_CPU0_SB_DQ<16>")
	)
	(gr_poly
		(pts
			(xy 389.255 -283.604208) (xy 389.255 -283.559758) (xy 389.054848 -283.559758) (xy 389.054848 -283.604208)
			(xy 389.154924 -283.704284)
		)
		(stroke
			(width 0)
			(type solid)
		)
		(fill yes)
		(layer "In4.Cu")
		(net "M_J_CPU0_SB_DQ<15>")
	)
	(gr_poly
		(pts
			(xy 389.255 -282.388056) (xy 389.154924 -282.28798) (xy 389.054848 -282.388056) (xy 389.054848 -282.432506)
			(xy 389.255 -282.432506)
		)
		(stroke
			(width 0)
			(type solid)
		)
		(fill yes)
		(layer "In4.Cu")
		(net "M_J_CPU0_SB_DQ<12>")
	)
	(gr_poly
		(pts
			(xy 389.255 -281.98445) (xy 389.255 -281.936698) (xy 389.054848 -281.936698) (xy 389.054848 -281.98445)
			(xy 389.154924 -282.084272)
		)
		(stroke
			(width 0)
			(type solid)
		)
		(fill yes)
		(layer "In4.Cu")
		(net "M_J_CPU0_SB_DQS_DP<6>")
	)
	(gr_poly
		(pts
			(xy 389.255 -280.76779) (xy 389.154924 -280.667968) (xy 389.054848 -280.76779) (xy 389.054848 -280.815542)
			(xy 389.255 -280.815542)
		)
		(stroke
			(width 0)
			(type solid)
		)
		(fill yes)
		(layer "In4.Cu")
		(net "M_J_CPU0_SB_DQS_DP<1>")
	)
	(gr_poly
		(pts
			(xy 389.255 -280.364184) (xy 389.255 -280.319734) (xy 389.054848 -280.319734) (xy 389.054848 -280.364184)
			(xy 389.154924 -280.46426)
		)
		(stroke
			(width 0)
			(type solid)
		)
		(fill yes)
		(layer "In4.Cu")
		(net "M_J_CPU0_SB_DQ<11>")
	)
	(gr_poly
		(pts
			(xy 389.255 -279.148032) (xy 389.154924 -279.047956) (xy 389.054848 -279.148032) (xy 389.054848 -279.192482)
			(xy 389.255 -279.192482)
		)
		(stroke
			(width 0)
			(type solid)
		)
		(fill yes)
		(layer "In4.Cu")
		(net "M_J_CPU0_SB_DQ<8>")
	)
	(gr_poly
		(pts
			(xy 389.255 -278.744172) (xy 389.255 -278.699722) (xy 389.054848 -278.699722) (xy 389.054848 -278.744172)
			(xy 389.154924 -278.844248)
		)
		(stroke
			(width 0)
			(type solid)
		)
		(fill yes)
		(layer "In4.Cu")
		(net "M_J_CPU0_SB_DQ<7>")
	)
	(gr_poly
		(pts
			(xy 389.255 -277.52802) (xy 389.154924 -277.427944) (xy 389.054848 -277.52802) (xy 389.054848 -277.57247)
			(xy 389.255 -277.57247)
		)
		(stroke
			(width 0)
			(type solid)
		)
		(fill yes)
		(layer "In4.Cu")
		(net "M_J_CPU0_SB_DQ<4>")
	)
	(gr_poly
		(pts
			(xy 389.255 -277.124414) (xy 389.255 -277.076662) (xy 389.054848 -277.076662) (xy 389.054848 -277.124414)
			(xy 389.154924 -277.224236)
		)
		(stroke
			(width 0)
			(type solid)
		)
		(fill yes)
		(layer "In4.Cu")
		(net "M_J_CPU0_SB_DQS_DP<5>")
	)
	(gr_poly
		(pts
			(xy 389.255 -275.907754) (xy 389.154924 -275.807932) (xy 389.054848 -275.907754) (xy 389.054848 -275.955506)
			(xy 389.255 -275.955506)
		)
		(stroke
			(width 0)
			(type solid)
		)
		(fill yes)
		(layer "In4.Cu")
		(net "M_J_CPU0_SB_DQS_DP<0>")
	)
	(gr_poly
		(pts
			(xy 389.255 -275.504148) (xy 389.255 -275.459698) (xy 389.054848 -275.459698) (xy 389.054848 -275.504148)
			(xy 389.154924 -275.604224)
		)
		(stroke
			(width 0)
			(type solid)
		)
		(fill yes)
		(layer "In4.Cu")
		(net "M_J_CPU0_SB_DQ<3>")
	)
	(gr_poly
		(pts
			(xy 389.255 -274.287996) (xy 389.154924 -274.18792) (xy 389.054848 -274.287996) (xy 389.054848 -274.332446)
			(xy 389.255 -274.332446)
		)
		(stroke
			(width 0)
			(type solid)
		)
		(fill yes)
		(layer "In4.Cu")
		(net "M_J_CPU0_SB_DQ<0>")
	)
	(gr_poly
		(pts
			(xy 389.255 -273.884136) (xy 389.255 -273.839686) (xy 389.054848 -273.839686) (xy 389.054848 -273.884136)
			(xy 389.154924 -273.984212)
		)
		(stroke
			(width 0)
			(type solid)
		)
		(fill yes)
		(layer "In4.Cu")
		(net "M_J_CPU0_SB_CB<3>")
	)
	(gr_poly
		(pts
			(xy 389.255 -272.667984) (xy 389.154924 -272.567908) (xy 389.054848 -272.667984) (xy 389.054848 -272.712434)
			(xy 389.255 -272.712434)
		)
		(stroke
			(width 0)
			(type solid)
		)
		(fill yes)
		(layer "In4.Cu")
		(net "M_J_CPU0_SB_CB<0>")
	)
	(gr_poly
		(pts
			(xy 389.255 -272.264378) (xy 389.255 -272.216626) (xy 389.054848 -272.216626) (xy 389.054848 -272.264378)
			(xy 389.154924 -272.3642)
		)
		(stroke
			(width 0)
			(type solid)
		)
		(fill yes)
		(layer "In4.Cu")
		(net "M_J_CPU0_SB_DQS_DP<4>")
	)
	(gr_poly
		(pts
			(xy 389.255 -271.047718) (xy 389.154924 -270.947896) (xy 389.054848 -271.047718) (xy 389.054848 -271.09547)
			(xy 389.255 -271.09547)
		)
		(stroke
			(width 0)
			(type solid)
		)
		(fill yes)
		(layer "In4.Cu")
		(net "M_J_CPU0_SB_DQS_DP<9>")
	)
	(gr_poly
		(pts
			(xy 389.255 -270.644112) (xy 389.255 -270.599662) (xy 389.054848 -270.599662) (xy 389.054848 -270.644112)
			(xy 389.154924 -270.744188)
		)
		(stroke
			(width 0)
			(type solid)
		)
		(fill yes)
		(layer "In4.Cu")
		(net "M_J_CPU0_SB_CB<7>")
	)
	(gr_poly
		(pts
			(xy 389.255 -269.42796) (xy 389.154924 -269.327884) (xy 389.054848 -269.42796) (xy 389.054848 -269.47241)
			(xy 389.255 -269.47241)
		)
		(stroke
			(width 0)
			(type solid)
		)
		(fill yes)
		(layer "In4.Cu")
		(net "M_J_CPU0_SB_CB<4>")
	)
	(gr_poly
		(pts
			(xy 389.255 -267.807948) (xy 389.154924 -267.707872) (xy 389.054848 -267.807948) (xy 389.054848 -267.852398)
			(xy 389.255 -267.852398)
		)
		(stroke
			(width 0)
			(type solid)
		)
		(fill yes)
		(layer "In4.Cu")
		(net "M_J_CPU0_SB_RSP<0>")
	)
	(gr_poly
		(pts
			(xy 389.255 -265.784076) (xy 389.255 -265.739626) (xy 389.054848 -265.739626) (xy 389.054848 -265.784076)
			(xy 389.154924 -265.884152)
		)
		(stroke
			(width 0)
			(type solid)
		)
		(fill yes)
		(layer "In4.Cu")
		(net "M_J_CPU0_SB_CS_N<0>")
	)
	(gr_poly
		(pts
			(xy 389.255 -264.567924) (xy 389.154924 -264.467848) (xy 389.054848 -264.567924) (xy 389.054848 -264.612374)
			(xy 389.255 -264.612374)
		)
		(stroke
			(width 0)
			(type solid)
		)
		(fill yes)
		(layer "In4.Cu")
		(net "M_J_CPU0_SB_CA<6>")
	)
	(gr_poly
		(pts
			(xy 389.255 -264.164064) (xy 389.255 -264.119614) (xy 389.054848 -264.119614) (xy 389.054848 -264.164064)
			(xy 389.154924 -264.26414)
		)
		(stroke
			(width 0)
			(type solid)
		)
		(fill yes)
		(layer "In4.Cu")
		(net "M_J_CPU0_SB_CA<5>")
	)
	(gr_poly
		(pts
			(xy 389.255 -262.947912) (xy 389.154924 -262.847836) (xy 389.054848 -262.947912) (xy 389.054848 -262.992362)
			(xy 389.255 -262.992362)
		)
		(stroke
			(width 0)
			(type solid)
		)
		(fill yes)
		(layer "In4.Cu")
		(net "M_J_CPU0_SB_CA<2>")
	)
	(gr_poly
		(pts
			(xy 389.255 -262.544052) (xy 389.255 -262.499602) (xy 389.054848 -262.499602) (xy 389.054848 -262.544052)
			(xy 389.154924 -262.644128)
		)
		(stroke
			(width 0)
			(type solid)
		)
		(fill yes)
		(layer "In4.Cu")
		(net "M_J_CPU0_SB_CA<1>")
	)
	(gr_poly
		(pts
			(xy 389.344662 -223.074738) (xy 389.306308 -223.052386) (xy 389.169656 -223.088962) (xy 389.206232 -223.225614)
			(xy 389.24484 -223.247966)
		)
		(stroke
			(width 0)
			(type solid)
		)
		(fill yes)
		(layer "In4.Cu")
		(net "M_J_CPU0_SA_DQ<0>")
	)
	(gr_poly
		(pts
			(xy 389.344916 -224.693988) (xy 389.306308 -224.67189) (xy 389.169656 -224.708466) (xy 389.206232 -224.845118)
			(xy 389.24484 -224.867216)
		)
		(stroke
			(width 0)
			(type solid)
		)
		(fill yes)
		(layer "In4.Cu")
		(net "M_J_CPU0_SA_DQ<1>")
	)
	(gr_poly
		(pts
			(xy 389.347964 -226.315016) (xy 389.306562 -226.29114) (xy 389.16991 -226.32797) (xy 389.20674 -226.464368)
			(xy 389.247888 -226.488244)
		)
		(stroke
			(width 0)
			(type solid)
		)
		(fill yes)
		(layer "In4.Cu")
		(net "M_J_CPU0_SA_DQS_DP<0>")
	)
	(gr_poly
		(pts
			(xy 389.424926 -256.025904) (xy 389.32485 -255.926082) (xy 389.224774 -256.025904) (xy 389.224774 -256.073656)
			(xy 389.424926 -256.073656)
		)
		(stroke
			(width 0)
			(type solid)
		)
		(fill yes)
		(layer "In4.Cu")
		(net "M_J_CPU0_CLK_DP<0>")
	)
	(gr_poly
		(pts
			(xy 389.424926 -255.622298) (xy 389.424926 -255.577848) (xy 389.224774 -255.577848) (xy 389.224774 -255.622298)
			(xy 389.32485 -255.722374)
		)
		(stroke
			(width 0)
			(type solid)
		)
		(fill yes)
		(layer "In4.Cu")
		(net "M_J_CPU0_SA_PAR")
	)
	(gr_poly
		(pts
			(xy 389.424926 -254.406146) (xy 389.32485 -254.30607) (xy 389.224774 -254.406146) (xy 389.224774 -254.450596)
			(xy 389.424926 -254.450596)
		)
		(stroke
			(width 0)
			(type solid)
		)
		(fill yes)
		(layer "In4.Cu")
		(net "M_J_CPU0_SA_CA<4>")
	)
	(gr_poly
		(pts
			(xy 389.424926 -254.002286) (xy 389.424926 -253.957836) (xy 389.224774 -253.957836) (xy 389.224774 -254.002286)
			(xy 389.32485 -254.102362)
		)
		(stroke
			(width 0)
			(type solid)
		)
		(fill yes)
		(layer "In4.Cu")
		(net "M_J_CPU0_SA_CA<3>")
	)
	(gr_poly
		(pts
			(xy 389.424926 -252.786134) (xy 389.32485 -252.686058) (xy 389.224774 -252.786134) (xy 389.224774 -252.830584)
			(xy 389.424926 -252.830584)
		)
		(stroke
			(width 0)
			(type solid)
		)
		(fill yes)
		(layer "In4.Cu")
		(net "M_J_CPU0_SA_CA<0>")
	)
	(gr_poly
		(pts
			(xy 389.424926 -251.166122) (xy 389.32485 -251.066046) (xy 389.224774 -251.166122) (xy 389.224774 -251.210572)
			(xy 389.424926 -251.210572)
		)
		(stroke
			(width 0)
			(type solid)
		)
		(fill yes)
		(layer "In4.Cu")
		(net "M_J_CPU0_SA_CS_N<0>")
	)
	(gr_poly
		(pts
			(xy 389.424926 -250.762262) (xy 389.424926 -250.717812) (xy 389.224774 -250.717812) (xy 389.224774 -250.762262)
			(xy 389.32485 -250.862338)
		)
		(stroke
			(width 0)
			(type solid)
		)
		(fill yes)
		(layer "In4.Cu")
		(net "M_J_CPU0_RESET_N")
	)
	(gr_poly
		(pts
			(xy 389.424926 -249.14225) (xy 389.424926 -249.0978) (xy 389.224774 -249.0978) (xy 389.224774 -249.14225)
			(xy 389.32485 -249.242326)
		)
		(stroke
			(width 0)
			(type solid)
		)
		(fill yes)
		(layer "In4.Cu")
		(net "M_J_CPU0_SA_CB<7>")
	)
	(gr_poly
		(pts
			(xy 389.424926 -247.926098) (xy 389.32485 -247.826022) (xy 389.224774 -247.926098) (xy 389.224774 -247.970548)
			(xy 389.424926 -247.970548)
		)
		(stroke
			(width 0)
			(type solid)
		)
		(fill yes)
		(layer "In4.Cu")
		(net "M_J_CPU0_SA_CB<4>")
	)
	(gr_poly
		(pts
			(xy 389.424926 -247.522492) (xy 389.424926 -247.47474) (xy 389.224774 -247.47474) (xy 389.224774 -247.522492)
			(xy 389.32485 -247.622314)
		)
		(stroke
			(width 0)
			(type solid)
		)
		(fill yes)
		(layer "In4.Cu")
		(net "M_J_CPU0_SA_DQS_DP<9>")
	)
	(gr_poly
		(pts
			(xy 389.424926 -246.305832) (xy 389.32485 -246.20601) (xy 389.224774 -246.305832) (xy 389.224774 -246.353584)
			(xy 389.424926 -246.353584)
		)
		(stroke
			(width 0)
			(type solid)
		)
		(fill yes)
		(layer "In4.Cu")
		(net "M_J_CPU0_SA_DQS_DP<4>")
	)
	(gr_poly
		(pts
			(xy 389.424926 -245.902226) (xy 389.424926 -245.857776) (xy 389.224774 -245.857776) (xy 389.224774 -245.902226)
			(xy 389.32485 -246.002302)
		)
		(stroke
			(width 0)
			(type solid)
		)
		(fill yes)
		(layer "In4.Cu")
		(net "M_J_CPU0_SA_CB<3>")
	)
	(gr_poly
		(pts
			(xy 389.424926 -244.686074) (xy 389.32485 -244.585998) (xy 389.224774 -244.686074) (xy 389.224774 -244.730524)
			(xy 389.424926 -244.730524)
		)
		(stroke
			(width 0)
			(type solid)
		)
		(fill yes)
		(layer "In4.Cu")
		(net "M_J_CPU0_SA_CB<0>")
	)
	(gr_poly
		(pts
			(xy 389.424926 -244.282214) (xy 389.424926 -244.237764) (xy 389.224774 -244.237764) (xy 389.224774 -244.282214)
			(xy 389.32485 -244.38229)
		)
		(stroke
			(width 0)
			(type solid)
		)
		(fill yes)
		(layer "In4.Cu")
		(net "M_J_CPU0_SA_DQ<31>")
	)
	(gr_poly
		(pts
			(xy 389.424926 -243.066062) (xy 389.32485 -242.965986) (xy 389.224774 -243.066062) (xy 389.224774 -243.110512)
			(xy 389.424926 -243.110512)
		)
		(stroke
			(width 0)
			(type solid)
		)
		(fill yes)
		(layer "In4.Cu")
		(net "M_J_CPU0_SA_DQ<28>")
	)
	(gr_poly
		(pts
			(xy 389.424926 -242.662456) (xy 389.424926 -242.614704) (xy 389.224774 -242.614704) (xy 389.224774 -242.662456)
			(xy 389.32485 -242.762278)
		)
		(stroke
			(width 0)
			(type solid)
		)
		(fill yes)
		(layer "In4.Cu")
		(net "M_J_CPU0_SA_DQS_DP<8>")
	)
	(gr_poly
		(pts
			(xy 389.424926 -241.445796) (xy 389.32485 -241.345974) (xy 389.224774 -241.445796) (xy 389.224774 -241.493548)
			(xy 389.424926 -241.493548)
		)
		(stroke
			(width 0)
			(type solid)
		)
		(fill yes)
		(layer "In4.Cu")
		(net "M_J_CPU0_SA_DQS_DP<3>")
	)
	(gr_poly
		(pts
			(xy 389.424926 -241.04219) (xy 389.424926 -240.99774) (xy 389.224774 -240.99774) (xy 389.224774 -241.04219)
			(xy 389.32485 -241.142266)
		)
		(stroke
			(width 0)
			(type solid)
		)
		(fill yes)
		(layer "In4.Cu")
		(net "M_J_CPU0_SA_DQ<27>")
	)
	(gr_poly
		(pts
			(xy 389.424926 -239.826038) (xy 389.32485 -239.725962) (xy 389.224774 -239.826038) (xy 389.224774 -239.870488)
			(xy 389.424926 -239.870488)
		)
		(stroke
			(width 0)
			(type solid)
		)
		(fill yes)
		(layer "In4.Cu")
		(net "M_J_CPU0_SA_DQ<24>")
	)
	(gr_poly
		(pts
			(xy 389.424926 -239.422178) (xy 389.424926 -239.377728) (xy 389.224774 -239.377728) (xy 389.224774 -239.422178)
			(xy 389.32485 -239.522254)
		)
		(stroke
			(width 0)
			(type solid)
		)
		(fill yes)
		(layer "In4.Cu")
		(net "M_J_CPU0_SA_DQ<23>")
	)
	(gr_poly
		(pts
			(xy 389.424926 -238.206026) (xy 389.32485 -238.10595) (xy 389.224774 -238.206026) (xy 389.224774 -238.250476)
			(xy 389.424926 -238.250476)
		)
		(stroke
			(width 0)
			(type solid)
		)
		(fill yes)
		(layer "In4.Cu")
		(net "M_J_CPU0_SA_DQ<20>")
	)
	(gr_poly
		(pts
			(xy 389.424926 -237.80242) (xy 389.424926 -237.754668) (xy 389.224774 -237.754668) (xy 389.224774 -237.80242)
			(xy 389.32485 -237.902242)
		)
		(stroke
			(width 0)
			(type solid)
		)
		(fill yes)
		(layer "In4.Cu")
		(net "M_J_CPU0_SA_DQS_DP<7>")
	)
	(gr_poly
		(pts
			(xy 389.424926 -236.58576) (xy 389.32485 -236.485938) (xy 389.224774 -236.58576) (xy 389.224774 -236.633512)
			(xy 389.424926 -236.633512)
		)
		(stroke
			(width 0)
			(type solid)
		)
		(fill yes)
		(layer "In4.Cu")
		(net "M_J_CPU0_SA_DQS_DP<2>")
	)
	(gr_poly
		(pts
			(xy 389.424926 -236.182154) (xy 389.424926 -236.137704) (xy 389.224774 -236.137704) (xy 389.224774 -236.182154)
			(xy 389.32485 -236.28223)
		)
		(stroke
			(width 0)
			(type solid)
		)
		(fill yes)
		(layer "In4.Cu")
		(net "M_J_CPU0_SA_DQ<19>")
	)
	(gr_poly
		(pts
			(xy 389.424926 -234.966002) (xy 389.32485 -234.865926) (xy 389.224774 -234.966002) (xy 389.224774 -235.010452)
			(xy 389.424926 -235.010452)
		)
		(stroke
			(width 0)
			(type solid)
		)
		(fill yes)
		(layer "In4.Cu")
		(net "M_J_CPU0_SA_DQ<16>")
	)
	(gr_poly
		(pts
			(xy 389.424926 -234.562142) (xy 389.424926 -234.517692) (xy 389.224774 -234.517692) (xy 389.224774 -234.562142)
			(xy 389.32485 -234.662218)
		)
		(stroke
			(width 0)
			(type solid)
		)
		(fill yes)
		(layer "In4.Cu")
		(net "M_J_CPU0_SA_DQ<15>")
	)
	(gr_poly
		(pts
			(xy 389.424926 -233.34599) (xy 389.32485 -233.245914) (xy 389.224774 -233.34599) (xy 389.224774 -233.39044)
			(xy 389.424926 -233.39044)
		)
		(stroke
			(width 0)
			(type solid)
		)
		(fill yes)
		(layer "In4.Cu")
		(net "M_J_CPU0_SA_DQ<12>")
	)
	(gr_poly
		(pts
			(xy 389.424926 -232.942384) (xy 389.424926 -232.894632) (xy 389.224774 -232.894632) (xy 389.224774 -232.942384)
			(xy 389.32485 -233.042206)
		)
		(stroke
			(width 0)
			(type solid)
		)
		(fill yes)
		(layer "In4.Cu")
		(net "M_J_CPU0_SA_DQS_DP<6>")
	)
	(gr_poly
		(pts
			(xy 389.424926 -231.725724) (xy 389.32485 -231.625902) (xy 389.224774 -231.725724) (xy 389.224774 -231.773476)
			(xy 389.424926 -231.773476)
		)
		(stroke
			(width 0)
			(type solid)
		)
		(fill yes)
		(layer "In4.Cu")
		(net "M_J_CPU0_SA_DQS_DP<1>")
	)
	(gr_poly
		(pts
			(xy 389.424926 -231.322372) (xy 389.424926 -231.277922) (xy 389.224774 -231.277922) (xy 389.224774 -231.322372)
			(xy 389.32485 -231.422448)
		)
		(stroke
			(width 0)
			(type solid)
		)
		(fill yes)
		(layer "In4.Cu")
		(net "M_J_CPU0_SA_DQ<11>")
	)
	(gr_poly
		(pts
			(xy 389.424926 -230.105966) (xy 389.32485 -230.006144) (xy 389.224774 -230.105966) (xy 389.224774 -230.150416)
			(xy 389.424926 -230.150416)
		)
		(stroke
			(width 0)
			(type solid)
		)
		(fill yes)
		(layer "In4.Cu")
		(net "M_J_CPU0_SA_DQ<8>")
	)
	(gr_poly
		(pts
			(xy 389.424926 -229.70236) (xy 389.424926 -229.65791) (xy 389.224774 -229.65791) (xy 389.224774 -229.70236)
			(xy 389.32485 -229.802436)
		)
		(stroke
			(width 0)
			(type solid)
		)
		(fill yes)
		(layer "In4.Cu")
		(net "M_J_CPU0_SA_DQ<7>")
	)
	(gr_poly
		(pts
			(xy 389.424926 -228.486208) (xy 389.32485 -228.386132) (xy 389.224774 -228.486208) (xy 389.224774 -228.530658)
			(xy 389.424926 -228.530658)
		)
		(stroke
			(width 0)
			(type solid)
		)
		(fill yes)
		(layer "In4.Cu")
		(net "M_J_CPU0_SA_DQ<4>")
	)
	(gr_poly
		(pts
			(xy 389.424926 -228.082602) (xy 389.424926 -228.03485) (xy 389.224774 -228.03485) (xy 389.224774 -228.082602)
			(xy 389.32485 -228.182424)
		)
		(stroke
			(width 0)
			(type solid)
		)
		(fill yes)
		(layer "In4.Cu")
		(net "M_J_CPU0_SA_DQS_DP<5>")
	)
	(gr_poly
		(pts
			(xy 389.47979 -227.000816) (xy 389.44296 -226.864164) (xy 389.401812 -226.840288) (xy 389.301736 -227.013516)
			(xy 389.343138 -227.037392)
		)
		(stroke
			(width 0)
			(type solid)
		)
		(fill yes)
		(layer "In4.Cu")
		(net "M_J_CPU0_SA_DQS_DN<0>")
	)
	(gr_poly
		(pts
			(xy 389.480044 -225.380042) (xy 389.443468 -225.24339) (xy 389.40486 -225.221292) (xy 389.304784 -225.39452)
			(xy 389.343392 -225.416618)
		)
		(stroke
			(width 0)
			(type solid)
		)
		(fill yes)
		(layer "In4.Cu")
		(net "M_J_CPU0_SA_DQ<3>")
	)
	(gr_poly
		(pts
			(xy 389.481314 -223.757998) (xy 389.444738 -223.6216) (xy 389.406384 -223.599248) (xy 389.306308 -223.772476)
			(xy 389.344916 -223.794828)
		)
		(stroke
			(width 0)
			(type solid)
		)
		(fill yes)
		(layer "In4.Cu")
		(net "M_J_CPU0_SA_DQ<2>")
	)
	(gr_poly
		(pts
			(xy 389.7249 -292.91788) (xy 389.624824 -292.817804) (xy 389.524748 -292.91788) (xy 389.524748 -292.96233)
			(xy 389.7249 -292.96233)
		)
		(stroke
			(width 0)
			(type solid)
		)
		(fill yes)
		(layer "In4.Cu")
		(net "M_J_CPU0_SB_DQ<29>")
	)
	(gr_poly
		(pts
			(xy 389.7249 -292.51402) (xy 389.7249 -292.46957) (xy 389.524748 -292.46957) (xy 389.524748 -292.51402)
			(xy 389.624824 -292.614096)
		)
		(stroke
			(width 0)
			(type solid)
		)
		(fill yes)
		(layer "In4.Cu")
		(net "M_J_CPU0_SB_DQ<30>")
	)
	(gr_poly
		(pts
			(xy 389.7249 -291.297614) (xy 389.624824 -291.197792) (xy 389.524748 -291.297614) (xy 389.524748 -291.345366)
			(xy 389.7249 -291.345366)
		)
		(stroke
			(width 0)
			(type solid)
		)
		(fill yes)
		(layer "In4.Cu")
		(net "M_J_CPU0_SB_DQS_DN<8>")
	)
	(gr_poly
		(pts
			(xy 389.7249 -290.894262) (xy 389.7249 -290.84651) (xy 389.524748 -290.84651) (xy 389.524748 -290.894262)
			(xy 389.624824 -290.994084)
		)
		(stroke
			(width 0)
			(type solid)
		)
		(fill yes)
		(layer "In4.Cu")
		(net "M_J_CPU0_SB_DQS_DN<3>")
	)
	(gr_poly
		(pts
			(xy 389.7249 -289.677856) (xy 389.624824 -289.57778) (xy 389.524748 -289.677856) (xy 389.524748 -289.722306)
			(xy 389.7249 -289.722306)
		)
		(stroke
			(width 0)
			(type solid)
		)
		(fill yes)
		(layer "In4.Cu")
		(net "M_J_CPU0_SB_DQ<25>")
	)
	(gr_poly
		(pts
			(xy 389.7249 -289.273996) (xy 389.7249 -289.229546) (xy 389.524748 -289.229546) (xy 389.524748 -289.273996)
			(xy 389.624824 -289.374072)
		)
		(stroke
			(width 0)
			(type solid)
		)
		(fill yes)
		(layer "In4.Cu")
		(net "M_J_CPU0_SB_DQ<26>")
	)
	(gr_poly
		(pts
			(xy 389.7249 -288.057844) (xy 389.624824 -287.957768) (xy 389.524748 -288.057844) (xy 389.524748 -288.102294)
			(xy 389.7249 -288.102294)
		)
		(stroke
			(width 0)
			(type solid)
		)
		(fill yes)
		(layer "In4.Cu")
		(net "M_J_CPU0_SB_DQ<21>")
	)
	(gr_poly
		(pts
			(xy 389.7249 -287.654238) (xy 389.7249 -287.609788) (xy 389.524748 -287.609788) (xy 389.524748 -287.654238)
			(xy 389.624824 -287.75406)
		)
		(stroke
			(width 0)
			(type solid)
		)
		(fill yes)
		(layer "In4.Cu")
		(net "M_J_CPU0_SB_DQ<22>")
	)
	(gr_poly
		(pts
			(xy 389.7249 -286.437832) (xy 389.624824 -286.337756) (xy 389.524748 -286.437832) (xy 389.524748 -286.485584)
			(xy 389.7249 -286.485584)
		)
		(stroke
			(width 0)
			(type solid)
		)
		(fill yes)
		(layer "In4.Cu")
		(net "M_J_CPU0_SB_DQS_DN<7>")
	)
	(gr_poly
		(pts
			(xy 389.7249 -286.03448) (xy 389.7249 -285.986728) (xy 389.524748 -285.986728) (xy 389.524748 -286.03448)
			(xy 389.624824 -286.134302)
		)
		(stroke
			(width 0)
			(type solid)
		)
		(fill yes)
		(layer "In4.Cu")
		(net "M_J_CPU0_SB_DQS_DN<2>")
	)
	(gr_poly
		(pts
			(xy 389.7249 -284.818074) (xy 389.624824 -284.717998) (xy 389.524748 -284.818074) (xy 389.524748 -284.862524)
			(xy 389.7249 -284.862524)
		)
		(stroke
			(width 0)
			(type solid)
		)
		(fill yes)
		(layer "In4.Cu")
		(net "M_J_CPU0_SB_DQ<17>")
	)
	(gr_poly
		(pts
			(xy 389.7249 -284.414214) (xy 389.7249 -284.369764) (xy 389.524748 -284.369764) (xy 389.524748 -284.414214)
			(xy 389.624824 -284.51429)
		)
		(stroke
			(width 0)
			(type solid)
		)
		(fill yes)
		(layer "In4.Cu")
		(net "M_J_CPU0_SB_DQ<18>")
	)
	(gr_poly
		(pts
			(xy 389.7249 -283.198062) (xy 389.624824 -283.097986) (xy 389.524748 -283.198062) (xy 389.524748 -283.242512)
			(xy 389.7249 -283.242512)
		)
		(stroke
			(width 0)
			(type solid)
		)
		(fill yes)
		(layer "In4.Cu")
		(net "M_J_CPU0_SB_DQ<13>")
	)
	(gr_poly
		(pts
			(xy 389.7249 -282.794202) (xy 389.7249 -282.749752) (xy 389.524748 -282.749752) (xy 389.524748 -282.794202)
			(xy 389.624824 -282.894278)
		)
		(stroke
			(width 0)
			(type solid)
		)
		(fill yes)
		(layer "In4.Cu")
		(net "M_J_CPU0_SB_DQ<14>")
	)
	(gr_poly
		(pts
			(xy 389.7249 -281.577796) (xy 389.624824 -281.477974) (xy 389.524748 -281.577796) (xy 389.524748 -281.625548)
			(xy 389.7249 -281.625548)
		)
		(stroke
			(width 0)
			(type solid)
		)
		(fill yes)
		(layer "In4.Cu")
		(net "M_J_CPU0_SB_DQS_DN<6>")
	)
	(gr_poly
		(pts
			(xy 389.7249 -281.174444) (xy 389.7249 -281.126692) (xy 389.524748 -281.126692) (xy 389.524748 -281.174444)
			(xy 389.624824 -281.274266)
		)
		(stroke
			(width 0)
			(type solid)
		)
		(fill yes)
		(layer "In4.Cu")
		(net "M_J_CPU0_SB_DQS_DN<1>")
	)
	(gr_poly
		(pts
			(xy 389.7249 -279.958038) (xy 389.624824 -279.857962) (xy 389.524748 -279.958038) (xy 389.524748 -280.002488)
			(xy 389.7249 -280.002488)
		)
		(stroke
			(width 0)
			(type solid)
		)
		(fill yes)
		(layer "In4.Cu")
		(net "M_J_CPU0_SB_DQ<9>")
	)
	(gr_poly
		(pts
			(xy 389.7249 -279.554178) (xy 389.7249 -279.509728) (xy 389.524748 -279.509728) (xy 389.524748 -279.554178)
			(xy 389.624824 -279.654254)
		)
		(stroke
			(width 0)
			(type solid)
		)
		(fill yes)
		(layer "In4.Cu")
		(net "M_J_CPU0_SB_DQ<10>")
	)
	(gr_poly
		(pts
			(xy 389.7249 -278.338026) (xy 389.624824 -278.23795) (xy 389.524748 -278.338026) (xy 389.524748 -278.382476)
			(xy 389.7249 -278.382476)
		)
		(stroke
			(width 0)
			(type solid)
		)
		(fill yes)
		(layer "In4.Cu")
		(net "M_J_CPU0_SB_DQ<5>")
	)
	(gr_poly
		(pts
			(xy 389.7249 -277.934166) (xy 389.7249 -277.889716) (xy 389.524748 -277.889716) (xy 389.524748 -277.934166)
			(xy 389.624824 -278.034242)
		)
		(stroke
			(width 0)
			(type solid)
		)
		(fill yes)
		(layer "In4.Cu")
		(net "M_J_CPU0_SB_DQ<6>")
	)
	(gr_poly
		(pts
			(xy 389.7249 -276.71776) (xy 389.624824 -276.617938) (xy 389.524748 -276.71776) (xy 389.524748 -276.765512)
			(xy 389.7249 -276.765512)
		)
		(stroke
			(width 0)
			(type solid)
		)
		(fill yes)
		(layer "In4.Cu")
		(net "M_J_CPU0_SB_DQS_DN<5>")
	)
	(gr_poly
		(pts
			(xy 389.7249 -276.314408) (xy 389.7249 -276.266656) (xy 389.524748 -276.266656) (xy 389.524748 -276.314408)
			(xy 389.624824 -276.41423)
		)
		(stroke
			(width 0)
			(type solid)
		)
		(fill yes)
		(layer "In4.Cu")
		(net "M_J_CPU0_SB_DQS_DN<0>")
	)
	(gr_poly
		(pts
			(xy 389.7249 -275.098002) (xy 389.624824 -274.997926) (xy 389.524748 -275.098002) (xy 389.524748 -275.142452)
			(xy 389.7249 -275.142452)
		)
		(stroke
			(width 0)
			(type solid)
		)
		(fill yes)
		(layer "In4.Cu")
		(net "M_J_CPU0_SB_DQ<1>")
	)
	(gr_poly
		(pts
			(xy 389.7249 -274.694142) (xy 389.7249 -274.649692) (xy 389.524748 -274.649692) (xy 389.524748 -274.694142)
			(xy 389.624824 -274.794218)
		)
		(stroke
			(width 0)
			(type solid)
		)
		(fill yes)
		(layer "In4.Cu")
		(net "M_J_CPU0_SB_DQ<2>")
	)
	(gr_poly
		(pts
			(xy 389.7249 -273.47799) (xy 389.624824 -273.377914) (xy 389.524748 -273.47799) (xy 389.524748 -273.52244)
			(xy 389.7249 -273.52244)
		)
		(stroke
			(width 0)
			(type solid)
		)
		(fill yes)
		(layer "In4.Cu")
		(net "M_J_CPU0_SB_CB<1>")
	)
	(gr_poly
		(pts
			(xy 389.7249 -273.07413) (xy 389.7249 -273.02968) (xy 389.524748 -273.02968) (xy 389.524748 -273.07413)
			(xy 389.624824 -273.174206)
		)
		(stroke
			(width 0)
			(type solid)
		)
		(fill yes)
		(layer "In4.Cu")
		(net "M_J_CPU0_SB_CB<2>")
	)
	(gr_poly
		(pts
			(xy 389.7249 -271.857724) (xy 389.624824 -271.757902) (xy 389.524748 -271.857724) (xy 389.524748 -271.905476)
			(xy 389.7249 -271.905476)
		)
		(stroke
			(width 0)
			(type solid)
		)
		(fill yes)
		(layer "In4.Cu")
		(net "M_J_CPU0_SB_DQS_DN<4>")
	)
	(gr_poly
		(pts
			(xy 389.7249 -271.454372) (xy 389.7249 -271.40662) (xy 389.524748 -271.40662) (xy 389.524748 -271.454372)
			(xy 389.624824 -271.554194)
		)
		(stroke
			(width 0)
			(type solid)
		)
		(fill yes)
		(layer "In4.Cu")
		(net "M_J_CPU0_SB_DQS_DN<9>")
	)
	(gr_poly
		(pts
			(xy 389.7249 -270.237966) (xy 389.624824 -270.13789) (xy 389.524748 -270.237966) (xy 389.524748 -270.282416)
			(xy 389.7249 -270.282416)
		)
		(stroke
			(width 0)
			(type solid)
		)
		(fill yes)
		(layer "In4.Cu")
		(net "M_J_CPU0_SB_CB<5>")
	)
	(gr_poly
		(pts
			(xy 389.7249 -269.834106) (xy 389.7249 -269.789656) (xy 389.524748 -269.789656) (xy 389.524748 -269.834106)
			(xy 389.624824 -269.934182)
		)
		(stroke
			(width 0)
			(type solid)
		)
		(fill yes)
		(layer "In4.Cu")
		(net "M_J_CPU0_SB_CB<6>")
	)
	(gr_poly
		(pts
			(xy 389.7249 -266.997942) (xy 389.624824 -266.897866) (xy 389.524748 -266.997942) (xy 389.524748 -267.042392)
			(xy 389.7249 -267.042392)
		)
		(stroke
			(width 0)
			(type solid)
		)
		(fill yes)
		(layer "In4.Cu")
		(net "M_J_CPU0_SA_RSP<0>")
	)
	(gr_poly
		(pts
			(xy 389.7249 -266.594082) (xy 389.7249 -266.549632) (xy 389.524748 -266.549632) (xy 389.524748 -266.594082)
			(xy 389.624824 -266.694158)
		)
		(stroke
			(width 0)
			(type solid)
		)
		(fill yes)
		(layer "In4.Cu")
		(net "M_J_CPU0_SB_CS_N<1>")
	)
	(gr_poly
		(pts
			(xy 389.7249 -265.37793) (xy 389.624824 -265.277854) (xy 389.524748 -265.37793) (xy 389.524748 -265.42238)
			(xy 389.7249 -265.42238)
		)
		(stroke
			(width 0)
			(type solid)
		)
		(fill yes)
		(layer "In4.Cu")
		(net "M_J_CPU0_SB_PAR")
	)
	(gr_poly
		(pts
			(xy 389.7249 -263.757918) (xy 389.624824 -263.657842) (xy 389.524748 -263.757918) (xy 389.524748 -263.802368)
			(xy 389.7249 -263.802368)
		)
		(stroke
			(width 0)
			(type solid)
		)
		(fill yes)
		(layer "In4.Cu")
		(net "M_J_CPU0_SB_CA<4>")
	)
	(gr_poly
		(pts
			(xy 389.7249 -263.354058) (xy 389.7249 -263.309608) (xy 389.524748 -263.309608) (xy 389.524748 -263.354058)
			(xy 389.624824 -263.454134)
		)
		(stroke
			(width 0)
			(type solid)
		)
		(fill yes)
		(layer "In4.Cu")
		(net "M_J_CPU0_SB_CA<3>")
	)
	(gr_poly
		(pts
			(xy 389.7249 -262.137906) (xy 389.624824 -262.03783) (xy 389.524748 -262.137906) (xy 389.524748 -262.182356)
			(xy 389.7249 -262.182356)
		)
		(stroke
			(width 0)
			(type solid)
		)
		(fill yes)
		(layer "In4.Cu")
		(net "M_J_CPU0_SB_CA<0>")
	)
	(gr_poly
		(pts
			(xy 389.8138 -223.886014) (xy 389.775192 -223.863916) (xy 389.638794 -223.900492) (xy 389.67537 -224.037144)
			(xy 389.713724 -224.059242)
		)
		(stroke
			(width 0)
			(type solid)
		)
		(fill yes)
		(layer "In4.Cu")
		(net "M_J_CPU0_SA_DQ<1>")
	)
	(gr_poly
		(pts
			(xy 389.816848 -227.126292) (xy 389.7757 -227.10267) (xy 389.639048 -227.139246) (xy 389.675624 -227.275644)
			(xy 389.717026 -227.29952)
		)
		(stroke
			(width 0)
			(type solid)
		)
		(fill yes)
		(layer "In4.Cu")
		(net "M_J_CPU0_SA_DQS_DN<5>")
	)
	(gr_poly
		(pts
			(xy 389.816848 -225.50628) (xy 389.7757 -225.482404) (xy 389.639048 -225.519234) (xy 389.675624 -225.655632)
			(xy 389.717026 -225.679508)
		)
		(stroke
			(width 0)
			(type solid)
		)
		(fill yes)
		(layer "In4.Cu")
		(net "M_J_CPU0_SA_DQS_DP<0>")
	)
	(gr_poly
		(pts
			(xy 389.894826 -256.432558) (xy 389.894826 -256.384806) (xy 389.694674 -256.384806) (xy 389.694674 -256.432558)
			(xy 389.79475 -256.53238)
		)
		(stroke
			(width 0)
			(type solid)
		)
		(fill yes)
		(layer "In4.Cu")
		(net "M_J_CPU0_CLK_DN<0>")
	)
	(gr_poly
		(pts
			(xy 389.894826 -255.216152) (xy 389.79475 -255.116076) (xy 389.694674 -255.216152) (xy 389.694674 -255.260602)
			(xy 389.894826 -255.260602)
		)
		(stroke
			(width 0)
			(type solid)
		)
		(fill yes)
		(layer "In4.Cu")
		(net "M_J_CPU0_SA_CA<6>")
	)
	(gr_poly
		(pts
			(xy 389.894826 -254.812292) (xy 389.894826 -254.767842) (xy 389.694674 -254.767842) (xy 389.694674 -254.812292)
			(xy 389.79475 -254.912368)
		)
		(stroke
			(width 0)
			(type solid)
		)
		(fill yes)
		(layer "In4.Cu")
		(net "M_J_CPU0_SA_CA<5>")
	)
	(gr_poly
		(pts
			(xy 389.894826 -253.59614) (xy 389.79475 -253.496064) (xy 389.694674 -253.59614) (xy 389.694674 -253.64059)
			(xy 389.894826 -253.64059)
		)
		(stroke
			(width 0)
			(type solid)
		)
		(fill yes)
		(layer "In4.Cu")
		(net "M_J_CPU0_SA_CA<2>")
	)
	(gr_poly
		(pts
			(xy 389.894826 -253.19228) (xy 389.894826 -253.14783) (xy 389.694674 -253.14783) (xy 389.694674 -253.19228)
			(xy 389.79475 -253.292356)
		)
		(stroke
			(width 0)
			(type solid)
		)
		(fill yes)
		(layer "In4.Cu")
		(net "M_J_CPU0_SA_CA<1>")
	)
	(gr_poly
		(pts
			(xy 389.894826 -251.976128) (xy 389.79475 -251.876052) (xy 389.694674 -251.976128) (xy 389.694674 -252.020578)
			(xy 389.894826 -252.020578)
		)
		(stroke
			(width 0)
			(type solid)
		)
		(fill yes)
		(layer "In4.Cu")
		(net "M_J_CPU0_SA_CS_N<1>")
	)
	(gr_poly
		(pts
			(xy 389.894826 -250.356116) (xy 389.79475 -250.25604) (xy 389.694674 -250.356116) (xy 389.694674 -250.400566)
			(xy 389.894826 -250.400566)
		)
		(stroke
			(width 0)
			(type solid)
		)
		(fill yes)
		(layer "In4.Cu")
		(net "M_J_CPU0_ALERT_R_N")
	)
	(gr_poly
		(pts
			(xy 389.894826 -248.736104) (xy 389.79475 -248.636028) (xy 389.694674 -248.736104) (xy 389.694674 -248.780554)
			(xy 389.894826 -248.780554)
		)
		(stroke
			(width 0)
			(type solid)
		)
		(fill yes)
		(layer "In4.Cu")
		(net "M_J_CPU0_SA_CB<5>")
	)
	(gr_poly
		(pts
			(xy 389.894826 -248.332244) (xy 389.894826 -248.287794) (xy 389.694674 -248.287794) (xy 389.694674 -248.332244)
			(xy 389.79475 -248.43232)
		)
		(stroke
			(width 0)
			(type solid)
		)
		(fill yes)
		(layer "In4.Cu")
		(net "M_J_CPU0_SA_CB<6>")
	)
	(gr_poly
		(pts
			(xy 389.894826 -247.115838) (xy 389.79475 -247.016016) (xy 389.694674 -247.115838) (xy 389.694674 -247.16359)
			(xy 389.894826 -247.16359)
		)
		(stroke
			(width 0)
			(type solid)
		)
		(fill yes)
		(layer "In4.Cu")
		(net "M_J_CPU0_SA_DQS_DN<9>")
	)
	(gr_poly
		(pts
			(xy 389.894826 -246.712486) (xy 389.894826 -246.664734) (xy 389.694674 -246.664734) (xy 389.694674 -246.712486)
			(xy 389.79475 -246.812308)
		)
		(stroke
			(width 0)
			(type solid)
		)
		(fill yes)
		(layer "In4.Cu")
		(net "M_J_CPU0_SA_DQS_DN<4>")
	)
	(gr_poly
		(pts
			(xy 389.894826 -245.49608) (xy 389.79475 -245.396004) (xy 389.694674 -245.49608) (xy 389.694674 -245.54053)
			(xy 389.894826 -245.54053)
		)
		(stroke
			(width 0)
			(type solid)
		)
		(fill yes)
		(layer "In4.Cu")
		(net "M_J_CPU0_SA_CB<1>")
	)
	(gr_poly
		(pts
			(xy 389.894826 -245.09222) (xy 389.894826 -245.04777) (xy 389.694674 -245.04777) (xy 389.694674 -245.09222)
			(xy 389.79475 -245.192296)
		)
		(stroke
			(width 0)
			(type solid)
		)
		(fill yes)
		(layer "In4.Cu")
		(net "M_J_CPU0_SA_CB<2>")
	)
	(gr_poly
		(pts
			(xy 389.894826 -243.876068) (xy 389.79475 -243.775992) (xy 389.694674 -243.876068) (xy 389.694674 -243.920518)
			(xy 389.894826 -243.920518)
		)
		(stroke
			(width 0)
			(type solid)
		)
		(fill yes)
		(layer "In4.Cu")
		(net "M_J_CPU0_SA_DQ<29>")
	)
	(gr_poly
		(pts
			(xy 389.894826 -243.472208) (xy 389.894826 -243.427758) (xy 389.694674 -243.427758) (xy 389.694674 -243.472208)
			(xy 389.79475 -243.572284)
		)
		(stroke
			(width 0)
			(type solid)
		)
		(fill yes)
		(layer "In4.Cu")
		(net "M_J_CPU0_SA_DQ<30>")
	)
	(gr_poly
		(pts
			(xy 389.894826 -242.255802) (xy 389.79475 -242.15598) (xy 389.694674 -242.255802) (xy 389.694674 -242.303554)
			(xy 389.894826 -242.303554)
		)
		(stroke
			(width 0)
			(type solid)
		)
		(fill yes)
		(layer "In4.Cu")
		(net "M_J_CPU0_SA_DQS_DN<8>")
	)
	(gr_poly
		(pts
			(xy 389.894826 -241.85245) (xy 389.894826 -241.804698) (xy 389.694674 -241.804698) (xy 389.694674 -241.85245)
			(xy 389.79475 -241.952272)
		)
		(stroke
			(width 0)
			(type solid)
		)
		(fill yes)
		(layer "In4.Cu")
		(net "M_J_CPU0_SA_DQS_DN<3>")
	)
	(gr_poly
		(pts
			(xy 389.894826 -240.636044) (xy 389.79475 -240.535968) (xy 389.694674 -240.636044) (xy 389.694674 -240.680494)
			(xy 389.894826 -240.680494)
		)
		(stroke
			(width 0)
			(type solid)
		)
		(fill yes)
		(layer "In4.Cu")
		(net "M_J_CPU0_SA_DQ<25>")
	)
	(gr_poly
		(pts
			(xy 389.894826 -240.232184) (xy 389.894826 -240.187734) (xy 389.694674 -240.187734) (xy 389.694674 -240.232184)
			(xy 389.79475 -240.33226)
		)
		(stroke
			(width 0)
			(type solid)
		)
		(fill yes)
		(layer "In4.Cu")
		(net "M_J_CPU0_SA_DQ<26>")
	)
	(gr_poly
		(pts
			(xy 389.894826 -239.016032) (xy 389.79475 -238.915956) (xy 389.694674 -239.016032) (xy 389.694674 -239.060482)
			(xy 389.894826 -239.060482)
		)
		(stroke
			(width 0)
			(type solid)
		)
		(fill yes)
		(layer "In4.Cu")
		(net "M_J_CPU0_SA_DQ<21>")
	)
	(gr_poly
		(pts
			(xy 389.894826 -238.612172) (xy 389.894826 -238.567722) (xy 389.694674 -238.567722) (xy 389.694674 -238.612172)
			(xy 389.79475 -238.712248)
		)
		(stroke
			(width 0)
			(type solid)
		)
		(fill yes)
		(layer "In4.Cu")
		(net "M_J_CPU0_SA_DQ<22>")
	)
	(gr_poly
		(pts
			(xy 389.894826 -237.395766) (xy 389.79475 -237.295944) (xy 389.694674 -237.395766) (xy 389.694674 -237.443518)
			(xy 389.894826 -237.443518)
		)
		(stroke
			(width 0)
			(type solid)
		)
		(fill yes)
		(layer "In4.Cu")
		(net "M_J_CPU0_SA_DQS_DN<7>")
	)
	(gr_poly
		(pts
			(xy 389.894826 -236.992414) (xy 389.894826 -236.944662) (xy 389.694674 -236.944662) (xy 389.694674 -236.992414)
			(xy 389.79475 -237.092236)
		)
		(stroke
			(width 0)
			(type solid)
		)
		(fill yes)
		(layer "In4.Cu")
		(net "M_J_CPU0_SA_DQS_DN<2>")
	)
	(gr_poly
		(pts
			(xy 389.894826 -235.776008) (xy 389.79475 -235.675932) (xy 389.694674 -235.776008) (xy 389.694674 -235.820458)
			(xy 389.894826 -235.820458)
		)
		(stroke
			(width 0)
			(type solid)
		)
		(fill yes)
		(layer "In4.Cu")
		(net "M_J_CPU0_SA_DQ<17>")
	)
	(gr_poly
		(pts
			(xy 389.894826 -235.372148) (xy 389.894826 -235.327698) (xy 389.694674 -235.327698) (xy 389.694674 -235.372148)
			(xy 389.79475 -235.472224)
		)
		(stroke
			(width 0)
			(type solid)
		)
		(fill yes)
		(layer "In4.Cu")
		(net "M_J_CPU0_SA_DQ<18>")
	)
	(gr_poly
		(pts
			(xy 389.894826 -234.155996) (xy 389.79475 -234.05592) (xy 389.694674 -234.155996) (xy 389.694674 -234.200446)
			(xy 389.894826 -234.200446)
		)
		(stroke
			(width 0)
			(type solid)
		)
		(fill yes)
		(layer "In4.Cu")
		(net "M_J_CPU0_SA_DQ<13>")
	)
	(gr_poly
		(pts
			(xy 389.894826 -233.752136) (xy 389.894826 -233.707686) (xy 389.694674 -233.707686) (xy 389.694674 -233.752136)
			(xy 389.79475 -233.852212)
		)
		(stroke
			(width 0)
			(type solid)
		)
		(fill yes)
		(layer "In4.Cu")
		(net "M_J_CPU0_SA_DQ<14>")
	)
	(gr_poly
		(pts
			(xy 389.894826 -232.53573) (xy 389.79475 -232.435908) (xy 389.694674 -232.53573) (xy 389.694674 -232.583482)
			(xy 389.894826 -232.583482)
		)
		(stroke
			(width 0)
			(type solid)
		)
		(fill yes)
		(layer "In4.Cu")
		(net "M_J_CPU0_SA_DQS_DN<6>")
	)
	(gr_poly
		(pts
			(xy 389.894826 -232.132378) (xy 389.894826 -232.084626) (xy 389.694674 -232.084626) (xy 389.694674 -232.132378)
			(xy 389.79475 -232.2322)
		)
		(stroke
			(width 0)
			(type solid)
		)
		(fill yes)
		(layer "In4.Cu")
		(net "M_J_CPU0_SA_DQS_DN<1>")
	)
	(gr_poly
		(pts
			(xy 389.894826 -230.915972) (xy 389.79475 -230.815896) (xy 389.694674 -230.915972) (xy 389.694674 -230.960422)
			(xy 389.894826 -230.960422)
		)
		(stroke
			(width 0)
			(type solid)
		)
		(fill yes)
		(layer "In4.Cu")
		(net "M_J_CPU0_SA_DQ<9>")
	)
	(gr_poly
		(pts
			(xy 389.894826 -230.512366) (xy 389.894826 -230.467916) (xy 389.694674 -230.467916) (xy 389.694674 -230.512366)
			(xy 389.79475 -230.612188)
		)
		(stroke
			(width 0)
			(type solid)
		)
		(fill yes)
		(layer "In4.Cu")
		(net "M_J_CPU0_SA_DQ<10>")
	)
	(gr_poly
		(pts
			(xy 389.894826 -229.29596) (xy 389.79475 -229.195884) (xy 389.694674 -229.29596) (xy 389.694674 -229.34041)
			(xy 389.894826 -229.34041)
		)
		(stroke
			(width 0)
			(type solid)
		)
		(fill yes)
		(layer "In4.Cu")
		(net "M_J_CPU0_SA_DQ<5>")
	)
	(gr_poly
		(pts
			(xy 389.894826 -228.892354) (xy 389.894826 -228.847904) (xy 389.694674 -228.847904) (xy 389.694674 -228.892354)
			(xy 389.79475 -228.99243)
		)
		(stroke
			(width 0)
			(type solid)
		)
		(fill yes)
		(layer "In4.Cu")
		(net "M_J_CPU0_SA_DQ<6>")
	)
	(gr_poly
		(pts
			(xy 389.950706 -227.809298) (xy 389.91413 -227.6729) (xy 389.872728 -227.649024) (xy 389.772906 -227.822252)
			(xy 389.814054 -227.846128)
		)
		(stroke
			(width 0)
			(type solid)
		)
		(fill yes)
		(layer "In4.Cu")
		(net "M_J_CPU0_SA_DQS_DP<5>")
	)
	(gr_poly
		(pts
			(xy 389.950706 -226.189286) (xy 389.91413 -226.052888) (xy 389.872728 -226.029012) (xy 389.772906 -226.20224)
			(xy 389.814054 -226.226116)
		)
		(stroke
			(width 0)
			(type solid)
		)
		(fill yes)
		(layer "In4.Cu")
		(net "M_J_CPU0_SA_DQS_DN<0>")
	)
	(gr_poly
		(pts
			(xy 389.950706 -224.568766) (xy 389.91413 -224.432114) (xy 389.875776 -224.409762) (xy 389.7757 -224.58299)
			(xy 389.814308 -224.605342)
		)
		(stroke
			(width 0)
			(type solid)
		)
		(fill yes)
		(layer "In4.Cu")
		(net "M_J_CPU0_SA_DQ<3>")
	)
	(gr_poly
		(pts
			(xy 389.951468 -222.947992) (xy 389.914892 -222.81134) (xy 389.876284 -222.789242) (xy 389.776462 -222.96247)
			(xy 389.814816 -222.984568)
		)
		(stroke
			(width 0)
			(type solid)
		)
		(fill yes)
		(layer "In4.Cu")
		(net "M_J_CPU0_SA_DQ<2>")
	)
	(gr_poly
		(pts
			(xy 390.1948 -293.324026) (xy 390.1948 -293.279576) (xy 389.994648 -293.279576) (xy 389.994648 -293.324026)
			(xy 390.094724 -293.424102)
		)
		(stroke
			(width 0)
			(type solid)
		)
		(fill yes)
		(layer "In4.Cu")
		(net "M_J_CPU0_SB_DQ<31>")
	)
	(gr_poly
		(pts
			(xy 390.1948 -292.107874) (xy 390.094724 -292.007798) (xy 389.994648 -292.107874) (xy 389.994648 -292.152324)
			(xy 390.1948 -292.152324)
		)
		(stroke
			(width 0)
			(type solid)
		)
		(fill yes)
		(layer "In4.Cu")
		(net "M_J_CPU0_SB_DQ<28>")
	)
	(gr_poly
		(pts
			(xy 390.1948 -291.704268) (xy 390.1948 -291.656516) (xy 389.994648 -291.656516) (xy 389.994648 -291.704268)
			(xy 390.094724 -291.80409)
		)
		(stroke
			(width 0)
			(type solid)
		)
		(fill yes)
		(layer "In4.Cu")
		(net "M_J_CPU0_SB_DQS_DP<8>")
	)
	(gr_poly
		(pts
			(xy 390.1948 -290.487608) (xy 390.094724 -290.387786) (xy 389.994648 -290.487608) (xy 389.994648 -290.53536)
			(xy 390.1948 -290.53536)
		)
		(stroke
			(width 0)
			(type solid)
		)
		(fill yes)
		(layer "In4.Cu")
		(net "M_J_CPU0_SB_DQS_DP<3>")
	)
	(gr_poly
		(pts
			(xy 390.1948 -290.084002) (xy 390.1948 -290.039552) (xy 389.994648 -290.039552) (xy 389.994648 -290.084002)
			(xy 390.094724 -290.184078)
		)
		(stroke
			(width 0)
			(type solid)
		)
		(fill yes)
		(layer "In4.Cu")
		(net "M_J_CPU0_SB_DQ<27>")
	)
	(gr_poly
		(pts
			(xy 390.1948 -288.86785) (xy 390.094724 -288.767774) (xy 389.994648 -288.86785) (xy 389.994648 -288.9123)
			(xy 390.1948 -288.9123)
		)
		(stroke
			(width 0)
			(type solid)
		)
		(fill yes)
		(layer "In4.Cu")
		(net "M_J_CPU0_SB_DQ<24>")
	)
	(gr_poly
		(pts
			(xy 390.1948 -288.464244) (xy 390.1948 -288.419794) (xy 389.994648 -288.419794) (xy 389.994648 -288.464244)
			(xy 390.094724 -288.56432)
		)
		(stroke
			(width 0)
			(type solid)
		)
		(fill yes)
		(layer "In4.Cu")
		(net "M_J_CPU0_SB_DQ<23>")
	)
	(gr_poly
		(pts
			(xy 390.1948 -287.247838) (xy 390.094724 -287.148016) (xy 389.994648 -287.247838) (xy 389.994648 -287.292288)
			(xy 390.1948 -287.292288)
		)
		(stroke
			(width 0)
			(type solid)
		)
		(fill yes)
		(layer "In4.Cu")
		(net "M_J_CPU0_SB_DQ<20>")
	)
	(gr_poly
		(pts
			(xy 390.1948 -286.844232) (xy 390.1948 -286.79648) (xy 389.994648 -286.79648) (xy 389.994648 -286.844232)
			(xy 390.094724 -286.944308)
		)
		(stroke
			(width 0)
			(type solid)
		)
		(fill yes)
		(layer "In4.Cu")
		(net "M_J_CPU0_SB_DQS_DP<7>")
	)
	(gr_poly
		(pts
			(xy 390.1948 -285.627826) (xy 390.094724 -285.528004) (xy 389.994648 -285.627826) (xy 389.994648 -285.675578)
			(xy 390.1948 -285.675578)
		)
		(stroke
			(width 0)
			(type solid)
		)
		(fill yes)
		(layer "In4.Cu")
		(net "M_J_CPU0_SB_DQS_DP<2>")
	)
	(gr_poly
		(pts
			(xy 390.1948 -285.22422) (xy 390.1948 -285.17977) (xy 389.994648 -285.17977) (xy 389.994648 -285.22422)
			(xy 390.094724 -285.324296)
		)
		(stroke
			(width 0)
			(type solid)
		)
		(fill yes)
		(layer "In4.Cu")
		(net "M_J_CPU0_SB_DQ<19>")
	)
	(gr_poly
		(pts
			(xy 390.1948 -284.008068) (xy 390.094724 -283.907992) (xy 389.994648 -284.008068) (xy 389.994648 -284.052518)
			(xy 390.1948 -284.052518)
		)
		(stroke
			(width 0)
			(type solid)
		)
		(fill yes)
		(layer "In4.Cu")
		(net "M_J_CPU0_SB_DQ<16>")
	)
	(gr_poly
		(pts
			(xy 390.1948 -283.604208) (xy 390.1948 -283.559758) (xy 389.994648 -283.559758) (xy 389.994648 -283.604208)
			(xy 390.094724 -283.704284)
		)
		(stroke
			(width 0)
			(type solid)
		)
		(fill yes)
		(layer "In4.Cu")
		(net "M_J_CPU0_SB_DQ<15>")
	)
	(gr_poly
		(pts
			(xy 390.1948 -282.388056) (xy 390.094724 -282.28798) (xy 389.994648 -282.388056) (xy 389.994648 -282.432506)
			(xy 390.1948 -282.432506)
		)
		(stroke
			(width 0)
			(type solid)
		)
		(fill yes)
		(layer "In4.Cu")
		(net "M_J_CPU0_SB_DQ<12>")
	)
	(gr_poly
		(pts
			(xy 390.1948 -281.98445) (xy 390.1948 -281.936698) (xy 389.994648 -281.936698) (xy 389.994648 -281.98445)
			(xy 390.094724 -282.084272)
		)
		(stroke
			(width 0)
			(type solid)
		)
		(fill yes)
		(layer "In4.Cu")
		(net "M_J_CPU0_SB_DQS_DP<6>")
	)
	(gr_poly
		(pts
			(xy 390.1948 -280.76779) (xy 390.094724 -280.667968) (xy 389.994648 -280.76779) (xy 389.994648 -280.815542)
			(xy 390.1948 -280.815542)
		)
		(stroke
			(width 0)
			(type solid)
		)
		(fill yes)
		(layer "In4.Cu")
		(net "M_J_CPU0_SB_DQS_DP<1>")
	)
	(gr_poly
		(pts
			(xy 390.1948 -280.364184) (xy 390.1948 -280.319734) (xy 389.994648 -280.319734) (xy 389.994648 -280.364184)
			(xy 390.094724 -280.46426)
		)
		(stroke
			(width 0)
			(type solid)
		)
		(fill yes)
		(layer "In4.Cu")
		(net "M_J_CPU0_SB_DQ<11>")
	)
	(gr_poly
		(pts
			(xy 390.1948 -279.148032) (xy 390.094724 -279.047956) (xy 389.994648 -279.148032) (xy 389.994648 -279.192482)
			(xy 390.1948 -279.192482)
		)
		(stroke
			(width 0)
			(type solid)
		)
		(fill yes)
		(layer "In4.Cu")
		(net "M_J_CPU0_SB_DQ<8>")
	)
	(gr_poly
		(pts
			(xy 390.1948 -278.744172) (xy 390.1948 -278.699722) (xy 389.994648 -278.699722) (xy 389.994648 -278.744172)
			(xy 390.094724 -278.844248)
		)
		(stroke
			(width 0)
			(type solid)
		)
		(fill yes)
		(layer "In4.Cu")
		(net "M_J_CPU0_SB_DQ<7>")
	)
	(gr_poly
		(pts
			(xy 390.1948 -277.52802) (xy 390.094724 -277.427944) (xy 389.994648 -277.52802) (xy 389.994648 -277.57247)
			(xy 390.1948 -277.57247)
		)
		(stroke
			(width 0)
			(type solid)
		)
		(fill yes)
		(layer "In4.Cu")
		(net "M_J_CPU0_SB_DQ<4>")
	)
	(gr_poly
		(pts
			(xy 390.1948 -277.124414) (xy 390.1948 -277.076662) (xy 389.994648 -277.076662) (xy 389.994648 -277.124414)
			(xy 390.094724 -277.224236)
		)
		(stroke
			(width 0)
			(type solid)
		)
		(fill yes)
		(layer "In4.Cu")
		(net "M_J_CPU0_SB_DQS_DP<5>")
	)
	(gr_poly
		(pts
			(xy 390.1948 -275.907754) (xy 390.094724 -275.807932) (xy 389.994648 -275.907754) (xy 389.994648 -275.955506)
			(xy 390.1948 -275.955506)
		)
		(stroke
			(width 0)
			(type solid)
		)
		(fill yes)
		(layer "In4.Cu")
		(net "M_J_CPU0_SB_DQS_DP<0>")
	)
	(gr_poly
		(pts
			(xy 390.1948 -275.504148) (xy 390.1948 -275.459698) (xy 389.994648 -275.459698) (xy 389.994648 -275.504148)
			(xy 390.094724 -275.604224)
		)
		(stroke
			(width 0)
			(type solid)
		)
		(fill yes)
		(layer "In4.Cu")
		(net "M_J_CPU0_SB_DQ<3>")
	)
	(gr_poly
		(pts
			(xy 390.1948 -274.287996) (xy 390.094724 -274.18792) (xy 389.994648 -274.287996) (xy 389.994648 -274.332446)
			(xy 390.1948 -274.332446)
		)
		(stroke
			(width 0)
			(type solid)
		)
		(fill yes)
		(layer "In4.Cu")
		(net "M_J_CPU0_SB_DQ<0>")
	)
	(gr_poly
		(pts
			(xy 390.1948 -273.884136) (xy 390.1948 -273.839686) (xy 389.994648 -273.839686) (xy 389.994648 -273.884136)
			(xy 390.094724 -273.984212)
		)
		(stroke
			(width 0)
			(type solid)
		)
		(fill yes)
		(layer "In4.Cu")
		(net "M_J_CPU0_SB_CB<3>")
	)
	(gr_poly
		(pts
			(xy 390.1948 -272.667984) (xy 390.094724 -272.567908) (xy 389.994648 -272.667984) (xy 389.994648 -272.712434)
			(xy 390.1948 -272.712434)
		)
		(stroke
			(width 0)
			(type solid)
		)
		(fill yes)
		(layer "In4.Cu")
		(net "M_J_CPU0_SB_CB<0>")
	)
	(gr_poly
		(pts
			(xy 390.1948 -272.264378) (xy 390.1948 -272.216626) (xy 389.994648 -272.216626) (xy 389.994648 -272.264378)
			(xy 390.094724 -272.3642)
		)
		(stroke
			(width 0)
			(type solid)
		)
		(fill yes)
		(layer "In4.Cu")
		(net "M_J_CPU0_SB_DQS_DP<4>")
	)
	(gr_poly
		(pts
			(xy 390.1948 -271.047718) (xy 390.094724 -270.947896) (xy 389.994648 -271.047718) (xy 389.994648 -271.09547)
			(xy 390.1948 -271.09547)
		)
		(stroke
			(width 0)
			(type solid)
		)
		(fill yes)
		(layer "In4.Cu")
		(net "M_J_CPU0_SB_DQS_DP<9>")
	)
	(gr_poly
		(pts
			(xy 390.1948 -270.644112) (xy 390.1948 -270.599662) (xy 389.994648 -270.599662) (xy 389.994648 -270.644112)
			(xy 390.094724 -270.744188)
		)
		(stroke
			(width 0)
			(type solid)
		)
		(fill yes)
		(layer "In4.Cu")
		(net "M_J_CPU0_SB_CB<7>")
	)
	(gr_poly
		(pts
			(xy 390.1948 -269.42796) (xy 390.094724 -269.327884) (xy 389.994648 -269.42796) (xy 389.994648 -269.47241)
			(xy 390.1948 -269.47241)
		)
		(stroke
			(width 0)
			(type solid)
		)
		(fill yes)
		(layer "In4.Cu")
		(net "M_J_CPU0_SB_CB<4>")
	)
	(gr_poly
		(pts
			(xy 390.1948 -267.807948) (xy 390.094724 -267.707872) (xy 389.994648 -267.807948) (xy 389.994648 -267.852398)
			(xy 390.1948 -267.852398)
		)
		(stroke
			(width 0)
			(type solid)
		)
		(fill yes)
		(layer "In4.Cu")
		(net "M_J_CPU0_SB_RSP<0>")
	)
	(gr_poly
		(pts
			(xy 390.1948 -265.784076) (xy 390.1948 -265.739626) (xy 389.994648 -265.739626) (xy 389.994648 -265.784076)
			(xy 390.094724 -265.884152)
		)
		(stroke
			(width 0)
			(type solid)
		)
		(fill yes)
		(layer "In4.Cu")
		(net "M_J_CPU0_SB_CS_N<0>")
	)
	(gr_poly
		(pts
			(xy 390.1948 -264.567924) (xy 390.094724 -264.467848) (xy 389.994648 -264.567924) (xy 389.994648 -264.612374)
			(xy 390.1948 -264.612374)
		)
		(stroke
			(width 0)
			(type solid)
		)
		(fill yes)
		(layer "In4.Cu")
		(net "M_J_CPU0_SB_CA<6>")
	)
	(gr_poly
		(pts
			(xy 390.1948 -264.164064) (xy 390.1948 -264.119614) (xy 389.994648 -264.119614) (xy 389.994648 -264.164064)
			(xy 390.094724 -264.26414)
		)
		(stroke
			(width 0)
			(type solid)
		)
		(fill yes)
		(layer "In4.Cu")
		(net "M_J_CPU0_SB_CA<5>")
	)
	(gr_poly
		(pts
			(xy 390.1948 -262.947912) (xy 390.094724 -262.847836) (xy 389.994648 -262.947912) (xy 389.994648 -262.992362)
			(xy 390.1948 -262.992362)
		)
		(stroke
			(width 0)
			(type solid)
		)
		(fill yes)
		(layer "In4.Cu")
		(net "M_J_CPU0_SB_CA<2>")
	)
	(gr_poly
		(pts
			(xy 390.1948 -262.544052) (xy 390.1948 -262.499602) (xy 389.994648 -262.499602) (xy 389.994648 -262.544052)
			(xy 390.094724 -262.644128)
		)
		(stroke
			(width 0)
			(type solid)
		)
		(fill yes)
		(layer "In4.Cu")
		(net "M_J_CPU0_SB_CA<1>")
	)
	(gr_poly
		(pts
			(xy 390.283954 -227.935536) (xy 390.245346 -227.913184) (xy 390.108694 -227.94976) (xy 390.145524 -228.086412)
			(xy 390.183878 -228.108764)
		)
		(stroke
			(width 0)
			(type solid)
		)
		(fill yes)
		(layer "In4.Cu")
		(net "M_J_CPU0_SA_DQ<4>")
	)
	(gr_poly
		(pts
			(xy 390.285986 -223.072452) (xy 390.247378 -223.050354) (xy 390.11098 -223.08693) (xy 390.147556 -223.223582)
			(xy 390.18591 -223.24568)
		)
		(stroke
			(width 0)
			(type solid)
		)
		(fill yes)
		(layer "In4.Cu")
		(net "M_J_CPU0_SA_DQ<1>")
	)
	(gr_poly
		(pts
			(xy 390.286748 -226.316286) (xy 390.2456 -226.292664) (xy 390.108948 -226.32924) (xy 390.145524 -226.465638)
			(xy 390.186926 -226.489514)
		)
		(stroke
			(width 0)
			(type solid)
		)
		(fill yes)
		(layer "In4.Cu")
		(net "M_J_CPU0_SA_DQS_DN<5>")
	)
	(gr_poly
		(pts
			(xy 390.286748 -224.696274) (xy 390.2456 -224.672652) (xy 390.108948 -224.709228) (xy 390.145524 -224.845626)
			(xy 390.186926 -224.869502)
		)
		(stroke
			(width 0)
			(type solid)
		)
		(fill yes)
		(layer "In4.Cu")
		(net "M_J_CPU0_SA_DQS_DP<0>")
	)
	(gr_poly
		(pts
			(xy 390.36498 -256.025904) (xy 390.264904 -255.926082) (xy 390.164828 -256.025904) (xy 390.164828 -256.073656)
			(xy 390.36498 -256.073656)
		)
		(stroke
			(width 0)
			(type solid)
		)
		(fill yes)
		(layer "In4.Cu")
		(net "M_J_CPU0_CLK_DP<0>")
	)
	(gr_poly
		(pts
			(xy 390.36498 -255.622298) (xy 390.36498 -255.577848) (xy 390.164828 -255.577848) (xy 390.164828 -255.622298)
			(xy 390.264904 -255.722374)
		)
		(stroke
			(width 0)
			(type solid)
		)
		(fill yes)
		(layer "In4.Cu")
		(net "M_J_CPU0_SA_PAR")
	)
	(gr_poly
		(pts
			(xy 390.36498 -254.406146) (xy 390.264904 -254.30607) (xy 390.164828 -254.406146) (xy 390.164828 -254.450596)
			(xy 390.36498 -254.450596)
		)
		(stroke
			(width 0)
			(type solid)
		)
		(fill yes)
		(layer "In4.Cu")
		(net "M_J_CPU0_SA_CA<4>")
	)
	(gr_poly
		(pts
			(xy 390.36498 -254.002286) (xy 390.36498 -253.957836) (xy 390.164828 -253.957836) (xy 390.164828 -254.002286)
			(xy 390.264904 -254.102362)
		)
		(stroke
			(width 0)
			(type solid)
		)
		(fill yes)
		(layer "In4.Cu")
		(net "M_J_CPU0_SA_CA<3>")
	)
	(gr_poly
		(pts
			(xy 390.36498 -252.786134) (xy 390.264904 -252.686058) (xy 390.164828 -252.786134) (xy 390.164828 -252.830584)
			(xy 390.36498 -252.830584)
		)
		(stroke
			(width 0)
			(type solid)
		)
		(fill yes)
		(layer "In4.Cu")
		(net "M_J_CPU0_SA_CA<0>")
	)
	(gr_poly
		(pts
			(xy 390.36498 -251.166122) (xy 390.264904 -251.066046) (xy 390.164828 -251.166122) (xy 390.164828 -251.210572)
			(xy 390.36498 -251.210572)
		)
		(stroke
			(width 0)
			(type solid)
		)
		(fill yes)
		(layer "In4.Cu")
		(net "M_J_CPU0_SA_CS_N<0>")
	)
	(gr_poly
		(pts
			(xy 390.36498 -250.762262) (xy 390.36498 -250.717812) (xy 390.164828 -250.717812) (xy 390.164828 -250.762262)
			(xy 390.264904 -250.862338)
		)
		(stroke
			(width 0)
			(type solid)
		)
		(fill yes)
		(layer "In4.Cu")
		(net "M_J_CPU0_RESET_N")
	)
	(gr_poly
		(pts
			(xy 390.36498 -249.14225) (xy 390.36498 -249.0978) (xy 390.164828 -249.0978) (xy 390.164828 -249.14225)
			(xy 390.264904 -249.242326)
		)
		(stroke
			(width 0)
			(type solid)
		)
		(fill yes)
		(layer "In4.Cu")
		(net "M_J_CPU0_SA_CB<7>")
	)
	(gr_poly
		(pts
			(xy 390.36498 -247.926098) (xy 390.264904 -247.826022) (xy 390.164828 -247.926098) (xy 390.164828 -247.970548)
			(xy 390.36498 -247.970548)
		)
		(stroke
			(width 0)
			(type solid)
		)
		(fill yes)
		(layer "In4.Cu")
		(net "M_J_CPU0_SA_CB<4>")
	)
	(gr_poly
		(pts
			(xy 390.36498 -247.522492) (xy 390.36498 -247.47474) (xy 390.164828 -247.47474) (xy 390.164828 -247.522492)
			(xy 390.264904 -247.622314)
		)
		(stroke
			(width 0)
			(type solid)
		)
		(fill yes)
		(layer "In4.Cu")
		(net "M_J_CPU0_SA_DQS_DP<9>")
	)
	(gr_poly
		(pts
			(xy 390.36498 -246.305832) (xy 390.264904 -246.20601) (xy 390.164828 -246.305832) (xy 390.164828 -246.353584)
			(xy 390.36498 -246.353584)
		)
		(stroke
			(width 0)
			(type solid)
		)
		(fill yes)
		(layer "In4.Cu")
		(net "M_J_CPU0_SA_DQS_DP<4>")
	)
	(gr_poly
		(pts
			(xy 390.36498 -245.902226) (xy 390.36498 -245.857776) (xy 390.164828 -245.857776) (xy 390.164828 -245.902226)
			(xy 390.264904 -246.002302)
		)
		(stroke
			(width 0)
			(type solid)
		)
		(fill yes)
		(layer "In4.Cu")
		(net "M_J_CPU0_SA_CB<3>")
	)
	(gr_poly
		(pts
			(xy 390.36498 -244.686074) (xy 390.264904 -244.585998) (xy 390.164828 -244.686074) (xy 390.164828 -244.730524)
			(xy 390.36498 -244.730524)
		)
		(stroke
			(width 0)
			(type solid)
		)
		(fill yes)
		(layer "In4.Cu")
		(net "M_J_CPU0_SA_CB<0>")
	)
	(gr_poly
		(pts
			(xy 390.36498 -244.282214) (xy 390.36498 -244.237764) (xy 390.164828 -244.237764) (xy 390.164828 -244.282214)
			(xy 390.264904 -244.38229)
		)
		(stroke
			(width 0)
			(type solid)
		)
		(fill yes)
		(layer "In4.Cu")
		(net "M_J_CPU0_SA_DQ<31>")
	)
	(gr_poly
		(pts
			(xy 390.36498 -243.066062) (xy 390.264904 -242.965986) (xy 390.164828 -243.066062) (xy 390.164828 -243.110512)
			(xy 390.36498 -243.110512)
		)
		(stroke
			(width 0)
			(type solid)
		)
		(fill yes)
		(layer "In4.Cu")
		(net "M_J_CPU0_SA_DQ<28>")
	)
	(gr_poly
		(pts
			(xy 390.36498 -242.662456) (xy 390.36498 -242.614704) (xy 390.164828 -242.614704) (xy 390.164828 -242.662456)
			(xy 390.264904 -242.762278)
		)
		(stroke
			(width 0)
			(type solid)
		)
		(fill yes)
		(layer "In4.Cu")
		(net "M_J_CPU0_SA_DQS_DP<8>")
	)
	(gr_poly
		(pts
			(xy 390.36498 -241.445796) (xy 390.264904 -241.345974) (xy 390.164828 -241.445796) (xy 390.164828 -241.493548)
			(xy 390.36498 -241.493548)
		)
		(stroke
			(width 0)
			(type solid)
		)
		(fill yes)
		(layer "In4.Cu")
		(net "M_J_CPU0_SA_DQS_DP<3>")
	)
	(gr_poly
		(pts
			(xy 390.36498 -241.04219) (xy 390.36498 -240.99774) (xy 390.164828 -240.99774) (xy 390.164828 -241.04219)
			(xy 390.264904 -241.142266)
		)
		(stroke
			(width 0)
			(type solid)
		)
		(fill yes)
		(layer "In4.Cu")
		(net "M_J_CPU0_SA_DQ<27>")
	)
	(gr_poly
		(pts
			(xy 390.36498 -239.826038) (xy 390.264904 -239.725962) (xy 390.164828 -239.826038) (xy 390.164828 -239.870488)
			(xy 390.36498 -239.870488)
		)
		(stroke
			(width 0)
			(type solid)
		)
		(fill yes)
		(layer "In4.Cu")
		(net "M_J_CPU0_SA_DQ<24>")
	)
	(gr_poly
		(pts
			(xy 390.36498 -239.422178) (xy 390.36498 -239.377728) (xy 390.164828 -239.377728) (xy 390.164828 -239.422178)
			(xy 390.264904 -239.522254)
		)
		(stroke
			(width 0)
			(type solid)
		)
		(fill yes)
		(layer "In4.Cu")
		(net "M_J_CPU0_SA_DQ<23>")
	)
	(gr_poly
		(pts
			(xy 390.36498 -238.206026) (xy 390.264904 -238.10595) (xy 390.164828 -238.206026) (xy 390.164828 -238.250476)
			(xy 390.36498 -238.250476)
		)
		(stroke
			(width 0)
			(type solid)
		)
		(fill yes)
		(layer "In4.Cu")
		(net "M_J_CPU0_SA_DQ<20>")
	)
	(gr_poly
		(pts
			(xy 390.36498 -237.80242) (xy 390.36498 -237.754668) (xy 390.164828 -237.754668) (xy 390.164828 -237.80242)
			(xy 390.264904 -237.902242)
		)
		(stroke
			(width 0)
			(type solid)
		)
		(fill yes)
		(layer "In4.Cu")
		(net "M_J_CPU0_SA_DQS_DP<7>")
	)
	(gr_poly
		(pts
			(xy 390.36498 -236.58576) (xy 390.264904 -236.485938) (xy 390.164828 -236.58576) (xy 390.164828 -236.633512)
			(xy 390.36498 -236.633512)
		)
		(stroke
			(width 0)
			(type solid)
		)
		(fill yes)
		(layer "In4.Cu")
		(net "M_J_CPU0_SA_DQS_DP<2>")
	)
	(gr_poly
		(pts
			(xy 390.36498 -236.182154) (xy 390.36498 -236.137704) (xy 390.164828 -236.137704) (xy 390.164828 -236.182154)
			(xy 390.264904 -236.28223)
		)
		(stroke
			(width 0)
			(type solid)
		)
		(fill yes)
		(layer "In4.Cu")
		(net "M_J_CPU0_SA_DQ<19>")
	)
	(gr_poly
		(pts
			(xy 390.36498 -234.966002) (xy 390.264904 -234.865926) (xy 390.164828 -234.966002) (xy 390.164828 -235.010452)
			(xy 390.36498 -235.010452)
		)
		(stroke
			(width 0)
			(type solid)
		)
		(fill yes)
		(layer "In4.Cu")
		(net "M_J_CPU0_SA_DQ<16>")
	)
	(gr_poly
		(pts
			(xy 390.36498 -234.562142) (xy 390.36498 -234.517692) (xy 390.164828 -234.517692) (xy 390.164828 -234.562142)
			(xy 390.264904 -234.662218)
		)
		(stroke
			(width 0)
			(type solid)
		)
		(fill yes)
		(layer "In4.Cu")
		(net "M_J_CPU0_SA_DQ<15>")
	)
	(gr_poly
		(pts
			(xy 390.36498 -233.34599) (xy 390.264904 -233.245914) (xy 390.164828 -233.34599) (xy 390.164828 -233.39044)
			(xy 390.36498 -233.39044)
		)
		(stroke
			(width 0)
			(type solid)
		)
		(fill yes)
		(layer "In4.Cu")
		(net "M_J_CPU0_SA_DQ<12>")
	)
	(gr_poly
		(pts
			(xy 390.36498 -232.942384) (xy 390.36498 -232.894632) (xy 390.164828 -232.894632) (xy 390.164828 -232.942384)
			(xy 390.264904 -233.042206)
		)
		(stroke
			(width 0)
			(type solid)
		)
		(fill yes)
		(layer "In4.Cu")
		(net "M_J_CPU0_SA_DQS_DP<6>")
	)
	(gr_poly
		(pts
			(xy 390.36498 -231.725724) (xy 390.264904 -231.625902) (xy 390.164828 -231.725724) (xy 390.164828 -231.773476)
			(xy 390.36498 -231.773476)
		)
		(stroke
			(width 0)
			(type solid)
		)
		(fill yes)
		(layer "In4.Cu")
		(net "M_J_CPU0_SA_DQS_DP<1>")
	)
	(gr_poly
		(pts
			(xy 390.36498 -231.322372) (xy 390.36498 -231.277922) (xy 390.164828 -231.277922) (xy 390.164828 -231.322372)
			(xy 390.264904 -231.422448)
		)
		(stroke
			(width 0)
			(type solid)
		)
		(fill yes)
		(layer "In4.Cu")
		(net "M_J_CPU0_SA_DQ<11>")
	)
	(gr_poly
		(pts
			(xy 390.36498 -230.105966) (xy 390.264904 -230.006144) (xy 390.164828 -230.105966) (xy 390.164828 -230.150416)
			(xy 390.36498 -230.150416)
		)
		(stroke
			(width 0)
			(type solid)
		)
		(fill yes)
		(layer "In4.Cu")
		(net "M_J_CPU0_SA_DQ<8>")
	)
	(gr_poly
		(pts
			(xy 390.36498 -229.70236) (xy 390.36498 -229.65791) (xy 390.164828 -229.65791) (xy 390.164828 -229.70236)
			(xy 390.264904 -229.802436)
		)
		(stroke
			(width 0)
			(type solid)
		)
		(fill yes)
		(layer "In4.Cu")
		(net "M_J_CPU0_SA_DQ<7>")
	)
	(gr_poly
		(pts
			(xy 390.419844 -223.760792) (xy 390.383268 -223.62414) (xy 390.34466 -223.601788) (xy 390.244838 -223.77527)
			(xy 390.283192 -223.797368)
		)
		(stroke
			(width 0)
			(type solid)
		)
		(fill yes)
		(layer "In4.Cu")
		(net "M_J_CPU0_SA_DQ<3>")
	)
	(gr_poly
		(pts
			(xy 390.420606 -228.618796) (xy 390.38403 -228.482144) (xy 390.345676 -228.459792) (xy 390.2456 -228.63302)
			(xy 390.284208 -228.655372)
		)
		(stroke
			(width 0)
			(type solid)
		)
		(fill yes)
		(layer "In4.Cu")
		(net "M_J_CPU0_SA_DQ<6>")
	)
	(gr_poly
		(pts
			(xy 390.420606 -226.999292) (xy 390.38403 -226.862894) (xy 390.342628 -226.839018) (xy 390.242806 -227.012246)
			(xy 390.283954 -227.035868)
		)
		(stroke
			(width 0)
			(type solid)
		)
		(fill yes)
		(layer "In4.Cu")
		(net "M_J_CPU0_SA_DQS_DP<5>")
	)
	(gr_poly
		(pts
			(xy 390.420606 -225.37928) (xy 390.38403 -225.242882) (xy 390.342628 -225.219006) (xy 390.242806 -225.392234)
			(xy 390.283954 -225.415856)
		)
		(stroke
			(width 0)
			(type solid)
		)
		(fill yes)
		(layer "In4.Cu")
		(net "M_J_CPU0_SA_DQS_DN<0>")
	)
	(gr_poly
		(pts
			(xy 390.664954 -292.91788) (xy 390.564878 -292.817804) (xy 390.464802 -292.91788) (xy 390.464802 -292.96233)
			(xy 390.664954 -292.96233)
		)
		(stroke
			(width 0)
			(type solid)
		)
		(fill yes)
		(layer "In4.Cu")
		(net "M_J_CPU0_SB_DQ<29>")
	)
	(gr_poly
		(pts
			(xy 390.664954 -292.51402) (xy 390.664954 -292.46957) (xy 390.464802 -292.46957) (xy 390.464802 -292.51402)
			(xy 390.564878 -292.614096)
		)
		(stroke
			(width 0)
			(type solid)
		)
		(fill yes)
		(layer "In4.Cu")
		(net "M_J_CPU0_SB_DQ<30>")
	)
	(gr_poly
		(pts
			(xy 390.664954 -291.297614) (xy 390.564878 -291.197792) (xy 390.464802 -291.297614) (xy 390.464802 -291.345366)
			(xy 390.664954 -291.345366)
		)
		(stroke
			(width 0)
			(type solid)
		)
		(fill yes)
		(layer "In4.Cu")
		(net "M_J_CPU0_SB_DQS_DN<8>")
	)
	(gr_poly
		(pts
			(xy 390.664954 -290.894262) (xy 390.664954 -290.84651) (xy 390.464802 -290.84651) (xy 390.464802 -290.894262)
			(xy 390.564878 -290.994084)
		)
		(stroke
			(width 0)
			(type solid)
		)
		(fill yes)
		(layer "In4.Cu")
		(net "M_J_CPU0_SB_DQS_DN<3>")
	)
	(gr_poly
		(pts
			(xy 390.664954 -289.677856) (xy 390.564878 -289.57778) (xy 390.464802 -289.677856) (xy 390.464802 -289.722306)
			(xy 390.664954 -289.722306)
		)
		(stroke
			(width 0)
			(type solid)
		)
		(fill yes)
		(layer "In4.Cu")
		(net "M_J_CPU0_SB_DQ<25>")
	)
	(gr_poly
		(pts
			(xy 390.664954 -289.273996) (xy 390.664954 -289.229546) (xy 390.464802 -289.229546) (xy 390.464802 -289.273996)
			(xy 390.564878 -289.374072)
		)
		(stroke
			(width 0)
			(type solid)
		)
		(fill yes)
		(layer "In4.Cu")
		(net "M_J_CPU0_SB_DQ<26>")
	)
	(gr_poly
		(pts
			(xy 390.664954 -288.057844) (xy 390.564878 -287.957768) (xy 390.464802 -288.057844) (xy 390.464802 -288.102294)
			(xy 390.664954 -288.102294)
		)
		(stroke
			(width 0)
			(type solid)
		)
		(fill yes)
		(layer "In4.Cu")
		(net "M_J_CPU0_SB_DQ<21>")
	)
	(gr_poly
		(pts
			(xy 390.664954 -287.654238) (xy 390.664954 -287.609788) (xy 390.464802 -287.609788) (xy 390.464802 -287.654238)
			(xy 390.564878 -287.75406)
		)
		(stroke
			(width 0)
			(type solid)
		)
		(fill yes)
		(layer "In4.Cu")
		(net "M_J_CPU0_SB_DQ<22>")
	)
	(gr_poly
		(pts
			(xy 390.664954 -286.437832) (xy 390.564878 -286.337756) (xy 390.464802 -286.437832) (xy 390.464802 -286.485584)
			(xy 390.664954 -286.485584)
		)
		(stroke
			(width 0)
			(type solid)
		)
		(fill yes)
		(layer "In4.Cu")
		(net "M_J_CPU0_SB_DQS_DN<7>")
	)
	(gr_poly
		(pts
			(xy 390.664954 -286.03448) (xy 390.664954 -285.986728) (xy 390.464802 -285.986728) (xy 390.464802 -286.03448)
			(xy 390.564878 -286.134302)
		)
		(stroke
			(width 0)
			(type solid)
		)
		(fill yes)
		(layer "In4.Cu")
		(net "M_J_CPU0_SB_DQS_DN<2>")
	)
	(gr_poly
		(pts
			(xy 390.664954 -284.818074) (xy 390.564878 -284.717998) (xy 390.464802 -284.818074) (xy 390.464802 -284.862524)
			(xy 390.664954 -284.862524)
		)
		(stroke
			(width 0)
			(type solid)
		)
		(fill yes)
		(layer "In4.Cu")
		(net "M_J_CPU0_SB_DQ<17>")
	)
	(gr_poly
		(pts
			(xy 390.664954 -284.414214) (xy 390.664954 -284.369764) (xy 390.464802 -284.369764) (xy 390.464802 -284.414214)
			(xy 390.564878 -284.51429)
		)
		(stroke
			(width 0)
			(type solid)
		)
		(fill yes)
		(layer "In4.Cu")
		(net "M_J_CPU0_SB_DQ<18>")
	)
	(gr_poly
		(pts
			(xy 390.664954 -283.198062) (xy 390.564878 -283.097986) (xy 390.464802 -283.198062) (xy 390.464802 -283.242512)
			(xy 390.664954 -283.242512)
		)
		(stroke
			(width 0)
			(type solid)
		)
		(fill yes)
		(layer "In4.Cu")
		(net "M_J_CPU0_SB_DQ<13>")
	)
	(gr_poly
		(pts
			(xy 390.664954 -282.794202) (xy 390.664954 -282.749752) (xy 390.464802 -282.749752) (xy 390.464802 -282.794202)
			(xy 390.564878 -282.894278)
		)
		(stroke
			(width 0)
			(type solid)
		)
		(fill yes)
		(layer "In4.Cu")
		(net "M_J_CPU0_SB_DQ<14>")
	)
	(gr_poly
		(pts
			(xy 390.664954 -281.577796) (xy 390.564878 -281.477974) (xy 390.464802 -281.577796) (xy 390.464802 -281.625548)
			(xy 390.664954 -281.625548)
		)
		(stroke
			(width 0)
			(type solid)
		)
		(fill yes)
		(layer "In4.Cu")
		(net "M_J_CPU0_SB_DQS_DN<6>")
	)
	(gr_poly
		(pts
			(xy 390.664954 -281.174444) (xy 390.664954 -281.126692) (xy 390.464802 -281.126692) (xy 390.464802 -281.174444)
			(xy 390.564878 -281.274266)
		)
		(stroke
			(width 0)
			(type solid)
		)
		(fill yes)
		(layer "In4.Cu")
		(net "M_J_CPU0_SB_DQS_DN<1>")
	)
	(gr_poly
		(pts
			(xy 390.664954 -279.958038) (xy 390.564878 -279.857962) (xy 390.464802 -279.958038) (xy 390.464802 -280.002488)
			(xy 390.664954 -280.002488)
		)
		(stroke
			(width 0)
			(type solid)
		)
		(fill yes)
		(layer "In4.Cu")
		(net "M_J_CPU0_SB_DQ<9>")
	)
	(gr_poly
		(pts
			(xy 390.664954 -279.554178) (xy 390.664954 -279.509728) (xy 390.464802 -279.509728) (xy 390.464802 -279.554178)
			(xy 390.564878 -279.654254)
		)
		(stroke
			(width 0)
			(type solid)
		)
		(fill yes)
		(layer "In4.Cu")
		(net "M_J_CPU0_SB_DQ<10>")
	)
	(gr_poly
		(pts
			(xy 390.664954 -278.338026) (xy 390.564878 -278.23795) (xy 390.464802 -278.338026) (xy 390.464802 -278.382476)
			(xy 390.664954 -278.382476)
		)
		(stroke
			(width 0)
			(type solid)
		)
		(fill yes)
		(layer "In4.Cu")
		(net "M_J_CPU0_SB_DQ<5>")
	)
	(gr_poly
		(pts
			(xy 390.664954 -277.934166) (xy 390.664954 -277.889716) (xy 390.464802 -277.889716) (xy 390.464802 -277.934166)
			(xy 390.564878 -278.034242)
		)
		(stroke
			(width 0)
			(type solid)
		)
		(fill yes)
		(layer "In4.Cu")
		(net "M_J_CPU0_SB_DQ<6>")
	)
	(gr_poly
		(pts
			(xy 390.664954 -276.71776) (xy 390.564878 -276.617938) (xy 390.464802 -276.71776) (xy 390.464802 -276.765512)
			(xy 390.664954 -276.765512)
		)
		(stroke
			(width 0)
			(type solid)
		)
		(fill yes)
		(layer "In4.Cu")
		(net "M_J_CPU0_SB_DQS_DN<5>")
	)
	(gr_poly
		(pts
			(xy 390.664954 -276.314408) (xy 390.664954 -276.266656) (xy 390.464802 -276.266656) (xy 390.464802 -276.314408)
			(xy 390.564878 -276.41423)
		)
		(stroke
			(width 0)
			(type solid)
		)
		(fill yes)
		(layer "In4.Cu")
		(net "M_J_CPU0_SB_DQS_DN<0>")
	)
	(gr_poly
		(pts
			(xy 390.664954 -275.098002) (xy 390.564878 -274.997926) (xy 390.464802 -275.098002) (xy 390.464802 -275.142452)
			(xy 390.664954 -275.142452)
		)
		(stroke
			(width 0)
			(type solid)
		)
		(fill yes)
		(layer "In4.Cu")
		(net "M_J_CPU0_SB_DQ<1>")
	)
	(gr_poly
		(pts
			(xy 390.664954 -274.694142) (xy 390.664954 -274.649692) (xy 390.464802 -274.649692) (xy 390.464802 -274.694142)
			(xy 390.564878 -274.794218)
		)
		(stroke
			(width 0)
			(type solid)
		)
		(fill yes)
		(layer "In4.Cu")
		(net "M_J_CPU0_SB_DQ<2>")
	)
	(gr_poly
		(pts
			(xy 390.664954 -273.47799) (xy 390.564878 -273.377914) (xy 390.464802 -273.47799) (xy 390.464802 -273.52244)
			(xy 390.664954 -273.52244)
		)
		(stroke
			(width 0)
			(type solid)
		)
		(fill yes)
		(layer "In4.Cu")
		(net "M_J_CPU0_SB_CB<1>")
	)
	(gr_poly
		(pts
			(xy 390.664954 -273.07413) (xy 390.664954 -273.02968) (xy 390.464802 -273.02968) (xy 390.464802 -273.07413)
			(xy 390.564878 -273.174206)
		)
		(stroke
			(width 0)
			(type solid)
		)
		(fill yes)
		(layer "In4.Cu")
		(net "M_J_CPU0_SB_CB<2>")
	)
	(gr_poly
		(pts
			(xy 390.664954 -271.857724) (xy 390.564878 -271.757902) (xy 390.464802 -271.857724) (xy 390.464802 -271.905476)
			(xy 390.664954 -271.905476)
		)
		(stroke
			(width 0)
			(type solid)
		)
		(fill yes)
		(layer "In4.Cu")
		(net "M_J_CPU0_SB_DQS_DN<4>")
	)
	(gr_poly
		(pts
			(xy 390.664954 -271.454372) (xy 390.664954 -271.40662) (xy 390.464802 -271.40662) (xy 390.464802 -271.454372)
			(xy 390.564878 -271.554194)
		)
		(stroke
			(width 0)
			(type solid)
		)
		(fill yes)
		(layer "In4.Cu")
		(net "M_J_CPU0_SB_DQS_DN<9>")
	)
	(gr_poly
		(pts
			(xy 390.664954 -270.237966) (xy 390.564878 -270.13789) (xy 390.464802 -270.237966) (xy 390.464802 -270.282416)
			(xy 390.664954 -270.282416)
		)
		(stroke
			(width 0)
			(type solid)
		)
		(fill yes)
		(layer "In4.Cu")
		(net "M_J_CPU0_SB_CB<5>")
	)
	(gr_poly
		(pts
			(xy 390.664954 -269.834106) (xy 390.664954 -269.789656) (xy 390.464802 -269.789656) (xy 390.464802 -269.834106)
			(xy 390.564878 -269.934182)
		)
		(stroke
			(width 0)
			(type solid)
		)
		(fill yes)
		(layer "In4.Cu")
		(net "M_J_CPU0_SB_CB<6>")
	)
	(gr_poly
		(pts
			(xy 390.664954 -266.997942) (xy 390.564878 -266.897866) (xy 390.464802 -266.997942) (xy 390.464802 -267.042392)
			(xy 390.664954 -267.042392)
		)
		(stroke
			(width 0)
			(type solid)
		)
		(fill yes)
		(layer "In4.Cu")
		(net "M_J_CPU0_SA_RSP<0>")
	)
	(gr_poly
		(pts
			(xy 390.664954 -266.594082) (xy 390.664954 -266.549632) (xy 390.464802 -266.549632) (xy 390.464802 -266.594082)
			(xy 390.564878 -266.694158)
		)
		(stroke
			(width 0)
			(type solid)
		)
		(fill yes)
		(layer "In4.Cu")
		(net "M_J_CPU0_SB_CS_N<1>")
	)
	(gr_poly
		(pts
			(xy 390.664954 -265.37793) (xy 390.564878 -265.277854) (xy 390.464802 -265.37793) (xy 390.464802 -265.42238)
			(xy 390.664954 -265.42238)
		)
		(stroke
			(width 0)
			(type solid)
		)
		(fill yes)
		(layer "In4.Cu")
		(net "M_J_CPU0_SB_PAR")
	)
	(gr_poly
		(pts
			(xy 390.664954 -263.757918) (xy 390.564878 -263.657842) (xy 390.464802 -263.757918) (xy 390.464802 -263.802368)
			(xy 390.664954 -263.802368)
		)
		(stroke
			(width 0)
			(type solid)
		)
		(fill yes)
		(layer "In4.Cu")
		(net "M_J_CPU0_SB_CA<4>")
	)
	(gr_poly
		(pts
			(xy 390.664954 -263.354058) (xy 390.664954 -263.309608) (xy 390.464802 -263.309608) (xy 390.464802 -263.354058)
			(xy 390.564878 -263.454134)
		)
		(stroke
			(width 0)
			(type solid)
		)
		(fill yes)
		(layer "In4.Cu")
		(net "M_J_CPU0_SB_CA<3>")
	)
	(gr_poly
		(pts
			(xy 390.664954 -262.137906) (xy 390.564878 -262.03783) (xy 390.464802 -262.137906) (xy 390.464802 -262.182356)
			(xy 390.664954 -262.182356)
		)
		(stroke
			(width 0)
			(type solid)
		)
		(fill yes)
		(layer "In4.Cu")
		(net "M_J_CPU0_SB_CA<0>")
	)
	(gr_poly
		(pts
			(xy 390.75487 -228.744018) (xy 390.716262 -228.72192) (xy 390.57961 -228.758496) (xy 390.616186 -228.895148)
			(xy 390.654794 -228.917246)
		)
		(stroke
			(width 0)
			(type solid)
		)
		(fill yes)
		(layer "In4.Cu")
		(net "M_J_CPU0_SA_DQ<5>")
	)
	(gr_poly
		(pts
			(xy 390.75487 -227.124006) (xy 390.716262 -227.101908) (xy 390.57961 -227.138484) (xy 390.616186 -227.275136)
			(xy 390.654794 -227.297234)
		)
		(stroke
			(width 0)
			(type solid)
		)
		(fill yes)
		(layer "In4.Cu")
		(net "M_J_CPU0_SA_DQ<4>")
	)
	(gr_poly
		(pts
			(xy 390.755378 -222.263208) (xy 390.717024 -222.24111) (xy 390.580372 -222.277686) (xy 390.616948 -222.414338)
			(xy 390.655556 -222.436436)
		)
		(stroke
			(width 0)
			(type solid)
		)
		(fill yes)
		(layer "In4.Cu")
		(net "M_J_CPU0_SA_DQ<1>")
	)
	(gr_poly
		(pts
			(xy 390.811258 -236.991906) (xy 390.811258 -236.944154) (xy 390.611106 -236.944154) (xy 390.611106 -236.991906)
			(xy 390.711182 -237.091982)
		)
		(stroke
			(width 0)
			(type solid)
		)
		(fill yes)
		(layer "In4.Cu")
		(net "M_J_CPU0_SA_DQS_DN<2>")
	)
	(gr_poly
		(pts
			(xy 390.83488 -256.432558) (xy 390.83488 -256.384806) (xy 390.634728 -256.384806) (xy 390.634728 -256.432558)
			(xy 390.734804 -256.53238)
		)
		(stroke
			(width 0)
			(type solid)
		)
		(fill yes)
		(layer "In4.Cu")
		(net "M_J_CPU0_CLK_DN<0>")
	)
	(gr_poly
		(pts
			(xy 390.83488 -255.216152) (xy 390.734804 -255.116076) (xy 390.634728 -255.216152) (xy 390.634728 -255.260602)
			(xy 390.83488 -255.260602)
		)
		(stroke
			(width 0)
			(type solid)
		)
		(fill yes)
		(layer "In4.Cu")
		(net "M_J_CPU0_SA_CA<6>")
	)
	(gr_poly
		(pts
			(xy 390.83488 -254.812292) (xy 390.83488 -254.767842) (xy 390.634728 -254.767842) (xy 390.634728 -254.812292)
			(xy 390.734804 -254.912368)
		)
		(stroke
			(width 0)
			(type solid)
		)
		(fill yes)
		(layer "In4.Cu")
		(net "M_J_CPU0_SA_CA<5>")
	)
	(gr_poly
		(pts
			(xy 390.83488 -253.59614) (xy 390.734804 -253.496064) (xy 390.634728 -253.59614) (xy 390.634728 -253.64059)
			(xy 390.83488 -253.64059)
		)
		(stroke
			(width 0)
			(type solid)
		)
		(fill yes)
		(layer "In4.Cu")
		(net "M_J_CPU0_SA_CA<2>")
	)
	(gr_poly
		(pts
			(xy 390.83488 -253.19228) (xy 390.83488 -253.14783) (xy 390.634728 -253.14783) (xy 390.634728 -253.19228)
			(xy 390.734804 -253.292356)
		)
		(stroke
			(width 0)
			(type solid)
		)
		(fill yes)
		(layer "In4.Cu")
		(net "M_J_CPU0_SA_CA<1>")
	)
	(gr_poly
		(pts
			(xy 390.83488 -251.976128) (xy 390.734804 -251.876052) (xy 390.634728 -251.976128) (xy 390.634728 -252.020578)
			(xy 390.83488 -252.020578)
		)
		(stroke
			(width 0)
			(type solid)
		)
		(fill yes)
		(layer "In4.Cu")
		(net "M_J_CPU0_SA_CS_N<1>")
	)
	(gr_poly
		(pts
			(xy 390.83488 -250.356116) (xy 390.734804 -250.25604) (xy 390.634728 -250.356116) (xy 390.634728 -250.400566)
			(xy 390.83488 -250.400566)
		)
		(stroke
			(width 0)
			(type solid)
		)
		(fill yes)
		(layer "In4.Cu")
		(net "M_J_CPU0_ALERT_R_N")
	)
	(gr_poly
		(pts
			(xy 390.83488 -248.736104) (xy 390.734804 -248.636028) (xy 390.634728 -248.736104) (xy 390.634728 -248.780554)
			(xy 390.83488 -248.780554)
		)
		(stroke
			(width 0)
			(type solid)
		)
		(fill yes)
		(layer "In4.Cu")
		(net "M_J_CPU0_SA_CB<5>")
	)
	(gr_poly
		(pts
			(xy 390.83488 -248.332244) (xy 390.83488 -248.287794) (xy 390.634728 -248.287794) (xy 390.634728 -248.332244)
			(xy 390.734804 -248.43232)
		)
		(stroke
			(width 0)
			(type solid)
		)
		(fill yes)
		(layer "In4.Cu")
		(net "M_J_CPU0_SA_CB<6>")
	)
	(gr_poly
		(pts
			(xy 390.83488 -247.115838) (xy 390.734804 -247.016016) (xy 390.634728 -247.115838) (xy 390.634728 -247.16359)
			(xy 390.83488 -247.16359)
		)
		(stroke
			(width 0)
			(type solid)
		)
		(fill yes)
		(layer "In4.Cu")
		(net "M_J_CPU0_SA_DQS_DN<9>")
	)
	(gr_poly
		(pts
			(xy 390.83488 -246.712486) (xy 390.83488 -246.664734) (xy 390.634728 -246.664734) (xy 390.634728 -246.712486)
			(xy 390.734804 -246.812308)
		)
		(stroke
			(width 0)
			(type solid)
		)
		(fill yes)
		(layer "In4.Cu")
		(net "M_J_CPU0_SA_DQS_DN<4>")
	)
	(gr_poly
		(pts
			(xy 390.83488 -245.49608) (xy 390.734804 -245.396004) (xy 390.634728 -245.49608) (xy 390.634728 -245.54053)
			(xy 390.83488 -245.54053)
		)
		(stroke
			(width 0)
			(type solid)
		)
		(fill yes)
		(layer "In4.Cu")
		(net "M_J_CPU0_SA_CB<1>")
	)
	(gr_poly
		(pts
			(xy 390.83488 -245.09222) (xy 390.83488 -245.04777) (xy 390.634728 -245.04777) (xy 390.634728 -245.09222)
			(xy 390.734804 -245.192296)
		)
		(stroke
			(width 0)
			(type solid)
		)
		(fill yes)
		(layer "In4.Cu")
		(net "M_J_CPU0_SA_CB<2>")
	)
	(gr_poly
		(pts
			(xy 390.83488 -243.876068) (xy 390.734804 -243.775992) (xy 390.634728 -243.876068) (xy 390.634728 -243.920518)
			(xy 390.83488 -243.920518)
		)
		(stroke
			(width 0)
			(type solid)
		)
		(fill yes)
		(layer "In4.Cu")
		(net "M_J_CPU0_SA_DQ<29>")
	)
	(gr_poly
		(pts
			(xy 390.83488 -243.472208) (xy 390.83488 -243.427758) (xy 390.634728 -243.427758) (xy 390.634728 -243.472208)
			(xy 390.734804 -243.572284)
		)
		(stroke
			(width 0)
			(type solid)
		)
		(fill yes)
		(layer "In4.Cu")
		(net "M_J_CPU0_SA_DQ<30>")
	)
	(gr_poly
		(pts
			(xy 390.83488 -242.255802) (xy 390.734804 -242.15598) (xy 390.634728 -242.255802) (xy 390.634728 -242.303554)
			(xy 390.83488 -242.303554)
		)
		(stroke
			(width 0)
			(type solid)
		)
		(fill yes)
		(layer "In4.Cu")
		(net "M_J_CPU0_SA_DQS_DN<8>")
	)
	(gr_poly
		(pts
			(xy 390.83488 -241.85245) (xy 390.83488 -241.804698) (xy 390.634728 -241.804698) (xy 390.634728 -241.85245)
			(xy 390.734804 -241.952272)
		)
		(stroke
			(width 0)
			(type solid)
		)
		(fill yes)
		(layer "In4.Cu")
		(net "M_J_CPU0_SA_DQS_DN<3>")
	)
	(gr_poly
		(pts
			(xy 390.83488 -240.636044) (xy 390.734804 -240.535968) (xy 390.634728 -240.636044) (xy 390.634728 -240.680494)
			(xy 390.83488 -240.680494)
		)
		(stroke
			(width 0)
			(type solid)
		)
		(fill yes)
		(layer "In4.Cu")
		(net "M_J_CPU0_SA_DQ<25>")
	)
	(gr_poly
		(pts
			(xy 390.83488 -240.232184) (xy 390.83488 -240.187734) (xy 390.634728 -240.187734) (xy 390.634728 -240.232184)
			(xy 390.734804 -240.33226)
		)
		(stroke
			(width 0)
			(type solid)
		)
		(fill yes)
		(layer "In4.Cu")
		(net "M_J_CPU0_SA_DQ<26>")
	)
	(gr_poly
		(pts
			(xy 390.83488 -239.016032) (xy 390.734804 -238.915956) (xy 390.634728 -239.016032) (xy 390.634728 -239.060482)
			(xy 390.83488 -239.060482)
		)
		(stroke
			(width 0)
			(type solid)
		)
		(fill yes)
		(layer "In4.Cu")
		(net "M_J_CPU0_SA_DQ<21>")
	)
	(gr_poly
		(pts
			(xy 390.83488 -238.612172) (xy 390.83488 -238.567722) (xy 390.634728 -238.567722) (xy 390.634728 -238.612172)
			(xy 390.734804 -238.712248)
		)
		(stroke
			(width 0)
			(type solid)
		)
		(fill yes)
		(layer "In4.Cu")
		(net "M_J_CPU0_SA_DQ<22>")
	)
	(gr_poly
		(pts
			(xy 390.83488 -237.395766) (xy 390.734804 -237.295944) (xy 390.634728 -237.395766) (xy 390.634728 -237.443518)
			(xy 390.83488 -237.443518)
		)
		(stroke
			(width 0)
			(type solid)
		)
		(fill yes)
		(layer "In4.Cu")
		(net "M_J_CPU0_SA_DQS_DN<7>")
	)
	(gr_poly
		(pts
			(xy 390.83488 -235.776008) (xy 390.734804 -235.675932) (xy 390.634728 -235.776008) (xy 390.634728 -235.820458)
			(xy 390.83488 -235.820458)
		)
		(stroke
			(width 0)
			(type solid)
		)
		(fill yes)
		(layer "In4.Cu")
		(net "M_J_CPU0_SA_DQ<17>")
	)
	(gr_poly
		(pts
			(xy 390.83488 -235.372148) (xy 390.83488 -235.327698) (xy 390.634728 -235.327698) (xy 390.634728 -235.372148)
			(xy 390.734804 -235.472224)
		)
		(stroke
			(width 0)
			(type solid)
		)
		(fill yes)
		(layer "In4.Cu")
		(net "M_J_CPU0_SA_DQ<18>")
	)
	(gr_poly
		(pts
			(xy 390.83488 -234.155996) (xy 390.734804 -234.05592) (xy 390.634728 -234.155996) (xy 390.634728 -234.200446)
			(xy 390.83488 -234.200446)
		)
		(stroke
			(width 0)
			(type solid)
		)
		(fill yes)
		(layer "In4.Cu")
		(net "M_J_CPU0_SA_DQ<13>")
	)
	(gr_poly
		(pts
			(xy 390.83488 -233.752136) (xy 390.83488 -233.707686) (xy 390.634728 -233.707686) (xy 390.634728 -233.752136)
			(xy 390.734804 -233.852212)
		)
		(stroke
			(width 0)
			(type solid)
		)
		(fill yes)
		(layer "In4.Cu")
		(net "M_J_CPU0_SA_DQ<14>")
	)
	(gr_poly
		(pts
			(xy 390.83488 -232.53573) (xy 390.734804 -232.435908) (xy 390.634728 -232.53573) (xy 390.634728 -232.583482)
			(xy 390.83488 -232.583482)
		)
		(stroke
			(width 0)
			(type solid)
		)
		(fill yes)
		(layer "In4.Cu")
		(net "M_J_CPU0_SA_DQS_DN<6>")
	)
	(gr_poly
		(pts
			(xy 390.83488 -232.132378) (xy 390.83488 -232.084626) (xy 390.634728 -232.084626) (xy 390.634728 -232.132378)
			(xy 390.734804 -232.2322)
		)
		(stroke
			(width 0)
			(type solid)
		)
		(fill yes)
		(layer "In4.Cu")
		(net "M_J_CPU0_SA_DQS_DN<1>")
	)
	(gr_poly
		(pts
			(xy 390.83488 -230.915972) (xy 390.734804 -230.815896) (xy 390.634728 -230.915972) (xy 390.634728 -230.960422)
			(xy 390.83488 -230.960422)
		)
		(stroke
			(width 0)
			(type solid)
		)
		(fill yes)
		(layer "In4.Cu")
		(net "M_J_CPU0_SA_DQ<9>")
	)
	(gr_poly
		(pts
			(xy 390.83488 -230.512366) (xy 390.83488 -230.467916) (xy 390.634728 -230.467916) (xy 390.634728 -230.512366)
			(xy 390.734804 -230.612188)
		)
		(stroke
			(width 0)
			(type solid)
		)
		(fill yes)
		(layer "In4.Cu")
		(net "M_J_CPU0_SA_DQ<10>")
	)
	(gr_poly
		(pts
			(xy 390.88949 -222.951548) (xy 390.852914 -222.814896) (xy 390.81456 -222.792798) (xy 390.714484 -222.966026)
			(xy 390.752838 -222.988124)
		)
		(stroke
			(width 0)
			(type solid)
		)
		(fill yes)
		(layer "In4.Cu")
		(net "M_J_CPU0_SA_DQ<3>")
	)
	(gr_poly
		(pts
			(xy 390.889998 -229.430072) (xy 390.853422 -229.29342) (xy 390.814814 -229.271322) (xy 390.714738 -229.44455)
			(xy 390.753346 -229.466648)
		)
		(stroke
			(width 0)
			(type solid)
		)
		(fill yes)
		(layer "In4.Cu")
		(net "M_J_CPU0_SA_DQ<7>")
	)
	(gr_poly
		(pts
			(xy 390.889998 -227.81006) (xy 390.853422 -227.673408) (xy 390.814814 -227.65131) (xy 390.714738 -227.824538)
			(xy 390.753346 -227.846636)
		)
		(stroke
			(width 0)
			(type solid)
		)
		(fill yes)
		(layer "In4.Cu")
		(net "M_J_CPU0_SA_DQ<6>")
	)
	(gr_poly
		(pts
			(xy 391.134854 -293.324026) (xy 391.134854 -293.279576) (xy 390.934702 -293.279576) (xy 390.934702 -293.324026)
			(xy 391.034778 -293.424102)
		)
		(stroke
			(width 0)
			(type solid)
		)
		(fill yes)
		(layer "In4.Cu")
		(net "M_J_CPU0_SB_DQ<31>")
	)
	(gr_poly
		(pts
			(xy 391.134854 -292.107874) (xy 391.034778 -292.007798) (xy 390.934702 -292.107874) (xy 390.934702 -292.152324)
			(xy 391.134854 -292.152324)
		)
		(stroke
			(width 0)
			(type solid)
		)
		(fill yes)
		(layer "In4.Cu")
		(net "M_J_CPU0_SB_DQ<28>")
	)
	(gr_poly
		(pts
			(xy 391.134854 -291.704268) (xy 391.134854 -291.656516) (xy 390.934702 -291.656516) (xy 390.934702 -291.704268)
			(xy 391.034778 -291.80409)
		)
		(stroke
			(width 0)
			(type solid)
		)
		(fill yes)
		(layer "In4.Cu")
		(net "M_J_CPU0_SB_DQS_DP<8>")
	)
	(gr_poly
		(pts
			(xy 391.134854 -290.487608) (xy 391.034778 -290.387786) (xy 390.934702 -290.487608) (xy 390.934702 -290.53536)
			(xy 391.134854 -290.53536)
		)
		(stroke
			(width 0)
			(type solid)
		)
		(fill yes)
		(layer "In4.Cu")
		(net "M_J_CPU0_SB_DQS_DP<3>")
	)
	(gr_poly
		(pts
			(xy 391.134854 -290.084002) (xy 391.134854 -290.039552) (xy 390.934702 -290.039552) (xy 390.934702 -290.084002)
			(xy 391.034778 -290.184078)
		)
		(stroke
			(width 0)
			(type solid)
		)
		(fill yes)
		(layer "In4.Cu")
		(net "M_J_CPU0_SB_DQ<27>")
	)
	(gr_poly
		(pts
			(xy 391.134854 -288.86785) (xy 391.034778 -288.767774) (xy 390.934702 -288.86785) (xy 390.934702 -288.9123)
			(xy 391.134854 -288.9123)
		)
		(stroke
			(width 0)
			(type solid)
		)
		(fill yes)
		(layer "In4.Cu")
		(net "M_J_CPU0_SB_DQ<24>")
	)
	(gr_poly
		(pts
			(xy 391.134854 -288.464244) (xy 391.134854 -288.419794) (xy 390.934702 -288.419794) (xy 390.934702 -288.464244)
			(xy 391.034778 -288.56432)
		)
		(stroke
			(width 0)
			(type solid)
		)
		(fill yes)
		(layer "In4.Cu")
		(net "M_J_CPU0_SB_DQ<23>")
	)
	(gr_poly
		(pts
			(xy 391.134854 -287.247838) (xy 391.034778 -287.148016) (xy 390.934702 -287.247838) (xy 390.934702 -287.292288)
			(xy 391.134854 -287.292288)
		)
		(stroke
			(width 0)
			(type solid)
		)
		(fill yes)
		(layer "In4.Cu")
		(net "M_J_CPU0_SB_DQ<20>")
	)
	(gr_poly
		(pts
			(xy 391.134854 -286.844232) (xy 391.134854 -286.79648) (xy 390.934702 -286.79648) (xy 390.934702 -286.844232)
			(xy 391.034778 -286.944308)
		)
		(stroke
			(width 0)
			(type solid)
		)
		(fill yes)
		(layer "In4.Cu")
		(net "M_J_CPU0_SB_DQS_DP<7>")
	)
	(gr_poly
		(pts
			(xy 391.134854 -285.627826) (xy 391.034778 -285.528004) (xy 390.934702 -285.627826) (xy 390.934702 -285.675578)
			(xy 391.134854 -285.675578)
		)
		(stroke
			(width 0)
			(type solid)
		)
		(fill yes)
		(layer "In4.Cu")
		(net "M_J_CPU0_SB_DQS_DP<2>")
	)
	(gr_poly
		(pts
			(xy 391.134854 -285.22422) (xy 391.134854 -285.17977) (xy 390.934702 -285.17977) (xy 390.934702 -285.22422)
			(xy 391.034778 -285.324296)
		)
		(stroke
			(width 0)
			(type solid)
		)
		(fill yes)
		(layer "In4.Cu")
		(net "M_J_CPU0_SB_DQ<19>")
	)
	(gr_poly
		(pts
			(xy 391.134854 -284.008068) (xy 391.034778 -283.907992) (xy 390.934702 -284.008068) (xy 390.934702 -284.052518)
			(xy 391.134854 -284.052518)
		)
		(stroke
			(width 0)
			(type solid)
		)
		(fill yes)
		(layer "In4.Cu")
		(net "M_J_CPU0_SB_DQ<16>")
	)
	(gr_poly
		(pts
			(xy 391.134854 -283.604208) (xy 391.134854 -283.559758) (xy 390.934702 -283.559758) (xy 390.934702 -283.604208)
			(xy 391.034778 -283.704284)
		)
		(stroke
			(width 0)
			(type solid)
		)
		(fill yes)
		(layer "In4.Cu")
		(net "M_J_CPU0_SB_DQ<15>")
	)
	(gr_poly
		(pts
			(xy 391.134854 -282.388056) (xy 391.034778 -282.28798) (xy 390.934702 -282.388056) (xy 390.934702 -282.432506)
			(xy 391.134854 -282.432506)
		)
		(stroke
			(width 0)
			(type solid)
		)
		(fill yes)
		(layer "In4.Cu")
		(net "M_J_CPU0_SB_DQ<12>")
	)
	(gr_poly
		(pts
			(xy 391.134854 -281.98445) (xy 391.134854 -281.936698) (xy 390.934702 -281.936698) (xy 390.934702 -281.98445)
			(xy 391.034778 -282.084272)
		)
		(stroke
			(width 0)
			(type solid)
		)
		(fill yes)
		(layer "In4.Cu")
		(net "M_J_CPU0_SB_DQS_DP<6>")
	)
	(gr_poly
		(pts
			(xy 391.134854 -280.76779) (xy 391.034778 -280.667968) (xy 390.934702 -280.76779) (xy 390.934702 -280.815542)
			(xy 391.134854 -280.815542)
		)
		(stroke
			(width 0)
			(type solid)
		)
		(fill yes)
		(layer "In4.Cu")
		(net "M_J_CPU0_SB_DQS_DP<1>")
	)
	(gr_poly
		(pts
			(xy 391.134854 -280.364184) (xy 391.134854 -280.319734) (xy 390.934702 -280.319734) (xy 390.934702 -280.364184)
			(xy 391.034778 -280.46426)
		)
		(stroke
			(width 0)
			(type solid)
		)
		(fill yes)
		(layer "In4.Cu")
		(net "M_J_CPU0_SB_DQ<11>")
	)
	(gr_poly
		(pts
			(xy 391.134854 -279.148032) (xy 391.034778 -279.047956) (xy 390.934702 -279.148032) (xy 390.934702 -279.192482)
			(xy 391.134854 -279.192482)
		)
		(stroke
			(width 0)
			(type solid)
		)
		(fill yes)
		(layer "In4.Cu")
		(net "M_J_CPU0_SB_DQ<8>")
	)
	(gr_poly
		(pts
			(xy 391.134854 -278.744172) (xy 391.134854 -278.699722) (xy 390.934702 -278.699722) (xy 390.934702 -278.744172)
			(xy 391.034778 -278.844248)
		)
		(stroke
			(width 0)
			(type solid)
		)
		(fill yes)
		(layer "In4.Cu")
		(net "M_J_CPU0_SB_DQ<7>")
	)
	(gr_poly
		(pts
			(xy 391.134854 -277.52802) (xy 391.034778 -277.427944) (xy 390.934702 -277.52802) (xy 390.934702 -277.57247)
			(xy 391.134854 -277.57247)
		)
		(stroke
			(width 0)
			(type solid)
		)
		(fill yes)
		(layer "In4.Cu")
		(net "M_J_CPU0_SB_DQ<4>")
	)
	(gr_poly
		(pts
			(xy 391.134854 -277.124414) (xy 391.134854 -277.076662) (xy 390.934702 -277.076662) (xy 390.934702 -277.124414)
			(xy 391.034778 -277.224236)
		)
		(stroke
			(width 0)
			(type solid)
		)
		(fill yes)
		(layer "In4.Cu")
		(net "M_J_CPU0_SB_DQS_DP<5>")
	)
	(gr_poly
		(pts
			(xy 391.134854 -275.907754) (xy 391.034778 -275.807932) (xy 390.934702 -275.907754) (xy 390.934702 -275.955506)
			(xy 391.134854 -275.955506)
		)
		(stroke
			(width 0)
			(type solid)
		)
		(fill yes)
		(layer "In4.Cu")
		(net "M_J_CPU0_SB_DQS_DP<0>")
	)
	(gr_poly
		(pts
			(xy 391.134854 -275.504148) (xy 391.134854 -275.459698) (xy 390.934702 -275.459698) (xy 390.934702 -275.504148)
			(xy 391.034778 -275.604224)
		)
		(stroke
			(width 0)
			(type solid)
		)
		(fill yes)
		(layer "In4.Cu")
		(net "M_J_CPU0_SB_DQ<3>")
	)
	(gr_poly
		(pts
			(xy 391.134854 -274.287996) (xy 391.034778 -274.18792) (xy 390.934702 -274.287996) (xy 390.934702 -274.332446)
			(xy 391.134854 -274.332446)
		)
		(stroke
			(width 0)
			(type solid)
		)
		(fill yes)
		(layer "In4.Cu")
		(net "M_J_CPU0_SB_DQ<0>")
	)
	(gr_poly
		(pts
			(xy 391.134854 -273.884136) (xy 391.134854 -273.839686) (xy 390.934702 -273.839686) (xy 390.934702 -273.884136)
			(xy 391.034778 -273.984212)
		)
		(stroke
			(width 0)
			(type solid)
		)
		(fill yes)
		(layer "In4.Cu")
		(net "M_J_CPU0_SB_CB<3>")
	)
	(gr_poly
		(pts
			(xy 391.134854 -272.667984) (xy 391.034778 -272.567908) (xy 390.934702 -272.667984) (xy 390.934702 -272.712434)
			(xy 391.134854 -272.712434)
		)
		(stroke
			(width 0)
			(type solid)
		)
		(fill yes)
		(layer "In4.Cu")
		(net "M_J_CPU0_SB_CB<0>")
	)
	(gr_poly
		(pts
			(xy 391.134854 -272.264378) (xy 391.134854 -272.216626) (xy 390.934702 -272.216626) (xy 390.934702 -272.264378)
			(xy 391.034778 -272.3642)
		)
		(stroke
			(width 0)
			(type solid)
		)
		(fill yes)
		(layer "In4.Cu")
		(net "M_J_CPU0_SB_DQS_DP<4>")
	)
	(gr_poly
		(pts
			(xy 391.134854 -271.047718) (xy 391.034778 -270.947896) (xy 390.934702 -271.047718) (xy 390.934702 -271.09547)
			(xy 391.134854 -271.09547)
		)
		(stroke
			(width 0)
			(type solid)
		)
		(fill yes)
		(layer "In4.Cu")
		(net "M_J_CPU0_SB_DQS_DP<9>")
	)
	(gr_poly
		(pts
			(xy 391.134854 -270.644112) (xy 391.134854 -270.599662) (xy 390.934702 -270.599662) (xy 390.934702 -270.644112)
			(xy 391.034778 -270.744188)
		)
		(stroke
			(width 0)
			(type solid)
		)
		(fill yes)
		(layer "In4.Cu")
		(net "M_J_CPU0_SB_CB<7>")
	)
	(gr_poly
		(pts
			(xy 391.134854 -269.42796) (xy 391.034778 -269.327884) (xy 390.934702 -269.42796) (xy 390.934702 -269.47241)
			(xy 391.134854 -269.47241)
		)
		(stroke
			(width 0)
			(type solid)
		)
		(fill yes)
		(layer "In4.Cu")
		(net "M_J_CPU0_SB_CB<4>")
	)
	(gr_poly
		(pts
			(xy 391.134854 -267.807948) (xy 391.034778 -267.707872) (xy 390.934702 -267.807948) (xy 390.934702 -267.852398)
			(xy 391.134854 -267.852398)
		)
		(stroke
			(width 0)
			(type solid)
		)
		(fill yes)
		(layer "In4.Cu")
		(net "M_J_CPU0_SB_RSP<0>")
	)
	(gr_poly
		(pts
			(xy 391.134854 -265.784076) (xy 391.134854 -265.739626) (xy 390.934702 -265.739626) (xy 390.934702 -265.784076)
			(xy 391.034778 -265.884152)
		)
		(stroke
			(width 0)
			(type solid)
		)
		(fill yes)
		(layer "In4.Cu")
		(net "M_J_CPU0_SB_CS_N<0>")
	)
	(gr_poly
		(pts
			(xy 391.134854 -264.567924) (xy 391.034778 -264.467848) (xy 390.934702 -264.567924) (xy 390.934702 -264.612374)
			(xy 391.134854 -264.612374)
		)
		(stroke
			(width 0)
			(type solid)
		)
		(fill yes)
		(layer "In4.Cu")
		(net "M_J_CPU0_SB_CA<6>")
	)
	(gr_poly
		(pts
			(xy 391.134854 -264.164064) (xy 391.134854 -264.119614) (xy 390.934702 -264.119614) (xy 390.934702 -264.164064)
			(xy 391.034778 -264.26414)
		)
		(stroke
			(width 0)
			(type solid)
		)
		(fill yes)
		(layer "In4.Cu")
		(net "M_J_CPU0_SB_CA<5>")
	)
	(gr_poly
		(pts
			(xy 391.134854 -262.947912) (xy 391.034778 -262.847836) (xy 390.934702 -262.947912) (xy 390.934702 -262.992362)
			(xy 391.134854 -262.992362)
		)
		(stroke
			(width 0)
			(type solid)
		)
		(fill yes)
		(layer "In4.Cu")
		(net "M_J_CPU0_SB_CA<2>")
	)
	(gr_poly
		(pts
			(xy 391.134854 -262.544052) (xy 391.134854 -262.499602) (xy 390.934702 -262.499602) (xy 390.934702 -262.544052)
			(xy 391.034778 -262.644128)
		)
		(stroke
			(width 0)
			(type solid)
		)
		(fill yes)
		(layer "In4.Cu")
		(net "M_J_CPU0_SB_CA<1>")
	)
	(gr_poly
		(pts
			(xy 391.224008 -229.555294) (xy 391.1854 -229.532942) (xy 391.049002 -229.569518) (xy 391.085578 -229.70617)
			(xy 391.123932 -229.728522)
		)
		(stroke
			(width 0)
			(type solid)
		)
		(fill yes)
		(layer "In4.Cu")
		(net "M_J_CPU0_SA_DQ<8>")
	)
	(gr_poly
		(pts
			(xy 391.224008 -227.935536) (xy 391.1854 -227.913184) (xy 391.049002 -227.94976) (xy 391.085578 -228.086412)
			(xy 391.123932 -228.108764)
		)
		(stroke
			(width 0)
			(type solid)
		)
		(fill yes)
		(layer "In4.Cu")
		(net "M_J_CPU0_SA_DQ<5>")
	)
	(gr_poly
		(pts
			(xy 391.224008 -226.315524) (xy 391.1854 -226.293172) (xy 391.049002 -226.329748) (xy 391.085578 -226.4664)
			(xy 391.123932 -226.488752)
		)
		(stroke
			(width 0)
			(type solid)
		)
		(fill yes)
		(layer "In4.Cu")
		(net "M_J_CPU0_SA_DQ<4>")
	)
	(gr_poly
		(pts
			(xy 391.226802 -224.696274) (xy 391.185654 -224.672652) (xy 391.049002 -224.709228) (xy 391.085578 -224.845626)
			(xy 391.12698 -224.869502)
		)
		(stroke
			(width 0)
			(type solid)
		)
		(fill yes)
		(layer "In4.Cu")
		(net "M_J_CPU0_SA_DQS_DN<5>")
	)
	(gr_poly
		(pts
			(xy 391.226802 -223.076262) (xy 391.185654 -223.05264) (xy 391.049002 -223.089216) (xy 391.085578 -223.225614)
			(xy 391.12698 -223.24949)
		)
		(stroke
			(width 0)
			(type solid)
		)
		(fill yes)
		(layer "In4.Cu")
		(net "M_J_CPU0_SA_DQS_DP<0>")
	)
	(gr_poly
		(pts
			(xy 391.280904 -236.586268) (xy 391.180828 -236.486192) (xy 391.081006 -236.586268) (xy 391.081006 -236.633766)
			(xy 391.280904 -236.633766)
		)
		(stroke
			(width 0)
			(type solid)
		)
		(fill yes)
		(layer "In4.Cu")
		(net "M_J_CPU0_SA_DQS_DP<2>")
	)
	(gr_poly
		(pts
			(xy 391.30478 -256.025904) (xy 391.204704 -255.926082) (xy 391.104628 -256.025904) (xy 391.104628 -256.073656)
			(xy 391.30478 -256.073656)
		)
		(stroke
			(width 0)
			(type solid)
		)
		(fill yes)
		(layer "In4.Cu")
		(net "M_J_CPU0_CLK_DP<0>")
	)
	(gr_poly
		(pts
			(xy 391.30478 -255.622298) (xy 391.30478 -255.577848) (xy 391.104628 -255.577848) (xy 391.104628 -255.622298)
			(xy 391.204704 -255.722374)
		)
		(stroke
			(width 0)
			(type solid)
		)
		(fill yes)
		(layer "In4.Cu")
		(net "M_J_CPU0_SA_PAR")
	)
	(gr_poly
		(pts
			(xy 391.30478 -254.406146) (xy 391.204704 -254.30607) (xy 391.104628 -254.406146) (xy 391.104628 -254.450596)
			(xy 391.30478 -254.450596)
		)
		(stroke
			(width 0)
			(type solid)
		)
		(fill yes)
		(layer "In4.Cu")
		(net "M_J_CPU0_SA_CA<4>")
	)
	(gr_poly
		(pts
			(xy 391.30478 -254.002286) (xy 391.30478 -253.957836) (xy 391.104628 -253.957836) (xy 391.104628 -254.002286)
			(xy 391.204704 -254.102362)
		)
		(stroke
			(width 0)
			(type solid)
		)
		(fill yes)
		(layer "In4.Cu")
		(net "M_J_CPU0_SA_CA<3>")
	)
	(gr_poly
		(pts
			(xy 391.30478 -252.786134) (xy 391.204704 -252.686058) (xy 391.104628 -252.786134) (xy 391.104628 -252.830584)
			(xy 391.30478 -252.830584)
		)
		(stroke
			(width 0)
			(type solid)
		)
		(fill yes)
		(layer "In4.Cu")
		(net "M_J_CPU0_SA_CA<0>")
	)
	(gr_poly
		(pts
			(xy 391.30478 -251.166122) (xy 391.204704 -251.066046) (xy 391.104628 -251.166122) (xy 391.104628 -251.210572)
			(xy 391.30478 -251.210572)
		)
		(stroke
			(width 0)
			(type solid)
		)
		(fill yes)
		(layer "In4.Cu")
		(net "M_J_CPU0_SA_CS_N<0>")
	)
	(gr_poly
		(pts
			(xy 391.30478 -250.762262) (xy 391.30478 -250.717812) (xy 391.104628 -250.717812) (xy 391.104628 -250.762262)
			(xy 391.204704 -250.862338)
		)
		(stroke
			(width 0)
			(type solid)
		)
		(fill yes)
		(layer "In4.Cu")
		(net "M_J_CPU0_RESET_N")
	)
	(gr_poly
		(pts
			(xy 391.30478 -249.14225) (xy 391.30478 -249.0978) (xy 391.104628 -249.0978) (xy 391.104628 -249.14225)
			(xy 391.204704 -249.242326)
		)
		(stroke
			(width 0)
			(type solid)
		)
		(fill yes)
		(layer "In4.Cu")
		(net "M_J_CPU0_SA_CB<7>")
	)
	(gr_poly
		(pts
			(xy 391.30478 -247.926098) (xy 391.204704 -247.826022) (xy 391.104628 -247.926098) (xy 391.104628 -247.970548)
			(xy 391.30478 -247.970548)
		)
		(stroke
			(width 0)
			(type solid)
		)
		(fill yes)
		(layer "In4.Cu")
		(net "M_J_CPU0_SA_CB<4>")
	)
	(gr_poly
		(pts
			(xy 391.30478 -247.522492) (xy 391.30478 -247.47474) (xy 391.104628 -247.47474) (xy 391.104628 -247.522492)
			(xy 391.204704 -247.622314)
		)
		(stroke
			(width 0)
			(type solid)
		)
		(fill yes)
		(layer "In4.Cu")
		(net "M_J_CPU0_SA_DQS_DP<9>")
	)
	(gr_poly
		(pts
			(xy 391.30478 -246.305832) (xy 391.204704 -246.20601) (xy 391.104628 -246.305832) (xy 391.104628 -246.353584)
			(xy 391.30478 -246.353584)
		)
		(stroke
			(width 0)
			(type solid)
		)
		(fill yes)
		(layer "In4.Cu")
		(net "M_J_CPU0_SA_DQS_DP<4>")
	)
	(gr_poly
		(pts
			(xy 391.30478 -245.902226) (xy 391.30478 -245.857776) (xy 391.104628 -245.857776) (xy 391.104628 -245.902226)
			(xy 391.204704 -246.002302)
		)
		(stroke
			(width 0)
			(type solid)
		)
		(fill yes)
		(layer "In4.Cu")
		(net "M_J_CPU0_SA_CB<3>")
	)
	(gr_poly
		(pts
			(xy 391.30478 -244.686074) (xy 391.204704 -244.585998) (xy 391.104628 -244.686074) (xy 391.104628 -244.730524)
			(xy 391.30478 -244.730524)
		)
		(stroke
			(width 0)
			(type solid)
		)
		(fill yes)
		(layer "In4.Cu")
		(net "M_J_CPU0_SA_CB<0>")
	)
	(gr_poly
		(pts
			(xy 391.30478 -244.282214) (xy 391.30478 -244.237764) (xy 391.104628 -244.237764) (xy 391.104628 -244.282214)
			(xy 391.204704 -244.38229)
		)
		(stroke
			(width 0)
			(type solid)
		)
		(fill yes)
		(layer "In4.Cu")
		(net "M_J_CPU0_SA_DQ<31>")
	)
	(gr_poly
		(pts
			(xy 391.30478 -243.066062) (xy 391.204704 -242.965986) (xy 391.104628 -243.066062) (xy 391.104628 -243.110512)
			(xy 391.30478 -243.110512)
		)
		(stroke
			(width 0)
			(type solid)
		)
		(fill yes)
		(layer "In4.Cu")
		(net "M_J_CPU0_SA_DQ<28>")
	)
	(gr_poly
		(pts
			(xy 391.30478 -242.662456) (xy 391.30478 -242.614704) (xy 391.104628 -242.614704) (xy 391.104628 -242.662456)
			(xy 391.204704 -242.762278)
		)
		(stroke
			(width 0)
			(type solid)
		)
		(fill yes)
		(layer "In4.Cu")
		(net "M_J_CPU0_SA_DQS_DP<8>")
	)
	(gr_poly
		(pts
			(xy 391.30478 -241.445796) (xy 391.204704 -241.345974) (xy 391.104628 -241.445796) (xy 391.104628 -241.493548)
			(xy 391.30478 -241.493548)
		)
		(stroke
			(width 0)
			(type solid)
		)
		(fill yes)
		(layer "In4.Cu")
		(net "M_J_CPU0_SA_DQS_DP<3>")
	)
	(gr_poly
		(pts
			(xy 391.30478 -241.04219) (xy 391.30478 -240.99774) (xy 391.104628 -240.99774) (xy 391.104628 -241.04219)
			(xy 391.204704 -241.142266)
		)
		(stroke
			(width 0)
			(type solid)
		)
		(fill yes)
		(layer "In4.Cu")
		(net "M_J_CPU0_SA_DQ<27>")
	)
	(gr_poly
		(pts
			(xy 391.30478 -239.826038) (xy 391.204704 -239.725962) (xy 391.104628 -239.826038) (xy 391.104628 -239.870488)
			(xy 391.30478 -239.870488)
		)
		(stroke
			(width 0)
			(type solid)
		)
		(fill yes)
		(layer "In4.Cu")
		(net "M_J_CPU0_SA_DQ<24>")
	)
	(gr_poly
		(pts
			(xy 391.30478 -239.422178) (xy 391.30478 -239.377728) (xy 391.104628 -239.377728) (xy 391.104628 -239.422178)
			(xy 391.204704 -239.522254)
		)
		(stroke
			(width 0)
			(type solid)
		)
		(fill yes)
		(layer "In4.Cu")
		(net "M_J_CPU0_SA_DQ<23>")
	)
	(gr_poly
		(pts
			(xy 391.30478 -238.206026) (xy 391.204704 -238.10595) (xy 391.104628 -238.206026) (xy 391.104628 -238.250476)
			(xy 391.30478 -238.250476)
		)
		(stroke
			(width 0)
			(type solid)
		)
		(fill yes)
		(layer "In4.Cu")
		(net "M_J_CPU0_SA_DQ<20>")
	)
	(gr_poly
		(pts
			(xy 391.30478 -237.80242) (xy 391.30478 -237.754668) (xy 391.104628 -237.754668) (xy 391.104628 -237.80242)
			(xy 391.204704 -237.902242)
		)
		(stroke
			(width 0)
			(type solid)
		)
		(fill yes)
		(layer "In4.Cu")
		(net "M_J_CPU0_SA_DQS_DP<7>")
	)
	(gr_poly
		(pts
			(xy 391.30478 -236.182154) (xy 391.30478 -236.137704) (xy 391.104628 -236.137704) (xy 391.104628 -236.182154)
			(xy 391.204704 -236.28223)
		)
		(stroke
			(width 0)
			(type solid)
		)
		(fill yes)
		(layer "In4.Cu")
		(net "M_J_CPU0_SA_DQ<19>")
	)
	(gr_poly
		(pts
			(xy 391.30478 -234.966002) (xy 391.204704 -234.865926) (xy 391.104628 -234.966002) (xy 391.104628 -235.010452)
			(xy 391.30478 -235.010452)
		)
		(stroke
			(width 0)
			(type solid)
		)
		(fill yes)
		(layer "In4.Cu")
		(net "M_J_CPU0_SA_DQ<16>")
	)
	(gr_poly
		(pts
			(xy 391.30478 -234.562142) (xy 391.30478 -234.517692) (xy 391.104628 -234.517692) (xy 391.104628 -234.562142)
			(xy 391.204704 -234.662218)
		)
		(stroke
			(width 0)
			(type solid)
		)
		(fill yes)
		(layer "In4.Cu")
		(net "M_J_CPU0_SA_DQ<15>")
	)
	(gr_poly
		(pts
			(xy 391.30478 -233.34599) (xy 391.204704 -233.245914) (xy 391.104628 -233.34599) (xy 391.104628 -233.39044)
			(xy 391.30478 -233.39044)
		)
		(stroke
			(width 0)
			(type solid)
		)
		(fill yes)
		(layer "In4.Cu")
		(net "M_J_CPU0_SA_DQ<12>")
	)
	(gr_poly
		(pts
			(xy 391.30478 -232.942384) (xy 391.30478 -232.894632) (xy 391.104628 -232.894632) (xy 391.104628 -232.942384)
			(xy 391.204704 -233.042206)
		)
		(stroke
			(width 0)
			(type solid)
		)
		(fill yes)
		(layer "In4.Cu")
		(net "M_J_CPU0_SA_DQS_DP<6>")
	)
	(gr_poly
		(pts
			(xy 391.30478 -231.725724) (xy 391.204704 -231.625902) (xy 391.104628 -231.725724) (xy 391.104628 -231.773476)
			(xy 391.30478 -231.773476)
		)
		(stroke
			(width 0)
			(type solid)
		)
		(fill yes)
		(layer "In4.Cu")
		(net "M_J_CPU0_SA_DQS_DP<1>")
	)
	(gr_poly
		(pts
			(xy 391.30478 -231.322372) (xy 391.30478 -231.277922) (xy 391.104628 -231.277922) (xy 391.104628 -231.322372)
			(xy 391.204704 -231.422448)
		)
		(stroke
			(width 0)
			(type solid)
		)
		(fill yes)
		(layer "In4.Cu")
		(net "M_J_CPU0_SA_DQ<11>")
	)
	(gr_poly
		(pts
			(xy 391.360152 -230.239824) (xy 391.323576 -230.103172) (xy 391.284968 -230.081074) (xy 391.184892 -230.254302)
			(xy 391.2235 -230.2764)
		)
		(stroke
			(width 0)
			(type solid)
		)
		(fill yes)
		(layer "In4.Cu")
		(net "M_J_CPU0_SA_DQ<10>")
	)
	(gr_poly
		(pts
			(xy 391.36066 -225.37928) (xy 391.324084 -225.242882) (xy 391.282682 -225.219006) (xy 391.18286 -225.392234)
			(xy 391.224008 -225.415856)
		)
		(stroke
			(width 0)
			(type solid)
		)
		(fill yes)
		(layer "In4.Cu")
		(net "M_J_CPU0_SA_DQS_DP<5>")
	)
	(gr_poly
		(pts
			(xy 391.36066 -223.759268) (xy 391.324084 -223.62287) (xy 391.282682 -223.598994) (xy 391.18286 -223.772222)
			(xy 391.224008 -223.795844)
		)
		(stroke
			(width 0)
			(type solid)
		)
		(fill yes)
		(layer "In4.Cu")
		(net "M_J_CPU0_SA_DQS_DN<0>")
	)
	(gr_poly
		(pts
			(xy 391.360914 -228.618796) (xy 391.324084 -228.482144) (xy 391.28573 -228.459792) (xy 391.185654 -228.63302)
			(xy 391.224262 -228.655372)
		)
		(stroke
			(width 0)
			(type solid)
		)
		(fill yes)
		(layer "In4.Cu")
		(net "M_J_CPU0_SA_DQ<7>")
	)
	(gr_poly
		(pts
			(xy 391.360914 -226.998784) (xy 391.324084 -226.862132) (xy 391.28573 -226.83978) (xy 391.185654 -227.013008)
			(xy 391.224262 -227.03536)
		)
		(stroke
			(width 0)
			(type solid)
		)
		(fill yes)
		(layer "In4.Cu")
		(net "M_J_CPU0_SA_DQ<6>")
	)
	(gr_poly
		(pts
			(xy 391.362184 -222.13824) (xy 391.325354 -222.001588) (xy 391.287 -221.979236) (xy 391.186924 -222.152464)
			(xy 391.225532 -222.174816)
		)
		(stroke
			(width 0)
			(type solid)
		)
		(fill yes)
		(layer "In4.Cu")
		(net "M_J_CPU0_SA_DQ<3>")
	)
	(gr_poly
		(pts
			(xy 391.604754 -292.91788) (xy 391.504678 -292.817804) (xy 391.404602 -292.91788) (xy 391.404602 -292.96233)
			(xy 391.604754 -292.96233)
		)
		(stroke
			(width 0)
			(type solid)
		)
		(fill yes)
		(layer "In4.Cu")
		(net "M_J_CPU0_SB_DQ<29>")
	)
	(gr_poly
		(pts
			(xy 391.604754 -292.51402) (xy 391.604754 -292.46957) (xy 391.404602 -292.46957) (xy 391.404602 -292.51402)
			(xy 391.504678 -292.614096)
		)
		(stroke
			(width 0)
			(type solid)
		)
		(fill yes)
		(layer "In4.Cu")
		(net "M_J_CPU0_SB_DQ<30>")
	)
	(gr_poly
		(pts
			(xy 391.604754 -291.297614) (xy 391.504678 -291.197792) (xy 391.404602 -291.297614) (xy 391.404602 -291.345366)
			(xy 391.604754 -291.345366)
		)
		(stroke
			(width 0)
			(type solid)
		)
		(fill yes)
		(layer "In4.Cu")
		(net "M_J_CPU0_SB_DQS_DN<8>")
	)
	(gr_poly
		(pts
			(xy 391.604754 -290.894262) (xy 391.604754 -290.84651) (xy 391.404602 -290.84651) (xy 391.404602 -290.894262)
			(xy 391.504678 -290.994084)
		)
		(stroke
			(width 0)
			(type solid)
		)
		(fill yes)
		(layer "In4.Cu")
		(net "M_J_CPU0_SB_DQS_DN<3>")
	)
	(gr_poly
		(pts
			(xy 391.604754 -289.677856) (xy 391.504678 -289.57778) (xy 391.404602 -289.677856) (xy 391.404602 -289.722306)
			(xy 391.604754 -289.722306)
		)
		(stroke
			(width 0)
			(type solid)
		)
		(fill yes)
		(layer "In4.Cu")
		(net "M_J_CPU0_SB_DQ<25>")
	)
	(gr_poly
		(pts
			(xy 391.604754 -289.273996) (xy 391.604754 -289.229546) (xy 391.404602 -289.229546) (xy 391.404602 -289.273996)
			(xy 391.504678 -289.374072)
		)
		(stroke
			(width 0)
			(type solid)
		)
		(fill yes)
		(layer "In4.Cu")
		(net "M_J_CPU0_SB_DQ<26>")
	)
	(gr_poly
		(pts
			(xy 391.604754 -288.057844) (xy 391.504678 -287.957768) (xy 391.404602 -288.057844) (xy 391.404602 -288.102294)
			(xy 391.604754 -288.102294)
		)
		(stroke
			(width 0)
			(type solid)
		)
		(fill yes)
		(layer "In4.Cu")
		(net "M_J_CPU0_SB_DQ<21>")
	)
	(gr_poly
		(pts
			(xy 391.604754 -287.654238) (xy 391.604754 -287.609788) (xy 391.404602 -287.609788) (xy 391.404602 -287.654238)
			(xy 391.504678 -287.75406)
		)
		(stroke
			(width 0)
			(type solid)
		)
		(fill yes)
		(layer "In4.Cu")
		(net "M_J_CPU0_SB_DQ<22>")
	)
	(gr_poly
		(pts
			(xy 391.604754 -286.437832) (xy 391.504678 -286.337756) (xy 391.404602 -286.437832) (xy 391.404602 -286.485584)
			(xy 391.604754 -286.485584)
		)
		(stroke
			(width 0)
			(type solid)
		)
		(fill yes)
		(layer "In4.Cu")
		(net "M_J_CPU0_SB_DQS_DN<7>")
	)
	(gr_poly
		(pts
			(xy 391.604754 -286.03448) (xy 391.604754 -285.986728) (xy 391.404602 -285.986728) (xy 391.404602 -286.03448)
			(xy 391.504678 -286.134302)
		)
		(stroke
			(width 0)
			(type solid)
		)
		(fill yes)
		(layer "In4.Cu")
		(net "M_J_CPU0_SB_DQS_DN<2>")
	)
	(gr_poly
		(pts
			(xy 391.604754 -284.818074) (xy 391.504678 -284.717998) (xy 391.404602 -284.818074) (xy 391.404602 -284.862524)
			(xy 391.604754 -284.862524)
		)
		(stroke
			(width 0)
			(type solid)
		)
		(fill yes)
		(layer "In4.Cu")
		(net "M_J_CPU0_SB_DQ<17>")
	)
	(gr_poly
		(pts
			(xy 391.604754 -284.414214) (xy 391.604754 -284.369764) (xy 391.404602 -284.369764) (xy 391.404602 -284.414214)
			(xy 391.504678 -284.51429)
		)
		(stroke
			(width 0)
			(type solid)
		)
		(fill yes)
		(layer "In4.Cu")
		(net "M_J_CPU0_SB_DQ<18>")
	)
	(gr_poly
		(pts
			(xy 391.604754 -283.198062) (xy 391.504678 -283.097986) (xy 391.404602 -283.198062) (xy 391.404602 -283.242512)
			(xy 391.604754 -283.242512)
		)
		(stroke
			(width 0)
			(type solid)
		)
		(fill yes)
		(layer "In4.Cu")
		(net "M_J_CPU0_SB_DQ<13>")
	)
	(gr_poly
		(pts
			(xy 391.604754 -282.794202) (xy 391.604754 -282.749752) (xy 391.404602 -282.749752) (xy 391.404602 -282.794202)
			(xy 391.504678 -282.894278)
		)
		(stroke
			(width 0)
			(type solid)
		)
		(fill yes)
		(layer "In4.Cu")
		(net "M_J_CPU0_SB_DQ<14>")
	)
	(gr_poly
		(pts
			(xy 391.604754 -281.577796) (xy 391.504678 -281.477974) (xy 391.404602 -281.577796) (xy 391.404602 -281.625548)
			(xy 391.604754 -281.625548)
		)
		(stroke
			(width 0)
			(type solid)
		)
		(fill yes)
		(layer "In4.Cu")
		(net "M_J_CPU0_SB_DQS_DN<6>")
	)
	(gr_poly
		(pts
			(xy 391.604754 -281.174444) (xy 391.604754 -281.126692) (xy 391.404602 -281.126692) (xy 391.404602 -281.174444)
			(xy 391.504678 -281.274266)
		)
		(stroke
			(width 0)
			(type solid)
		)
		(fill yes)
		(layer "In4.Cu")
		(net "M_J_CPU0_SB_DQS_DN<1>")
	)
	(gr_poly
		(pts
			(xy 391.604754 -279.958038) (xy 391.504678 -279.857962) (xy 391.404602 -279.958038) (xy 391.404602 -280.002488)
			(xy 391.604754 -280.002488)
		)
		(stroke
			(width 0)
			(type solid)
		)
		(fill yes)
		(layer "In4.Cu")
		(net "M_J_CPU0_SB_DQ<9>")
	)
	(gr_poly
		(pts
			(xy 391.604754 -279.554178) (xy 391.604754 -279.509728) (xy 391.404602 -279.509728) (xy 391.404602 -279.554178)
			(xy 391.504678 -279.654254)
		)
		(stroke
			(width 0)
			(type solid)
		)
		(fill yes)
		(layer "In4.Cu")
		(net "M_J_CPU0_SB_DQ<10>")
	)
	(gr_poly
		(pts
			(xy 391.604754 -278.338026) (xy 391.504678 -278.23795) (xy 391.404602 -278.338026) (xy 391.404602 -278.382476)
			(xy 391.604754 -278.382476)
		)
		(stroke
			(width 0)
			(type solid)
		)
		(fill yes)
		(layer "In4.Cu")
		(net "M_J_CPU0_SB_DQ<5>")
	)
	(gr_poly
		(pts
			(xy 391.604754 -277.934166) (xy 391.604754 -277.889716) (xy 391.404602 -277.889716) (xy 391.404602 -277.934166)
			(xy 391.504678 -278.034242)
		)
		(stroke
			(width 0)
			(type solid)
		)
		(fill yes)
		(layer "In4.Cu")
		(net "M_J_CPU0_SB_DQ<6>")
	)
	(gr_poly
		(pts
			(xy 391.604754 -276.71776) (xy 391.504678 -276.617938) (xy 391.404602 -276.71776) (xy 391.404602 -276.765512)
			(xy 391.604754 -276.765512)
		)
		(stroke
			(width 0)
			(type solid)
		)
		(fill yes)
		(layer "In4.Cu")
		(net "M_J_CPU0_SB_DQS_DN<5>")
	)
	(gr_poly
		(pts
			(xy 391.604754 -276.314408) (xy 391.604754 -276.266656) (xy 391.404602 -276.266656) (xy 391.404602 -276.314408)
			(xy 391.504678 -276.41423)
		)
		(stroke
			(width 0)
			(type solid)
		)
		(fill yes)
		(layer "In4.Cu")
		(net "M_J_CPU0_SB_DQS_DN<0>")
	)
	(gr_poly
		(pts
			(xy 391.604754 -275.098002) (xy 391.504678 -274.997926) (xy 391.404602 -275.098002) (xy 391.404602 -275.142452)
			(xy 391.604754 -275.142452)
		)
		(stroke
			(width 0)
			(type solid)
		)
		(fill yes)
		(layer "In4.Cu")
		(net "M_J_CPU0_SB_DQ<1>")
	)
	(gr_poly
		(pts
			(xy 391.604754 -274.694142) (xy 391.604754 -274.649692) (xy 391.404602 -274.649692) (xy 391.404602 -274.694142)
			(xy 391.504678 -274.794218)
		)
		(stroke
			(width 0)
			(type solid)
		)
		(fill yes)
		(layer "In4.Cu")
		(net "M_J_CPU0_SB_DQ<2>")
	)
	(gr_poly
		(pts
			(xy 391.604754 -273.47799) (xy 391.504678 -273.377914) (xy 391.404602 -273.47799) (xy 391.404602 -273.52244)
			(xy 391.604754 -273.52244)
		)
		(stroke
			(width 0)
			(type solid)
		)
		(fill yes)
		(layer "In4.Cu")
		(net "M_J_CPU0_SB_CB<1>")
	)
	(gr_poly
		(pts
			(xy 391.604754 -273.07413) (xy 391.604754 -273.02968) (xy 391.404602 -273.02968) (xy 391.404602 -273.07413)
			(xy 391.504678 -273.174206)
		)
		(stroke
			(width 0)
			(type solid)
		)
		(fill yes)
		(layer "In4.Cu")
		(net "M_J_CPU0_SB_CB<2>")
	)
	(gr_poly
		(pts
			(xy 391.604754 -271.857724) (xy 391.504678 -271.757902) (xy 391.404602 -271.857724) (xy 391.404602 -271.905476)
			(xy 391.604754 -271.905476)
		)
		(stroke
			(width 0)
			(type solid)
		)
		(fill yes)
		(layer "In4.Cu")
		(net "M_J_CPU0_SB_DQS_DN<4>")
	)
	(gr_poly
		(pts
			(xy 391.604754 -271.454372) (xy 391.604754 -271.40662) (xy 391.404602 -271.40662) (xy 391.404602 -271.454372)
			(xy 391.504678 -271.554194)
		)
		(stroke
			(width 0)
			(type solid)
		)
		(fill yes)
		(layer "In4.Cu")
		(net "M_J_CPU0_SB_DQS_DN<9>")
	)
	(gr_poly
		(pts
			(xy 391.604754 -270.237966) (xy 391.504678 -270.13789) (xy 391.404602 -270.237966) (xy 391.404602 -270.282416)
			(xy 391.604754 -270.282416)
		)
		(stroke
			(width 0)
			(type solid)
		)
		(fill yes)
		(layer "In4.Cu")
		(net "M_J_CPU0_SB_CB<5>")
	)
	(gr_poly
		(pts
			(xy 391.604754 -269.834106) (xy 391.604754 -269.789656) (xy 391.404602 -269.789656) (xy 391.404602 -269.834106)
			(xy 391.504678 -269.934182)
		)
		(stroke
			(width 0)
			(type solid)
		)
		(fill yes)
		(layer "In4.Cu")
		(net "M_J_CPU0_SB_CB<6>")
	)
	(gr_poly
		(pts
			(xy 391.604754 -266.997942) (xy 391.504678 -266.897866) (xy 391.404602 -266.997942) (xy 391.404602 -267.042392)
			(xy 391.604754 -267.042392)
		)
		(stroke
			(width 0)
			(type solid)
		)
		(fill yes)
		(layer "In4.Cu")
		(net "M_J_CPU0_SA_RSP<0>")
	)
	(gr_poly
		(pts
			(xy 391.604754 -266.594082) (xy 391.604754 -266.549632) (xy 391.404602 -266.549632) (xy 391.404602 -266.594082)
			(xy 391.504678 -266.694158)
		)
		(stroke
			(width 0)
			(type solid)
		)
		(fill yes)
		(layer "In4.Cu")
		(net "M_J_CPU0_SB_CS_N<1>")
	)
	(gr_poly
		(pts
			(xy 391.604754 -265.37793) (xy 391.504678 -265.277854) (xy 391.404602 -265.37793) (xy 391.404602 -265.42238)
			(xy 391.604754 -265.42238)
		)
		(stroke
			(width 0)
			(type solid)
		)
		(fill yes)
		(layer "In4.Cu")
		(net "M_J_CPU0_SB_PAR")
	)
	(gr_poly
		(pts
			(xy 391.604754 -263.757918) (xy 391.504678 -263.657842) (xy 391.404602 -263.757918) (xy 391.404602 -263.802368)
			(xy 391.604754 -263.802368)
		)
		(stroke
			(width 0)
			(type solid)
		)
		(fill yes)
		(layer "In4.Cu")
		(net "M_J_CPU0_SB_CA<4>")
	)
	(gr_poly
		(pts
			(xy 391.604754 -263.354058) (xy 391.604754 -263.309608) (xy 391.404602 -263.309608) (xy 391.404602 -263.354058)
			(xy 391.504678 -263.454134)
		)
		(stroke
			(width 0)
			(type solid)
		)
		(fill yes)
		(layer "In4.Cu")
		(net "M_J_CPU0_SB_CA<3>")
	)
	(gr_poly
		(pts
			(xy 391.604754 -262.137906) (xy 391.504678 -262.03783) (xy 391.404602 -262.137906) (xy 391.404602 -262.182356)
			(xy 391.604754 -262.182356)
		)
		(stroke
			(width 0)
			(type solid)
		)
		(fill yes)
		(layer "In4.Cu")
		(net "M_J_CPU0_SB_CA<0>")
	)
	(gr_poly
		(pts
			(xy 391.693908 -225.505518) (xy 391.6553 -225.483166) (xy 391.518902 -225.519742) (xy 391.555478 -225.656394)
			(xy 391.593832 -225.678746)
		)
		(stroke
			(width 0)
			(type solid)
		)
		(fill yes)
		(layer "In4.Cu")
		(net "M_J_CPU0_SA_DQ<4>")
	)
	(gr_poly
		(pts
			(xy 391.694924 -230.36403) (xy 391.656316 -230.341932) (xy 391.519664 -230.378508) (xy 391.55624 -230.51516)
			(xy 391.594848 -230.537258)
		)
		(stroke
			(width 0)
			(type solid)
		)
		(fill yes)
		(layer "In4.Cu")
		(net "M_J_CPU0_SA_DQ<9>")
	)
	(gr_poly
		(pts
			(xy 391.696702 -223.886268) (xy 391.655554 -223.862392) (xy 391.518902 -223.899222) (xy 391.555478 -224.03562)
			(xy 391.59688 -224.059496)
		)
		(stroke
			(width 0)
			(type solid)
		)
		(fill yes)
		(layer "In4.Cu")
		(net "M_J_CPU0_SA_DQS_DN<5>")
	)
	(gr_poly
		(pts
			(xy 391.69721 -222.265748) (xy 391.655808 -222.241872) (xy 391.51941 -222.278448) (xy 391.555986 -222.4151)
			(xy 391.597134 -222.438976)
		)
		(stroke
			(width 0)
			(type solid)
		)
		(fill yes)
		(layer "In4.Cu")
		(net "M_J_CPU0_SA_DQS_DP<0>")
	)
	(gr_poly
		(pts
			(xy 391.741152 -235.381038) (xy 391.744962 -235.336842) (xy 391.545826 -235.31957) (xy 391.542016 -235.363766)
			(xy 391.632948 -235.47197)
		)
		(stroke
			(width 0)
			(type solid)
		)
		(fill yes)
		(layer "In4.Cu")
		(net "M_J_CPU0_SA_DQ<18>")
	)
	(gr_poly
		(pts
			(xy 391.768838 -237.395766) (xy 391.668762 -237.295944) (xy 391.568686 -237.395766) (xy 391.568686 -237.443518)
			(xy 391.768838 -237.443518)
		)
		(stroke
			(width 0)
			(type solid)
		)
		(fill yes)
		(layer "In4.Cu")
		(net "M_J_CPU0_SA_DQS_DN<7>")
	)
	(gr_poly
		(pts
			(xy 391.768838 -232.132378) (xy 391.768838 -232.084626) (xy 391.568686 -232.084626) (xy 391.568686 -232.132378)
			(xy 391.668762 -232.2322)
		)
		(stroke
			(width 0)
			(type solid)
		)
		(fill yes)
		(layer "In4.Cu")
		(net "M_J_CPU0_SA_DQS_DN<1>")
	)
	(gr_poly
		(pts
			(xy 391.774934 -256.432558) (xy 391.774934 -256.384806) (xy 391.574782 -256.384806) (xy 391.574782 -256.432558)
			(xy 391.674858 -256.53238)
		)
		(stroke
			(width 0)
			(type solid)
		)
		(fill yes)
		(layer "In4.Cu")
		(net "M_J_CPU0_CLK_DN<0>")
	)
	(gr_poly
		(pts
			(xy 391.78103 -254.812292) (xy 391.78103 -254.767842) (xy 391.580878 -254.767842) (xy 391.580878 -254.812292)
			(xy 391.680954 -254.912368)
		)
		(stroke
			(width 0)
			(type solid)
		)
		(fill yes)
		(layer "In4.Cu")
		(net "M_J_CPU0_SA_CA<5>")
	)
	(gr_poly
		(pts
			(xy 391.78103 -253.19228) (xy 391.78103 -253.14783) (xy 391.580878 -253.14783) (xy 391.580878 -253.19228)
			(xy 391.680954 -253.292356)
		)
		(stroke
			(width 0)
			(type solid)
		)
		(fill yes)
		(layer "In4.Cu")
		(net "M_J_CPU0_SA_CA<1>")
	)
	(gr_poly
		(pts
			(xy 391.78103 -248.332244) (xy 391.78103 -248.287794) (xy 391.580878 -248.287794) (xy 391.580878 -248.332244)
			(xy 391.680954 -248.43232)
		)
		(stroke
			(width 0)
			(type solid)
		)
		(fill yes)
		(layer "In4.Cu")
		(net "M_J_CPU0_SA_CB<6>")
	)
	(gr_poly
		(pts
			(xy 391.78103 -246.712486) (xy 391.78103 -246.664988) (xy 391.580878 -246.664988) (xy 391.580878 -246.712486)
			(xy 391.680954 -246.812562)
		)
		(stroke
			(width 0)
			(type solid)
		)
		(fill yes)
		(layer "In4.Cu")
		(net "M_J_CPU0_SA_DQS_DN<4>")
	)
	(gr_poly
		(pts
			(xy 391.78103 -245.09222) (xy 391.78103 -245.04777) (xy 391.580878 -245.04777) (xy 391.580878 -245.09222)
			(xy 391.680954 -245.192296)
		)
		(stroke
			(width 0)
			(type solid)
		)
		(fill yes)
		(layer "In4.Cu")
		(net "M_J_CPU0_SA_CB<2>")
	)
	(gr_poly
		(pts
			(xy 391.78103 -243.472208) (xy 391.78103 -243.427758) (xy 391.580878 -243.427758) (xy 391.580878 -243.472208)
			(xy 391.680954 -243.572284)
		)
		(stroke
			(width 0)
			(type solid)
		)
		(fill yes)
		(layer "In4.Cu")
		(net "M_J_CPU0_SA_DQ<30>")
	)
	(gr_poly
		(pts
			(xy 391.78103 -241.85245) (xy 391.78103 -241.804952) (xy 391.580878 -241.804952) (xy 391.580878 -241.85245)
			(xy 391.680954 -241.952526)
		)
		(stroke
			(width 0)
			(type solid)
		)
		(fill yes)
		(layer "In4.Cu")
		(net "M_J_CPU0_SA_DQS_DN<3>")
	)
	(gr_poly
		(pts
			(xy 391.78103 -240.232184) (xy 391.78103 -240.187734) (xy 391.580878 -240.187734) (xy 391.580878 -240.232184)
			(xy 391.680954 -240.33226)
		)
		(stroke
			(width 0)
			(type solid)
		)
		(fill yes)
		(layer "In4.Cu")
		(net "M_J_CPU0_SA_DQ<26>")
	)
	(gr_poly
		(pts
			(xy 391.78103 -238.612172) (xy 391.78103 -238.567722) (xy 391.580878 -238.567722) (xy 391.580878 -238.612172)
			(xy 391.680954 -238.712248)
		)
		(stroke
			(width 0)
			(type solid)
		)
		(fill yes)
		(layer "In4.Cu")
		(net "M_J_CPU0_SA_DQ<22>")
	)
	(gr_poly
		(pts
			(xy 391.78103 -233.752136) (xy 391.78103 -233.707686) (xy 391.580878 -233.707686) (xy 391.580878 -233.752136)
			(xy 391.680954 -233.852212)
		)
		(stroke
			(width 0)
			(type solid)
		)
		(fill yes)
		(layer "In4.Cu")
		(net "M_J_CPU0_SA_DQ<14>")
	)
	(gr_poly
		(pts
			(xy 391.78357 -255.215898) (xy 391.683494 -255.116076) (xy 391.583672 -255.215898) (xy 391.583672 -255.260348)
			(xy 391.78357 -255.260348)
		)
		(stroke
			(width 0)
			(type solid)
		)
		(fill yes)
		(layer "In4.Cu")
		(net "M_J_CPU0_SA_CA<6>")
	)
	(gr_poly
		(pts
			(xy 391.78357 -253.595886) (xy 391.683494 -253.496064) (xy 391.583672 -253.595886) (xy 391.583672 -253.640336)
			(xy 391.78357 -253.640336)
		)
		(stroke
			(width 0)
			(type solid)
		)
		(fill yes)
		(layer "In4.Cu")
		(net "M_J_CPU0_SA_CA<2>")
	)
	(gr_poly
		(pts
			(xy 391.78357 -251.975874) (xy 391.683494 -251.876052) (xy 391.583672 -251.975874) (xy 391.583672 -252.020324)
			(xy 391.78357 -252.020324)
		)
		(stroke
			(width 0)
			(type solid)
		)
		(fill yes)
		(layer "In4.Cu")
		(net "M_J_CPU0_SA_CS_N<1>")
	)
	(gr_poly
		(pts
			(xy 391.78357 -250.355862) (xy 391.683494 -250.25604) (xy 391.583672 -250.355862) (xy 391.583672 -250.400312)
			(xy 391.78357 -250.400312)
		)
		(stroke
			(width 0)
			(type solid)
		)
		(fill yes)
		(layer "In4.Cu")
		(net "M_J_CPU0_ALERT_R_N")
	)
	(gr_poly
		(pts
			(xy 391.78357 -248.73585) (xy 391.683494 -248.636028) (xy 391.583672 -248.73585) (xy 391.583672 -248.7803)
			(xy 391.78357 -248.7803)
		)
		(stroke
			(width 0)
			(type solid)
		)
		(fill yes)
		(layer "In4.Cu")
		(net "M_J_CPU0_SA_CB<5>")
	)
	(gr_poly
		(pts
			(xy 391.78357 -247.115584) (xy 391.683494 -247.015762) (xy 391.583672 -247.115584) (xy 391.583672 -247.163336)
			(xy 391.78357 -247.163336)
		)
		(stroke
			(width 0)
			(type solid)
		)
		(fill yes)
		(layer "In4.Cu")
		(net "M_J_CPU0_SA_DQS_DN<9>")
	)
	(gr_poly
		(pts
			(xy 391.78357 -245.495826) (xy 391.683494 -245.396004) (xy 391.583672 -245.495826) (xy 391.583672 -245.540276)
			(xy 391.78357 -245.540276)
		)
		(stroke
			(width 0)
			(type solid)
		)
		(fill yes)
		(layer "In4.Cu")
		(net "M_J_CPU0_SA_CB<1>")
	)
	(gr_poly
		(pts
			(xy 391.78357 -243.875814) (xy 391.683494 -243.775738) (xy 391.583672 -243.875814) (xy 391.583672 -243.920264)
			(xy 391.78357 -243.920264)
		)
		(stroke
			(width 0)
			(type solid)
		)
		(fill yes)
		(layer "In4.Cu")
		(net "M_J_CPU0_SA_DQ<29>")
	)
	(gr_poly
		(pts
			(xy 391.78357 -242.255548) (xy 391.683494 -242.155726) (xy 391.583672 -242.255548) (xy 391.583672 -242.3033)
			(xy 391.78357 -242.3033)
		)
		(stroke
			(width 0)
			(type solid)
		)
		(fill yes)
		(layer "In4.Cu")
		(net "M_J_CPU0_SA_DQS_DN<8>")
	)
	(gr_poly
		(pts
			(xy 391.78357 -240.63579) (xy 391.683494 -240.535968) (xy 391.583672 -240.63579) (xy 391.583672 -240.68024)
			(xy 391.78357 -240.68024)
		)
		(stroke
			(width 0)
			(type solid)
		)
		(fill yes)
		(layer "In4.Cu")
		(net "M_J_CPU0_SA_DQ<25>")
	)
	(gr_poly
		(pts
			(xy 391.78357 -239.015778) (xy 391.683494 -238.915702) (xy 391.583672 -239.015778) (xy 391.583672 -239.060228)
			(xy 391.78357 -239.060228)
		)
		(stroke
			(width 0)
			(type solid)
		)
		(fill yes)
		(layer "In4.Cu")
		(net "M_J_CPU0_SA_DQ<21>")
	)
	(gr_poly
		(pts
			(xy 391.78357 -235.775754) (xy 391.683494 -235.675932) (xy 391.583672 -235.775754) (xy 391.583672 -235.820204)
			(xy 391.78357 -235.820204)
		)
		(stroke
			(width 0)
			(type solid)
		)
		(fill yes)
		(layer "In4.Cu")
		(net "M_J_CPU0_SA_DQ<17>")
	)
	(gr_poly
		(pts
			(xy 391.78611 -236.972348) (xy 391.78611 -236.924596) (xy 391.586212 -236.924596) (xy 391.586212 -236.972348)
			(xy 391.686288 -237.07217)
		)
		(stroke
			(width 0)
			(type solid)
		)
		(fill yes)
		(layer "In4.Cu")
		(net "M_J_CPU0_SA_DQS_DN<2>")
	)
	(gr_poly
		(pts
			(xy 391.83056 -224.569274) (xy 391.793984 -224.432876) (xy 391.752582 -224.409) (xy 391.65276 -224.582228)
			(xy 391.693908 -224.606104)
		)
		(stroke
			(width 0)
			(type solid)
		)
		(fill yes)
		(layer "In4.Cu")
		(net "M_J_CPU0_SA_DQS_DP<5>")
	)
	(gr_poly
		(pts
			(xy 391.83056 -222.949262) (xy 391.793984 -222.812864) (xy 391.752582 -222.788988) (xy 391.65276 -222.962216)
			(xy 391.693908 -222.985838)
		)
		(stroke
			(width 0)
			(type solid)
		)
		(fill yes)
		(layer "In4.Cu")
		(net "M_J_CPU0_SA_DQS_DN<0>")
	)
	(gr_poly
		(pts
			(xy 391.830814 -231.048814) (xy 391.793984 -230.912162) (xy 391.75563 -230.88981) (xy 391.655554 -231.063038)
			(xy 391.694162 -231.08539)
		)
		(stroke
			(width 0)
			(type solid)
		)
		(fill yes)
		(layer "In4.Cu")
		(net "M_J_CPU0_SA_DQ<11>")
	)
	(gr_poly
		(pts
			(xy 391.830814 -226.188778) (xy 391.793984 -226.052126) (xy 391.75563 -226.029774) (xy 391.655554 -226.203002)
			(xy 391.694162 -226.225354)
		)
		(stroke
			(width 0)
			(type solid)
		)
		(fill yes)
		(layer "In4.Cu")
		(net "M_J_CPU0_SA_DQ<6>")
	)
	(gr_poly
		(pts
			(xy 391.993882 -293.874698) (xy 391.893806 -293.70147) (xy 391.855452 -293.723822) (xy 391.818622 -293.860474)
			(xy 391.955274 -293.89705)
		)
		(stroke
			(width 0)
			(type solid)
		)
		(fill yes)
		(layer "In4.Cu")
		(net "M_J_CPU0_SB_DQ<31>")
	)
	(gr_poly
		(pts
			(xy 391.993882 -268.877288) (xy 391.955274 -268.854936) (xy 391.818622 -268.891512) (xy 391.855452 -269.028164)
			(xy 391.893806 -269.050516)
		)
		(stroke
			(width 0)
			(type solid)
		)
		(fill yes)
		(layer "In4.Cu")
		(net "M_J_CPU0_SB_CB<4>")
	)
	(gr_poly
		(pts
			(xy 392.059414 -290.487862) (xy 391.959592 -290.387786) (xy 391.859516 -290.487862) (xy 391.859516 -290.53536)
			(xy 392.059414 -290.53536)
		)
		(stroke
			(width 0)
			(type solid)
		)
		(fill yes)
		(layer "In4.Cu")
		(net "M_J_CPU0_SB_DQS_DP<3>")
	)
	(gr_poly
		(pts
			(xy 392.059414 -285.62808) (xy 391.959592 -285.528004) (xy 391.859516 -285.62808) (xy 391.859516 -285.675578)
			(xy 392.059414 -285.675578)
		)
		(stroke
			(width 0)
			(type solid)
		)
		(fill yes)
		(layer "In4.Cu")
		(net "M_J_CPU0_SB_DQS_DP<2>")
	)
	(gr_poly
		(pts
			(xy 392.059414 -280.768044) (xy 391.959592 -280.667968) (xy 391.859516 -280.768044) (xy 391.859516 -280.815542)
			(xy 392.059414 -280.815542)
		)
		(stroke
			(width 0)
			(type solid)
		)
		(fill yes)
		(layer "In4.Cu")
		(net "M_J_CPU0_SB_DQS_DP<1>")
	)
	(gr_poly
		(pts
			(xy 392.059414 -275.908008) (xy 391.959592 -275.807932) (xy 391.859516 -275.908008) (xy 391.859516 -275.955506)
			(xy 392.059414 -275.955506)
		)
		(stroke
			(width 0)
			(type solid)
		)
		(fill yes)
		(layer "In4.Cu")
		(net "M_J_CPU0_SB_DQS_DP<0>")
	)
	(gr_poly
		(pts
			(xy 392.059414 -271.047972) (xy 391.959592 -270.947896) (xy 391.859516 -271.047972) (xy 391.859516 -271.09547)
			(xy 392.059414 -271.09547)
		)
		(stroke
			(width 0)
			(type solid)
		)
		(fill yes)
		(layer "In4.Cu")
		(net "M_J_CPU0_SB_DQS_DP<9>")
	)
	(gr_poly
		(pts
			(xy 392.0617 -288.868104) (xy 391.961624 -288.768028) (xy 391.861548 -288.868104) (xy 391.861548 -288.912554)
			(xy 392.0617 -288.912554)
		)
		(stroke
			(width 0)
			(type solid)
		)
		(fill yes)
		(layer "In4.Cu")
		(net "M_J_CPU0_SB_DQ<24>")
	)
	(gr_poly
		(pts
			(xy 392.0617 -284.008322) (xy 391.961624 -283.908246) (xy 391.861548 -284.008322) (xy 391.861548 -284.052772)
			(xy 392.0617 -284.052772)
		)
		(stroke
			(width 0)
			(type solid)
		)
		(fill yes)
		(layer "In4.Cu")
		(net "M_J_CPU0_SB_DQ<16>")
	)
	(gr_poly
		(pts
			(xy 392.0617 -282.38831) (xy 391.961624 -282.288234) (xy 391.861548 -282.38831) (xy 391.861548 -282.43276)
			(xy 392.0617 -282.43276)
		)
		(stroke
			(width 0)
			(type solid)
		)
		(fill yes)
		(layer "In4.Cu")
		(net "M_J_CPU0_SB_DQ<12>")
	)
	(gr_poly
		(pts
			(xy 392.0617 -279.148286) (xy 391.961624 -279.04821) (xy 391.861548 -279.148286) (xy 391.861548 -279.192736)
			(xy 392.0617 -279.192736)
		)
		(stroke
			(width 0)
			(type solid)
		)
		(fill yes)
		(layer "In4.Cu")
		(net "M_J_CPU0_SB_DQ<8>")
	)
	(gr_poly
		(pts
			(xy 392.0617 -277.528274) (xy 391.961624 -277.428198) (xy 391.861548 -277.528274) (xy 391.861548 -277.572724)
			(xy 392.0617 -277.572724)
		)
		(stroke
			(width 0)
			(type solid)
		)
		(fill yes)
		(layer "In4.Cu")
		(net "M_J_CPU0_SB_DQ<4>")
	)
	(gr_poly
		(pts
			(xy 392.0617 -274.28825) (xy 391.961624 -274.188174) (xy 391.861548 -274.28825) (xy 391.861548 -274.3327)
			(xy 392.0617 -274.3327)
		)
		(stroke
			(width 0)
			(type solid)
		)
		(fill yes)
		(layer "In4.Cu")
		(net "M_J_CPU0_SB_DQ<0>")
	)
	(gr_poly
		(pts
			(xy 392.0617 -272.668238) (xy 391.961624 -272.568162) (xy 391.861548 -272.668238) (xy 391.861548 -272.712688)
			(xy 392.0617 -272.712688)
		)
		(stroke
			(width 0)
			(type solid)
		)
		(fill yes)
		(layer "In4.Cu")
		(net "M_J_CPU0_SB_CB<0>")
	)
	(gr_poly
		(pts
			(xy 392.0617 -267.808202) (xy 391.961624 -267.708126) (xy 391.861548 -267.808202) (xy 391.861548 -267.852652)
			(xy 392.0617 -267.852652)
		)
		(stroke
			(width 0)
			(type solid)
		)
		(fill yes)
		(layer "In4.Cu")
		(net "M_J_CPU0_SB_RSP<0>")
	)
	(gr_poly
		(pts
			(xy 392.0617 -264.568178) (xy 391.961624 -264.468102) (xy 391.861548 -264.568178) (xy 391.861548 -264.612628)
			(xy 392.0617 -264.612628)
		)
		(stroke
			(width 0)
			(type solid)
		)
		(fill yes)
		(layer "In4.Cu")
		(net "M_J_CPU0_SB_CA<6>")
	)
	(gr_poly
		(pts
			(xy 392.0617 -262.948166) (xy 391.961624 -262.84809) (xy 391.861548 -262.948166) (xy 391.861548 -262.992616)
			(xy 392.0617 -262.992616)
		)
		(stroke
			(width 0)
			(type solid)
		)
		(fill yes)
		(layer "In4.Cu")
		(net "M_J_CPU0_SB_CA<2>")
	)
	(gr_poly
		(pts
			(xy 392.074908 -292.107874) (xy 391.974832 -292.007798) (xy 391.874756 -292.107874) (xy 391.874756 -292.152324)
			(xy 392.074908 -292.152324)
		)
		(stroke
			(width 0)
			(type solid)
		)
		(fill yes)
		(layer "In4.Cu")
		(net "M_J_CPU0_SB_DQ<28>")
	)
	(gr_poly
		(pts
			(xy 392.074908 -291.704268) (xy 392.074908 -291.656516) (xy 391.874756 -291.656516) (xy 391.874756 -291.704268)
			(xy 391.974832 -291.80409)
		)
		(stroke
			(width 0)
			(type solid)
		)
		(fill yes)
		(layer "In4.Cu")
		(net "M_J_CPU0_SB_DQS_DP<8>")
	)
	(gr_poly
		(pts
			(xy 392.074908 -270.644112) (xy 392.074908 -270.599662) (xy 391.874756 -270.599662) (xy 391.874756 -270.644112)
			(xy 391.974832 -270.744188)
		)
		(stroke
			(width 0)
			(type solid)
		)
		(fill yes)
		(layer "In4.Cu")
		(net "M_J_CPU0_SB_CB<7>")
	)
	(gr_poly
		(pts
			(xy 392.081004 -286.844232) (xy 392.081004 -286.796734) (xy 391.881106 -286.796734) (xy 391.881106 -286.844232)
			(xy 391.980928 -286.944308)
		)
		(stroke
			(width 0)
			(type solid)
		)
		(fill yes)
		(layer "In4.Cu")
		(net "M_J_CPU0_SB_DQS_DP<7>")
	)
	(gr_poly
		(pts
			(xy 392.081004 -285.22422) (xy 392.081004 -285.17977) (xy 391.881106 -285.17977) (xy 391.881106 -285.22422)
			(xy 391.980928 -285.324296)
		)
		(stroke
			(width 0)
			(type solid)
		)
		(fill yes)
		(layer "In4.Cu")
		(net "M_J_CPU0_SB_DQ<19>")
	)
	(gr_poly
		(pts
			(xy 392.081004 -283.604208) (xy 392.081004 -283.559758) (xy 391.881106 -283.559758) (xy 391.881106 -283.604208)
			(xy 391.980928 -283.704284)
		)
		(stroke
			(width 0)
			(type solid)
		)
		(fill yes)
		(layer "In4.Cu")
		(net "M_J_CPU0_SB_DQ<15>")
	)
	(gr_poly
		(pts
			(xy 392.081004 -281.98445) (xy 392.081004 -281.936952) (xy 391.881106 -281.936952) (xy 391.881106 -281.98445)
			(xy 391.980928 -282.084526)
		)
		(stroke
			(width 0)
			(type solid)
		)
		(fill yes)
		(layer "In4.Cu")
		(net "M_J_CPU0_SB_DQS_DP<6>")
	)
	(gr_poly
		(pts
			(xy 392.081004 -280.364184) (xy 392.081004 -280.319734) (xy 391.881106 -280.319734) (xy 391.881106 -280.364184)
			(xy 391.980928 -280.46426)
		)
		(stroke
			(width 0)
			(type solid)
		)
		(fill yes)
		(layer "In4.Cu")
		(net "M_J_CPU0_SB_DQ<11>")
	)
	(gr_poly
		(pts
			(xy 392.081004 -278.744172) (xy 392.081004 -278.699722) (xy 391.881106 -278.699722) (xy 391.881106 -278.744172)
			(xy 391.980928 -278.844248)
		)
		(stroke
			(width 0)
			(type solid)
		)
		(fill yes)
		(layer "In4.Cu")
		(net "M_J_CPU0_SB_DQ<7>")
	)
	(gr_poly
		(pts
			(xy 392.081004 -277.124414) (xy 392.081004 -277.076916) (xy 391.881106 -277.076916) (xy 391.881106 -277.124414)
			(xy 391.980928 -277.22449)
		)
		(stroke
			(width 0)
			(type solid)
		)
		(fill yes)
		(layer "In4.Cu")
		(net "M_J_CPU0_SB_DQS_DP<5>")
	)
	(gr_poly
		(pts
			(xy 392.081004 -275.504148) (xy 392.081004 -275.459698) (xy 391.881106 -275.459698) (xy 391.881106 -275.504148)
			(xy 391.980928 -275.604224)
		)
		(stroke
			(width 0)
			(type solid)
		)
		(fill yes)
		(layer "In4.Cu")
		(net "M_J_CPU0_SB_DQ<3>")
	)
	(gr_poly
		(pts
			(xy 392.081004 -273.884136) (xy 392.081004 -273.839686) (xy 391.881106 -273.839686) (xy 391.881106 -273.884136)
			(xy 391.980928 -273.984212)
		)
		(stroke
			(width 0)
			(type solid)
		)
		(fill yes)
		(layer "In4.Cu")
		(net "M_J_CPU0_SB_CB<3>")
	)
	(gr_poly
		(pts
			(xy 392.081004 -272.264378) (xy 392.081004 -272.21688) (xy 391.881106 -272.21688) (xy 391.881106 -272.264378)
			(xy 391.980928 -272.364454)
		)
		(stroke
			(width 0)
			(type solid)
		)
		(fill yes)
		(layer "In4.Cu")
		(net "M_J_CPU0_SB_DQS_DP<4>")
	)
	(gr_poly
		(pts
			(xy 392.081004 -265.784076) (xy 392.081004 -265.739626) (xy 391.881106 -265.739626) (xy 391.881106 -265.784076)
			(xy 391.980928 -265.884152)
		)
		(stroke
			(width 0)
			(type solid)
		)
		(fill yes)
		(layer "In4.Cu")
		(net "M_J_CPU0_SB_CS_N<0>")
	)
	(gr_poly
		(pts
			(xy 392.081004 -264.164064) (xy 392.081004 -264.119614) (xy 391.881106 -264.119614) (xy 391.881106 -264.164064)
			(xy 391.980928 -264.26414)
		)
		(stroke
			(width 0)
			(type solid)
		)
		(fill yes)
		(layer "In4.Cu")
		(net "M_J_CPU0_SB_CA<5>")
	)
	(gr_poly
		(pts
			(xy 392.081004 -262.544052) (xy 392.081004 -262.499602) (xy 391.881106 -262.499602) (xy 391.881106 -262.544052)
			(xy 391.980928 -262.644128)
		)
		(stroke
			(width 0)
			(type solid)
		)
		(fill yes)
		(layer "In4.Cu")
		(net "M_J_CPU0_SB_CA<1>")
	)
	(gr_poly
		(pts
			(xy 392.093958 -293.32809) (xy 392.130534 -293.191438) (xy 391.994136 -293.154862) (xy 391.955528 -293.177214)
			(xy 392.055604 -293.350442)
		)
		(stroke
			(width 0)
			(type solid)
		)
		(fill yes)
		(layer "In4.Cu")
		(net "M_J_CPU0_SB_DQ<29>")
	)
	(gr_poly
		(pts
			(xy 392.130534 -269.560548) (xy 392.093958 -269.423896) (xy 392.055604 -269.401544) (xy 391.955528 -269.574772)
			(xy 391.994136 -269.597124)
		)
		(stroke
			(width 0)
			(type solid)
		)
		(fill yes)
		(layer "In4.Cu")
		(net "M_J_CPU0_SB_CB<6>")
	)
	(gr_poly
		(pts
			(xy 392.164062 -224.695512) (xy 392.125454 -224.67316) (xy 391.988802 -224.709736) (xy 392.025632 -224.846388)
			(xy 392.063986 -224.86874)
		)
		(stroke
			(width 0)
			(type solid)
		)
		(fill yes)
		(layer "In4.Cu")
		(net "M_J_CPU0_SA_DQ<4>")
	)
	(gr_poly
		(pts
			(xy 392.166856 -223.076262) (xy 392.125708 -223.05264) (xy 391.989056 -223.089216) (xy 392.025632 -223.225614)
			(xy 392.067034 -223.24949)
		)
		(stroke
			(width 0)
			(type solid)
		)
		(fill yes)
		(layer "In4.Cu")
		(net "M_J_CPU0_SA_DQS_DN<5>")
	)
	(gr_poly
		(pts
			(xy 392.23696 -255.622552) (xy 392.23696 -255.578102) (xy 392.037062 -255.578102) (xy 392.037062 -255.622552)
			(xy 392.137138 -255.722628)
		)
		(stroke
			(width 0)
			(type solid)
		)
		(fill yes)
		(layer "In4.Cu")
		(net "M_J_CPU0_SA_PAR")
	)
	(gr_poly
		(pts
			(xy 392.23696 -254.00254) (xy 392.23696 -253.95809) (xy 392.037062 -253.95809) (xy 392.037062 -254.00254)
			(xy 392.137138 -254.102616)
		)
		(stroke
			(width 0)
			(type solid)
		)
		(fill yes)
		(layer "In4.Cu")
		(net "M_J_CPU0_SA_CA<3>")
	)
	(gr_poly
		(pts
			(xy 392.23696 -250.762516) (xy 392.23696 -250.718066) (xy 392.037062 -250.718066) (xy 392.037062 -250.762516)
			(xy 392.137138 -250.862338)
		)
		(stroke
			(width 0)
			(type solid)
		)
		(fill yes)
		(layer "In4.Cu")
		(net "M_J_CPU0_RESET_N")
	)
	(gr_poly
		(pts
			(xy 392.23696 -249.142504) (xy 392.23696 -249.098054) (xy 392.037062 -249.098054) (xy 392.037062 -249.142504)
			(xy 392.137138 -249.24258)
		)
		(stroke
			(width 0)
			(type solid)
		)
		(fill yes)
		(layer "In4.Cu")
		(net "M_J_CPU0_SA_CB<7>")
	)
	(gr_poly
		(pts
			(xy 392.23696 -247.522746) (xy 392.23696 -247.474994) (xy 392.037062 -247.474994) (xy 392.037062 -247.522746)
			(xy 392.137138 -247.622568)
		)
		(stroke
			(width 0)
			(type solid)
		)
		(fill yes)
		(layer "In4.Cu")
		(net "M_J_CPU0_SA_DQS_DP<9>")
	)
	(gr_poly
		(pts
			(xy 392.23696 -245.90248) (xy 392.23696 -245.85803) (xy 392.037062 -245.85803) (xy 392.037062 -245.90248)
			(xy 392.137138 -246.002302)
		)
		(stroke
			(width 0)
			(type solid)
		)
		(fill yes)
		(layer "In4.Cu")
		(net "M_J_CPU0_SA_CB<3>")
	)
	(gr_poly
		(pts
			(xy 392.23696 -244.282468) (xy 392.23696 -244.238018) (xy 392.037062 -244.238018) (xy 392.037062 -244.282468)
			(xy 392.137138 -244.382544)
		)
		(stroke
			(width 0)
			(type solid)
		)
		(fill yes)
		(layer "In4.Cu")
		(net "M_J_CPU0_SA_DQ<31>")
	)
	(gr_poly
		(pts
			(xy 392.23696 -241.042444) (xy 392.23696 -240.997994) (xy 392.037062 -240.997994) (xy 392.037062 -241.042444)
			(xy 392.137138 -241.14252)
		)
		(stroke
			(width 0)
			(type solid)
		)
		(fill yes)
		(layer "In4.Cu")
		(net "M_J_CPU0_SA_DQ<27>")
	)
	(gr_poly
		(pts
			(xy 392.23696 -239.422432) (xy 392.23696 -239.377982) (xy 392.037062 -239.377982) (xy 392.037062 -239.422432)
			(xy 392.137138 -239.522508)
		)
		(stroke
			(width 0)
			(type solid)
		)
		(fill yes)
		(layer "In4.Cu")
		(net "M_J_CPU0_SA_DQ<23>")
	)
	(gr_poly
		(pts
			(xy 392.239246 -254.406146) (xy 392.139424 -254.30607) (xy 392.039348 -254.406146) (xy 392.039348 -254.450596)
			(xy 392.239246 -254.450596)
		)
		(stroke
			(width 0)
			(type solid)
		)
		(fill yes)
		(layer "In4.Cu")
		(net "M_J_CPU0_SA_CA<4>")
	)
	(gr_poly
		(pts
			(xy 392.239246 -252.786134) (xy 392.139424 -252.686058) (xy 392.039348 -252.786134) (xy 392.039348 -252.830584)
			(xy 392.239246 -252.830584)
		)
		(stroke
			(width 0)
			(type solid)
		)
		(fill yes)
		(layer "In4.Cu")
		(net "M_J_CPU0_SA_CA<0>")
	)
	(gr_poly
		(pts
			(xy 392.239246 -251.166122) (xy 392.139424 -251.066046) (xy 392.039348 -251.166122) (xy 392.039348 -251.210572)
			(xy 392.239246 -251.210572)
		)
		(stroke
			(width 0)
			(type solid)
		)
		(fill yes)
		(layer "In4.Cu")
		(net "M_J_CPU0_SA_CS_N<0>")
	)
	(gr_poly
		(pts
			(xy 392.239246 -247.926098) (xy 392.139424 -247.826022) (xy 392.039348 -247.926098) (xy 392.039348 -247.970548)
			(xy 392.239246 -247.970548)
		)
		(stroke
			(width 0)
			(type solid)
		)
		(fill yes)
		(layer "In4.Cu")
		(net "M_J_CPU0_SA_CB<4>")
	)
	(gr_poly
		(pts
			(xy 392.239246 -246.305832) (xy 392.139424 -246.205756) (xy 392.039348 -246.305832) (xy 392.039348 -246.35333)
			(xy 392.239246 -246.35333)
		)
		(stroke
			(width 0)
			(type solid)
		)
		(fill yes)
		(layer "In4.Cu")
		(net "M_J_CPU0_SA_DQS_DP<4>")
	)
	(gr_poly
		(pts
			(xy 392.239246 -244.686074) (xy 392.139424 -244.585998) (xy 392.039348 -244.686074) (xy 392.039348 -244.730524)
			(xy 392.239246 -244.730524)
		)
		(stroke
			(width 0)
			(type solid)
		)
		(fill yes)
		(layer "In4.Cu")
		(net "M_J_CPU0_SA_CB<0>")
	)
	(gr_poly
		(pts
			(xy 392.239246 -243.066062) (xy 392.139424 -242.965986) (xy 392.039348 -243.066062) (xy 392.039348 -243.110512)
			(xy 392.239246 -243.110512)
		)
		(stroke
			(width 0)
			(type solid)
		)
		(fill yes)
		(layer "In4.Cu")
		(net "M_J_CPU0_SA_DQ<28>")
	)
	(gr_poly
		(pts
			(xy 392.239246 -241.445796) (xy 392.139424 -241.34572) (xy 392.039348 -241.445796) (xy 392.039348 -241.493294)
			(xy 392.239246 -241.493294)
		)
		(stroke
			(width 0)
			(type solid)
		)
		(fill yes)
		(layer "In4.Cu")
		(net "M_J_CPU0_SA_DQS_DP<3>")
	)
	(gr_poly
		(pts
			(xy 392.239246 -239.826038) (xy 392.139424 -239.725962) (xy 392.039348 -239.826038) (xy 392.039348 -239.870488)
			(xy 392.239246 -239.870488)
		)
		(stroke
			(width 0)
			(type solid)
		)
		(fill yes)
		(layer "In4.Cu")
		(net "M_J_CPU0_SA_DQ<24>")
	)
	(gr_poly
		(pts
			(xy 392.239246 -238.206026) (xy 392.139424 -238.10595) (xy 392.039348 -238.206026) (xy 392.039348 -238.250476)
			(xy 392.239246 -238.250476)
		)
		(stroke
			(width 0)
			(type solid)
		)
		(fill yes)
		(layer "In4.Cu")
		(net "M_J_CPU0_SA_DQ<20>")
	)
	(gr_poly
		(pts
			(xy 392.250676 -237.80242) (xy 392.250676 -237.754668) (xy 392.050778 -237.754668) (xy 392.050778 -237.80242)
			(xy 392.1506 -237.902242)
		)
		(stroke
			(width 0)
			(type solid)
		)
		(fill yes)
		(layer "In4.Cu")
		(net "M_J_CPU0_SA_DQS_DP<7>")
	)
	(gr_poly
		(pts
			(xy 392.25347 -256.02565) (xy 392.153394 -255.925828) (xy 392.053572 -256.02565) (xy 392.053572 -256.073402)
			(xy 392.25347 -256.073402)
		)
		(stroke
			(width 0)
			(type solid)
		)
		(fill yes)
		(layer "In4.Cu")
		(net "M_J_CPU0_CLK_DP<0>")
	)
	(gr_poly
		(pts
			(xy 392.300714 -225.378772) (xy 392.264138 -225.24212) (xy 392.225784 -225.219768) (xy 392.125708 -225.392996)
			(xy 392.164316 -225.415348)
		)
		(stroke
			(width 0)
			(type solid)
		)
		(fill yes)
		(layer "In4.Cu")
		(net "M_J_CPU0_SA_DQ<6>")
	)
	(gr_poly
		(pts
			(xy 392.300714 -223.759268) (xy 392.264138 -223.62287) (xy 392.222736 -223.598994) (xy 392.122914 -223.772222)
			(xy 392.164062 -223.795844)
		)
		(stroke
			(width 0)
			(type solid)
		)
		(fill yes)
		(layer "In4.Cu")
		(net "M_J_CPU0_SA_DQS_DP<5>")
	)
	(gr_poly
		(pts
			(xy 392.300714 -222.138748) (xy 392.264138 -222.002096) (xy 392.22299 -221.97822) (xy 392.122914 -222.151448)
			(xy 392.164062 -222.175324)
		)
		(stroke
			(width 0)
			(type solid)
		)
		(fill yes)
		(layer "In4.Cu")
		(net "M_J_CPU0_SA_DQS_DN<0>")
	)
	(gr_poly
		(pts
			(xy 392.463782 -294.684704) (xy 392.363706 -294.511476) (xy 392.325352 -294.533828) (xy 392.288522 -294.67048)
			(xy 392.425174 -294.707056)
		)
		(stroke
			(width 0)
			(type solid)
		)
		(fill yes)
		(layer "In4.Cu")
		(net "M_J_CPU0_SB_DQ<31>")
	)
	(gr_poly
		(pts
			(xy 392.464036 -293.064692) (xy 392.36396 -292.891464) (xy 392.325606 -292.913816) (xy 392.28903 -293.050468)
			(xy 392.425428 -293.087044)
		)
		(stroke
			(width 0)
			(type solid)
		)
		(fill yes)
		(layer "In4.Cu")
		(net "M_J_CPU0_SB_DQ<30>")
	)
	(gr_poly
		(pts
			(xy 392.464036 -269.687294) (xy 392.425428 -269.664942) (xy 392.28903 -269.701518) (xy 392.325606 -269.83817)
			(xy 392.36396 -269.860522)
		)
		(stroke
			(width 0)
			(type solid)
		)
		(fill yes)
		(layer "In4.Cu")
		(net "M_J_CPU0_SB_CB<5>")
	)
	(gr_poly
		(pts
			(xy 392.539474 -284.818074) (xy 392.439398 -284.717998) (xy 392.339322 -284.818074) (xy 392.339322 -284.862524)
			(xy 392.539474 -284.862524)
		)
		(stroke
			(width 0)
			(type solid)
		)
		(fill yes)
		(layer "In4.Cu")
		(net "M_J_CPU0_SB_DQ<17>")
	)
	(gr_poly
		(pts
			(xy 392.539474 -283.198062) (xy 392.439398 -283.097986) (xy 392.339322 -283.198062) (xy 392.339322 -283.242512)
			(xy 392.539474 -283.242512)
		)
		(stroke
			(width 0)
			(type solid)
		)
		(fill yes)
		(layer "In4.Cu")
		(net "M_J_CPU0_SB_DQ<13>")
	)
	(gr_poly
		(pts
			(xy 392.539474 -281.577796) (xy 392.439398 -281.47772) (xy 392.339322 -281.577796) (xy 392.339322 -281.625294)
			(xy 392.539474 -281.625294)
		)
		(stroke
			(width 0)
			(type solid)
		)
		(fill yes)
		(layer "In4.Cu")
		(net "M_J_CPU0_SB_DQS_DN<6>")
	)
	(gr_poly
		(pts
			(xy 392.539474 -279.958038) (xy 392.439398 -279.857962) (xy 392.339322 -279.958038) (xy 392.339322 -280.002488)
			(xy 392.539474 -280.002488)
		)
		(stroke
			(width 0)
			(type solid)
		)
		(fill yes)
		(layer "In4.Cu")
		(net "M_J_CPU0_SB_DQ<9>")
	)
	(gr_poly
		(pts
			(xy 392.539474 -278.338026) (xy 392.439398 -278.23795) (xy 392.339322 -278.338026) (xy 392.339322 -278.382476)
			(xy 392.539474 -278.382476)
		)
		(stroke
			(width 0)
			(type solid)
		)
		(fill yes)
		(layer "In4.Cu")
		(net "M_J_CPU0_SB_DQ<5>")
	)
	(gr_poly
		(pts
			(xy 392.539474 -276.71776) (xy 392.439398 -276.617684) (xy 392.339322 -276.71776) (xy 392.339322 -276.765258)
			(xy 392.539474 -276.765258)
		)
		(stroke
			(width 0)
			(type solid)
		)
		(fill yes)
		(layer "In4.Cu")
		(net "M_J_CPU0_SB_DQS_DN<5>")
	)
	(gr_poly
		(pts
			(xy 392.539474 -275.098002) (xy 392.439398 -274.997926) (xy 392.339322 -275.098002) (xy 392.339322 -275.142452)
			(xy 392.539474 -275.142452)
		)
		(stroke
			(width 0)
			(type solid)
		)
		(fill yes)
		(layer "In4.Cu")
		(net "M_J_CPU0_SB_DQ<1>")
	)
	(gr_poly
		(pts
			(xy 392.539474 -273.47799) (xy 392.439398 -273.377914) (xy 392.339322 -273.47799) (xy 392.339322 -273.52244)
			(xy 392.539474 -273.52244)
		)
		(stroke
			(width 0)
			(type solid)
		)
		(fill yes)
		(layer "In4.Cu")
		(net "M_J_CPU0_SB_CB<1>")
	)
	(gr_poly
		(pts
			(xy 392.539474 -266.997942) (xy 392.439398 -266.897866) (xy 392.339322 -266.997942) (xy 392.339322 -267.042392)
			(xy 392.539474 -267.042392)
		)
		(stroke
			(width 0)
			(type solid)
		)
		(fill yes)
		(layer "In4.Cu")
		(net "M_J_CPU0_SA_RSP<0>")
	)
	(gr_poly
		(pts
			(xy 392.539474 -265.37793) (xy 392.439398 -265.277854) (xy 392.339322 -265.37793) (xy 392.339322 -265.42238)
			(xy 392.539474 -265.42238)
		)
		(stroke
			(width 0)
			(type solid)
		)
		(fill yes)
		(layer "In4.Cu")
		(net "M_J_CPU0_SB_PAR")
	)
	(gr_poly
		(pts
			(xy 392.539474 -263.757918) (xy 392.439398 -263.657842) (xy 392.339322 -263.757918) (xy 392.339322 -263.802368)
			(xy 392.539474 -263.802368)
		)
		(stroke
			(width 0)
			(type solid)
		)
		(fill yes)
		(layer "In4.Cu")
		(net "M_J_CPU0_SB_CA<4>")
	)
	(gr_poly
		(pts
			(xy 392.539474 -262.137906) (xy 392.439398 -262.03783) (xy 392.339322 -262.137906) (xy 392.339322 -262.182356)
			(xy 392.539474 -262.182356)
		)
		(stroke
			(width 0)
			(type solid)
		)
		(fill yes)
		(layer "In4.Cu")
		(net "M_J_CPU0_SB_CA<0>")
	)
	(gr_poly
		(pts
			(xy 392.544808 -291.297614) (xy 392.444732 -291.197792) (xy 392.344656 -291.297614) (xy 392.344656 -291.345366)
			(xy 392.544808 -291.345366)
		)
		(stroke
			(width 0)
			(type solid)
		)
		(fill yes)
		(layer "In4.Cu")
		(net "M_J_CPU0_SB_DQS_DN<8>")
	)
	(gr_poly
		(pts
			(xy 392.544808 -271.454372) (xy 392.544808 -271.40662) (xy 392.344656 -271.40662) (xy 392.344656 -271.454372)
			(xy 392.444732 -271.554194)
		)
		(stroke
			(width 0)
			(type solid)
		)
		(fill yes)
		(layer "In4.Cu")
		(net "M_J_CPU0_SB_DQS_DN<9>")
	)
	(gr_poly
		(pts
			(xy 392.544808 -268.617954) (xy 392.444732 -268.517878) (xy 392.344656 -268.617954) (xy 392.344656 -268.662404)
			(xy 392.544808 -268.662404)
		)
		(stroke
			(width 0)
			(type solid)
		)
		(fill yes)
		(layer "In4.Cu")
		(net "M_J_CPU0_SB_CB<4>")
	)
	(gr_poly
		(pts
			(xy 392.55573 -284.41396) (xy 392.55573 -284.36951) (xy 392.355578 -284.36951) (xy 392.355578 -284.41396)
			(xy 392.455654 -284.514036)
		)
		(stroke
			(width 0)
			(type solid)
		)
		(fill yes)
		(layer "In4.Cu")
		(net "M_J_CPU0_SB_DQ<18>")
	)
	(gr_poly
		(pts
			(xy 392.55573 -282.793948) (xy 392.55573 -282.749498) (xy 392.355578 -282.749498) (xy 392.355578 -282.793948)
			(xy 392.455654 -282.894024)
		)
		(stroke
			(width 0)
			(type solid)
		)
		(fill yes)
		(layer "In4.Cu")
		(net "M_J_CPU0_SB_DQ<14>")
	)
	(gr_poly
		(pts
			(xy 392.55573 -279.553924) (xy 392.55573 -279.509474) (xy 392.355578 -279.509474) (xy 392.355578 -279.553924)
			(xy 392.455654 -279.654)
		)
		(stroke
			(width 0)
			(type solid)
		)
		(fill yes)
		(layer "In4.Cu")
		(net "M_J_CPU0_SB_DQ<10>")
	)
	(gr_poly
		(pts
			(xy 392.55573 -277.933912) (xy 392.55573 -277.889462) (xy 392.355578 -277.889462) (xy 392.355578 -277.933912)
			(xy 392.455654 -278.033988)
		)
		(stroke
			(width 0)
			(type solid)
		)
		(fill yes)
		(layer "In4.Cu")
		(net "M_J_CPU0_SB_DQ<6>")
	)
	(gr_poly
		(pts
			(xy 392.55573 -274.693888) (xy 392.55573 -274.649438) (xy 392.355578 -274.649438) (xy 392.355578 -274.693888)
			(xy 392.455654 -274.793964)
		)
		(stroke
			(width 0)
			(type solid)
		)
		(fill yes)
		(layer "In4.Cu")
		(net "M_J_CPU0_SB_DQ<2>")
	)
	(gr_poly
		(pts
			(xy 392.55573 -273.073876) (xy 392.55573 -273.029426) (xy 392.355578 -273.029426) (xy 392.355578 -273.073876)
			(xy 392.455654 -273.173952)
		)
		(stroke
			(width 0)
			(type solid)
		)
		(fill yes)
		(layer "In4.Cu")
		(net "M_J_CPU0_SB_CB<2>")
	)
	(gr_poly
		(pts
			(xy 392.55573 -266.593828) (xy 392.55573 -266.549378) (xy 392.355578 -266.549378) (xy 392.355578 -266.593828)
			(xy 392.455654 -266.693904)
		)
		(stroke
			(width 0)
			(type solid)
		)
		(fill yes)
		(layer "In4.Cu")
		(net "M_J_CPU0_SB_CS_N<1>")
	)
	(gr_poly
		(pts
			(xy 392.55573 -263.353804) (xy 392.55573 -263.309354) (xy 392.355578 -263.309354) (xy 392.355578 -263.353804)
			(xy 392.455654 -263.45388)
		)
		(stroke
			(width 0)
			(type solid)
		)
		(fill yes)
		(layer "In4.Cu")
		(net "M_J_CPU0_SB_CA<3>")
	)
	(gr_poly
		(pts
			(xy 392.557762 -290.894008) (xy 392.557762 -290.84651) (xy 392.357864 -290.84651) (xy 392.357864 -290.894008)
			(xy 392.457686 -290.994084)
		)
		(stroke
			(width 0)
			(type solid)
		)
		(fill yes)
		(layer "In4.Cu")
		(net "M_J_CPU0_SB_DQS_DN<3>")
	)
	(gr_poly
		(pts
			(xy 392.557762 -286.034226) (xy 392.557762 -285.986728) (xy 392.357864 -285.986728) (xy 392.357864 -286.034226)
			(xy 392.457686 -286.134302)
		)
		(stroke
			(width 0)
			(type solid)
		)
		(fill yes)
		(layer "In4.Cu")
		(net "M_J_CPU0_SB_DQS_DN<2>")
	)
	(gr_poly
		(pts
			(xy 392.557762 -281.17419) (xy 392.557762 -281.126692) (xy 392.357864 -281.126692) (xy 392.357864 -281.17419)
			(xy 392.457686 -281.274266)
		)
		(stroke
			(width 0)
			(type solid)
		)
		(fill yes)
		(layer "In4.Cu")
		(net "M_J_CPU0_SB_DQS_DN<1>")
	)
	(gr_poly
		(pts
			(xy 392.557762 -276.314154) (xy 392.557762 -276.266656) (xy 392.357864 -276.266656) (xy 392.357864 -276.314154)
			(xy 392.457686 -276.41423)
		)
		(stroke
			(width 0)
			(type solid)
		)
		(fill yes)
		(layer "In4.Cu")
		(net "M_J_CPU0_SB_DQS_DN<0>")
	)
	(gr_poly
		(pts
			(xy 392.563858 -294.138096) (xy 392.600434 -294.001444) (xy 392.464036 -293.964868) (xy 392.425428 -293.98722)
			(xy 392.525504 -294.160448)
		)
		(stroke
			(width 0)
			(type solid)
		)
		(fill yes)
		(layer "In4.Cu")
		(net "M_J_CPU0_SB_DQ<29>")
	)
	(gr_poly
		(pts
			(xy 392.564112 -292.518084) (xy 392.600942 -292.381432) (xy 392.46429 -292.344856) (xy 392.425682 -292.367208)
			(xy 392.525758 -292.540436)
		)
		(stroke
			(width 0)
			(type solid)
		)
		(fill yes)
		(layer "In4.Cu")
		(net "M_J_CPU0_SB_DQ<28>")
	)
	(gr_poly
		(pts
			(xy 392.600942 -270.370554) (xy 392.564112 -270.233902) (xy 392.525758 -270.21155) (xy 392.425682 -270.384778)
			(xy 392.46429 -270.40713)
		)
		(stroke
			(width 0)
			(type solid)
		)
		(fill yes)
		(layer "In4.Cu")
		(net "M_J_CPU0_SB_CB<7>")
	)
	(gr_poly
		(pts
			(xy 392.633962 -223.885506) (xy 392.595354 -223.863154) (xy 392.458702 -223.89973) (xy 392.495532 -224.036382)
			(xy 392.533886 -224.058734)
		)
		(stroke
			(width 0)
			(type solid)
		)
		(fill yes)
		(layer "In4.Cu")
		(net "M_J_CPU0_SA_DQ<4>")
	)
	(gr_poly
		(pts
			(xy 392.636756 -222.26651) (xy 392.595608 -222.242888) (xy 392.458956 -222.279464) (xy 392.495532 -222.416116)
			(xy 392.53668 -222.439738)
		)
		(stroke
			(width 0)
			(type solid)
		)
		(fill yes)
		(layer "In4.Cu")
		(net "M_J_CPU0_SA_DQS_DN<5>")
	)
	(gr_poly
		(pts
			(xy 392.70305 -256.432558) (xy 392.70305 -256.38506) (xy 392.503152 -256.38506) (xy 392.503152 -256.432558)
			(xy 392.603228 -256.532634)
		)
		(stroke
			(width 0)
			(type solid)
		)
		(fill yes)
		(layer "In4.Cu")
		(net "M_J_CPU0_CLK_DN<0>")
	)
	(gr_poly
		(pts
			(xy 392.70686 -247.115838) (xy 392.607038 -247.016016) (xy 392.506962 -247.115838) (xy 392.506962 -247.16359)
			(xy 392.70686 -247.16359)
		)
		(stroke
			(width 0)
			(type solid)
		)
		(fill yes)
		(layer "In4.Cu")
		(net "M_J_CPU0_SA_DQS_DN<9>")
	)
	(gr_poly
		(pts
			(xy 392.70686 -246.712486) (xy 392.70686 -246.664734) (xy 392.506962 -246.664734) (xy 392.506962 -246.712486)
			(xy 392.607038 -246.812308)
		)
		(stroke
			(width 0)
			(type solid)
		)
		(fill yes)
		(layer "In4.Cu")
		(net "M_J_CPU0_SA_DQS_DN<4>")
	)
	(gr_poly
		(pts
			(xy 392.70686 -241.85245) (xy 392.70686 -241.804698) (xy 392.506962 -241.804698) (xy 392.506962 -241.85245)
			(xy 392.607038 -241.952272)
		)
		(stroke
			(width 0)
			(type solid)
		)
		(fill yes)
		(layer "In4.Cu")
		(net "M_J_CPU0_SA_DQS_DN<3>")
	)
	(gr_poly
		(pts
			(xy 392.712194 -255.216152) (xy 392.612118 -255.116076) (xy 392.512042 -255.216152) (xy 392.512042 -255.260602)
			(xy 392.712194 -255.260602)
		)
		(stroke
			(width 0)
			(type solid)
		)
		(fill yes)
		(layer "In4.Cu")
		(net "M_J_CPU0_SA_CA<6>")
	)
	(gr_poly
		(pts
			(xy 392.712194 -254.812292) (xy 392.712194 -254.767842) (xy 392.512042 -254.767842) (xy 392.512042 -254.812292)
			(xy 392.612118 -254.912368)
		)
		(stroke
			(width 0)
			(type solid)
		)
		(fill yes)
		(layer "In4.Cu")
		(net "M_J_CPU0_SA_CA<5>")
	)
	(gr_poly
		(pts
			(xy 392.712194 -253.59614) (xy 392.612118 -253.496064) (xy 392.512042 -253.59614) (xy 392.512042 -253.64059)
			(xy 392.712194 -253.64059)
		)
		(stroke
			(width 0)
			(type solid)
		)
		(fill yes)
		(layer "In4.Cu")
		(net "M_J_CPU0_SA_CA<2>")
	)
	(gr_poly
		(pts
			(xy 392.712194 -253.19228) (xy 392.712194 -253.14783) (xy 392.512042 -253.14783) (xy 392.512042 -253.19228)
			(xy 392.612118 -253.292356)
		)
		(stroke
			(width 0)
			(type solid)
		)
		(fill yes)
		(layer "In4.Cu")
		(net "M_J_CPU0_SA_CA<1>")
	)
	(gr_poly
		(pts
			(xy 392.712194 -251.976128) (xy 392.612118 -251.876052) (xy 392.512042 -251.976128) (xy 392.512042 -252.020578)
			(xy 392.712194 -252.020578)
		)
		(stroke
			(width 0)
			(type solid)
		)
		(fill yes)
		(layer "In4.Cu")
		(net "M_J_CPU0_SA_CS_N<1>")
	)
	(gr_poly
		(pts
			(xy 392.712194 -250.356116) (xy 392.612118 -250.25604) (xy 392.512042 -250.356116) (xy 392.512042 -250.400566)
			(xy 392.712194 -250.400566)
		)
		(stroke
			(width 0)
			(type solid)
		)
		(fill yes)
		(layer "In4.Cu")
		(net "M_J_CPU0_ALERT_R_N")
	)
	(gr_poly
		(pts
			(xy 392.712194 -248.736104) (xy 392.612118 -248.636028) (xy 392.512042 -248.736104) (xy 392.512042 -248.780554)
			(xy 392.712194 -248.780554)
		)
		(stroke
			(width 0)
			(type solid)
		)
		(fill yes)
		(layer "In4.Cu")
		(net "M_J_CPU0_SA_CB<5>")
	)
	(gr_poly
		(pts
			(xy 392.712194 -248.332244) (xy 392.712194 -248.287794) (xy 392.512042 -248.287794) (xy 392.512042 -248.332244)
			(xy 392.612118 -248.43232)
		)
		(stroke
			(width 0)
			(type solid)
		)
		(fill yes)
		(layer "In4.Cu")
		(net "M_J_CPU0_SA_CB<6>")
	)
	(gr_poly
		(pts
			(xy 392.712194 -245.49608) (xy 392.612118 -245.396004) (xy 392.512042 -245.49608) (xy 392.512042 -245.54053)
			(xy 392.712194 -245.54053)
		)
		(stroke
			(width 0)
			(type solid)
		)
		(fill yes)
		(layer "In4.Cu")
		(net "M_J_CPU0_SA_CB<1>")
	)
	(gr_poly
		(pts
			(xy 392.712194 -245.09222) (xy 392.712194 -245.04777) (xy 392.512042 -245.04777) (xy 392.512042 -245.09222)
			(xy 392.612118 -245.192296)
		)
		(stroke
			(width 0)
			(type solid)
		)
		(fill yes)
		(layer "In4.Cu")
		(net "M_J_CPU0_SA_CB<2>")
	)
	(gr_poly
		(pts
			(xy 392.712194 -243.876068) (xy 392.612118 -243.775992) (xy 392.512042 -243.876068) (xy 392.512042 -243.920518)
			(xy 392.712194 -243.920518)
		)
		(stroke
			(width 0)
			(type solid)
		)
		(fill yes)
		(layer "In4.Cu")
		(net "M_J_CPU0_SA_DQ<29>")
	)
	(gr_poly
		(pts
			(xy 392.712194 -243.472208) (xy 392.712194 -243.427758) (xy 392.512042 -243.427758) (xy 392.512042 -243.472208)
			(xy 392.612118 -243.572284)
		)
		(stroke
			(width 0)
			(type solid)
		)
		(fill yes)
		(layer "In4.Cu")
		(net "M_J_CPU0_SA_DQ<30>")
	)
	(gr_poly
		(pts
			(xy 392.712194 -240.636044) (xy 392.612118 -240.535968) (xy 392.512042 -240.636044) (xy 392.512042 -240.680494)
			(xy 392.712194 -240.680494)
		)
		(stroke
			(width 0)
			(type solid)
		)
		(fill yes)
		(layer "In4.Cu")
		(net "M_J_CPU0_SA_DQ<25>")
	)
	(gr_poly
		(pts
			(xy 392.712194 -240.232184) (xy 392.712194 -240.187734) (xy 392.512042 -240.187734) (xy 392.512042 -240.232184)
			(xy 392.612118 -240.33226)
		)
		(stroke
			(width 0)
			(type solid)
		)
		(fill yes)
		(layer "In4.Cu")
		(net "M_J_CPU0_SA_DQ<26>")
	)
	(gr_poly
		(pts
			(xy 392.712194 -239.016032) (xy 392.612118 -238.915956) (xy 392.512042 -239.016032) (xy 392.512042 -239.060482)
			(xy 392.712194 -239.060482)
		)
		(stroke
			(width 0)
			(type solid)
		)
		(fill yes)
		(layer "In4.Cu")
		(net "M_J_CPU0_SA_DQ<21>")
	)
	(gr_poly
		(pts
			(xy 392.712194 -238.612172) (xy 392.712194 -238.567722) (xy 392.512042 -238.567722) (xy 392.512042 -238.612172)
			(xy 392.612118 -238.712248)
		)
		(stroke
			(width 0)
			(type solid)
		)
		(fill yes)
		(layer "In4.Cu")
		(net "M_J_CPU0_SA_DQ<22>")
	)
	(gr_poly
		(pts
			(xy 392.720576 -237.395766) (xy 392.6205 -237.29569) (xy 392.520678 -237.395766) (xy 392.520678 -237.443264)
			(xy 392.720576 -237.443264)
		)
		(stroke
			(width 0)
			(type solid)
		)
		(fill yes)
		(layer "In4.Cu")
		(net "M_J_CPU0_SA_DQS_DN<7>")
	)
	(gr_poly
		(pts
			(xy 392.763756 -236.936026) (xy 392.759692 -236.888528) (xy 392.560302 -236.906054) (xy 392.56462 -236.953552)
			(xy 392.672824 -237.044484)
		)
		(stroke
			(width 0)
			(type solid)
		)
		(fill yes)
		(layer "In4.Cu")
		(net "M_J_CPU0_SA_DQS_DN<2>")
	)
	(gr_poly
		(pts
			(xy 392.768582 -222.95231) (xy 392.732006 -222.815658) (xy 392.690604 -222.791782) (xy 392.590528 -222.96501)
			(xy 392.63193 -222.988886)
		)
		(stroke
			(width 0)
			(type solid)
		)
		(fill yes)
		(layer "In4.Cu")
		(net "M_J_CPU0_SA_DQS_DP<5>")
	)
	(gr_poly
		(pts
			(xy 392.770614 -224.568766) (xy 392.734038 -224.432114) (xy 392.695684 -224.409762) (xy 392.595608 -224.58299)
			(xy 392.634216 -224.605342)
		)
		(stroke
			(width 0)
			(type solid)
		)
		(fill yes)
		(layer "In4.Cu")
		(net "M_J_CPU0_SA_DQ<6>")
	)
	(gr_poly
		(pts
			(xy 392.933936 -295.49471) (xy 392.83386 -295.321482) (xy 392.795506 -295.343834) (xy 392.75893 -295.480486)
			(xy 392.895328 -295.517062)
		)
		(stroke
			(width 0)
			(type solid)
		)
		(fill yes)
		(layer "In4.Cu")
		(net "M_J_CPU0_SB_DQ<31>")
	)
	(gr_poly
		(pts
			(xy 392.933936 -293.874698) (xy 392.83386 -293.70147) (xy 392.795506 -293.723822) (xy 392.75893 -293.860474)
			(xy 392.895328 -293.89705)
		)
		(stroke
			(width 0)
			(type solid)
		)
		(fill yes)
		(layer "In4.Cu")
		(net "M_J_CPU0_SB_DQ<30>")
	)
	(gr_poly
		(pts
			(xy 392.93673 -270.498062) (xy 392.895582 -270.47444) (xy 392.75893 -270.511016) (xy 392.795506 -270.647414)
			(xy 392.836908 -270.67129)
		)
		(stroke
			(width 0)
			(type solid)
		)
		(fill yes)
		(layer "In4.Cu")
		(net "M_J_CPU0_SB_DQS_DP<9>")
	)
	(gr_poly
		(pts
			(xy 392.996166 -277.121366) (xy 392.996166 -277.073868) (xy 392.796014 -277.073868) (xy 392.796014 -277.121366)
			(xy 392.89609 -277.221442)
		)
		(stroke
			(width 0)
			(type solid)
		)
		(fill yes)
		(layer "In4.Cu")
		(net "M_J_CPU0_SB_DQS_DP<5>")
	)
	(gr_poly
		(pts
			(xy 393.012168 -285.22422) (xy 393.012168 -285.17977) (xy 392.812016 -285.17977) (xy 392.812016 -285.22422)
			(xy 392.912092 -285.324296)
		)
		(stroke
			(width 0)
			(type solid)
		)
		(fill yes)
		(layer "In4.Cu")
		(net "M_J_CPU0_SB_DQ<19>")
	)
	(gr_poly
		(pts
			(xy 393.012168 -283.604208) (xy 393.012168 -283.559758) (xy 392.812016 -283.559758) (xy 392.812016 -283.604208)
			(xy 392.912092 -283.704284)
		)
		(stroke
			(width 0)
			(type solid)
		)
		(fill yes)
		(layer "In4.Cu")
		(net "M_J_CPU0_SB_DQ<15>")
	)
	(gr_poly
		(pts
			(xy 393.012168 -280.364184) (xy 393.012168 -280.319734) (xy 392.812016 -280.319734) (xy 392.812016 -280.364184)
			(xy 392.912092 -280.46426)
		)
		(stroke
			(width 0)
			(type solid)
		)
		(fill yes)
		(layer "In4.Cu")
		(net "M_J_CPU0_SB_DQ<11>")
	)
	(gr_poly
		(pts
			(xy 393.012168 -278.744172) (xy 393.012168 -278.699722) (xy 392.812016 -278.699722) (xy 392.812016 -278.744172)
			(xy 392.912092 -278.844248)
		)
		(stroke
			(width 0)
			(type solid)
		)
		(fill yes)
		(layer "In4.Cu")
		(net "M_J_CPU0_SB_DQ<7>")
	)
	(gr_poly
		(pts
			(xy 393.012168 -275.504148) (xy 393.012168 -275.459698) (xy 392.812016 -275.459698) (xy 392.812016 -275.504148)
			(xy 392.912092 -275.604224)
		)
		(stroke
			(width 0)
			(type solid)
		)
		(fill yes)
		(layer "In4.Cu")
		(net "M_J_CPU0_SB_DQ<3>")
	)
	(gr_poly
		(pts
			(xy 393.012168 -273.884136) (xy 393.012168 -273.839686) (xy 392.812016 -273.839686) (xy 392.812016 -273.884136)
			(xy 392.912092 -273.984212)
		)
		(stroke
			(width 0)
			(type solid)
		)
		(fill yes)
		(layer "In4.Cu")
		(net "M_J_CPU0_SB_CB<3>")
	)
	(gr_poly
		(pts
			(xy 393.012168 -265.784076) (xy 393.012168 -265.739626) (xy 392.812016 -265.739626) (xy 392.812016 -265.784076)
			(xy 392.912092 -265.884152)
		)
		(stroke
			(width 0)
			(type solid)
		)
		(fill yes)
		(layer "In4.Cu")
		(net "M_J_CPU0_SB_CS_N<0>")
	)
	(gr_poly
		(pts
			(xy 393.012168 -264.164064) (xy 393.012168 -264.119614) (xy 392.812016 -264.119614) (xy 392.812016 -264.164064)
			(xy 392.912092 -264.26414)
		)
		(stroke
			(width 0)
			(type solid)
		)
		(fill yes)
		(layer "In4.Cu")
		(net "M_J_CPU0_SB_CA<5>")
	)
	(gr_poly
		(pts
			(xy 393.012168 -262.544052) (xy 393.012168 -262.499602) (xy 392.812016 -262.499602) (xy 392.812016 -262.544052)
			(xy 392.912092 -262.644128)
		)
		(stroke
			(width 0)
			(type solid)
		)
		(fill yes)
		(layer "In4.Cu")
		(net "M_J_CPU0_SB_CA<1>")
	)
	(gr_poly
		(pts
			(xy 393.014962 -269.42796) (xy 392.914886 -269.327884) (xy 392.81481 -269.42796) (xy 392.81481 -269.47241)
			(xy 393.014962 -269.47241)
		)
		(stroke
			(width 0)
			(type solid)
		)
		(fill yes)
		(layer "In4.Cu")
		(net "M_J_CPU0_SB_CB<5>")
	)
	(gr_poly
		(pts
			(xy 393.014962 -269.0241) (xy 393.014962 -268.97965) (xy 392.81481 -268.97965) (xy 392.81481 -269.0241)
			(xy 392.914886 -269.124176)
		)
		(stroke
			(width 0)
			(type solid)
		)
		(fill yes)
		(layer "In4.Cu")
		(net "M_J_CPU0_SB_CB<6>")
	)
	(gr_poly
		(pts
			(xy 393.026392 -290.487354) (xy 392.926316 -290.387278) (xy 392.826494 -290.487354) (xy 392.826494 -290.534852)
			(xy 393.026392 -290.534852)
		)
		(stroke
			(width 0)
			(type solid)
		)
		(fill yes)
		(layer "In4.Cu")
		(net "M_J_CPU0_SB_DQS_DP<3>")
	)
	(gr_poly
		(pts
			(xy 393.026392 -285.627572) (xy 392.926316 -285.527496) (xy 392.826494 -285.627572) (xy 392.826494 -285.67507)
			(xy 393.026392 -285.67507)
		)
		(stroke
			(width 0)
			(type solid)
		)
		(fill yes)
		(layer "In4.Cu")
		(net "M_J_CPU0_SB_DQS_DP<2>")
	)
	(gr_poly
		(pts
			(xy 393.026392 -284.00756) (xy 392.926316 -283.907484) (xy 392.826494 -284.00756) (xy 392.826494 -284.05201)
			(xy 393.026392 -284.05201)
		)
		(stroke
			(width 0)
			(type solid)
		)
		(fill yes)
		(layer "In4.Cu")
		(net "M_J_CPU0_SB_DQ<16>")
	)
	(gr_poly
		(pts
			(xy 393.026392 -282.387548) (xy 392.926316 -282.287472) (xy 392.826494 -282.387548) (xy 392.826494 -282.431998)
			(xy 393.026392 -282.431998)
		)
		(stroke
			(width 0)
			(type solid)
		)
		(fill yes)
		(layer "In4.Cu")
		(net "M_J_CPU0_SB_DQ<12>")
	)
	(gr_poly
		(pts
			(xy 393.026392 -280.767536) (xy 392.926316 -280.66746) (xy 392.826494 -280.767536) (xy 392.826494 -280.815034)
			(xy 393.026392 -280.815034)
		)
		(stroke
			(width 0)
			(type solid)
		)
		(fill yes)
		(layer "In4.Cu")
		(net "M_J_CPU0_SB_DQS_DP<1>")
	)
	(gr_poly
		(pts
			(xy 393.026392 -279.147524) (xy 392.926316 -279.047448) (xy 392.826494 -279.147524) (xy 392.826494 -279.191974)
			(xy 393.026392 -279.191974)
		)
		(stroke
			(width 0)
			(type solid)
		)
		(fill yes)
		(layer "In4.Cu")
		(net "M_J_CPU0_SB_DQ<8>")
	)
	(gr_poly
		(pts
			(xy 393.026392 -277.527512) (xy 392.926316 -277.427436) (xy 392.826494 -277.527512) (xy 392.826494 -277.571962)
			(xy 393.026392 -277.571962)
		)
		(stroke
			(width 0)
			(type solid)
		)
		(fill yes)
		(layer "In4.Cu")
		(net "M_J_CPU0_SB_DQ<4>")
	)
	(gr_poly
		(pts
			(xy 393.026392 -275.9075) (xy 392.926316 -275.807424) (xy 392.826494 -275.9075) (xy 392.826494 -275.954998)
			(xy 393.026392 -275.954998)
		)
		(stroke
			(width 0)
			(type solid)
		)
		(fill yes)
		(layer "In4.Cu")
		(net "M_J_CPU0_SB_DQS_DP<0>")
	)
	(gr_poly
		(pts
			(xy 393.026392 -274.287488) (xy 392.926316 -274.187412) (xy 392.826494 -274.287488) (xy 392.826494 -274.331938)
			(xy 393.026392 -274.331938)
		)
		(stroke
			(width 0)
			(type solid)
		)
		(fill yes)
		(layer "In4.Cu")
		(net "M_J_CPU0_SB_DQ<0>")
	)
	(gr_poly
		(pts
			(xy 393.026392 -272.667476) (xy 392.926316 -272.5674) (xy 392.826494 -272.667476) (xy 392.826494 -272.711926)
			(xy 393.026392 -272.711926)
		)
		(stroke
			(width 0)
			(type solid)
		)
		(fill yes)
		(layer "In4.Cu")
		(net "M_J_CPU0_SB_CB<0>")
	)
	(gr_poly
		(pts
			(xy 393.026392 -267.80744) (xy 392.926316 -267.707364) (xy 392.826494 -267.80744) (xy 392.826494 -267.85189)
			(xy 393.026392 -267.85189)
		)
		(stroke
			(width 0)
			(type solid)
		)
		(fill yes)
		(layer "In4.Cu")
		(net "M_J_CPU0_SB_RSP<0>")
	)
	(gr_poly
		(pts
			(xy 393.026392 -264.567416) (xy 392.926316 -264.46734) (xy 392.826494 -264.567416) (xy 392.826494 -264.611866)
			(xy 393.026392 -264.611866)
		)
		(stroke
			(width 0)
			(type solid)
		)
		(fill yes)
		(layer "In4.Cu")
		(net "M_J_CPU0_SB_CA<6>")
	)
	(gr_poly
		(pts
			(xy 393.026392 -262.947404) (xy 392.926316 -262.847328) (xy 392.826494 -262.947404) (xy 392.826494 -262.991854)
			(xy 393.026392 -262.991854)
		)
		(stroke
			(width 0)
			(type solid)
		)
		(fill yes)
		(layer "In4.Cu")
		(net "M_J_CPU0_SB_CA<2>")
	)
	(gr_poly
		(pts
			(xy 393.033758 -294.948102) (xy 393.070334 -294.81145) (xy 392.933936 -294.774874) (xy 392.895328 -294.797226)
			(xy 392.995404 -294.970454)
		)
		(stroke
			(width 0)
			(type solid)
		)
		(fill yes)
		(layer "In4.Cu")
		(net "M_J_CPU0_SB_DQ<29>")
	)
	(gr_poly
		(pts
			(xy 393.034012 -293.32809) (xy 393.070842 -293.191438) (xy 392.93419 -293.154862) (xy 392.895582 -293.177214)
			(xy 392.995658 -293.350442)
		)
		(stroke
			(width 0)
			(type solid)
		)
		(fill yes)
		(layer "In4.Cu")
		(net "M_J_CPU0_SB_DQ<28>")
	)
	(gr_poly
		(pts
			(xy 393.034012 -291.707316) (xy 393.070588 -291.570918) (xy 392.933936 -291.534088) (xy 392.892788 -291.557964)
			(xy 392.99261 -291.731192)
		)
		(stroke
			(width 0)
			(type solid)
		)
		(fill yes)
		(layer "In4.Cu")
		(net "M_J_CPU0_SB_DQS_DN<8>")
	)
	(gr_poly
		(pts
			(xy 393.070588 -271.181068) (xy 393.034012 -271.04467) (xy 392.99261 -271.020794) (xy 392.892788 -271.194022)
			(xy 392.933936 -271.217644)
		)
		(stroke
			(width 0)
			(type solid)
		)
		(fill yes)
		(layer "In4.Cu")
		(net "M_J_CPU0_SB_DQS_DN<9>")
	)
	(gr_poly
		(pts
			(xy 393.104624 -223.074484) (xy 393.066016 -223.052386) (xy 392.929364 -223.088962) (xy 392.96594 -223.225614)
			(xy 393.004548 -223.247966)
		)
		(stroke
			(width 0)
			(type solid)
		)
		(fill yes)
		(layer "In4.Cu")
		(net "M_J_CPU0_SA_DQ<4>")
	)
	(gr_poly
		(pts
			(xy 393.175998 -237.80242) (xy 393.175998 -237.754922) (xy 392.9761 -237.754922) (xy 392.9761 -237.80242)
			(xy 393.076176 -237.902496)
		)
		(stroke
			(width 0)
			(type solid)
		)
		(fill yes)
		(layer "In4.Cu")
		(net "M_J_CPU0_SA_DQS_DP<7>")
	)
	(gr_poly
		(pts
			(xy 393.194286 -254.405892) (xy 393.094464 -254.30607) (xy 392.994388 -254.405892) (xy 392.994388 -254.450342)
			(xy 393.194286 -254.450342)
		)
		(stroke
			(width 0)
			(type solid)
		)
		(fill yes)
		(layer "In4.Cu")
		(net "M_J_CPU0_SA_CA<4>")
	)
	(gr_poly
		(pts
			(xy 393.194286 -254.00254) (xy 393.194286 -253.95809) (xy 392.994388 -253.95809) (xy 392.994388 -254.00254)
			(xy 393.094464 -254.102362)
		)
		(stroke
			(width 0)
			(type solid)
		)
		(fill yes)
		(layer "In4.Cu")
		(net "M_J_CPU0_SA_CA<3>")
	)
	(gr_poly
		(pts
			(xy 393.194286 -252.78588) (xy 393.094464 -252.686058) (xy 392.994388 -252.78588) (xy 392.994388 -252.83033)
			(xy 393.194286 -252.83033)
		)
		(stroke
			(width 0)
			(type solid)
		)
		(fill yes)
		(layer "In4.Cu")
		(net "M_J_CPU0_SA_CA<0>")
	)
	(gr_poly
		(pts
			(xy 393.194286 -251.165868) (xy 393.094464 -251.066046) (xy 392.994388 -251.165868) (xy 392.994388 -251.210318)
			(xy 393.194286 -251.210318)
		)
		(stroke
			(width 0)
			(type solid)
		)
		(fill yes)
		(layer "In4.Cu")
		(net "M_J_CPU0_SA_CS_N<0>")
	)
	(gr_poly
		(pts
			(xy 393.194286 -249.142504) (xy 393.194286 -249.098054) (xy 392.994388 -249.098054) (xy 392.994388 -249.142504)
			(xy 393.094464 -249.242326)
		)
		(stroke
			(width 0)
			(type solid)
		)
		(fill yes)
		(layer "In4.Cu")
		(net "M_J_CPU0_SA_CB<7>")
	)
	(gr_poly
		(pts
			(xy 393.194286 -247.925844) (xy 393.094464 -247.826022) (xy 392.994388 -247.925844) (xy 392.994388 -247.970294)
			(xy 393.194286 -247.970294)
		)
		(stroke
			(width 0)
			(type solid)
		)
		(fill yes)
		(layer "In4.Cu")
		(net "M_J_CPU0_SA_CB<4>")
	)
	(gr_poly
		(pts
			(xy 393.194286 -245.90248) (xy 393.194286 -245.85803) (xy 392.994388 -245.85803) (xy 392.994388 -245.90248)
			(xy 393.094464 -246.002302)
		)
		(stroke
			(width 0)
			(type solid)
		)
		(fill yes)
		(layer "In4.Cu")
		(net "M_J_CPU0_SA_CB<3>")
	)
	(gr_poly
		(pts
			(xy 393.197334 -256.025904) (xy 393.097258 -255.925828) (xy 392.997182 -256.025904) (xy 392.997182 -256.073402)
			(xy 393.197334 -256.073402)
		)
		(stroke
			(width 0)
			(type solid)
		)
		(fill yes)
		(layer "In4.Cu")
		(net "M_J_CPU0_CLK_DP<0>")
	)
	(gr_poly
		(pts
			(xy 393.197334 -247.522492) (xy 393.197334 -247.474994) (xy 392.997182 -247.474994) (xy 392.997182 -247.522492)
			(xy 393.097258 -247.622568)
		)
		(stroke
			(width 0)
			(type solid)
		)
		(fill yes)
		(layer "In4.Cu")
		(net "M_J_CPU0_SA_DQS_DP<9>")
	)
	(gr_poly
		(pts
			(xy 393.197334 -246.305832) (xy 393.097258 -246.205756) (xy 392.997182 -246.305832) (xy 392.997182 -246.35333)
			(xy 393.197334 -246.35333)
		)
		(stroke
			(width 0)
			(type solid)
		)
		(fill yes)
		(layer "In4.Cu")
		(net "M_J_CPU0_SA_DQS_DP<4>")
	)
	(gr_poly
		(pts
			(xy 393.240006 -223.76003) (xy 393.20343 -223.623378) (xy 393.164822 -223.60128) (xy 393.064746 -223.774508)
			(xy 393.103354 -223.796606)
		)
		(stroke
			(width 0)
			(type solid)
		)
		(fill yes)
		(layer "In4.Cu")
		(net "M_J_CPU0_SA_DQ<6>")
	)
	(gr_poly
		(pts
			(xy 393.403836 -294.684704) (xy 393.30376 -294.511476) (xy 393.265406 -294.533828) (xy 393.22883 -294.67048)
			(xy 393.365228 -294.707056)
		)
		(stroke
			(width 0)
			(type solid)
		)
		(fill yes)
		(layer "In4.Cu")
		(net "M_J_CPU0_SB_DQ<30>")
	)
	(gr_poly
		(pts
			(xy 393.463526 -276.314662) (xy 393.463526 -276.267164) (xy 393.263628 -276.267164) (xy 393.263628 -276.314662)
			(xy 393.363704 -276.414738)
		)
		(stroke
			(width 0)
			(type solid)
		)
		(fill yes)
		(layer "In4.Cu")
		(net "M_J_CPU0_SB_DQS_DN<0>")
	)
	(gr_poly
		(pts
			(xy 393.46505 -273.074384) (xy 393.46505 -273.029934) (xy 393.265152 -273.029934) (xy 393.265152 -273.074384)
			(xy 393.365228 -273.17446)
		)
		(stroke
			(width 0)
			(type solid)
		)
		(fill yes)
		(layer "In4.Cu")
		(net "M_J_CPU0_SB_CB<2>")
	)
	(gr_poly
		(pts
			(xy 393.484862 -269.834106) (xy 393.484862 -269.789656) (xy 393.28471 -269.789656) (xy 393.28471 -269.834106)
			(xy 393.384786 -269.934182)
		)
		(stroke
			(width 0)
			(type solid)
		)
		(fill yes)
		(layer "In4.Cu")
		(net "M_J_CPU0_SB_CB<7>")
	)
	(gr_poly
		(pts
			(xy 393.503912 -294.138096) (xy 393.540742 -294.001444) (xy 393.40409 -293.964868) (xy 393.365482 -293.98722)
			(xy 393.465558 -294.160448)
		)
		(stroke
			(width 0)
			(type solid)
		)
		(fill yes)
		(layer "In4.Cu")
		(net "M_J_CPU0_SB_DQ<28>")
	)
	(gr_poly
		(pts
			(xy 393.646914 -253.595886) (xy 393.547092 -253.496064) (xy 393.447016 -253.595886) (xy 393.447016 -253.640336)
			(xy 393.646914 -253.640336)
		)
		(stroke
			(width 0)
			(type solid)
		)
		(fill yes)
		(layer "In4.Cu")
		(net "M_J_CPU0_SA_CA<2>")
	)
	(gr_poly
		(pts
			(xy 393.646914 -248.73585) (xy 393.547092 -248.636028) (xy 393.447016 -248.73585) (xy 393.447016 -248.7803)
			(xy 393.646914 -248.7803)
		)
		(stroke
			(width 0)
			(type solid)
		)
		(fill yes)
		(layer "In4.Cu")
		(net "M_J_CPU0_SA_CB<5>")
	)
	(gr_poly
		(pts
			(xy 393.646914 -245.495826) (xy 393.547092 -245.396004) (xy 393.447016 -245.495826) (xy 393.447016 -245.540276)
			(xy 393.646914 -245.540276)
		)
		(stroke
			(width 0)
			(type solid)
		)
		(fill yes)
		(layer "In4.Cu")
		(net "M_J_CPU0_SA_CB<1>")
	)
	(gr_poly
		(pts
			(xy 393.648184 -247.115584) (xy 393.548362 -247.015762) (xy 393.448286 -247.115584) (xy 393.448286 -247.163336)
			(xy 393.648184 -247.163336)
		)
		(stroke
			(width 0)
			(type solid)
		)
		(fill yes)
		(layer "In4.Cu")
		(net "M_J_CPU0_SA_DQS_DN<9>")
	)
	(gr_poly
		(pts
			(xy 393.973304 -294.946832) (xy 394.00988 -294.81018) (xy 393.873228 -294.773604) (xy 393.83462 -294.795702)
			(xy 393.934696 -294.96893)
		)
		(stroke
			(width 0)
			(type solid)
		)
		(fill yes)
		(layer "In4.Cu")
		(net "M_J_CPU0_SB_DQ<28>")
	)
	(gr_poly
		(pts
			(xy 78.526894 -224.841308) (xy 78.56347 -224.70491) (xy 78.56347 -224.704656) (xy 78.427072 -224.66808)
			(xy 78.388464 -224.690432) (xy 78.48854 -224.86366)
		)
		(stroke
			(width 0)
			(type solid)
		)
		(fill yes)
		(layer "In4.Cu")
		(net "M_D_CPU1_SA_DQ<5>")
	)
	(gr_poly
		(pts
			(xy 78.532228 -256.025904) (xy 78.432406 -255.925828) (xy 78.432152 -255.925828) (xy 78.33233 -256.025904)
			(xy 78.33233 -256.073402) (xy 78.532228 -256.073402)
		)
		(stroke
			(width 0)
			(type solid)
		)
		(fill yes)
		(layer "In4.Cu")
		(net "M_D_CPU1_CLK_DP<0>")
	)
	(gr_poly
		(pts
			(xy 78.532228 -246.305832) (xy 78.432406 -246.205756) (xy 78.432152 -246.205756) (xy 78.33233 -246.305832)
			(xy 78.33233 -246.353584) (xy 78.532228 -246.353584)
		)
		(stroke
			(width 0)
			(type solid)
		)
		(fill yes)
		(layer "In4.Cu")
		(net "M_D_CPU1_SA_DQS_DP<4>")
	)
	(gr_poly
		(pts
			(xy 79.43723 -237.80242) (xy 79.43723 -237.754922) (xy 79.237332 -237.754922) (xy 79.237332 -237.80242)
			(xy 79.337154 -237.902496) (xy 79.337408 -237.902496)
		)
		(stroke
			(width 0)
			(type solid)
		)
		(fill yes)
		(layer "In4.Cu")
		(net "M_D_CPU1_SA_DQS_DP<7>")
	)
	(gr_poly
		(pts
			(xy 79.93761 -237.396274) (xy 79.837788 -237.296198) (xy 79.837534 -237.296198) (xy 79.737712 -237.396274)
			(xy 79.737712 -237.443772) (xy 79.93761 -237.443772)
		)
		(stroke
			(width 0)
			(type solid)
		)
		(fill yes)
		(layer "In4.Cu")
		(net "M_D_CPU1_SA_DQS_DN<7>")
	)
	(gr_poly
		(pts
			(xy 92.098876 -227.717096) (xy 92.094812 -227.669598) (xy 91.986608 -227.578666) (xy 91.986354 -227.578666)
			(xy 91.895676 -227.687124) (xy 91.89974 -227.734368)
		)
		(stroke
			(width 0)
			(type solid)
		)
		(fill yes)
		(layer "In4.Cu")
		(net "M_D_CPU1_SA_DQS_DN<5>")
	)
	(gr_poly
		(pts
			(xy 142.81785 -225.505264) (xy 142.776448 -225.481388) (xy 142.64005 -225.517964) (xy 142.639796 -225.517964)
			(xy 142.676626 -225.654616) (xy 142.717774 -225.678492)
		)
		(stroke
			(width 0)
			(type solid)
		)
		(fill yes)
		(layer "In4.Cu")
		(net "M_J_CPU1_SA_DQS_DN<5>")
	)
	(gr_poly
		(pts
			(xy 142.81785 -223.885252) (xy 142.776448 -223.861376) (xy 142.64005 -223.897952) (xy 142.639796 -223.897952)
			(xy 142.676626 -224.034604) (xy 142.717774 -224.05848)
		)
		(stroke
			(width 0)
			(type solid)
		)
		(fill yes)
		(layer "In4.Cu")
		(net "M_J_CPU1_SA_DQS_DP<0>")
	)
	(gr_poly
		(pts
			(xy 142.949422 -226.191064) (xy 142.949676 -226.191064) (xy 142.912846 -226.054412) (xy 142.871698 -226.030536)
			(xy 142.771622 -226.203764) (xy 142.813024 -226.22764)
		)
		(stroke
			(width 0)
			(type solid)
		)
		(fill yes)
		(layer "In4.Cu")
		(net "M_J_CPU1_SA_DQS_DP<5>")
	)
	(gr_poly
		(pts
			(xy 142.949422 -224.571052) (xy 142.949676 -224.571052) (xy 142.912846 -224.4344) (xy 142.871698 -224.410524)
			(xy 142.771622 -224.583752) (xy 142.813024 -224.607628)
		)
		(stroke
			(width 0)
			(type solid)
		)
		(fill yes)
		(layer "In4.Cu")
		(net "M_J_CPU1_SA_DQS_DN<0>")
	)
	(gr_poly
		(pts
			(xy 326.466962 -224.841054) (xy 326.503538 -224.704656) (xy 326.503538 -224.704402) (xy 326.36714 -224.667826)
			(xy 326.328532 -224.690178) (xy 326.428608 -224.863406)
		)
		(stroke
			(width 0)
			(type solid)
		)
		(fill yes)
		(layer "In4.Cu")
		(net "M_D_CPU0_SA_DQ<5>")
	)
	(gr_poly
		(pts
			(xy 327.879456 -227.274628) (xy 327.916032 -227.13823) (xy 327.916032 -227.137976) (xy 327.77938 -227.1014)
			(xy 327.740772 -227.123752) (xy 327.840848 -227.29698)
		)
		(stroke
			(width 0)
			(type solid)
		)
		(fill yes)
		(layer "In4.Cu")
		(net "M_D_CPU0_SA_DQ<5>")
	)
	(gr_poly
		(pts
			(xy 340.038944 -227.716842) (xy 340.03488 -227.669344) (xy 339.926676 -227.578412) (xy 339.926422 -227.578412)
			(xy 339.835744 -227.68687) (xy 339.839808 -227.734368)
		)
		(stroke
			(width 0)
			(type solid)
		)
		(fill yes)
		(layer "In4.Cu")
		(net "M_D_CPU0_SA_DQS_DN<5>")
	)
	(gr_poly
		(pts
			(xy 390.757918 -225.50501) (xy 390.716516 -225.481134) (xy 390.580118 -225.517964) (xy 390.579864 -225.517964)
			(xy 390.616694 -225.654362) (xy 390.657842 -225.678238)
		)
		(stroke
			(width 0)
			(type solid)
		)
		(fill yes)
		(layer "In4.Cu")
		(net "M_J_CPU0_SA_DQS_DN<5>")
	)
	(gr_poly
		(pts
			(xy 390.757918 -223.884998) (xy 390.716516 -223.861122) (xy 390.580118 -223.897952) (xy 390.579864 -223.897952)
			(xy 390.616694 -224.03435) (xy 390.657842 -224.058226)
		)
		(stroke
			(width 0)
			(type solid)
		)
		(fill yes)
		(layer "In4.Cu")
		(net "M_J_CPU0_SA_DQS_DP<0>")
	)
	(gr_poly
		(pts
			(xy 390.88949 -226.190556) (xy 390.889744 -226.190556) (xy 390.852914 -226.054158) (xy 390.811766 -226.030282)
			(xy 390.71169 -226.20351) (xy 390.753092 -226.227386)
		)
		(stroke
			(width 0)
			(type solid)
		)
		(fill yes)
		(layer "In4.Cu")
		(net "M_J_CPU0_SA_DQS_DP<5>")
	)
	(gr_poly
		(pts
			(xy 390.88949 -224.570544) (xy 390.889744 -224.570544) (xy 390.852914 -224.434146) (xy 390.811766 -224.41027)
			(xy 390.71169 -224.583498) (xy 390.753092 -224.607374)
		)
		(stroke
			(width 0)
			(type solid)
		)
		(fill yes)
		(layer "In4.Cu")
		(net "M_J_CPU0_SA_DQS_DN<0>")
	)
	(gr_poly
		(pts
			(xy 392.230864 -236.602016) (xy 392.131042 -236.50194) (xy 392.130788 -236.50194) (xy 392.030966 -236.602016)
			(xy 392.030966 -236.649514) (xy 392.230864 -236.649514)
		)
		(stroke
			(width 0)
			(type solid)
		)
		(fill yes)
		(layer "In4.Cu")
		(net "M_J_CPU0_SA_DQS_DP<2>")
	)
	(gr_poly
		(pts
			(xy 393.006834 -281.98445) (xy 393.006834 -281.936698) (xy 392.806936 -281.936698) (xy 392.806936 -281.98445)
			(xy 392.906758 -282.084272) (xy 392.907012 -282.084272)
		)
		(stroke
			(width 0)
			(type solid)
		)
		(fill yes)
		(layer "In4.Cu")
		(net "M_J_CPU0_SB_DQS_DP<6>")
	)
	(gr_poly
		(pts
			(xy 404.143972 -318.199008) (xy 404.143972 -316.039246) (xy 403.091142 -314.986416) (xy 394.941552 -314.986416)
			(xy 394.802106 -315.125862) (xy 394.802106 -317.75654) (xy 395.678406 -318.63284) (xy 403.71014 -318.63284)
		)
		(stroke
			(width 0)
			(type solid)
		)
		(fill yes)
		(layer "In4.Cu")
		(net "GND")
	)
	(gr_poly
		(pts
			(xy 8.62076 -102.117144) (xy 8.878824 -101.85908) (xy 8.878824 -97.439734) (xy 8.678672 -97.239582)
			(xy 5.757672 -97.239582) (xy 5.084572 -97.912682) (xy 5.084572 -101.669088) (xy 5.65785 -102.242366)
			(xy 8.495538 -102.242366)
		)
		(stroke
			(width 0)
			(type solid)
		)
		(fill yes)
		(layer "In4.Cu")
		(net "GND")
	)
	(gr_poly
		(pts
			(xy 108.331 -23.9268) (xy 108.331 -20.6756) (xy 107.4928 -19.8374) (xy 105.204768 -19.8374) (xy 104.726486 -20.315682)
			(xy 104.726486 -24.051768) (xy 104.8258 -24.151082) (xy 107.850686 -24.151082) (xy 108.106718 -24.151082)
		)
		(stroke
			(width 0)
			(type solid)
		)
		(fill yes)
		(layer "In4.Cu")
		(net "GND")
	)
	(gr_poly
		(pts
			(xy 126.0094 -30.353) (xy 126.0094 -26.8478) (xy 125.8316 -26.67) (xy 123.693682 -26.67) (xy 123.0884 -27.275282)
			(xy 123.079764 -27.275282) (xy 123.079764 -30.27299) (xy 123.2408 -30.434026) (xy 125.840236 -30.434026)
			(xy 125.928374 -30.434026)
		)
		(stroke
			(width 0)
			(type solid)
		)
		(fill yes)
		(layer "In4.Cu")
		(net "GND")
	)
	(gr_poly
		(pts
			(xy 312.3692 -362.88853) (xy 312.3692 -358.6734) (xy 312.3692 -358.4702) (xy 312.3438 -358.4448)
			(xy 307.9496 -358.4448) (xy 307.899308 -358.495092) (xy 307.899308 -358.657144) (xy 307.899308 -362.889292)
			(xy 307.9242 -362.91393) (xy 312.3438 -362.91393)
		)
		(stroke
			(width 0)
			(type solid)
		)
		(fill yes)
		(layer "In4.Cu")
		(net "GND")
	)
	(gr_poly
		(pts
			(xy 441.045092 -43.578018) (xy 441.045092 -43.451018) (xy 441.045092 -38.853618) (xy 440.918092 -38.726618)
			(xy 434.288692 -38.726618) (xy 433.780692 -38.726618) (xy 433.628292 -38.879018) (xy 433.628292 -43.001946)
			(xy 433.628292 -43.618658) (xy 433.780692 -43.771058) (xy 438.893458 -43.771058) (xy 440.852052 -43.771058)
		)
		(stroke
			(width 0)
			(type solid)
		)
		(fill yes)
		(layer "In4.Cu")
		(net "P12V_AUX")
	)
	(gr_poly
		(pts
			(xy 155.952952 -319.820798) (xy 155.952952 -316.907418) (xy 155.693364 -316.64783) (xy 151.944832 -316.64783)
			(xy 151.40559 -316.108588) (xy 151.40559 -315.483494) (xy 151.140414 -315.218318) (xy 147.148804 -315.218318)
			(xy 147.023582 -315.34354) (xy 146.703796 -315.663326) (xy 146.703796 -318.473074) (xy 147.209256 -318.978534)
			(xy 150.965154 -318.978534) (xy 151.2951 -319.30848) (xy 151.2951 -319.870074) (xy 151.382476 -319.95745)
			(xy 151.549608 -319.95745) (xy 155.8163 -319.95745)
		)
		(stroke
			(width 0)
			(type solid)
		)
		(fill yes)
		(layer "In4.Cu")
		(net "GND")
	)
	(gr_poly
		(pts
			(xy 4.051554 -398.108424)
			(arc
				(start 9.90219 -392.257788)
				(mid 9.913301 -392.241254)
				(end 9.917176 -392.22172)
			)
			(arc
				(start 9.917176 -388.822184)
				(mid 9.913275 -388.802661)
				(end 9.90219 -388.786116)
			)
			(arc
				(start 4.062476 -382.946656)
				(mid 4.036485 -382.93265)
				(end 4.007104 -382.93548)
			)
			(xy 3.99288 -382.941576) (xy 3.975862 -382.966722)
			(arc
				(start 3.975862 -398.061434)
				(mid 3.984399 -398.089621)
				(end 4.007104 -398.108424)
			)
			(xy 4.021582 -398.114266)
		)
		(stroke
			(width 0)
			(type solid)
		)
		(fill yes)
		(layer "In4.Cu")
		(net "GND")
	)
	(gr_poly
		(pts
			(arc
				(start 9.889744 -421.400986)
				(mid 9.630664 -421.400986)
				(end 9.889744 -421.400986)
			)
		)
		(stroke
			(width 0)
			(type solid)
		)
		(fill yes)
		(layer "In4.Cu")
		(net "GND")
	)
	(gr_poly
		(pts
			(arc
				(start 9.889744 -420.136066)
				(mid 9.630664 -420.136066)
				(end 9.889744 -420.136066)
			)
		)
		(stroke
			(width 0)
			(type solid)
		)
		(fill yes)
		(layer "In4.Cu")
		(net "GND")
	)
	(gr_poly
		(pts
			(arc
				(start 11.453622 -426.113702)
				(mid 11.194542 -426.113702)
				(end 11.453622 -426.113702)
			)
		)
		(stroke
			(width 0)
			(type solid)
		)
		(fill yes)
		(layer "In4.Cu")
		(net "GND")
	)
	(gr_poly
		(pts
			(arc
				(start 11.453622 -424.797982)
				(mid 11.194542 -424.797982)
				(end 11.453622 -424.797982)
			)
		)
		(stroke
			(width 0)
			(type solid)
		)
		(fill yes)
		(layer "In4.Cu")
		(net "GND")
	)
	(gr_poly
		(pts
			(arc
				(start 20.32254 -436.9943)
				(mid 20.06346 -436.9943)
				(end 20.32254 -436.9943)
			)
		)
		(stroke
			(width 0)
			(type solid)
		)
		(fill yes)
		(layer "In4.Cu")
		(net "GND")
	)
	(gr_poly
		(pts
			(arc
				(start 20.44954 -432.4223)
				(mid 20.19046 -432.4223)
				(end 20.44954 -432.4223)
			)
		)
		(stroke
			(width 0)
			(type solid)
		)
		(fill yes)
		(layer "In4.Cu")
		(net "GND")
	)
	(gr_poly
		(pts
			(arc
				(start 21.2979 -421.470582)
				(mid 21.03882 -421.470582)
				(end 21.2979 -421.470582)
			)
		)
		(stroke
			(width 0)
			(type solid)
		)
		(fill yes)
		(layer "In4.Cu")
		(net "GND")
	)
	(gr_poly
		(pts
			(arc
				(start 21.2979 -420.205662)
				(mid 21.03882 -420.205662)
				(end 21.2979 -420.205662)
			)
		)
		(stroke
			(width 0)
			(type solid)
		)
		(fill yes)
		(layer "In4.Cu")
		(net "GND")
	)
	(gr_poly
		(pts
			(arc
				(start 21.81987 -425.528994)
				(mid 21.56079 -425.528994)
				(end 21.81987 -425.528994)
			)
		)
		(stroke
			(width 0)
			(type solid)
		)
		(fill yes)
		(layer "In4.Cu")
		(net "GND")
	)
	(gr_poly
		(pts
			(arc
				(start 21.81987 -424.264074)
				(mid 21.56079 -424.264074)
				(end 21.81987 -424.264074)
			)
		)
		(stroke
			(width 0)
			(type solid)
		)
		(fill yes)
		(layer "In4.Cu")
		(net "GND")
	)
	(gr_poly
		(pts
			(arc
				(start 23.758906 -433.12715)
				(mid 23.499826 -433.12715)
				(end 23.758906 -433.12715)
			)
		)
		(stroke
			(width 0)
			(type solid)
		)
		(fill yes)
		(layer "In4.Cu")
		(net "GND")
	)
	(gr_poly
		(pts
			(arc
				(start 24.941022 -437.509158)
				(mid 24.681942 -437.509158)
				(end 24.941022 -437.509158)
			)
		)
		(stroke
			(width 0)
			(type solid)
		)
		(fill yes)
		(layer "In4.Cu")
		(net "GND")
	)
	(gr_poly
		(pts
			(arc
				(start 26.022046 -422.332912)
				(mid 25.762966 -422.332912)
				(end 26.022046 -422.332912)
			)
		)
		(stroke
			(width 0)
			(type solid)
		)
		(fill yes)
		(layer "In4.Cu")
		(net "GND")
	)
	(gr_poly
		(pts
			(arc
				(start 26.022046 -421.066468)
				(mid 25.762966 -421.066468)
				(end 26.022046 -421.066468)
			)
		)
		(stroke
			(width 0)
			(type solid)
		)
		(fill yes)
		(layer "In4.Cu")
		(net "GND")
	)
	(gr_poly
		(pts
			(arc
				(start 26.099262 -429.072802)
				(mid 25.840182 -429.072802)
				(end 26.099262 -429.072802)
			)
		)
		(stroke
			(width 0)
			(type solid)
		)
		(fill yes)
		(layer "In4.Cu")
		(net "GND")
	)
	(gr_poly
		(pts
			(arc
				(start 26.099262 -427.294802)
				(mid 25.840182 -427.294802)
				(end 26.099262 -427.294802)
			)
		)
		(stroke
			(width 0)
			(type solid)
		)
		(fill yes)
		(layer "In4.Cu")
		(net "GND")
	)
	(gr_poly
		(pts
			(arc
				(start 26.817066 -428.183802)
				(mid 26.557986 -428.183802)
				(end 26.817066 -428.183802)
			)
		)
		(stroke
			(width 0)
			(type solid)
		)
		(fill yes)
		(layer "In4.Cu")
		(net "GND")
	)
	(gr_poly
		(pts
			(arc
				(start 27.199082 -421.69969)
				(mid 26.940002 -421.69969)
				(end 27.199082 -421.69969)
			)
		)
		(stroke
			(width 0)
			(type solid)
		)
		(fill yes)
		(layer "In4.Cu")
		(net "GND")
	)
	(gr_poly
		(pts
			(arc
				(start 28.950666 -428.183802)
				(mid 28.691586 -428.183802)
				(end 28.950666 -428.183802)
			)
		)
		(stroke
			(width 0)
			(type solid)
		)
		(fill yes)
		(layer "In4.Cu")
		(net "GND")
	)
	(gr_poly
		(pts
			(arc
				(start 29.332682 -421.69969)
				(mid 29.073602 -421.69969)
				(end 29.332682 -421.69969)
			)
		)
		(stroke
			(width 0)
			(type solid)
		)
		(fill yes)
		(layer "In4.Cu")
		(net "GND")
	)
	(gr_poly
		(pts
			(arc
				(start 31.906718 -432.477164)
				(mid 31.647638 -432.477164)
				(end 31.906718 -432.477164)
			)
		)
		(stroke
			(width 0)
			(type solid)
		)
		(fill yes)
		(layer "In4.Cu")
		(net "GND")
	)
	(gr_poly
		(pts
			(arc
				(start 33.14954 -436.7403)
				(mid 32.89046 -436.7403)
				(end 33.14954 -436.7403)
			)
		)
		(stroke
			(width 0)
			(type solid)
		)
		(fill yes)
		(layer "In4.Cu")
		(net "GND")
	)
	(gr_poly
		(pts
			(arc
				(start 35.88639 -416.06089)
				(mid 35.62731 -416.06089)
				(end 35.88639 -416.06089)
			)
		)
		(stroke
			(width 0)
			(type solid)
		)
		(fill yes)
		(layer "In4.Cu")
		(net "GND")
	)
	(gr_poly
		(pts
			(arc
				(start 38.61308 -425.909994)
				(mid 38.354 -425.909994)
				(end 38.61308 -425.909994)
			)
		)
		(stroke
			(width 0)
			(type solid)
		)
		(fill yes)
		(layer "In4.Cu")
		(net "GND")
	)
	(gr_poly
		(pts
			(arc
				(start 38.638734 -422.638982)
				(mid 38.379654 -422.638982)
				(end 38.638734 -422.638982)
			)
		)
		(stroke
			(width 0)
			(type solid)
		)
		(fill yes)
		(layer "In4.Cu")
		(net "GND")
	)
	(gr_poly
		(pts
			(arc
				(start 38.851586 -413.646112)
				(mid 38.592506 -413.646112)
				(end 38.851586 -413.646112)
			)
		)
		(stroke
			(width 0)
			(type solid)
		)
		(fill yes)
		(layer "In4.Cu")
		(net "GND")
	)
	(gr_poly
		(pts
			(arc
				(start 38.851586 -412.387288)
				(mid 38.592506 -412.387288)
				(end 38.851586 -412.387288)
			)
		)
		(stroke
			(width 0)
			(type solid)
		)
		(fill yes)
		(layer "In4.Cu")
		(net "GND")
	)
	(gr_poly
		(pts
			(arc
				(start 40.74668 -425.909994)
				(mid 40.4876 -425.909994)
				(end 40.74668 -425.909994)
			)
		)
		(stroke
			(width 0)
			(type solid)
		)
		(fill yes)
		(layer "In4.Cu")
		(net "GND")
	)
	(gr_poly
		(pts
			(arc
				(start 40.772334 -422.638982)
				(mid 40.513254 -422.638982)
				(end 40.772334 -422.638982)
			)
		)
		(stroke
			(width 0)
			(type solid)
		)
		(fill yes)
		(layer "In4.Cu")
		(net "GND")
	)
	(gr_poly
		(pts
			(arc
				(start 41.084246 -415.581338)
				(mid 40.825166 -415.581338)
				(end 41.084246 -415.581338)
			)
		)
		(stroke
			(width 0)
			(type solid)
		)
		(fill yes)
		(layer "In4.Cu")
		(net "GND")
	)
	(gr_poly
		(pts
			(arc
				(start 41.084246 -414.322514)
				(mid 40.825166 -414.322514)
				(end 41.084246 -414.322514)
			)
		)
		(stroke
			(width 0)
			(type solid)
		)
		(fill yes)
		(layer "In4.Cu")
		(net "GND")
	)
	(gr_poly
		(pts
			(arc
				(start 41.4909 -425.265088)
				(mid 41.23182 -425.265088)
				(end 41.4909 -425.265088)
			)
		)
		(stroke
			(width 0)
			(type solid)
		)
		(fill yes)
		(layer "In4.Cu")
		(net "GND")
	)
	(gr_poly
		(pts
			(arc
				(start 41.492932 -426.556678)
				(mid 41.233852 -426.556678)
				(end 41.492932 -426.556678)
			)
		)
		(stroke
			(width 0)
			(type solid)
		)
		(fill yes)
		(layer "In4.Cu")
		(net "GND")
	)
	(gr_poly
		(pts
			(arc
				(start 41.53027 -421.989758)
				(mid 41.27119 -421.989758)
				(end 41.53027 -421.989758)
			)
		)
		(stroke
			(width 0)
			(type solid)
		)
		(fill yes)
		(layer "In4.Cu")
		(net "GND")
	)
	(gr_poly
		(pts
			(arc
				(start 41.532302 -423.281348)
				(mid 41.273222 -423.281348)
				(end 41.532302 -423.281348)
			)
		)
		(stroke
			(width 0)
			(type solid)
		)
		(fill yes)
		(layer "In4.Cu")
		(net "GND")
	)
	(gr_poly
		(pts
			(arc
				(start 47.364904 -412.570168)
				(mid 47.105824 -412.570168)
				(end 47.364904 -412.570168)
			)
		)
		(stroke
			(width 0)
			(type solid)
		)
		(fill yes)
		(layer "In4.Cu")
		(net "GND")
	)
	(gr_poly
		(pts
			(arc
				(start 47.364904 -404.46452)
				(mid 47.105824 -404.46452)
				(end 47.364904 -404.46452)
			)
		)
		(stroke
			(width 0)
			(type solid)
		)
		(fill yes)
		(layer "In4.Cu")
		(net "GND")
	)
	(gr_poly
		(pts
			(arc
				(start 47.726092 -413.204152)
				(mid 47.467012 -413.204152)
				(end 47.726092 -413.204152)
			)
		)
		(stroke
			(width 0)
			(type solid)
		)
		(fill yes)
		(layer "In4.Cu")
		(net "GND")
	)
	(gr_poly
		(pts
			(arc
				(start 47.726092 -411.936184)
				(mid 47.467012 -411.936184)
				(end 47.726092 -411.936184)
			)
		)
		(stroke
			(width 0)
			(type solid)
		)
		(fill yes)
		(layer "In4.Cu")
		(net "GND")
	)
	(gr_poly
		(pts
			(arc
				(start 47.726092 -405.098504)
				(mid 47.467012 -405.098504)
				(end 47.726092 -405.098504)
			)
		)
		(stroke
			(width 0)
			(type solid)
		)
		(fill yes)
		(layer "In4.Cu")
		(net "GND")
	)
	(gr_poly
		(pts
			(arc
				(start 47.726092 -403.830536)
				(mid 47.467012 -403.830536)
				(end 47.726092 -403.830536)
			)
		)
		(stroke
			(width 0)
			(type solid)
		)
		(fill yes)
		(layer "In4.Cu")
		(net "GND")
	)
	(gr_poly
		(pts
			(arc
				(start 48.896524 -410.030168)
				(mid 48.637444 -410.030168)
				(end 48.896524 -410.030168)
			)
		)
		(stroke
			(width 0)
			(type solid)
		)
		(fill yes)
		(layer "In4.Cu")
		(net "GND")
	)
	(gr_poly
		(pts
			(arc
				(start 48.896524 -407.00452)
				(mid 48.637444 -407.00452)
				(end 48.896524 -407.00452)
			)
		)
		(stroke
			(width 0)
			(type solid)
		)
		(fill yes)
		(layer "In4.Cu")
		(net "GND")
	)
	(gr_poly
		(pts
			(arc
				(start 48.984916 -413.204152)
				(mid 48.725836 -413.204152)
				(end 48.984916 -413.204152)
			)
		)
		(stroke
			(width 0)
			(type solid)
		)
		(fill yes)
		(layer "In4.Cu")
		(net "GND")
	)
	(gr_poly
		(pts
			(arc
				(start 48.984916 -411.936184)
				(mid 48.725836 -411.936184)
				(end 48.984916 -411.936184)
			)
		)
		(stroke
			(width 0)
			(type solid)
		)
		(fill yes)
		(layer "In4.Cu")
		(net "GND")
	)
	(gr_poly
		(pts
			(arc
				(start 48.984916 -405.098504)
				(mid 48.725836 -405.098504)
				(end 48.984916 -405.098504)
			)
		)
		(stroke
			(width 0)
			(type solid)
		)
		(fill yes)
		(layer "In4.Cu")
		(net "GND")
	)
	(gr_poly
		(pts
			(arc
				(start 48.984916 -403.830536)
				(mid 48.725836 -403.830536)
				(end 48.984916 -403.830536)
			)
		)
		(stroke
			(width 0)
			(type solid)
		)
		(fill yes)
		(layer "In4.Cu")
		(net "GND")
	)
	(gr_poly
		(pts
			(arc
				(start 49.257712 -410.664152)
				(mid 48.998632 -410.664152)
				(end 49.257712 -410.664152)
			)
		)
		(stroke
			(width 0)
			(type solid)
		)
		(fill yes)
		(layer "In4.Cu")
		(net "GND")
	)
	(gr_poly
		(pts
			(arc
				(start 49.257712 -409.396184)
				(mid 48.998632 -409.396184)
				(end 49.257712 -409.396184)
			)
		)
		(stroke
			(width 0)
			(type solid)
		)
		(fill yes)
		(layer "In4.Cu")
		(net "GND")
	)
	(gr_poly
		(pts
			(arc
				(start 49.257712 -407.638504)
				(mid 48.998632 -407.638504)
				(end 49.257712 -407.638504)
			)
		)
		(stroke
			(width 0)
			(type solid)
		)
		(fill yes)
		(layer "In4.Cu")
		(net "GND")
	)
	(gr_poly
		(pts
			(arc
				(start 49.257712 -406.370536)
				(mid 48.998632 -406.370536)
				(end 49.257712 -406.370536)
			)
		)
		(stroke
			(width 0)
			(type solid)
		)
		(fill yes)
		(layer "In4.Cu")
		(net "GND")
	)
	(gr_poly
		(pts
			(arc
				(start 49.346104 -412.570168)
				(mid 49.087024 -412.570168)
				(end 49.346104 -412.570168)
			)
		)
		(stroke
			(width 0)
			(type solid)
		)
		(fill yes)
		(layer "In4.Cu")
		(net "GND")
	)
	(gr_poly
		(pts
			(arc
				(start 49.346104 -404.46452)
				(mid 49.087024 -404.46452)
				(end 49.346104 -404.46452)
			)
		)
		(stroke
			(width 0)
			(type solid)
		)
		(fill yes)
		(layer "In4.Cu")
		(net "GND")
	)
	(gr_poly
		(pts
			(arc
				(start 49.787556 -417.921186)
				(mid 49.528476 -417.921186)
				(end 49.787556 -417.921186)
			)
		)
		(stroke
			(width 0)
			(type solid)
		)
		(fill yes)
		(layer "In4.Cu")
		(net "GND")
	)
	(gr_poly
		(pts
			(arc
				(start 49.934114 -416.394646)
				(mid 49.675034 -416.394646)
				(end 49.934114 -416.394646)
			)
		)
		(stroke
			(width 0)
			(type solid)
		)
		(fill yes)
		(layer "In4.Cu")
		(net "GND")
	)
	(gr_poly
		(pts
			(arc
				(start 50.428144 -412.570168)
				(mid 50.169064 -412.570168)
				(end 50.428144 -412.570168)
			)
		)
		(stroke
			(width 0)
			(type solid)
		)
		(fill yes)
		(layer "In4.Cu")
		(net "GND")
	)
	(gr_poly
		(pts
			(arc
				(start 50.428144 -404.46452)
				(mid 50.169064 -404.46452)
				(end 50.428144 -404.46452)
			)
		)
		(stroke
			(width 0)
			(type solid)
		)
		(fill yes)
		(layer "In4.Cu")
		(net "GND")
	)
	(gr_poly
		(pts
			(arc
				(start 50.516536 -410.664152)
				(mid 50.257456 -410.664152)
				(end 50.516536 -410.664152)
			)
		)
		(stroke
			(width 0)
			(type solid)
		)
		(fill yes)
		(layer "In4.Cu")
		(net "GND")
	)
	(gr_poly
		(pts
			(arc
				(start 50.516536 -409.396184)
				(mid 50.257456 -409.396184)
				(end 50.516536 -409.396184)
			)
		)
		(stroke
			(width 0)
			(type solid)
		)
		(fill yes)
		(layer "In4.Cu")
		(net "GND")
	)
	(gr_poly
		(pts
			(arc
				(start 50.516536 -407.638504)
				(mid 50.257456 -407.638504)
				(end 50.516536 -407.638504)
			)
		)
		(stroke
			(width 0)
			(type solid)
		)
		(fill yes)
		(layer "In4.Cu")
		(net "GND")
	)
	(gr_poly
		(pts
			(arc
				(start 50.516536 -406.370536)
				(mid 50.257456 -406.370536)
				(end 50.516536 -406.370536)
			)
		)
		(stroke
			(width 0)
			(type solid)
		)
		(fill yes)
		(layer "In4.Cu")
		(net "GND")
	)
	(gr_poly
		(pts
			(arc
				(start 50.789332 -413.204152)
				(mid 50.530252 -413.204152)
				(end 50.789332 -413.204152)
			)
		)
		(stroke
			(width 0)
			(type solid)
		)
		(fill yes)
		(layer "In4.Cu")
		(net "GND")
	)
	(gr_poly
		(pts
			(arc
				(start 50.789332 -411.936184)
				(mid 50.530252 -411.936184)
				(end 50.789332 -411.936184)
			)
		)
		(stroke
			(width 0)
			(type solid)
		)
		(fill yes)
		(layer "In4.Cu")
		(net "GND")
	)
	(gr_poly
		(pts
			(arc
				(start 50.789332 -405.098504)
				(mid 50.530252 -405.098504)
				(end 50.789332 -405.098504)
			)
		)
		(stroke
			(width 0)
			(type solid)
		)
		(fill yes)
		(layer "In4.Cu")
		(net "GND")
	)
	(gr_poly
		(pts
			(arc
				(start 50.789332 -403.830536)
				(mid 50.530252 -403.830536)
				(end 50.789332 -403.830536)
			)
		)
		(stroke
			(width 0)
			(type solid)
		)
		(fill yes)
		(layer "In4.Cu")
		(net "GND")
	)
	(gr_poly
		(pts
			(arc
				(start 50.877724 -410.030168)
				(mid 50.618644 -410.030168)
				(end 50.877724 -410.030168)
			)
		)
		(stroke
			(width 0)
			(type solid)
		)
		(fill yes)
		(layer "In4.Cu")
		(net "GND")
	)
	(gr_poly
		(pts
			(arc
				(start 50.877724 -407.00452)
				(mid 50.618644 -407.00452)
				(end 50.877724 -407.00452)
			)
		)
		(stroke
			(width 0)
			(type solid)
		)
		(fill yes)
		(layer "In4.Cu")
		(net "GND")
	)
	(gr_poly
		(pts
			(arc
				(start 51.89474 -418.295328)
				(mid 51.63566 -418.295328)
				(end 51.89474 -418.295328)
			)
		)
		(stroke
			(width 0)
			(type solid)
		)
		(fill yes)
		(layer "In4.Cu")
		(net "GND")
	)
	(gr_poly
		(pts
			(arc
				(start 51.959764 -410.030168)
				(mid 51.700684 -410.030168)
				(end 51.959764 -410.030168)
			)
		)
		(stroke
			(width 0)
			(type solid)
		)
		(fill yes)
		(layer "In4.Cu")
		(net "GND")
	)
	(gr_poly
		(pts
			(arc
				(start 51.959764 -407.00452)
				(mid 51.700684 -407.00452)
				(end 51.959764 -407.00452)
			)
		)
		(stroke
			(width 0)
			(type solid)
		)
		(fill yes)
		(layer "In4.Cu")
		(net "GND")
	)
	(gr_poly
		(pts
			(arc
				(start 52.048156 -413.204152)
				(mid 51.789076 -413.204152)
				(end 52.048156 -413.204152)
			)
		)
		(stroke
			(width 0)
			(type solid)
		)
		(fill yes)
		(layer "In4.Cu")
		(net "GND")
	)
	(gr_poly
		(pts
			(arc
				(start 52.048156 -411.936184)
				(mid 51.789076 -411.936184)
				(end 52.048156 -411.936184)
			)
		)
		(stroke
			(width 0)
			(type solid)
		)
		(fill yes)
		(layer "In4.Cu")
		(net "GND")
	)
	(gr_poly
		(pts
			(arc
				(start 52.048156 -405.098504)
				(mid 51.789076 -405.098504)
				(end 52.048156 -405.098504)
			)
		)
		(stroke
			(width 0)
			(type solid)
		)
		(fill yes)
		(layer "In4.Cu")
		(net "GND")
	)
	(gr_poly
		(pts
			(arc
				(start 52.048156 -403.830536)
				(mid 51.789076 -403.830536)
				(end 52.048156 -403.830536)
			)
		)
		(stroke
			(width 0)
			(type solid)
		)
		(fill yes)
		(layer "In4.Cu")
		(net "GND")
	)
	(gr_poly
		(pts
			(arc
				(start 52.320952 -410.664152)
				(mid 52.061872 -410.664152)
				(end 52.320952 -410.664152)
			)
		)
		(stroke
			(width 0)
			(type solid)
		)
		(fill yes)
		(layer "In4.Cu")
		(net "GND")
	)
	(gr_poly
		(pts
			(arc
				(start 52.320952 -409.396184)
				(mid 52.061872 -409.396184)
				(end 52.320952 -409.396184)
			)
		)
		(stroke
			(width 0)
			(type solid)
		)
		(fill yes)
		(layer "In4.Cu")
		(net "GND")
	)
	(gr_poly
		(pts
			(arc
				(start 52.320952 -407.638504)
				(mid 52.061872 -407.638504)
				(end 52.320952 -407.638504)
			)
		)
		(stroke
			(width 0)
			(type solid)
		)
		(fill yes)
		(layer "In4.Cu")
		(net "GND")
	)
	(gr_poly
		(pts
			(arc
				(start 52.320952 -406.370536)
				(mid 52.061872 -406.370536)
				(end 52.320952 -406.370536)
			)
		)
		(stroke
			(width 0)
			(type solid)
		)
		(fill yes)
		(layer "In4.Cu")
		(net "GND")
	)
	(gr_poly
		(pts
			(arc
				(start 52.409344 -412.570168)
				(mid 52.150264 -412.570168)
				(end 52.409344 -412.570168)
			)
		)
		(stroke
			(width 0)
			(type solid)
		)
		(fill yes)
		(layer "In4.Cu")
		(net "GND")
	)
	(gr_poly
		(pts
			(arc
				(start 52.409344 -404.46452)
				(mid 52.150264 -404.46452)
				(end 52.409344 -404.46452)
			)
		)
		(stroke
			(width 0)
			(type solid)
		)
		(fill yes)
		(layer "In4.Cu")
		(net "GND")
	)
	(gr_poly
		(pts
			(arc
				(start 52.953412 -419.89502)
				(mid 52.694332 -419.89502)
				(end 52.953412 -419.89502)
			)
		)
		(stroke
			(width 0)
			(type solid)
		)
		(fill yes)
		(layer "In4.Cu")
		(net "GND")
	)
	(gr_poly
		(pts
			(arc
				(start 53.491384 -412.570168)
				(mid 53.232304 -412.570168)
				(end 53.491384 -412.570168)
			)
		)
		(stroke
			(width 0)
			(type solid)
		)
		(fill yes)
		(layer "In4.Cu")
		(net "GND")
	)
	(gr_poly
		(pts
			(arc
				(start 53.491384 -404.46452)
				(mid 53.232304 -404.46452)
				(end 53.491384 -404.46452)
			)
		)
		(stroke
			(width 0)
			(type solid)
		)
		(fill yes)
		(layer "In4.Cu")
		(net "GND")
	)
	(gr_poly
		(pts
			(arc
				(start 53.579776 -410.664152)
				(mid 53.320696 -410.664152)
				(end 53.579776 -410.664152)
			)
		)
		(stroke
			(width 0)
			(type solid)
		)
		(fill yes)
		(layer "In4.Cu")
		(net "GND")
	)
	(gr_poly
		(pts
			(arc
				(start 53.579776 -409.396184)
				(mid 53.320696 -409.396184)
				(end 53.579776 -409.396184)
			)
		)
		(stroke
			(width 0)
			(type solid)
		)
		(fill yes)
		(layer "In4.Cu")
		(net "GND")
	)
	(gr_poly
		(pts
			(arc
				(start 53.579776 -407.638504)
				(mid 53.320696 -407.638504)
				(end 53.579776 -407.638504)
			)
		)
		(stroke
			(width 0)
			(type solid)
		)
		(fill yes)
		(layer "In4.Cu")
		(net "GND")
	)
	(gr_poly
		(pts
			(arc
				(start 53.579776 -406.370536)
				(mid 53.320696 -406.370536)
				(end 53.579776 -406.370536)
			)
		)
		(stroke
			(width 0)
			(type solid)
		)
		(fill yes)
		(layer "In4.Cu")
		(net "GND")
	)
	(gr_poly
		(pts
			(arc
				(start 53.852572 -413.204152)
				(mid 53.593492 -413.204152)
				(end 53.852572 -413.204152)
			)
		)
		(stroke
			(width 0)
			(type solid)
		)
		(fill yes)
		(layer "In4.Cu")
		(net "GND")
	)
	(gr_poly
		(pts
			(arc
				(start 53.852572 -411.936184)
				(mid 53.593492 -411.936184)
				(end 53.852572 -411.936184)
			)
		)
		(stroke
			(width 0)
			(type solid)
		)
		(fill yes)
		(layer "In4.Cu")
		(net "GND")
	)
	(gr_poly
		(pts
			(arc
				(start 53.852572 -405.098504)
				(mid 53.593492 -405.098504)
				(end 53.852572 -405.098504)
			)
		)
		(stroke
			(width 0)
			(type solid)
		)
		(fill yes)
		(layer "In4.Cu")
		(net "GND")
	)
	(gr_poly
		(pts
			(arc
				(start 53.852572 -403.830536)
				(mid 53.593492 -403.830536)
				(end 53.852572 -403.830536)
			)
		)
		(stroke
			(width 0)
			(type solid)
		)
		(fill yes)
		(layer "In4.Cu")
		(net "GND")
	)
	(gr_poly
		(pts
			(arc
				(start 53.940964 -410.030168)
				(mid 53.681884 -410.030168)
				(end 53.940964 -410.030168)
			)
		)
		(stroke
			(width 0)
			(type solid)
		)
		(fill yes)
		(layer "In4.Cu")
		(net "GND")
	)
	(gr_poly
		(pts
			(arc
				(start 53.940964 -407.00452)
				(mid 53.681884 -407.00452)
				(end 53.940964 -407.00452)
			)
		)
		(stroke
			(width 0)
			(type solid)
		)
		(fill yes)
		(layer "In4.Cu")
		(net "GND")
	)
	(gr_poly
		(pts
			(arc
				(start 55.023004 -410.030168)
				(mid 54.763924 -410.030168)
				(end 55.023004 -410.030168)
			)
		)
		(stroke
			(width 0)
			(type solid)
		)
		(fill yes)
		(layer "In4.Cu")
		(net "GND")
	)
	(gr_poly
		(pts
			(arc
				(start 55.023004 -407.00452)
				(mid 54.763924 -407.00452)
				(end 55.023004 -407.00452)
			)
		)
		(stroke
			(width 0)
			(type solid)
		)
		(fill yes)
		(layer "In4.Cu")
		(net "GND")
	)
	(gr_poly
		(pts
			(arc
				(start 55.111396 -413.204152)
				(mid 54.852316 -413.204152)
				(end 55.111396 -413.204152)
			)
		)
		(stroke
			(width 0)
			(type solid)
		)
		(fill yes)
		(layer "In4.Cu")
		(net "GND")
	)
	(gr_poly
		(pts
			(arc
				(start 55.111396 -411.936184)
				(mid 54.852316 -411.936184)
				(end 55.111396 -411.936184)
			)
		)
		(stroke
			(width 0)
			(type solid)
		)
		(fill yes)
		(layer "In4.Cu")
		(net "GND")
	)
	(gr_poly
		(pts
			(arc
				(start 55.111396 -405.098504)
				(mid 54.852316 -405.098504)
				(end 55.111396 -405.098504)
			)
		)
		(stroke
			(width 0)
			(type solid)
		)
		(fill yes)
		(layer "In4.Cu")
		(net "GND")
	)
	(gr_poly
		(pts
			(arc
				(start 55.111396 -403.830536)
				(mid 54.852316 -403.830536)
				(end 55.111396 -403.830536)
			)
		)
		(stroke
			(width 0)
			(type solid)
		)
		(fill yes)
		(layer "In4.Cu")
		(net "GND")
	)
	(gr_poly
		(pts
			(arc
				(start 55.384192 -410.664152)
				(mid 55.125112 -410.664152)
				(end 55.384192 -410.664152)
			)
		)
		(stroke
			(width 0)
			(type solid)
		)
		(fill yes)
		(layer "In4.Cu")
		(net "GND")
	)
	(gr_poly
		(pts
			(arc
				(start 55.384192 -409.396184)
				(mid 55.125112 -409.396184)
				(end 55.384192 -409.396184)
			)
		)
		(stroke
			(width 0)
			(type solid)
		)
		(fill yes)
		(layer "In4.Cu")
		(net "GND")
	)
	(gr_poly
		(pts
			(arc
				(start 55.384192 -407.638504)
				(mid 55.125112 -407.638504)
				(end 55.384192 -407.638504)
			)
		)
		(stroke
			(width 0)
			(type solid)
		)
		(fill yes)
		(layer "In4.Cu")
		(net "GND")
	)
	(gr_poly
		(pts
			(arc
				(start 55.384192 -406.370536)
				(mid 55.125112 -406.370536)
				(end 55.384192 -406.370536)
			)
		)
		(stroke
			(width 0)
			(type solid)
		)
		(fill yes)
		(layer "In4.Cu")
		(net "GND")
	)
	(gr_poly
		(pts
			(arc
				(start 55.472584 -412.570168)
				(mid 55.213504 -412.570168)
				(end 55.472584 -412.570168)
			)
		)
		(stroke
			(width 0)
			(type solid)
		)
		(fill yes)
		(layer "In4.Cu")
		(net "GND")
	)
	(gr_poly
		(pts
			(arc
				(start 55.472584 -404.46452)
				(mid 55.213504 -404.46452)
				(end 55.472584 -404.46452)
			)
		)
		(stroke
			(width 0)
			(type solid)
		)
		(fill yes)
		(layer "In4.Cu")
		(net "GND")
	)
	(gr_poly
		(pts
			(arc
				(start 56.554624 -412.570168)
				(mid 56.295544 -412.570168)
				(end 56.554624 -412.570168)
			)
		)
		(stroke
			(width 0)
			(type solid)
		)
		(fill yes)
		(layer "In4.Cu")
		(net "GND")
	)
	(gr_poly
		(pts
			(arc
				(start 56.554624 -404.46452)
				(mid 56.295544 -404.46452)
				(end 56.554624 -404.46452)
			)
		)
		(stroke
			(width 0)
			(type solid)
		)
		(fill yes)
		(layer "In4.Cu")
		(net "GND")
	)
	(gr_poly
		(pts
			(arc
				(start 56.643016 -410.664152)
				(mid 56.383936 -410.664152)
				(end 56.643016 -410.664152)
			)
		)
		(stroke
			(width 0)
			(type solid)
		)
		(fill yes)
		(layer "In4.Cu")
		(net "GND")
	)
	(gr_poly
		(pts
			(arc
				(start 56.643016 -409.396184)
				(mid 56.383936 -409.396184)
				(end 56.643016 -409.396184)
			)
		)
		(stroke
			(width 0)
			(type solid)
		)
		(fill yes)
		(layer "In4.Cu")
		(net "GND")
	)
	(gr_poly
		(pts
			(arc
				(start 56.643016 -407.638504)
				(mid 56.383936 -407.638504)
				(end 56.643016 -407.638504)
			)
		)
		(stroke
			(width 0)
			(type solid)
		)
		(fill yes)
		(layer "In4.Cu")
		(net "GND")
	)
	(gr_poly
		(pts
			(arc
				(start 56.643016 -406.370536)
				(mid 56.383936 -406.370536)
				(end 56.643016 -406.370536)
			)
		)
		(stroke
			(width 0)
			(type solid)
		)
		(fill yes)
		(layer "In4.Cu")
		(net "GND")
	)
	(gr_poly
		(pts
			(arc
				(start 56.915812 -413.204152)
				(mid 56.656732 -413.204152)
				(end 56.915812 -413.204152)
			)
		)
		(stroke
			(width 0)
			(type solid)
		)
		(fill yes)
		(layer "In4.Cu")
		(net "GND")
	)
	(gr_poly
		(pts
			(arc
				(start 56.915812 -411.936184)
				(mid 56.656732 -411.936184)
				(end 56.915812 -411.936184)
			)
		)
		(stroke
			(width 0)
			(type solid)
		)
		(fill yes)
		(layer "In4.Cu")
		(net "GND")
	)
	(gr_poly
		(pts
			(arc
				(start 56.915812 -405.098504)
				(mid 56.656732 -405.098504)
				(end 56.915812 -405.098504)
			)
		)
		(stroke
			(width 0)
			(type solid)
		)
		(fill yes)
		(layer "In4.Cu")
		(net "GND")
	)
	(gr_poly
		(pts
			(arc
				(start 56.915812 -403.830536)
				(mid 56.656732 -403.830536)
				(end 56.915812 -403.830536)
			)
		)
		(stroke
			(width 0)
			(type solid)
		)
		(fill yes)
		(layer "In4.Cu")
		(net "GND")
	)
	(gr_poly
		(pts
			(arc
				(start 57.004204 -410.030168)
				(mid 56.745124 -410.030168)
				(end 57.004204 -410.030168)
			)
		)
		(stroke
			(width 0)
			(type solid)
		)
		(fill yes)
		(layer "In4.Cu")
		(net "GND")
	)
	(gr_poly
		(pts
			(arc
				(start 57.004204 -407.00452)
				(mid 56.745124 -407.00452)
				(end 57.004204 -407.00452)
			)
		)
		(stroke
			(width 0)
			(type solid)
		)
		(fill yes)
		(layer "In4.Cu")
		(net "GND")
	)
	(gr_poly
		(pts
			(arc
				(start 58.086244 -410.030168)
				(mid 57.827164 -410.030168)
				(end 58.086244 -410.030168)
			)
		)
		(stroke
			(width 0)
			(type solid)
		)
		(fill yes)
		(layer "In4.Cu")
		(net "GND")
	)
	(gr_poly
		(pts
			(arc
				(start 58.086244 -407.00452)
				(mid 57.827164 -407.00452)
				(end 58.086244 -407.00452)
			)
		)
		(stroke
			(width 0)
			(type solid)
		)
		(fill yes)
		(layer "In4.Cu")
		(net "GND")
	)
	(gr_poly
		(pts
			(arc
				(start 58.174636 -413.204152)
				(mid 57.915556 -413.204152)
				(end 58.174636 -413.204152)
			)
		)
		(stroke
			(width 0)
			(type solid)
		)
		(fill yes)
		(layer "In4.Cu")
		(net "GND")
	)
	(gr_poly
		(pts
			(arc
				(start 58.174636 -411.936184)
				(mid 57.915556 -411.936184)
				(end 58.174636 -411.936184)
			)
		)
		(stroke
			(width 0)
			(type solid)
		)
		(fill yes)
		(layer "In4.Cu")
		(net "GND")
	)
	(gr_poly
		(pts
			(arc
				(start 58.174636 -405.098504)
				(mid 57.915556 -405.098504)
				(end 58.174636 -405.098504)
			)
		)
		(stroke
			(width 0)
			(type solid)
		)
		(fill yes)
		(layer "In4.Cu")
		(net "GND")
	)
	(gr_poly
		(pts
			(arc
				(start 58.174636 -403.830536)
				(mid 57.915556 -403.830536)
				(end 58.174636 -403.830536)
			)
		)
		(stroke
			(width 0)
			(type solid)
		)
		(fill yes)
		(layer "In4.Cu")
		(net "GND")
	)
	(gr_poly
		(pts
			(arc
				(start 58.447432 -410.664152)
				(mid 58.188352 -410.664152)
				(end 58.447432 -410.664152)
			)
		)
		(stroke
			(width 0)
			(type solid)
		)
		(fill yes)
		(layer "In4.Cu")
		(net "GND")
	)
	(gr_poly
		(pts
			(arc
				(start 58.447432 -409.396184)
				(mid 58.188352 -409.396184)
				(end 58.447432 -409.396184)
			)
		)
		(stroke
			(width 0)
			(type solid)
		)
		(fill yes)
		(layer "In4.Cu")
		(net "GND")
	)
	(gr_poly
		(pts
			(arc
				(start 58.447432 -407.638504)
				(mid 58.188352 -407.638504)
				(end 58.447432 -407.638504)
			)
		)
		(stroke
			(width 0)
			(type solid)
		)
		(fill yes)
		(layer "In4.Cu")
		(net "GND")
	)
	(gr_poly
		(pts
			(arc
				(start 58.447432 -406.370536)
				(mid 58.188352 -406.370536)
				(end 58.447432 -406.370536)
			)
		)
		(stroke
			(width 0)
			(type solid)
		)
		(fill yes)
		(layer "In4.Cu")
		(net "GND")
	)
	(gr_poly
		(pts
			(arc
				(start 58.535824 -404.46452)
				(mid 58.276744 -404.46452)
				(end 58.535824 -404.46452)
			)
		)
		(stroke
			(width 0)
			(type solid)
		)
		(fill yes)
		(layer "In4.Cu")
		(net "GND")
	)
	(gr_poly
		(pts
			(arc
				(start 59.617864 -404.46452)
				(mid 59.358784 -404.46452)
				(end 59.617864 -404.46452)
			)
		)
		(stroke
			(width 0)
			(type solid)
		)
		(fill yes)
		(layer "In4.Cu")
		(net "GND")
	)
	(gr_poly
		(pts
			(arc
				(start 59.706256 -409.396184)
				(mid 59.447176 -409.396184)
				(end 59.706256 -409.396184)
			)
		)
		(stroke
			(width 0)
			(type solid)
		)
		(fill yes)
		(layer "In4.Cu")
		(net "GND")
	)
	(gr_poly
		(pts
			(arc
				(start 59.706256 -407.638504)
				(mid 59.447176 -407.638504)
				(end 59.706256 -407.638504)
			)
		)
		(stroke
			(width 0)
			(type solid)
		)
		(fill yes)
		(layer "In4.Cu")
		(net "GND")
	)
	(gr_poly
		(pts
			(arc
				(start 59.706256 -406.370536)
				(mid 59.447176 -406.370536)
				(end 59.706256 -406.370536)
			)
		)
		(stroke
			(width 0)
			(type solid)
		)
		(fill yes)
		(layer "In4.Cu")
		(net "GND")
	)
	(gr_poly
		(pts
			(arc
				(start 59.979052 -413.204152)
				(mid 59.719972 -413.204152)
				(end 59.979052 -413.204152)
			)
		)
		(stroke
			(width 0)
			(type solid)
		)
		(fill yes)
		(layer "In4.Cu")
		(net "GND")
	)
	(gr_poly
		(pts
			(arc
				(start 59.979052 -405.098504)
				(mid 59.719972 -405.098504)
				(end 59.979052 -405.098504)
			)
		)
		(stroke
			(width 0)
			(type solid)
		)
		(fill yes)
		(layer "In4.Cu")
		(net "GND")
	)
	(gr_poly
		(pts
			(arc
				(start 59.979052 -403.830536)
				(mid 59.719972 -403.830536)
				(end 59.979052 -403.830536)
			)
		)
		(stroke
			(width 0)
			(type solid)
		)
		(fill yes)
		(layer "In4.Cu")
		(net "GND")
	)
	(gr_poly
		(pts
			(arc
				(start 60.067444 -407.00452)
				(mid 59.808364 -407.00452)
				(end 60.067444 -407.00452)
			)
		)
		(stroke
			(width 0)
			(type solid)
		)
		(fill yes)
		(layer "In4.Cu")
		(net "GND")
	)
	(gr_poly
		(pts
			(arc
				(start 61.149484 -407.00452)
				(mid 60.890404 -407.00452)
				(end 61.149484 -407.00452)
			)
		)
		(stroke
			(width 0)
			(type solid)
		)
		(fill yes)
		(layer "In4.Cu")
		(net "GND")
	)
	(gr_poly
		(pts
			(arc
				(start 61.237876 -413.204152)
				(mid 60.978796 -413.204152)
				(end 61.237876 -413.204152)
			)
		)
		(stroke
			(width 0)
			(type solid)
		)
		(fill yes)
		(layer "In4.Cu")
		(net "GND")
	)
	(gr_poly
		(pts
			(arc
				(start 61.237876 -411.936184)
				(mid 60.978796 -411.936184)
				(end 61.237876 -411.936184)
			)
		)
		(stroke
			(width 0)
			(type solid)
		)
		(fill yes)
		(layer "In4.Cu")
		(net "GND")
	)
	(gr_poly
		(pts
			(arc
				(start 61.237876 -405.098504)
				(mid 60.978796 -405.098504)
				(end 61.237876 -405.098504)
			)
		)
		(stroke
			(width 0)
			(type solid)
		)
		(fill yes)
		(layer "In4.Cu")
		(net "GND")
	)
	(gr_poly
		(pts
			(arc
				(start 61.237876 -403.830536)
				(mid 60.978796 -403.830536)
				(end 61.237876 -403.830536)
			)
		)
		(stroke
			(width 0)
			(type solid)
		)
		(fill yes)
		(layer "In4.Cu")
		(net "GND")
	)
	(gr_poly
		(pts
			(arc
				(start 61.510672 -410.664152)
				(mid 61.251592 -410.664152)
				(end 61.510672 -410.664152)
			)
		)
		(stroke
			(width 0)
			(type solid)
		)
		(fill yes)
		(layer "In4.Cu")
		(net "GND")
	)
	(gr_poly
		(pts
			(arc
				(start 61.510672 -409.396184)
				(mid 61.251592 -409.396184)
				(end 61.510672 -409.396184)
			)
		)
		(stroke
			(width 0)
			(type solid)
		)
		(fill yes)
		(layer "In4.Cu")
		(net "GND")
	)
	(gr_poly
		(pts
			(arc
				(start 61.510672 -407.638504)
				(mid 61.251592 -407.638504)
				(end 61.510672 -407.638504)
			)
		)
		(stroke
			(width 0)
			(type solid)
		)
		(fill yes)
		(layer "In4.Cu")
		(net "GND")
	)
	(gr_poly
		(pts
			(arc
				(start 61.510672 -406.370536)
				(mid 61.251592 -406.370536)
				(end 61.510672 -406.370536)
			)
		)
		(stroke
			(width 0)
			(type solid)
		)
		(fill yes)
		(layer "In4.Cu")
		(net "GND")
	)
	(gr_poly
		(pts
			(arc
				(start 61.599064 -412.570168)
				(mid 61.339984 -412.570168)
				(end 61.599064 -412.570168)
			)
		)
		(stroke
			(width 0)
			(type solid)
		)
		(fill yes)
		(layer "In4.Cu")
		(net "GND")
	)
	(gr_poly
		(pts
			(arc
				(start 61.599064 -404.46452)
				(mid 61.339984 -404.46452)
				(end 61.599064 -404.46452)
			)
		)
		(stroke
			(width 0)
			(type solid)
		)
		(fill yes)
		(layer "In4.Cu")
		(net "GND")
	)
	(gr_poly
		(pts
			(arc
				(start 62.681104 -412.570168)
				(mid 62.422024 -412.570168)
				(end 62.681104 -412.570168)
			)
		)
		(stroke
			(width 0)
			(type solid)
		)
		(fill yes)
		(layer "In4.Cu")
		(net "GND")
	)
	(gr_poly
		(pts
			(arc
				(start 62.681104 -404.46452)
				(mid 62.422024 -404.46452)
				(end 62.681104 -404.46452)
			)
		)
		(stroke
			(width 0)
			(type solid)
		)
		(fill yes)
		(layer "In4.Cu")
		(net "GND")
	)
	(gr_poly
		(pts
			(arc
				(start 62.769496 -410.664152)
				(mid 62.510416 -410.664152)
				(end 62.769496 -410.664152)
			)
		)
		(stroke
			(width 0)
			(type solid)
		)
		(fill yes)
		(layer "In4.Cu")
		(net "GND")
	)
	(gr_poly
		(pts
			(arc
				(start 62.769496 -409.396184)
				(mid 62.510416 -409.396184)
				(end 62.769496 -409.396184)
			)
		)
		(stroke
			(width 0)
			(type solid)
		)
		(fill yes)
		(layer "In4.Cu")
		(net "GND")
	)
	(gr_poly
		(pts
			(arc
				(start 62.769496 -407.638504)
				(mid 62.510416 -407.638504)
				(end 62.769496 -407.638504)
			)
		)
		(stroke
			(width 0)
			(type solid)
		)
		(fill yes)
		(layer "In4.Cu")
		(net "GND")
	)
	(gr_poly
		(pts
			(arc
				(start 62.769496 -406.370536)
				(mid 62.510416 -406.370536)
				(end 62.769496 -406.370536)
			)
		)
		(stroke
			(width 0)
			(type solid)
		)
		(fill yes)
		(layer "In4.Cu")
		(net "GND")
	)
	(gr_poly
		(pts
			(arc
				(start 63.042292 -413.204152)
				(mid 62.783212 -413.204152)
				(end 63.042292 -413.204152)
			)
		)
		(stroke
			(width 0)
			(type solid)
		)
		(fill yes)
		(layer "In4.Cu")
		(net "GND")
	)
	(gr_poly
		(pts
			(arc
				(start 63.042292 -411.936184)
				(mid 62.783212 -411.936184)
				(end 63.042292 -411.936184)
			)
		)
		(stroke
			(width 0)
			(type solid)
		)
		(fill yes)
		(layer "In4.Cu")
		(net "GND")
	)
	(gr_poly
		(pts
			(arc
				(start 63.042292 -405.098504)
				(mid 62.783212 -405.098504)
				(end 63.042292 -405.098504)
			)
		)
		(stroke
			(width 0)
			(type solid)
		)
		(fill yes)
		(layer "In4.Cu")
		(net "GND")
	)
	(gr_poly
		(pts
			(arc
				(start 63.042292 -403.830536)
				(mid 62.783212 -403.830536)
				(end 63.042292 -403.830536)
			)
		)
		(stroke
			(width 0)
			(type solid)
		)
		(fill yes)
		(layer "In4.Cu")
		(net "GND")
	)
	(gr_poly
		(pts
			(arc
				(start 63.130684 -410.030168)
				(mid 62.871604 -410.030168)
				(end 63.130684 -410.030168)
			)
		)
		(stroke
			(width 0)
			(type solid)
		)
		(fill yes)
		(layer "In4.Cu")
		(net "GND")
	)
	(gr_poly
		(pts
			(arc
				(start 63.130684 -407.00452)
				(mid 62.871604 -407.00452)
				(end 63.130684 -407.00452)
			)
		)
		(stroke
			(width 0)
			(type solid)
		)
		(fill yes)
		(layer "In4.Cu")
		(net "GND")
	)
	(gr_poly
		(pts
			(arc
				(start 64.212724 -410.030168)
				(mid 63.953644 -410.030168)
				(end 64.212724 -410.030168)
			)
		)
		(stroke
			(width 0)
			(type solid)
		)
		(fill yes)
		(layer "In4.Cu")
		(net "GND")
	)
	(gr_poly
		(pts
			(arc
				(start 64.212724 -407.00452)
				(mid 63.953644 -407.00452)
				(end 64.212724 -407.00452)
			)
		)
		(stroke
			(width 0)
			(type solid)
		)
		(fill yes)
		(layer "In4.Cu")
		(net "GND")
	)
	(gr_poly
		(pts
			(arc
				(start 64.301116 -413.204152)
				(mid 64.042036 -413.204152)
				(end 64.301116 -413.204152)
			)
		)
		(stroke
			(width 0)
			(type solid)
		)
		(fill yes)
		(layer "In4.Cu")
		(net "GND")
	)
	(gr_poly
		(pts
			(arc
				(start 64.301116 -411.936184)
				(mid 64.042036 -411.936184)
				(end 64.301116 -411.936184)
			)
		)
		(stroke
			(width 0)
			(type solid)
		)
		(fill yes)
		(layer "In4.Cu")
		(net "GND")
	)
	(gr_poly
		(pts
			(arc
				(start 64.301116 -405.098504)
				(mid 64.042036 -405.098504)
				(end 64.301116 -405.098504)
			)
		)
		(stroke
			(width 0)
			(type solid)
		)
		(fill yes)
		(layer "In4.Cu")
		(net "GND")
	)
	(gr_poly
		(pts
			(arc
				(start 64.301116 -403.830536)
				(mid 64.042036 -403.830536)
				(end 64.301116 -403.830536)
			)
		)
		(stroke
			(width 0)
			(type solid)
		)
		(fill yes)
		(layer "In4.Cu")
		(net "GND")
	)
	(gr_poly
		(pts
			(arc
				(start 64.573912 -410.664152)
				(mid 64.314832 -410.664152)
				(end 64.573912 -410.664152)
			)
		)
		(stroke
			(width 0)
			(type solid)
		)
		(fill yes)
		(layer "In4.Cu")
		(net "GND")
	)
	(gr_poly
		(pts
			(arc
				(start 64.573912 -409.396184)
				(mid 64.314832 -409.396184)
				(end 64.573912 -409.396184)
			)
		)
		(stroke
			(width 0)
			(type solid)
		)
		(fill yes)
		(layer "In4.Cu")
		(net "GND")
	)
	(gr_poly
		(pts
			(arc
				(start 64.573912 -407.638504)
				(mid 64.314832 -407.638504)
				(end 64.573912 -407.638504)
			)
		)
		(stroke
			(width 0)
			(type solid)
		)
		(fill yes)
		(layer "In4.Cu")
		(net "GND")
	)
	(gr_poly
		(pts
			(arc
				(start 64.573912 -406.370536)
				(mid 64.314832 -406.370536)
				(end 64.573912 -406.370536)
			)
		)
		(stroke
			(width 0)
			(type solid)
		)
		(fill yes)
		(layer "In4.Cu")
		(net "GND")
	)
	(gr_poly
		(pts
			(arc
				(start 64.662304 -404.46452)
				(mid 64.403224 -404.46452)
				(end 64.662304 -404.46452)
			)
		)
		(stroke
			(width 0)
			(type solid)
		)
		(fill yes)
		(layer "In4.Cu")
		(net "GND")
	)
	(gr_poly
		(pts
			(arc
				(start 65.744344 -404.46452)
				(mid 65.485264 -404.46452)
				(end 65.744344 -404.46452)
			)
		)
		(stroke
			(width 0)
			(type solid)
		)
		(fill yes)
		(layer "In4.Cu")
		(net "GND")
	)
	(gr_poly
		(pts
			(arc
				(start 65.832736 -409.396184)
				(mid 65.573656 -409.396184)
				(end 65.832736 -409.396184)
			)
		)
		(stroke
			(width 0)
			(type solid)
		)
		(fill yes)
		(layer "In4.Cu")
		(net "GND")
	)
	(gr_poly
		(pts
			(arc
				(start 65.832736 -407.638504)
				(mid 65.573656 -407.638504)
				(end 65.832736 -407.638504)
			)
		)
		(stroke
			(width 0)
			(type solid)
		)
		(fill yes)
		(layer "In4.Cu")
		(net "GND")
	)
	(gr_poly
		(pts
			(arc
				(start 65.832736 -406.370536)
				(mid 65.573656 -406.370536)
				(end 65.832736 -406.370536)
			)
		)
		(stroke
			(width 0)
			(type solid)
		)
		(fill yes)
		(layer "In4.Cu")
		(net "GND")
	)
	(gr_poly
		(pts
			(arc
				(start 66.105532 -413.204152)
				(mid 65.846452 -413.204152)
				(end 66.105532 -413.204152)
			)
		)
		(stroke
			(width 0)
			(type solid)
		)
		(fill yes)
		(layer "In4.Cu")
		(net "GND")
	)
	(gr_poly
		(pts
			(arc
				(start 66.105532 -405.098504)
				(mid 65.846452 -405.098504)
				(end 66.105532 -405.098504)
			)
		)
		(stroke
			(width 0)
			(type solid)
		)
		(fill yes)
		(layer "In4.Cu")
		(net "GND")
	)
	(gr_poly
		(pts
			(arc
				(start 66.105532 -403.830536)
				(mid 65.846452 -403.830536)
				(end 66.105532 -403.830536)
			)
		)
		(stroke
			(width 0)
			(type solid)
		)
		(fill yes)
		(layer "In4.Cu")
		(net "GND")
	)
	(gr_poly
		(pts
			(arc
				(start 66.193924 -410.030168)
				(mid 65.934844 -410.030168)
				(end 66.193924 -410.030168)
			)
		)
		(stroke
			(width 0)
			(type solid)
		)
		(fill yes)
		(layer "In4.Cu")
		(net "GND")
	)
	(gr_poly
		(pts
			(arc
				(start 66.193924 -407.00452)
				(mid 65.934844 -407.00452)
				(end 66.193924 -407.00452)
			)
		)
		(stroke
			(width 0)
			(type solid)
		)
		(fill yes)
		(layer "In4.Cu")
		(net "GND")
	)
	(gr_poly
		(pts
			(arc
				(start 67.275964 -410.030168)
				(mid 67.016884 -410.030168)
				(end 67.275964 -410.030168)
			)
		)
		(stroke
			(width 0)
			(type solid)
		)
		(fill yes)
		(layer "In4.Cu")
		(net "GND")
	)
	(gr_poly
		(pts
			(arc
				(start 67.275964 -407.00452)
				(mid 67.016884 -407.00452)
				(end 67.275964 -407.00452)
			)
		)
		(stroke
			(width 0)
			(type solid)
		)
		(fill yes)
		(layer "In4.Cu")
		(net "GND")
	)
	(gr_poly
		(pts
			(arc
				(start 67.364356 -413.204152)
				(mid 67.105276 -413.204152)
				(end 67.364356 -413.204152)
			)
		)
		(stroke
			(width 0)
			(type solid)
		)
		(fill yes)
		(layer "In4.Cu")
		(net "GND")
	)
	(gr_poly
		(pts
			(arc
				(start 67.364356 -405.098504)
				(mid 67.105276 -405.098504)
				(end 67.364356 -405.098504)
			)
		)
		(stroke
			(width 0)
			(type solid)
		)
		(fill yes)
		(layer "In4.Cu")
		(net "GND")
	)
	(gr_poly
		(pts
			(arc
				(start 67.364356 -403.830536)
				(mid 67.105276 -403.830536)
				(end 67.364356 -403.830536)
			)
		)
		(stroke
			(width 0)
			(type solid)
		)
		(fill yes)
		(layer "In4.Cu")
		(net "GND")
	)
	(gr_poly
		(pts
			(arc
				(start 67.637152 -409.396184)
				(mid 67.378072 -409.396184)
				(end 67.637152 -409.396184)
			)
		)
		(stroke
			(width 0)
			(type solid)
		)
		(fill yes)
		(layer "In4.Cu")
		(net "GND")
	)
	(gr_poly
		(pts
			(arc
				(start 67.637152 -407.638504)
				(mid 67.378072 -407.638504)
				(end 67.637152 -407.638504)
			)
		)
		(stroke
			(width 0)
			(type solid)
		)
		(fill yes)
		(layer "In4.Cu")
		(net "GND")
	)
	(gr_poly
		(pts
			(arc
				(start 67.637152 -406.370536)
				(mid 67.378072 -406.370536)
				(end 67.637152 -406.370536)
			)
		)
		(stroke
			(width 0)
			(type solid)
		)
		(fill yes)
		(layer "In4.Cu")
		(net "GND")
	)
	(gr_poly
		(pts
			(arc
				(start 67.725544 -412.570168)
				(mid 67.466464 -412.570168)
				(end 67.725544 -412.570168)
			)
		)
		(stroke
			(width 0)
			(type solid)
		)
		(fill yes)
		(layer "In4.Cu")
		(net "GND")
	)
	(gr_poly
		(pts
			(arc
				(start 67.725544 -404.46452)
				(mid 67.466464 -404.46452)
				(end 67.725544 -404.46452)
			)
		)
		(stroke
			(width 0)
			(type solid)
		)
		(fill yes)
		(layer "In4.Cu")
		(net "GND")
	)
	(gr_poly
		(pts
			(arc
				(start 68.807584 -412.570168)
				(mid 68.548504 -412.570168)
				(end 68.807584 -412.570168)
			)
		)
		(stroke
			(width 0)
			(type solid)
		)
		(fill yes)
		(layer "In4.Cu")
		(net "GND")
	)
	(gr_poly
		(pts
			(arc
				(start 68.807584 -404.46452)
				(mid 68.548504 -404.46452)
				(end 68.807584 -404.46452)
			)
		)
		(stroke
			(width 0)
			(type solid)
		)
		(fill yes)
		(layer "In4.Cu")
		(net "GND")
	)
	(gr_poly
		(pts
			(arc
				(start 68.895976 -409.396184)
				(mid 68.636896 -409.396184)
				(end 68.895976 -409.396184)
			)
		)
		(stroke
			(width 0)
			(type solid)
		)
		(fill yes)
		(layer "In4.Cu")
		(net "GND")
	)
	(gr_poly
		(pts
			(arc
				(start 68.895976 -407.638504)
				(mid 68.636896 -407.638504)
				(end 68.895976 -407.638504)
			)
		)
		(stroke
			(width 0)
			(type solid)
		)
		(fill yes)
		(layer "In4.Cu")
		(net "GND")
	)
	(gr_poly
		(pts
			(arc
				(start 68.895976 -406.370536)
				(mid 68.636896 -406.370536)
				(end 68.895976 -406.370536)
			)
		)
		(stroke
			(width 0)
			(type solid)
		)
		(fill yes)
		(layer "In4.Cu")
		(net "GND")
	)
	(gr_poly
		(pts
			(arc
				(start 69.168772 -413.204152)
				(mid 68.909692 -413.204152)
				(end 69.168772 -413.204152)
			)
		)
		(stroke
			(width 0)
			(type solid)
		)
		(fill yes)
		(layer "In4.Cu")
		(net "GND")
	)
	(gr_poly
		(pts
			(arc
				(start 69.168772 -405.098504)
				(mid 68.909692 -405.098504)
				(end 69.168772 -405.098504)
			)
		)
		(stroke
			(width 0)
			(type solid)
		)
		(fill yes)
		(layer "In4.Cu")
		(net "GND")
	)
	(gr_poly
		(pts
			(arc
				(start 69.168772 -403.830536)
				(mid 68.909692 -403.830536)
				(end 69.168772 -403.830536)
			)
		)
		(stroke
			(width 0)
			(type solid)
		)
		(fill yes)
		(layer "In4.Cu")
		(net "GND")
	)
	(gr_poly
		(pts
			(arc
				(start 69.257164 -410.030168)
				(mid 68.998084 -410.030168)
				(end 69.257164 -410.030168)
			)
		)
		(stroke
			(width 0)
			(type solid)
		)
		(fill yes)
		(layer "In4.Cu")
		(net "GND")
	)
	(gr_poly
		(pts
			(arc
				(start 69.257164 -407.00452)
				(mid 68.998084 -407.00452)
				(end 69.257164 -407.00452)
			)
		)
		(stroke
			(width 0)
			(type solid)
		)
		(fill yes)
		(layer "In4.Cu")
		(net "GND")
	)
	(gr_poly
		(pts
			(arc
				(start 70.339204 -410.030168)
				(mid 70.080124 -410.030168)
				(end 70.339204 -410.030168)
			)
		)
		(stroke
			(width 0)
			(type solid)
		)
		(fill yes)
		(layer "In4.Cu")
		(net "GND")
	)
	(gr_poly
		(pts
			(arc
				(start 70.339204 -407.00452)
				(mid 70.080124 -407.00452)
				(end 70.339204 -407.00452)
			)
		)
		(stroke
			(width 0)
			(type solid)
		)
		(fill yes)
		(layer "In4.Cu")
		(net "GND")
	)
	(gr_poly
		(pts
			(arc
				(start 70.427596 -413.204152)
				(mid 70.168516 -413.204152)
				(end 70.427596 -413.204152)
			)
		)
		(stroke
			(width 0)
			(type solid)
		)
		(fill yes)
		(layer "In4.Cu")
		(net "GND")
	)
	(gr_poly
		(pts
			(arc
				(start 70.427596 -405.098504)
				(mid 70.168516 -405.098504)
				(end 70.427596 -405.098504)
			)
		)
		(stroke
			(width 0)
			(type solid)
		)
		(fill yes)
		(layer "In4.Cu")
		(net "GND")
	)
	(gr_poly
		(pts
			(arc
				(start 70.427596 -403.830536)
				(mid 70.168516 -403.830536)
				(end 70.427596 -403.830536)
			)
		)
		(stroke
			(width 0)
			(type solid)
		)
		(fill yes)
		(layer "In4.Cu")
		(net "GND")
	)
	(gr_poly
		(pts
			(arc
				(start 70.700392 -409.396184)
				(mid 70.441312 -409.396184)
				(end 70.700392 -409.396184)
			)
		)
		(stroke
			(width 0)
			(type solid)
		)
		(fill yes)
		(layer "In4.Cu")
		(net "GND")
	)
	(gr_poly
		(pts
			(arc
				(start 70.700392 -407.638504)
				(mid 70.441312 -407.638504)
				(end 70.700392 -407.638504)
			)
		)
		(stroke
			(width 0)
			(type solid)
		)
		(fill yes)
		(layer "In4.Cu")
		(net "GND")
	)
	(gr_poly
		(pts
			(arc
				(start 70.700392 -406.370536)
				(mid 70.441312 -406.370536)
				(end 70.700392 -406.370536)
			)
		)
		(stroke
			(width 0)
			(type solid)
		)
		(fill yes)
		(layer "In4.Cu")
		(net "GND")
	)
	(gr_poly
		(pts
			(arc
				(start 70.788784 -412.570168)
				(mid 70.529704 -412.570168)
				(end 70.788784 -412.570168)
			)
		)
		(stroke
			(width 0)
			(type solid)
		)
		(fill yes)
		(layer "In4.Cu")
		(net "GND")
	)
	(gr_poly
		(pts
			(arc
				(start 70.788784 -404.46452)
				(mid 70.529704 -404.46452)
				(end 70.788784 -404.46452)
			)
		)
		(stroke
			(width 0)
			(type solid)
		)
		(fill yes)
		(layer "In4.Cu")
		(net "GND")
	)
	(gr_poly
		(pts
			(arc
				(start 71.870824 -412.570168)
				(mid 71.611744 -412.570168)
				(end 71.870824 -412.570168)
			)
		)
		(stroke
			(width 0)
			(type solid)
		)
		(fill yes)
		(layer "In4.Cu")
		(net "GND")
	)
	(gr_poly
		(pts
			(arc
				(start 71.870824 -404.46452)
				(mid 71.611744 -404.46452)
				(end 71.870824 -404.46452)
			)
		)
		(stroke
			(width 0)
			(type solid)
		)
		(fill yes)
		(layer "In4.Cu")
		(net "GND")
	)
	(gr_poly
		(pts
			(arc
				(start 71.959216 -409.396184)
				(mid 71.700136 -409.396184)
				(end 71.959216 -409.396184)
			)
		)
		(stroke
			(width 0)
			(type solid)
		)
		(fill yes)
		(layer "In4.Cu")
		(net "GND")
	)
	(gr_poly
		(pts
			(arc
				(start 71.959216 -407.638504)
				(mid 71.700136 -407.638504)
				(end 71.959216 -407.638504)
			)
		)
		(stroke
			(width 0)
			(type solid)
		)
		(fill yes)
		(layer "In4.Cu")
		(net "GND")
	)
	(gr_poly
		(pts
			(arc
				(start 71.959216 -406.370536)
				(mid 71.700136 -406.370536)
				(end 71.959216 -406.370536)
			)
		)
		(stroke
			(width 0)
			(type solid)
		)
		(fill yes)
		(layer "In4.Cu")
		(net "GND")
	)
	(gr_poly
		(pts
			(arc
				(start 72.232012 -413.204152)
				(mid 71.972932 -413.204152)
				(end 72.232012 -413.204152)
			)
		)
		(stroke
			(width 0)
			(type solid)
		)
		(fill yes)
		(layer "In4.Cu")
		(net "GND")
	)
	(gr_poly
		(pts
			(arc
				(start 72.232012 -405.098504)
				(mid 71.972932 -405.098504)
				(end 72.232012 -405.098504)
			)
		)
		(stroke
			(width 0)
			(type solid)
		)
		(fill yes)
		(layer "In4.Cu")
		(net "GND")
	)
	(gr_poly
		(pts
			(arc
				(start 72.232012 -403.830536)
				(mid 71.972932 -403.830536)
				(end 72.232012 -403.830536)
			)
		)
		(stroke
			(width 0)
			(type solid)
		)
		(fill yes)
		(layer "In4.Cu")
		(net "GND")
	)
	(gr_poly
		(pts
			(arc
				(start 72.320404 -410.030168)
				(mid 72.061324 -410.030168)
				(end 72.320404 -410.030168)
			)
		)
		(stroke
			(width 0)
			(type solid)
		)
		(fill yes)
		(layer "In4.Cu")
		(net "GND")
	)
	(gr_poly
		(pts
			(arc
				(start 72.320404 -407.00452)
				(mid 72.061324 -407.00452)
				(end 72.320404 -407.00452)
			)
		)
		(stroke
			(width 0)
			(type solid)
		)
		(fill yes)
		(layer "In4.Cu")
		(net "GND")
	)
	(gr_poly
		(pts
			(arc
				(start 73.402444 -410.030168)
				(mid 73.143364 -410.030168)
				(end 73.402444 -410.030168)
			)
		)
		(stroke
			(width 0)
			(type solid)
		)
		(fill yes)
		(layer "In4.Cu")
		(net "GND")
	)
	(gr_poly
		(pts
			(arc
				(start 73.402444 -407.00452)
				(mid 73.143364 -407.00452)
				(end 73.402444 -407.00452)
			)
		)
		(stroke
			(width 0)
			(type solid)
		)
		(fill yes)
		(layer "In4.Cu")
		(net "GND")
	)
	(gr_poly
		(pts
			(arc
				(start 73.490836 -413.204152)
				(mid 73.231756 -413.204152)
				(end 73.490836 -413.204152)
			)
		)
		(stroke
			(width 0)
			(type solid)
		)
		(fill yes)
		(layer "In4.Cu")
		(net "GND")
	)
	(gr_poly
		(pts
			(arc
				(start 73.490836 -405.098504)
				(mid 73.231756 -405.098504)
				(end 73.490836 -405.098504)
			)
		)
		(stroke
			(width 0)
			(type solid)
		)
		(fill yes)
		(layer "In4.Cu")
		(net "GND")
	)
	(gr_poly
		(pts
			(arc
				(start 73.490836 -403.830536)
				(mid 73.231756 -403.830536)
				(end 73.490836 -403.830536)
			)
		)
		(stroke
			(width 0)
			(type solid)
		)
		(fill yes)
		(layer "In4.Cu")
		(net "GND")
	)
	(gr_poly
		(pts
			(arc
				(start 73.763632 -409.396184)
				(mid 73.504552 -409.396184)
				(end 73.763632 -409.396184)
			)
		)
		(stroke
			(width 0)
			(type solid)
		)
		(fill yes)
		(layer "In4.Cu")
		(net "GND")
	)
	(gr_poly
		(pts
			(arc
				(start 73.763632 -407.638504)
				(mid 73.504552 -407.638504)
				(end 73.763632 -407.638504)
			)
		)
		(stroke
			(width 0)
			(type solid)
		)
		(fill yes)
		(layer "In4.Cu")
		(net "GND")
	)
	(gr_poly
		(pts
			(arc
				(start 73.763632 -406.370536)
				(mid 73.504552 -406.370536)
				(end 73.763632 -406.370536)
			)
		)
		(stroke
			(width 0)
			(type solid)
		)
		(fill yes)
		(layer "In4.Cu")
		(net "GND")
	)
	(gr_poly
		(pts
			(arc
				(start 73.852024 -412.570168)
				(mid 73.592944 -412.570168)
				(end 73.852024 -412.570168)
			)
		)
		(stroke
			(width 0)
			(type solid)
		)
		(fill yes)
		(layer "In4.Cu")
		(net "GND")
	)
	(gr_poly
		(pts
			(arc
				(start 73.852024 -404.46452)
				(mid 73.592944 -404.46452)
				(end 73.852024 -404.46452)
			)
		)
		(stroke
			(width 0)
			(type solid)
		)
		(fill yes)
		(layer "In4.Cu")
		(net "GND")
	)
	(gr_poly
		(pts
			(arc
				(start 74.934064 -412.570168)
				(mid 74.674984 -412.570168)
				(end 74.934064 -412.570168)
			)
		)
		(stroke
			(width 0)
			(type solid)
		)
		(fill yes)
		(layer "In4.Cu")
		(net "GND")
	)
	(gr_poly
		(pts
			(arc
				(start 74.934064 -404.46452)
				(mid 74.674984 -404.46452)
				(end 74.934064 -404.46452)
			)
		)
		(stroke
			(width 0)
			(type solid)
		)
		(fill yes)
		(layer "In4.Cu")
		(net "GND")
	)
	(gr_poly
		(pts
			(arc
				(start 75.022456 -409.396184)
				(mid 74.763376 -409.396184)
				(end 75.022456 -409.396184)
			)
		)
		(stroke
			(width 0)
			(type solid)
		)
		(fill yes)
		(layer "In4.Cu")
		(net "GND")
	)
	(gr_poly
		(pts
			(arc
				(start 75.022456 -407.638504)
				(mid 74.763376 -407.638504)
				(end 75.022456 -407.638504)
			)
		)
		(stroke
			(width 0)
			(type solid)
		)
		(fill yes)
		(layer "In4.Cu")
		(net "GND")
	)
	(gr_poly
		(pts
			(arc
				(start 75.022456 -406.370536)
				(mid 74.763376 -406.370536)
				(end 75.022456 -406.370536)
			)
		)
		(stroke
			(width 0)
			(type solid)
		)
		(fill yes)
		(layer "In4.Cu")
		(net "GND")
	)
	(gr_poly
		(pts
			(arc
				(start 75.295252 -413.204152)
				(mid 75.036172 -413.204152)
				(end 75.295252 -413.204152)
			)
		)
		(stroke
			(width 0)
			(type solid)
		)
		(fill yes)
		(layer "In4.Cu")
		(net "GND")
	)
	(gr_poly
		(pts
			(arc
				(start 75.295252 -405.098504)
				(mid 75.036172 -405.098504)
				(end 75.295252 -405.098504)
			)
		)
		(stroke
			(width 0)
			(type solid)
		)
		(fill yes)
		(layer "In4.Cu")
		(net "GND")
	)
	(gr_poly
		(pts
			(arc
				(start 75.295252 -403.830536)
				(mid 75.036172 -403.830536)
				(end 75.295252 -403.830536)
			)
		)
		(stroke
			(width 0)
			(type solid)
		)
		(fill yes)
		(layer "In4.Cu")
		(net "GND")
	)
	(gr_poly
		(pts
			(arc
				(start 75.383644 -410.030168)
				(mid 75.124564 -410.030168)
				(end 75.383644 -410.030168)
			)
		)
		(stroke
			(width 0)
			(type solid)
		)
		(fill yes)
		(layer "In4.Cu")
		(net "GND")
	)
	(gr_poly
		(pts
			(arc
				(start 75.383644 -407.00452)
				(mid 75.124564 -407.00452)
				(end 75.383644 -407.00452)
			)
		)
		(stroke
			(width 0)
			(type solid)
		)
		(fill yes)
		(layer "In4.Cu")
		(net "GND")
	)
	(gr_poly
		(pts
			(arc
				(start 76.465684 -410.030168)
				(mid 76.206604 -410.030168)
				(end 76.465684 -410.030168)
			)
		)
		(stroke
			(width 0)
			(type solid)
		)
		(fill yes)
		(layer "In4.Cu")
		(net "GND")
	)
	(gr_poly
		(pts
			(arc
				(start 76.465684 -407.00452)
				(mid 76.206604 -407.00452)
				(end 76.465684 -407.00452)
			)
		)
		(stroke
			(width 0)
			(type solid)
		)
		(fill yes)
		(layer "In4.Cu")
		(net "GND")
	)
	(gr_poly
		(pts
			(arc
				(start 76.554076 -413.204152)
				(mid 76.294996 -413.204152)
				(end 76.554076 -413.204152)
			)
		)
		(stroke
			(width 0)
			(type solid)
		)
		(fill yes)
		(layer "In4.Cu")
		(net "GND")
	)
	(gr_poly
		(pts
			(arc
				(start 76.554076 -405.098504)
				(mid 76.294996 -405.098504)
				(end 76.554076 -405.098504)
			)
		)
		(stroke
			(width 0)
			(type solid)
		)
		(fill yes)
		(layer "In4.Cu")
		(net "GND")
	)
	(gr_poly
		(pts
			(arc
				(start 76.554076 -403.830536)
				(mid 76.294996 -403.830536)
				(end 76.554076 -403.830536)
			)
		)
		(stroke
			(width 0)
			(type solid)
		)
		(fill yes)
		(layer "In4.Cu")
		(net "GND")
	)
	(gr_poly
		(pts
			(arc
				(start 76.826872 -409.396184)
				(mid 76.567792 -409.396184)
				(end 76.826872 -409.396184)
			)
		)
		(stroke
			(width 0)
			(type solid)
		)
		(fill yes)
		(layer "In4.Cu")
		(net "GND")
	)
	(gr_poly
		(pts
			(arc
				(start 76.826872 -407.638504)
				(mid 76.567792 -407.638504)
				(end 76.826872 -407.638504)
			)
		)
		(stroke
			(width 0)
			(type solid)
		)
		(fill yes)
		(layer "In4.Cu")
		(net "GND")
	)
	(gr_poly
		(pts
			(arc
				(start 76.826872 -406.370536)
				(mid 76.567792 -406.370536)
				(end 76.826872 -406.370536)
			)
		)
		(stroke
			(width 0)
			(type solid)
		)
		(fill yes)
		(layer "In4.Cu")
		(net "GND")
	)
	(gr_poly
		(pts
			(arc
				(start 76.915264 -412.570168)
				(mid 76.656184 -412.570168)
				(end 76.915264 -412.570168)
			)
		)
		(stroke
			(width 0)
			(type solid)
		)
		(fill yes)
		(layer "In4.Cu")
		(net "GND")
	)
	(gr_poly
		(pts
			(arc
				(start 76.915264 -404.46452)
				(mid 76.656184 -404.46452)
				(end 76.915264 -404.46452)
			)
		)
		(stroke
			(width 0)
			(type solid)
		)
		(fill yes)
		(layer "In4.Cu")
		(net "GND")
	)
	(gr_poly
		(pts
			(arc
				(start 77.997304 -412.570168)
				(mid 77.738224 -412.570168)
				(end 77.997304 -412.570168)
			)
		)
		(stroke
			(width 0)
			(type solid)
		)
		(fill yes)
		(layer "In4.Cu")
		(net "GND")
	)
	(gr_poly
		(pts
			(arc
				(start 77.997304 -404.46452)
				(mid 77.738224 -404.46452)
				(end 77.997304 -404.46452)
			)
		)
		(stroke
			(width 0)
			(type solid)
		)
		(fill yes)
		(layer "In4.Cu")
		(net "GND")
	)
	(gr_poly
		(pts
			(arc
				(start 78.085696 -409.396184)
				(mid 77.826616 -409.396184)
				(end 78.085696 -409.396184)
			)
		)
		(stroke
			(width 0)
			(type solid)
		)
		(fill yes)
		(layer "In4.Cu")
		(net "GND")
	)
	(gr_poly
		(pts
			(arc
				(start 78.085696 -407.638504)
				(mid 77.826616 -407.638504)
				(end 78.085696 -407.638504)
			)
		)
		(stroke
			(width 0)
			(type solid)
		)
		(fill yes)
		(layer "In4.Cu")
		(net "GND")
	)
	(gr_poly
		(pts
			(arc
				(start 78.085696 -406.370536)
				(mid 77.826616 -406.370536)
				(end 78.085696 -406.370536)
			)
		)
		(stroke
			(width 0)
			(type solid)
		)
		(fill yes)
		(layer "In4.Cu")
		(net "GND")
	)
	(gr_poly
		(pts
			(arc
				(start 78.358492 -413.204152)
				(mid 78.099412 -413.204152)
				(end 78.358492 -413.204152)
			)
		)
		(stroke
			(width 0)
			(type solid)
		)
		(fill yes)
		(layer "In4.Cu")
		(net "GND")
	)
	(gr_poly
		(pts
			(arc
				(start 78.358492 -405.098504)
				(mid 78.099412 -405.098504)
				(end 78.358492 -405.098504)
			)
		)
		(stroke
			(width 0)
			(type solid)
		)
		(fill yes)
		(layer "In4.Cu")
		(net "GND")
	)
	(gr_poly
		(pts
			(arc
				(start 78.358492 -403.830536)
				(mid 78.099412 -403.830536)
				(end 78.358492 -403.830536)
			)
		)
		(stroke
			(width 0)
			(type solid)
		)
		(fill yes)
		(layer "In4.Cu")
		(net "GND")
	)
	(gr_poly
		(pts
			(arc
				(start 78.446884 -410.030168)
				(mid 78.187804 -410.030168)
				(end 78.446884 -410.030168)
			)
		)
		(stroke
			(width 0)
			(type solid)
		)
		(fill yes)
		(layer "In4.Cu")
		(net "GND")
	)
	(gr_poly
		(pts
			(arc
				(start 78.446884 -407.00452)
				(mid 78.187804 -407.00452)
				(end 78.446884 -407.00452)
			)
		)
		(stroke
			(width 0)
			(type solid)
		)
		(fill yes)
		(layer "In4.Cu")
		(net "GND")
	)
	(gr_poly
		(pts
			(arc
				(start 79.528924 -410.030168)
				(mid 79.269844 -410.030168)
				(end 79.528924 -410.030168)
			)
		)
		(stroke
			(width 0)
			(type solid)
		)
		(fill yes)
		(layer "In4.Cu")
		(net "GND")
	)
	(gr_poly
		(pts
			(arc
				(start 79.528924 -407.00452)
				(mid 79.269844 -407.00452)
				(end 79.528924 -407.00452)
			)
		)
		(stroke
			(width 0)
			(type solid)
		)
		(fill yes)
		(layer "In4.Cu")
		(net "GND")
	)
	(gr_poly
		(pts
			(arc
				(start 79.617316 -413.204152)
				(mid 79.358236 -413.204152)
				(end 79.617316 -413.204152)
			)
		)
		(stroke
			(width 0)
			(type solid)
		)
		(fill yes)
		(layer "In4.Cu")
		(net "GND")
	)
	(gr_poly
		(pts
			(arc
				(start 79.617316 -405.098504)
				(mid 79.358236 -405.098504)
				(end 79.617316 -405.098504)
			)
		)
		(stroke
			(width 0)
			(type solid)
		)
		(fill yes)
		(layer "In4.Cu")
		(net "GND")
	)
	(gr_poly
		(pts
			(arc
				(start 79.617316 -403.830536)
				(mid 79.358236 -403.830536)
				(end 79.617316 -403.830536)
			)
		)
		(stroke
			(width 0)
			(type solid)
		)
		(fill yes)
		(layer "In4.Cu")
		(net "GND")
	)
	(gr_poly
		(pts
			(arc
				(start 79.890112 -409.396184)
				(mid 79.631032 -409.396184)
				(end 79.890112 -409.396184)
			)
		)
		(stroke
			(width 0)
			(type solid)
		)
		(fill yes)
		(layer "In4.Cu")
		(net "GND")
	)
	(gr_poly
		(pts
			(arc
				(start 79.890112 -407.638504)
				(mid 79.631032 -407.638504)
				(end 79.890112 -407.638504)
			)
		)
		(stroke
			(width 0)
			(type solid)
		)
		(fill yes)
		(layer "In4.Cu")
		(net "GND")
	)
	(gr_poly
		(pts
			(arc
				(start 79.890112 -406.370536)
				(mid 79.631032 -406.370536)
				(end 79.890112 -406.370536)
			)
		)
		(stroke
			(width 0)
			(type solid)
		)
		(fill yes)
		(layer "In4.Cu")
		(net "GND")
	)
	(gr_poly
		(pts
			(arc
				(start 79.978504 -412.570168)
				(mid 79.719424 -412.570168)
				(end 79.978504 -412.570168)
			)
		)
		(stroke
			(width 0)
			(type solid)
		)
		(fill yes)
		(layer "In4.Cu")
		(net "GND")
	)
	(gr_poly
		(pts
			(arc
				(start 79.978504 -404.46452)
				(mid 79.719424 -404.46452)
				(end 79.978504 -404.46452)
			)
		)
		(stroke
			(width 0)
			(type solid)
		)
		(fill yes)
		(layer "In4.Cu")
		(net "GND")
	)
	(gr_poly
		(pts
			(arc
				(start 81.060544 -412.570168)
				(mid 80.801464 -412.570168)
				(end 81.060544 -412.570168)
			)
		)
		(stroke
			(width 0)
			(type solid)
		)
		(fill yes)
		(layer "In4.Cu")
		(net "GND")
	)
	(gr_poly
		(pts
			(arc
				(start 81.060544 -404.46452)
				(mid 80.801464 -404.46452)
				(end 81.060544 -404.46452)
			)
		)
		(stroke
			(width 0)
			(type solid)
		)
		(fill yes)
		(layer "In4.Cu")
		(net "GND")
	)
	(gr_poly
		(pts
			(arc
				(start 81.148936 -409.396184)
				(mid 80.889856 -409.396184)
				(end 81.148936 -409.396184)
			)
		)
		(stroke
			(width 0)
			(type solid)
		)
		(fill yes)
		(layer "In4.Cu")
		(net "GND")
	)
	(gr_poly
		(pts
			(arc
				(start 81.148936 -407.638504)
				(mid 80.889856 -407.638504)
				(end 81.148936 -407.638504)
			)
		)
		(stroke
			(width 0)
			(type solid)
		)
		(fill yes)
		(layer "In4.Cu")
		(net "GND")
	)
	(gr_poly
		(pts
			(arc
				(start 81.148936 -406.370536)
				(mid 80.889856 -406.370536)
				(end 81.148936 -406.370536)
			)
		)
		(stroke
			(width 0)
			(type solid)
		)
		(fill yes)
		(layer "In4.Cu")
		(net "GND")
	)
	(gr_poly
		(pts
			(arc
				(start 81.421732 -413.204152)
				(mid 81.162652 -413.204152)
				(end 81.421732 -413.204152)
			)
		)
		(stroke
			(width 0)
			(type solid)
		)
		(fill yes)
		(layer "In4.Cu")
		(net "GND")
	)
	(gr_poly
		(pts
			(arc
				(start 81.421732 -405.098504)
				(mid 81.162652 -405.098504)
				(end 81.421732 -405.098504)
			)
		)
		(stroke
			(width 0)
			(type solid)
		)
		(fill yes)
		(layer "In4.Cu")
		(net "GND")
	)
	(gr_poly
		(pts
			(arc
				(start 81.421732 -403.830536)
				(mid 81.162652 -403.830536)
				(end 81.421732 -403.830536)
			)
		)
		(stroke
			(width 0)
			(type solid)
		)
		(fill yes)
		(layer "In4.Cu")
		(net "GND")
	)
	(gr_poly
		(pts
			(arc
				(start 81.510124 -410.030168)
				(mid 81.251044 -410.030168)
				(end 81.510124 -410.030168)
			)
		)
		(stroke
			(width 0)
			(type solid)
		)
		(fill yes)
		(layer "In4.Cu")
		(net "GND")
	)
	(gr_poly
		(pts
			(arc
				(start 81.510124 -407.00452)
				(mid 81.251044 -407.00452)
				(end 81.510124 -407.00452)
			)
		)
		(stroke
			(width 0)
			(type solid)
		)
		(fill yes)
		(layer "In4.Cu")
		(net "GND")
	)
	(gr_poly
		(pts
			(arc
				(start 82.592164 -410.030168)
				(mid 82.333084 -410.030168)
				(end 82.592164 -410.030168)
			)
		)
		(stroke
			(width 0)
			(type solid)
		)
		(fill yes)
		(layer "In4.Cu")
		(net "GND")
	)
	(gr_poly
		(pts
			(arc
				(start 82.592164 -407.00452)
				(mid 82.333084 -407.00452)
				(end 82.592164 -407.00452)
			)
		)
		(stroke
			(width 0)
			(type solid)
		)
		(fill yes)
		(layer "In4.Cu")
		(net "GND")
	)
	(gr_poly
		(pts
			(arc
				(start 82.680556 -413.204152)
				(mid 82.421476 -413.204152)
				(end 82.680556 -413.204152)
			)
		)
		(stroke
			(width 0)
			(type solid)
		)
		(fill yes)
		(layer "In4.Cu")
		(net "GND")
	)
	(gr_poly
		(pts
			(arc
				(start 82.680556 -405.098504)
				(mid 82.421476 -405.098504)
				(end 82.680556 -405.098504)
			)
		)
		(stroke
			(width 0)
			(type solid)
		)
		(fill yes)
		(layer "In4.Cu")
		(net "GND")
	)
	(gr_poly
		(pts
			(arc
				(start 82.680556 -403.830536)
				(mid 82.421476 -403.830536)
				(end 82.680556 -403.830536)
			)
		)
		(stroke
			(width 0)
			(type solid)
		)
		(fill yes)
		(layer "In4.Cu")
		(net "GND")
	)
	(gr_poly
		(pts
			(arc
				(start 82.953352 -409.396184)
				(mid 82.694272 -409.396184)
				(end 82.953352 -409.396184)
			)
		)
		(stroke
			(width 0)
			(type solid)
		)
		(fill yes)
		(layer "In4.Cu")
		(net "GND")
	)
	(gr_poly
		(pts
			(arc
				(start 82.953352 -407.638504)
				(mid 82.694272 -407.638504)
				(end 82.953352 -407.638504)
			)
		)
		(stroke
			(width 0)
			(type solid)
		)
		(fill yes)
		(layer "In4.Cu")
		(net "GND")
	)
	(gr_poly
		(pts
			(arc
				(start 82.953352 -406.370536)
				(mid 82.694272 -406.370536)
				(end 82.953352 -406.370536)
			)
		)
		(stroke
			(width 0)
			(type solid)
		)
		(fill yes)
		(layer "In4.Cu")
		(net "GND")
	)
	(gr_poly
		(pts
			(arc
				(start 83.041744 -412.570168)
				(mid 82.782664 -412.570168)
				(end 83.041744 -412.570168)
			)
		)
		(stroke
			(width 0)
			(type solid)
		)
		(fill yes)
		(layer "In4.Cu")
		(net "GND")
	)
	(gr_poly
		(pts
			(arc
				(start 83.041744 -404.46452)
				(mid 82.782664 -404.46452)
				(end 83.041744 -404.46452)
			)
		)
		(stroke
			(width 0)
			(type solid)
		)
		(fill yes)
		(layer "In4.Cu")
		(net "GND")
	)
	(gr_poly
		(pts
			(arc
				(start 84.123784 -412.570168)
				(mid 83.864704 -412.570168)
				(end 84.123784 -412.570168)
			)
		)
		(stroke
			(width 0)
			(type solid)
		)
		(fill yes)
		(layer "In4.Cu")
		(net "GND")
	)
	(gr_poly
		(pts
			(arc
				(start 84.123784 -404.46452)
				(mid 83.864704 -404.46452)
				(end 84.123784 -404.46452)
			)
		)
		(stroke
			(width 0)
			(type solid)
		)
		(fill yes)
		(layer "In4.Cu")
		(net "GND")
	)
	(gr_poly
		(pts
			(arc
				(start 84.212176 -409.396184)
				(mid 83.953096 -409.396184)
				(end 84.212176 -409.396184)
			)
		)
		(stroke
			(width 0)
			(type solid)
		)
		(fill yes)
		(layer "In4.Cu")
		(net "GND")
	)
	(gr_poly
		(pts
			(arc
				(start 84.212176 -407.638504)
				(mid 83.953096 -407.638504)
				(end 84.212176 -407.638504)
			)
		)
		(stroke
			(width 0)
			(type solid)
		)
		(fill yes)
		(layer "In4.Cu")
		(net "GND")
	)
	(gr_poly
		(pts
			(arc
				(start 84.212176 -406.370536)
				(mid 83.953096 -406.370536)
				(end 84.212176 -406.370536)
			)
		)
		(stroke
			(width 0)
			(type solid)
		)
		(fill yes)
		(layer "In4.Cu")
		(net "GND")
	)
	(gr_poly
		(pts
			(arc
				(start 84.484972 -413.204152)
				(mid 84.225892 -413.204152)
				(end 84.484972 -413.204152)
			)
		)
		(stroke
			(width 0)
			(type solid)
		)
		(fill yes)
		(layer "In4.Cu")
		(net "GND")
	)
	(gr_poly
		(pts
			(arc
				(start 84.484972 -405.098504)
				(mid 84.225892 -405.098504)
				(end 84.484972 -405.098504)
			)
		)
		(stroke
			(width 0)
			(type solid)
		)
		(fill yes)
		(layer "In4.Cu")
		(net "GND")
	)
	(gr_poly
		(pts
			(arc
				(start 84.484972 -403.830536)
				(mid 84.225892 -403.830536)
				(end 84.484972 -403.830536)
			)
		)
		(stroke
			(width 0)
			(type solid)
		)
		(fill yes)
		(layer "In4.Cu")
		(net "GND")
	)
	(gr_poly
		(pts
			(arc
				(start 84.573364 -410.030168)
				(mid 84.314284 -410.030168)
				(end 84.573364 -410.030168)
			)
		)
		(stroke
			(width 0)
			(type solid)
		)
		(fill yes)
		(layer "In4.Cu")
		(net "GND")
	)
	(gr_poly
		(pts
			(arc
				(start 84.573364 -407.00452)
				(mid 84.314284 -407.00452)
				(end 84.573364 -407.00452)
			)
		)
		(stroke
			(width 0)
			(type solid)
		)
		(fill yes)
		(layer "In4.Cu")
		(net "GND")
	)
	(gr_poly
		(pts
			(arc
				(start 85.655404 -410.030168)
				(mid 85.396324 -410.030168)
				(end 85.655404 -410.030168)
			)
		)
		(stroke
			(width 0)
			(type solid)
		)
		(fill yes)
		(layer "In4.Cu")
		(net "GND")
	)
	(gr_poly
		(pts
			(arc
				(start 85.655404 -407.00452)
				(mid 85.396324 -407.00452)
				(end 85.655404 -407.00452)
			)
		)
		(stroke
			(width 0)
			(type solid)
		)
		(fill yes)
		(layer "In4.Cu")
		(net "GND")
	)
	(gr_poly
		(pts
			(arc
				(start 85.743796 -413.204152)
				(mid 85.484716 -413.204152)
				(end 85.743796 -413.204152)
			)
		)
		(stroke
			(width 0)
			(type solid)
		)
		(fill yes)
		(layer "In4.Cu")
		(net "GND")
	)
	(gr_poly
		(pts
			(arc
				(start 85.743796 -405.098504)
				(mid 85.484716 -405.098504)
				(end 85.743796 -405.098504)
			)
		)
		(stroke
			(width 0)
			(type solid)
		)
		(fill yes)
		(layer "In4.Cu")
		(net "GND")
	)
	(gr_poly
		(pts
			(arc
				(start 85.743796 -403.830536)
				(mid 85.484716 -403.830536)
				(end 85.743796 -403.830536)
			)
		)
		(stroke
			(width 0)
			(type solid)
		)
		(fill yes)
		(layer "In4.Cu")
		(net "GND")
	)
	(gr_poly
		(pts
			(arc
				(start 86.016592 -409.396184)
				(mid 85.757512 -409.396184)
				(end 86.016592 -409.396184)
			)
		)
		(stroke
			(width 0)
			(type solid)
		)
		(fill yes)
		(layer "In4.Cu")
		(net "GND")
	)
	(gr_poly
		(pts
			(arc
				(start 86.016592 -407.638504)
				(mid 85.757512 -407.638504)
				(end 86.016592 -407.638504)
			)
		)
		(stroke
			(width 0)
			(type solid)
		)
		(fill yes)
		(layer "In4.Cu")
		(net "GND")
	)
	(gr_poly
		(pts
			(arc
				(start 86.016592 -406.370536)
				(mid 85.757512 -406.370536)
				(end 86.016592 -406.370536)
			)
		)
		(stroke
			(width 0)
			(type solid)
		)
		(fill yes)
		(layer "In4.Cu")
		(net "GND")
	)
	(gr_poly
		(pts
			(arc
				(start 86.104984 -412.570168)
				(mid 85.845904 -412.570168)
				(end 86.104984 -412.570168)
			)
		)
		(stroke
			(width 0)
			(type solid)
		)
		(fill yes)
		(layer "In4.Cu")
		(net "GND")
	)
	(gr_poly
		(pts
			(arc
				(start 86.104984 -404.46452)
				(mid 85.845904 -404.46452)
				(end 86.104984 -404.46452)
			)
		)
		(stroke
			(width 0)
			(type solid)
		)
		(fill yes)
		(layer "In4.Cu")
		(net "GND")
	)
	(gr_poly
		(pts
			(arc
				(start 87.187024 -412.570168)
				(mid 86.927944 -412.570168)
				(end 87.187024 -412.570168)
			)
		)
		(stroke
			(width 0)
			(type solid)
		)
		(fill yes)
		(layer "In4.Cu")
		(net "GND")
	)
	(gr_poly
		(pts
			(arc
				(start 87.187024 -404.46452)
				(mid 86.927944 -404.46452)
				(end 87.187024 -404.46452)
			)
		)
		(stroke
			(width 0)
			(type solid)
		)
		(fill yes)
		(layer "In4.Cu")
		(net "GND")
	)
	(gr_poly
		(pts
			(arc
				(start 87.275416 -409.396184)
				(mid 87.016336 -409.396184)
				(end 87.275416 -409.396184)
			)
		)
		(stroke
			(width 0)
			(type solid)
		)
		(fill yes)
		(layer "In4.Cu")
		(net "GND")
	)
	(gr_poly
		(pts
			(arc
				(start 87.275416 -407.638504)
				(mid 87.016336 -407.638504)
				(end 87.275416 -407.638504)
			)
		)
		(stroke
			(width 0)
			(type solid)
		)
		(fill yes)
		(layer "In4.Cu")
		(net "GND")
	)
	(gr_poly
		(pts
			(arc
				(start 87.275416 -406.370536)
				(mid 87.016336 -406.370536)
				(end 87.275416 -406.370536)
			)
		)
		(stroke
			(width 0)
			(type solid)
		)
		(fill yes)
		(layer "In4.Cu")
		(net "GND")
	)
	(gr_poly
		(pts
			(arc
				(start 87.548212 -413.204152)
				(mid 87.289132 -413.204152)
				(end 87.548212 -413.204152)
			)
		)
		(stroke
			(width 0)
			(type solid)
		)
		(fill yes)
		(layer "In4.Cu")
		(net "GND")
	)
	(gr_poly
		(pts
			(arc
				(start 87.548212 -405.098504)
				(mid 87.289132 -405.098504)
				(end 87.548212 -405.098504)
			)
		)
		(stroke
			(width 0)
			(type solid)
		)
		(fill yes)
		(layer "In4.Cu")
		(net "GND")
	)
	(gr_poly
		(pts
			(arc
				(start 87.548212 -403.830536)
				(mid 87.289132 -403.830536)
				(end 87.548212 -403.830536)
			)
		)
		(stroke
			(width 0)
			(type solid)
		)
		(fill yes)
		(layer "In4.Cu")
		(net "GND")
	)
	(gr_poly
		(pts
			(arc
				(start 87.636604 -410.030168)
				(mid 87.377524 -410.030168)
				(end 87.636604 -410.030168)
			)
		)
		(stroke
			(width 0)
			(type solid)
		)
		(fill yes)
		(layer "In4.Cu")
		(net "GND")
	)
	(gr_poly
		(pts
			(arc
				(start 87.636604 -407.00452)
				(mid 87.377524 -407.00452)
				(end 87.636604 -407.00452)
			)
		)
		(stroke
			(width 0)
			(type solid)
		)
		(fill yes)
		(layer "In4.Cu")
		(net "GND")
	)
	(gr_poly
		(pts
			(arc
				(start 88.718644 -410.030168)
				(mid 88.459564 -410.030168)
				(end 88.718644 -410.030168)
			)
		)
		(stroke
			(width 0)
			(type solid)
		)
		(fill yes)
		(layer "In4.Cu")
		(net "GND")
	)
	(gr_poly
		(pts
			(arc
				(start 88.718644 -407.00452)
				(mid 88.459564 -407.00452)
				(end 88.718644 -407.00452)
			)
		)
		(stroke
			(width 0)
			(type solid)
		)
		(fill yes)
		(layer "In4.Cu")
		(net "GND")
	)
	(gr_poly
		(pts
			(arc
				(start 88.807036 -413.204152)
				(mid 88.547956 -413.204152)
				(end 88.807036 -413.204152)
			)
		)
		(stroke
			(width 0)
			(type solid)
		)
		(fill yes)
		(layer "In4.Cu")
		(net "GND")
	)
	(gr_poly
		(pts
			(arc
				(start 88.807036 -405.098504)
				(mid 88.547956 -405.098504)
				(end 88.807036 -405.098504)
			)
		)
		(stroke
			(width 0)
			(type solid)
		)
		(fill yes)
		(layer "In4.Cu")
		(net "GND")
	)
	(gr_poly
		(pts
			(arc
				(start 88.807036 -403.830536)
				(mid 88.547956 -403.830536)
				(end 88.807036 -403.830536)
			)
		)
		(stroke
			(width 0)
			(type solid)
		)
		(fill yes)
		(layer "In4.Cu")
		(net "GND")
	)
	(gr_poly
		(pts
			(arc
				(start 89.079832 -409.396184)
				(mid 88.820752 -409.396184)
				(end 89.079832 -409.396184)
			)
		)
		(stroke
			(width 0)
			(type solid)
		)
		(fill yes)
		(layer "In4.Cu")
		(net "GND")
	)
	(gr_poly
		(pts
			(arc
				(start 89.079832 -407.638504)
				(mid 88.820752 -407.638504)
				(end 89.079832 -407.638504)
			)
		)
		(stroke
			(width 0)
			(type solid)
		)
		(fill yes)
		(layer "In4.Cu")
		(net "GND")
	)
	(gr_poly
		(pts
			(arc
				(start 89.079832 -406.370536)
				(mid 88.820752 -406.370536)
				(end 89.079832 -406.370536)
			)
		)
		(stroke
			(width 0)
			(type solid)
		)
		(fill yes)
		(layer "In4.Cu")
		(net "GND")
	)
	(gr_poly
		(pts
			(arc
				(start 89.168224 -412.570168)
				(mid 88.909144 -412.570168)
				(end 89.168224 -412.570168)
			)
		)
		(stroke
			(width 0)
			(type solid)
		)
		(fill yes)
		(layer "In4.Cu")
		(net "GND")
	)
	(gr_poly
		(pts
			(arc
				(start 89.168224 -404.46452)
				(mid 88.909144 -404.46452)
				(end 89.168224 -404.46452)
			)
		)
		(stroke
			(width 0)
			(type solid)
		)
		(fill yes)
		(layer "In4.Cu")
		(net "GND")
	)
	(gr_poly
		(pts
			(arc
				(start 90.250264 -412.570168)
				(mid 89.991184 -412.570168)
				(end 90.250264 -412.570168)
			)
		)
		(stroke
			(width 0)
			(type solid)
		)
		(fill yes)
		(layer "In4.Cu")
		(net "GND")
	)
	(gr_poly
		(pts
			(arc
				(start 90.250264 -404.46452)
				(mid 89.991184 -404.46452)
				(end 90.250264 -404.46452)
			)
		)
		(stroke
			(width 0)
			(type solid)
		)
		(fill yes)
		(layer "In4.Cu")
		(net "GND")
	)
	(gr_poly
		(pts
			(arc
				(start 90.338656 -409.396184)
				(mid 90.079576 -409.396184)
				(end 90.338656 -409.396184)
			)
		)
		(stroke
			(width 0)
			(type solid)
		)
		(fill yes)
		(layer "In4.Cu")
		(net "GND")
	)
	(gr_poly
		(pts
			(arc
				(start 90.338656 -407.638504)
				(mid 90.079576 -407.638504)
				(end 90.338656 -407.638504)
			)
		)
		(stroke
			(width 0)
			(type solid)
		)
		(fill yes)
		(layer "In4.Cu")
		(net "GND")
	)
	(gr_poly
		(pts
			(arc
				(start 90.338656 -406.370536)
				(mid 90.079576 -406.370536)
				(end 90.338656 -406.370536)
			)
		)
		(stroke
			(width 0)
			(type solid)
		)
		(fill yes)
		(layer "In4.Cu")
		(net "GND")
	)
	(gr_poly
		(pts
			(arc
				(start 90.611452 -413.204152)
				(mid 90.352372 -413.204152)
				(end 90.611452 -413.204152)
			)
		)
		(stroke
			(width 0)
			(type solid)
		)
		(fill yes)
		(layer "In4.Cu")
		(net "GND")
	)
	(gr_poly
		(pts
			(arc
				(start 90.611452 -405.098504)
				(mid 90.352372 -405.098504)
				(end 90.611452 -405.098504)
			)
		)
		(stroke
			(width 0)
			(type solid)
		)
		(fill yes)
		(layer "In4.Cu")
		(net "GND")
	)
	(gr_poly
		(pts
			(arc
				(start 90.611452 -403.830536)
				(mid 90.352372 -403.830536)
				(end 90.611452 -403.830536)
			)
		)
		(stroke
			(width 0)
			(type solid)
		)
		(fill yes)
		(layer "In4.Cu")
		(net "GND")
	)
	(gr_poly
		(pts
			(arc
				(start 90.699844 -410.030168)
				(mid 90.440764 -410.030168)
				(end 90.699844 -410.030168)
			)
		)
		(stroke
			(width 0)
			(type solid)
		)
		(fill yes)
		(layer "In4.Cu")
		(net "GND")
	)
	(gr_poly
		(pts
			(arc
				(start 90.699844 -407.00452)
				(mid 90.440764 -407.00452)
				(end 90.699844 -407.00452)
			)
		)
		(stroke
			(width 0)
			(type solid)
		)
		(fill yes)
		(layer "In4.Cu")
		(net "GND")
	)
	(gr_poly
		(pts
			(arc
				(start 91.781884 -410.030168)
				(mid 91.522804 -410.030168)
				(end 91.781884 -410.030168)
			)
		)
		(stroke
			(width 0)
			(type solid)
		)
		(fill yes)
		(layer "In4.Cu")
		(net "GND")
	)
	(gr_poly
		(pts
			(arc
				(start 91.781884 -407.00452)
				(mid 91.522804 -407.00452)
				(end 91.781884 -407.00452)
			)
		)
		(stroke
			(width 0)
			(type solid)
		)
		(fill yes)
		(layer "In4.Cu")
		(net "GND")
	)
	(gr_poly
		(pts
			(arc
				(start 91.870276 -413.204152)
				(mid 91.611196 -413.204152)
				(end 91.870276 -413.204152)
			)
		)
		(stroke
			(width 0)
			(type solid)
		)
		(fill yes)
		(layer "In4.Cu")
		(net "GND")
	)
	(gr_poly
		(pts
			(arc
				(start 91.870276 -405.098504)
				(mid 91.611196 -405.098504)
				(end 91.870276 -405.098504)
			)
		)
		(stroke
			(width 0)
			(type solid)
		)
		(fill yes)
		(layer "In4.Cu")
		(net "GND")
	)
	(gr_poly
		(pts
			(arc
				(start 91.870276 -403.830536)
				(mid 91.611196 -403.830536)
				(end 91.870276 -403.830536)
			)
		)
		(stroke
			(width 0)
			(type solid)
		)
		(fill yes)
		(layer "In4.Cu")
		(net "GND")
	)
	(gr_poly
		(pts
			(arc
				(start 92.143072 -409.396184)
				(mid 91.883992 -409.396184)
				(end 92.143072 -409.396184)
			)
		)
		(stroke
			(width 0)
			(type solid)
		)
		(fill yes)
		(layer "In4.Cu")
		(net "GND")
	)
	(gr_poly
		(pts
			(arc
				(start 92.143072 -407.638504)
				(mid 91.883992 -407.638504)
				(end 92.143072 -407.638504)
			)
		)
		(stroke
			(width 0)
			(type solid)
		)
		(fill yes)
		(layer "In4.Cu")
		(net "GND")
	)
	(gr_poly
		(pts
			(arc
				(start 92.143072 -406.370536)
				(mid 91.883992 -406.370536)
				(end 92.143072 -406.370536)
			)
		)
		(stroke
			(width 0)
			(type solid)
		)
		(fill yes)
		(layer "In4.Cu")
		(net "GND")
	)
	(gr_poly
		(pts
			(arc
				(start 92.231464 -412.570168)
				(mid 91.972384 -412.570168)
				(end 92.231464 -412.570168)
			)
		)
		(stroke
			(width 0)
			(type solid)
		)
		(fill yes)
		(layer "In4.Cu")
		(net "GND")
	)
	(gr_poly
		(pts
			(arc
				(start 92.231464 -404.46452)
				(mid 91.972384 -404.46452)
				(end 92.231464 -404.46452)
			)
		)
		(stroke
			(width 0)
			(type solid)
		)
		(fill yes)
		(layer "In4.Cu")
		(net "GND")
	)
	(gr_poly
		(pts
			(arc
				(start 93.313504 -412.570168)
				(mid 93.054424 -412.570168)
				(end 93.313504 -412.570168)
			)
		)
		(stroke
			(width 0)
			(type solid)
		)
		(fill yes)
		(layer "In4.Cu")
		(net "GND")
	)
	(gr_poly
		(pts
			(arc
				(start 93.313504 -404.46452)
				(mid 93.054424 -404.46452)
				(end 93.313504 -404.46452)
			)
		)
		(stroke
			(width 0)
			(type solid)
		)
		(fill yes)
		(layer "In4.Cu")
		(net "GND")
	)
	(gr_poly
		(pts
			(arc
				(start 93.401896 -409.396184)
				(mid 93.142816 -409.396184)
				(end 93.401896 -409.396184)
			)
		)
		(stroke
			(width 0)
			(type solid)
		)
		(fill yes)
		(layer "In4.Cu")
		(net "GND")
	)
	(gr_poly
		(pts
			(arc
				(start 93.401896 -407.638504)
				(mid 93.142816 -407.638504)
				(end 93.401896 -407.638504)
			)
		)
		(stroke
			(width 0)
			(type solid)
		)
		(fill yes)
		(layer "In4.Cu")
		(net "GND")
	)
	(gr_poly
		(pts
			(arc
				(start 93.401896 -406.370536)
				(mid 93.142816 -406.370536)
				(end 93.401896 -406.370536)
			)
		)
		(stroke
			(width 0)
			(type solid)
		)
		(fill yes)
		(layer "In4.Cu")
		(net "GND")
	)
	(gr_poly
		(pts
			(arc
				(start 93.674692 -413.204152)
				(mid 93.415612 -413.204152)
				(end 93.674692 -413.204152)
			)
		)
		(stroke
			(width 0)
			(type solid)
		)
		(fill yes)
		(layer "In4.Cu")
		(net "GND")
	)
	(gr_poly
		(pts
			(arc
				(start 93.674692 -405.098504)
				(mid 93.415612 -405.098504)
				(end 93.674692 -405.098504)
			)
		)
		(stroke
			(width 0)
			(type solid)
		)
		(fill yes)
		(layer "In4.Cu")
		(net "GND")
	)
	(gr_poly
		(pts
			(arc
				(start 93.674692 -403.830536)
				(mid 93.415612 -403.830536)
				(end 93.674692 -403.830536)
			)
		)
		(stroke
			(width 0)
			(type solid)
		)
		(fill yes)
		(layer "In4.Cu")
		(net "GND")
	)
	(gr_poly
		(pts
			(arc
				(start 93.763084 -410.030168)
				(mid 93.504004 -410.030168)
				(end 93.763084 -410.030168)
			)
		)
		(stroke
			(width 0)
			(type solid)
		)
		(fill yes)
		(layer "In4.Cu")
		(net "GND")
	)
	(gr_poly
		(pts
			(arc
				(start 93.763084 -407.00452)
				(mid 93.504004 -407.00452)
				(end 93.763084 -407.00452)
			)
		)
		(stroke
			(width 0)
			(type solid)
		)
		(fill yes)
		(layer "In4.Cu")
		(net "GND")
	)
	(gr_poly
		(pts
			(arc
				(start 94.845124 -410.030168)
				(mid 94.586044 -410.030168)
				(end 94.845124 -410.030168)
			)
		)
		(stroke
			(width 0)
			(type solid)
		)
		(fill yes)
		(layer "In4.Cu")
		(net "GND")
	)
	(gr_poly
		(pts
			(arc
				(start 94.845124 -407.00452)
				(mid 94.586044 -407.00452)
				(end 94.845124 -407.00452)
			)
		)
		(stroke
			(width 0)
			(type solid)
		)
		(fill yes)
		(layer "In4.Cu")
		(net "GND")
	)
	(gr_poly
		(pts
			(arc
				(start 94.933516 -413.204152)
				(mid 94.674436 -413.204152)
				(end 94.933516 -413.204152)
			)
		)
		(stroke
			(width 0)
			(type solid)
		)
		(fill yes)
		(layer "In4.Cu")
		(net "GND")
	)
	(gr_poly
		(pts
			(arc
				(start 94.933516 -405.098504)
				(mid 94.674436 -405.098504)
				(end 94.933516 -405.098504)
			)
		)
		(stroke
			(width 0)
			(type solid)
		)
		(fill yes)
		(layer "In4.Cu")
		(net "GND")
	)
	(gr_poly
		(pts
			(arc
				(start 94.933516 -403.830536)
				(mid 94.674436 -403.830536)
				(end 94.933516 -403.830536)
			)
		)
		(stroke
			(width 0)
			(type solid)
		)
		(fill yes)
		(layer "In4.Cu")
		(net "GND")
	)
	(gr_poly
		(pts
			(arc
				(start 95.206312 -409.396184)
				(mid 94.947232 -409.396184)
				(end 95.206312 -409.396184)
			)
		)
		(stroke
			(width 0)
			(type solid)
		)
		(fill yes)
		(layer "In4.Cu")
		(net "GND")
	)
	(gr_poly
		(pts
			(arc
				(start 95.206312 -407.638504)
				(mid 94.947232 -407.638504)
				(end 95.206312 -407.638504)
			)
		)
		(stroke
			(width 0)
			(type solid)
		)
		(fill yes)
		(layer "In4.Cu")
		(net "GND")
	)
	(gr_poly
		(pts
			(arc
				(start 95.206312 -406.370536)
				(mid 94.947232 -406.370536)
				(end 95.206312 -406.370536)
			)
		)
		(stroke
			(width 0)
			(type solid)
		)
		(fill yes)
		(layer "In4.Cu")
		(net "GND")
	)
	(gr_poly
		(pts
			(arc
				(start 95.294704 -412.570168)
				(mid 95.035624 -412.570168)
				(end 95.294704 -412.570168)
			)
		)
		(stroke
			(width 0)
			(type solid)
		)
		(fill yes)
		(layer "In4.Cu")
		(net "GND")
	)
	(gr_poly
		(pts
			(arc
				(start 95.294704 -404.46452)
				(mid 95.035624 -404.46452)
				(end 95.294704 -404.46452)
			)
		)
		(stroke
			(width 0)
			(type solid)
		)
		(fill yes)
		(layer "In4.Cu")
		(net "GND")
	)
	(gr_poly
		(pts
			(arc
				(start 96.465136 -410.664152)
				(mid 96.206056 -410.664152)
				(end 96.465136 -410.664152)
			)
		)
		(stroke
			(width 0)
			(type solid)
		)
		(fill yes)
		(layer "In4.Cu")
		(net "GND")
	)
	(gr_poly
		(pts
			(arc
				(start 96.465136 -409.396184)
				(mid 96.206056 -409.396184)
				(end 96.465136 -409.396184)
			)
		)
		(stroke
			(width 0)
			(type solid)
		)
		(fill yes)
		(layer "In4.Cu")
		(net "GND")
	)
	(gr_poly
		(pts
			(arc
				(start 96.465136 -407.638504)
				(mid 96.206056 -407.638504)
				(end 96.465136 -407.638504)
			)
		)
		(stroke
			(width 0)
			(type solid)
		)
		(fill yes)
		(layer "In4.Cu")
		(net "GND")
	)
	(gr_poly
		(pts
			(arc
				(start 96.465136 -406.370536)
				(mid 96.206056 -406.370536)
				(end 96.465136 -406.370536)
			)
		)
		(stroke
			(width 0)
			(type solid)
		)
		(fill yes)
		(layer "In4.Cu")
		(net "GND")
	)
	(gr_poly
		(pts
			(arc
				(start 96.826324 -410.030168)
				(mid 96.567244 -410.030168)
				(end 96.826324 -410.030168)
			)
		)
		(stroke
			(width 0)
			(type solid)
		)
		(fill yes)
		(layer "In4.Cu")
		(net "GND")
	)
	(gr_poly
		(pts
			(arc
				(start 96.826324 -407.00452)
				(mid 96.567244 -407.00452)
				(end 96.826324 -407.00452)
			)
		)
		(stroke
			(width 0)
			(type solid)
		)
		(fill yes)
		(layer "In4.Cu")
		(net "GND")
	)
	(gr_poly
		(pts
			(arc
				(start 137.846816 -375.917968)
				(mid 137.587736 -375.917968)
				(end 137.846816 -375.917968)
			)
		)
		(stroke
			(width 0)
			(type solid)
		)
		(fill yes)
		(layer "In4.Cu")
		(net "GND")
	)
	(gr_poly
		(pts
			(arc
				(start 152.843738 -413.204152)
				(mid 152.584658 -413.204152)
				(end 152.843738 -413.204152)
			)
		)
		(stroke
			(width 0)
			(type solid)
		)
		(fill yes)
		(layer "In4.Cu")
		(net "GND")
	)
	(gr_poly
		(pts
			(arc
				(start 154.286966 -412.570168)
				(mid 154.027886 -412.570168)
				(end 154.286966 -412.570168)
			)
		)
		(stroke
			(width 0)
			(type solid)
		)
		(fill yes)
		(layer "In4.Cu")
		(net "GND")
	)
	(gr_poly
		(pts
			(arc
				(start 154.648154 -413.204152)
				(mid 154.389074 -413.204152)
				(end 154.648154 -413.204152)
			)
		)
		(stroke
			(width 0)
			(type solid)
		)
		(fill yes)
		(layer "In4.Cu")
		(net "GND")
	)
	(gr_poly
		(pts
			(arc
				(start 154.648154 -411.936184)
				(mid 154.389074 -411.936184)
				(end 154.648154 -411.936184)
			)
		)
		(stroke
			(width 0)
			(type solid)
		)
		(fill yes)
		(layer "In4.Cu")
		(net "GND")
	)
	(gr_poly
		(pts
			(arc
				(start 155.906978 -413.204152)
				(mid 155.647898 -413.204152)
				(end 155.906978 -413.204152)
			)
		)
		(stroke
			(width 0)
			(type solid)
		)
		(fill yes)
		(layer "In4.Cu")
		(net "GND")
	)
	(gr_poly
		(pts
			(arc
				(start 155.906978 -411.936184)
				(mid 155.647898 -411.936184)
				(end 155.906978 -411.936184)
			)
		)
		(stroke
			(width 0)
			(type solid)
		)
		(fill yes)
		(layer "In4.Cu")
		(net "GND")
	)
	(gr_poly
		(pts
			(arc
				(start 156.268166 -412.570168)
				(mid 156.009086 -412.570168)
				(end 156.268166 -412.570168)
			)
		)
		(stroke
			(width 0)
			(type solid)
		)
		(fill yes)
		(layer "In4.Cu")
		(net "GND")
	)
	(gr_poly
		(pts
			(arc
				(start 157.350206 -412.570168)
				(mid 157.091126 -412.570168)
				(end 157.350206 -412.570168)
			)
		)
		(stroke
			(width 0)
			(type solid)
		)
		(fill yes)
		(layer "In4.Cu")
		(net "GND")
	)
	(gr_poly
		(pts
			(arc
				(start 157.711394 -413.204152)
				(mid 157.452314 -413.204152)
				(end 157.711394 -413.204152)
			)
		)
		(stroke
			(width 0)
			(type solid)
		)
		(fill yes)
		(layer "In4.Cu")
		(net "GND")
	)
	(gr_poly
		(pts
			(arc
				(start 157.711394 -411.936184)
				(mid 157.452314 -411.936184)
				(end 157.711394 -411.936184)
			)
		)
		(stroke
			(width 0)
			(type solid)
		)
		(fill yes)
		(layer "In4.Cu")
		(net "GND")
	)
	(gr_poly
		(pts
			(arc
				(start 158.970218 -413.204152)
				(mid 158.711138 -413.204152)
				(end 158.970218 -413.204152)
			)
		)
		(stroke
			(width 0)
			(type solid)
		)
		(fill yes)
		(layer "In4.Cu")
		(net "GND")
	)
	(gr_poly
		(pts
			(arc
				(start 158.970218 -411.936184)
				(mid 158.711138 -411.936184)
				(end 158.970218 -411.936184)
			)
		)
		(stroke
			(width 0)
			(type solid)
		)
		(fill yes)
		(layer "In4.Cu")
		(net "GND")
	)
	(gr_poly
		(pts
			(arc
				(start 159.331406 -412.570168)
				(mid 159.072326 -412.570168)
				(end 159.331406 -412.570168)
			)
		)
		(stroke
			(width 0)
			(type solid)
		)
		(fill yes)
		(layer "In4.Cu")
		(net "GND")
	)
	(gr_poly
		(pts
			(arc
				(start 160.413446 -412.570168)
				(mid 160.154366 -412.570168)
				(end 160.413446 -412.570168)
			)
		)
		(stroke
			(width 0)
			(type solid)
		)
		(fill yes)
		(layer "In4.Cu")
		(net "GND")
	)
	(gr_poly
		(pts
			(arc
				(start 160.774634 -413.204152)
				(mid 160.515554 -413.204152)
				(end 160.774634 -413.204152)
			)
		)
		(stroke
			(width 0)
			(type solid)
		)
		(fill yes)
		(layer "In4.Cu")
		(net "GND")
	)
	(gr_poly
		(pts
			(arc
				(start 160.774634 -411.936184)
				(mid 160.515554 -411.936184)
				(end 160.774634 -411.936184)
			)
		)
		(stroke
			(width 0)
			(type solid)
		)
		(fill yes)
		(layer "In4.Cu")
		(net "GND")
	)
	(gr_poly
		(pts
			(arc
				(start 161.309304 -103.593392)
				(mid 161.050224 -103.593392)
				(end 161.309304 -103.593392)
			)
		)
		(stroke
			(width 0)
			(type solid)
		)
		(fill yes)
		(layer "In4.Cu")
		(net "GND")
	)
	(gr_poly
		(pts
			(arc
				(start 162.033458 -413.204152)
				(mid 161.774378 -413.204152)
				(end 162.033458 -413.204152)
			)
		)
		(stroke
			(width 0)
			(type solid)
		)
		(fill yes)
		(layer "In4.Cu")
		(net "GND")
	)
	(gr_poly
		(pts
			(arc
				(start 162.033458 -411.936184)
				(mid 161.774378 -411.936184)
				(end 162.033458 -411.936184)
			)
		)
		(stroke
			(width 0)
			(type solid)
		)
		(fill yes)
		(layer "In4.Cu")
		(net "GND")
	)
	(gr_poly
		(pts
			(arc
				(start 162.394646 -412.570168)
				(mid 162.135566 -412.570168)
				(end 162.394646 -412.570168)
			)
		)
		(stroke
			(width 0)
			(type solid)
		)
		(fill yes)
		(layer "In4.Cu")
		(net "GND")
	)
	(gr_poly
		(pts
			(arc
				(start 170.3705 -375.917968)
				(mid 170.119548 -375.917968)
				(end 170.3705 -375.917968)
			)
		)
		(stroke
			(width 0)
			(type solid)
		)
		(fill yes)
		(layer "In4.Cu")
		(net "GND")
	)
	(gr_poly
		(pts
			(xy 229.6795 -435.74208) (xy 229.6795 -424.561) (xy 237.319566 -416.920934) (xy 272.877026 -416.920934)
			(xy 279.44318 -410.35478) (xy 280.05024 -409.74772) (xy 280.05024 -398.559782) (xy 279.274778 -397.78432)
			(xy 240.064544 -397.78432) (xy 239.755934 -398.09293) (xy 239.755934 -405.758142) (xy 234.870752 -410.643324)
			(xy 229.7176 -410.643324) (xy 227.051616 -413.309308) (xy 196.736716 -413.309308) (xy 196.014086 -414.031938)
			(xy 196.014086 -415.651442) (xy 196.06006 -415.697416) (xy 196.06006 -421.557196)
			(arc
				(start 206.039974 -431.536856)
				(mid 206.051085 -431.55339)
				(end 206.05496 -431.572924)
			)
			(xy 206.05496 -435.09946) (xy 207.43418 -436.47868) (xy 228.9429 -436.47868)
		)
		(stroke
			(width 0)
			(type solid)
		)
		(fill yes)
		(layer "In4.Cu")
		(net "P12V_PSU")
	)
	(gr_poly
		(pts
			(arc
				(start 181.544722 -52.884578)
				(mid 181.270402 -52.884578)
				(end 181.544722 -52.884578)
			)
		)
		(stroke
			(width 0)
			(type solid)
		)
		(fill yes)
		(layer "In4.Cu")
		(net "GND")
	)
	(gr_poly
		(pts
			(arc
				(start 182.81523 -52.884578)
				(mid 182.53583 -52.884578)
				(end 182.81523 -52.884578)
			)
		)
		(stroke
			(width 0)
			(type solid)
		)
		(fill yes)
		(layer "In4.Cu")
		(net "GND")
	)
	(gr_poly
		(pts
			(arc
				(start 189.644528 -382.760474)
				(mid 189.365128 -382.760474)
				(end 189.644528 -382.760474)
			)
		)
		(stroke
			(width 0)
			(type solid)
		)
		(fill yes)
		(layer "In4.Cu")
		(net "GND")
	)
	(gr_poly
		(pts
			(arc
				(start 305.259994 -417.778184)
				(mid 304.995834 -417.778184)
				(end 305.259994 -417.778184)
			)
		)
		(stroke
			(width 0)
			(type solid)
		)
		(fill yes)
		(layer "In4.Cu")
		(net "GND")
	)
	(gr_poly
		(pts
			(arc
				(start 306.518818 -417.778184)
				(mid 306.254658 -417.778184)
				(end 306.518818 -417.778184)
			)
		)
		(stroke
			(width 0)
			(type solid)
		)
		(fill yes)
		(layer "In4.Cu")
		(net "GND")
	)
	(gr_poly
		(pts
			(arc
				(start 308.323234 -417.778184)
				(mid 308.059074 -417.778184)
				(end 308.323234 -417.778184)
			)
		)
		(stroke
			(width 0)
			(type solid)
		)
		(fill yes)
		(layer "In4.Cu")
		(net "GND")
	)
	(gr_poly
		(pts
			(arc
				(start 190.70574 -18.49628)
				(mid 190.33998 -18.49628)
				(end 190.70574 -18.49628)
			)
		)
		(stroke
			(width 0)
			(type solid)
		)
		(fill yes)
		(layer "In4.Cu")
		(net "GND")
	)
	(gr_poly
		(pts
			(arc
				(start 81.154778 -2.750312)
				(mid 81.182917 -2.732466)
				(end 81.193894 -2.701036)
			)
			(arc
				(start 81.193894 -0.5588)
				(mid 81.179015 -0.522879)
				(end 81.143094 -0.508)
			)
			(arc
				(start 13.660882 -0.508)
				(mid 13.624961 -0.522879)
				(end 13.610082 -0.5588)
			)
			(arc
				(start 13.610082 -2.701036)
				(mid 13.621129 -2.732411)
				(end 13.649198 -2.750312)
			)
			(xy 13.762482 -2.77749) (xy 13.794486 -2.762504)
			(arc
				(start 13.80236 -2.746756)
				(mid 13.928356 -2.557713)
				(end 14.095984 -2.404364)
			)
			(xy 14.11732 -2.363216) (xy 14.11732 -1.014984) (xy 80.686656 -1.014984) (xy 80.686656 -2.363216)
			(arc
				(start 80.707992 -2.404364)
				(mid 80.875659 -2.55768)
				(end 81.001616 -2.746756)
			)
			(xy 81.00949 -2.762504) (xy 81.041494 -2.77749)
		)
		(stroke
			(width 0)
			(type solid)
		)
		(fill yes)
		(layer "In4.Cu")
		(net "GND")
	)
	(gr_poly
		(pts
			(arc
				(start 194.154806 -8.03021)
				(mid 194.182945 -8.012364)
				(end 194.193922 -7.980934)
			)
			(arc
				(start 194.193922 -5.838698)
				(mid 194.179043 -5.802777)
				(end 194.143122 -5.787898)
			)
			(arc
				(start 126.66091 -5.787898)
				(mid 126.624989 -5.802777)
				(end 126.61011 -5.838698)
			)
			(arc
				(start 126.61011 -7.980934)
				(mid 126.621157 -8.012309)
				(end 126.649226 -8.03021)
			)
			(xy 126.76251 -8.057388) (xy 126.794514 -8.042402)
			(arc
				(start 126.802388 -8.026654)
				(mid 126.928384 -7.837611)
				(end 127.096012 -7.684262)
			)
			(xy 127.117348 -7.643114) (xy 127.117348 -6.295136) (xy 193.686684 -6.295136) (xy 193.686684 -7.643114)
			(arc
				(start 193.70802 -7.684262)
				(mid 193.875687 -7.837578)
				(end 194.001644 -8.026654)
			)
			(xy 194.009518 -8.042402) (xy 194.041522 -8.057388)
		)
		(stroke
			(width 0)
			(type solid)
		)
		(fill yes)
		(layer "In4.Cu")
		(net "GND")
	)
	(gr_poly
		(pts
			(arc
				(start 455.654918 -2.75082)
				(mid 455.683057 -2.732974)
				(end 455.694034 -2.701544)
			)
			(arc
				(start 455.694034 -0.5588)
				(mid 455.679155 -0.522879)
				(end 455.643234 -0.508)
			)
			(arc
				(start 388.160768 -0.508)
				(mid 388.124847 -0.522879)
				(end 388.109968 -0.5588)
			)
			(arc
				(start 388.109968 -2.701036)
				(mid 388.121015 -2.732411)
				(end 388.149084 -2.750312)
			)
			(xy 388.262368 -2.77749) (xy 388.294372 -2.762504)
			(arc
				(start 388.302246 -2.746756)
				(mid 388.428345 -2.557672)
				(end 388.596124 -2.404364)
			)
			(arc
				(start 388.596124 -2.404364)
				(mid 388.610195 -2.388884)
				(end 388.616952 -2.369058)
			)
			(xy 388.616952 -1.014984) (xy 455.186796 -1.014984) (xy 455.186796 -2.36347)
			(arc
				(start 455.208132 -2.404618)
				(mid 455.3758 -2.558068)
				(end 455.501756 -2.747264)
			)
			(xy 455.50963 -2.763012) (xy 455.54138 -2.777744)
		)
		(stroke
			(width 0)
			(type solid)
		)
		(fill yes)
		(layer "In4.Cu")
		(net "GND")
	)
	(gr_poly
		(pts
			(arc
				(start 431.511202 -376.09272)
				(mid 431.530725 -376.088819)
				(end 431.54727 -376.077734)
			)
			(arc
				(start 433.687728 -373.93753)
				(mid 433.702488 -373.901626)
				(end 433.687728 -373.865648)
			)
			(arc
				(start 433.171346 -373.349266)
				(mid 433.154812 -373.338155)
				(end 433.135278 -373.33428)
			)
			(arc
				(start 425.110402 -373.33428)
				(mid 425.090879 -373.330379)
				(end 425.074334 -373.319294)
			)
			(xy 425.071032 -373.315992)
			(arc
				(start 424.99915 -373.315992)
				(mid 424.879441 -373.292274)
				(end 424.777916 -373.224552)
			)
			(arc
				(start 423.36339 -371.810026)
				(mid 423.346973 -371.798964)
				(end 423.327576 -371.79504)
			)
			(arc
				(start 416.126422 -371.79504)
				(mid 416.106899 -371.791139)
				(end 416.090354 -371.780054)
			)
			(arc
				(start 410.283406 -365.973106)
				(mid 410.266872 -365.961995)
				(end 410.247338 -365.95812)
			)
			(arc
				(start 409.390342 -365.95812)
				(mid 409.370819 -365.962021)
				(end 409.354274 -365.973106)
			)
			(arc
				(start 407.225246 -368.102134)
				(mid 407.214135 -368.118668)
				(end 407.21026 -368.138202)
			)
			(arc
				(start 407.21026 -369.680998)
				(mid 407.214161 -369.700521)
				(end 407.225246 -369.717066)
			)
			(arc
				(start 413.585914 -376.077734)
				(mid 413.602448 -376.088845)
				(end 413.621982 -376.09272)
			)
		)
		(stroke
			(width 0)
			(type solid)
		)
		(fill yes)
		(layer "In4.Cu")
		(net "P5V_AUX")
	)
	(gr_poly
		(pts
			(arc
				(start 7.548626 -137.9601)
				(mid 7.568149 -137.956199)
				(end 7.584694 -137.945114)
			)
			(arc
				(start 7.679944 -137.849864)
				(mid 7.691055 -137.83333)
				(end 7.69493 -137.813796)
			)
			(xy 7.69493 -135.794496) (xy 7.67461 -135.767572)
			(arc
				(start 7.6581 -135.762746)
				(mid 7.381151 -135.39597)
				(end 7.6581 -135.029194)
			)
			(xy 7.67461 -135.024368) (xy 7.69493 -134.997444)
			(arc
				(start 7.69493 -132.962396)
				(mid 7.691029 -132.942873)
				(end 7.679944 -132.926328)
			)
			(arc
				(start 7.584694 -132.831078)
				(mid 7.56816 -132.819967)
				(end 7.548626 -132.816092)
			)
			(arc
				(start 4.00177 -132.816092)
				(mid 3.982247 -132.819993)
				(end 3.965702 -132.831078)
			)
			(arc
				(start 3.870452 -132.926328)
				(mid 3.859341 -132.942862)
				(end 3.855466 -132.962396)
			)
			(arc
				(start 3.855466 -137.813796)
				(mid 3.859367 -137.833319)
				(end 3.870452 -137.849864)
			)
			(arc
				(start 3.965702 -137.945114)
				(mid 3.982236 -137.956225)
				(end 4.00177 -137.9601)
			)
		)
		(stroke
			(width 0)
			(type solid)
		)
		(fill yes)
		(layer "In4.Cu")
		(net "GND")
	)
	(gr_poly
		(pts
			(arc
				(start 192.194434 -404.25878)
				(mid 192.213957 -404.254879)
				(end 192.230502 -404.243794)
			)
			(arc
				(start 192.702434 -403.771862)
				(mid 192.784956 -403.716786)
				(end 192.882266 -403.69744)
			)
			(arc
				(start 194.761612 -403.69744)
				(mid 194.841907 -403.710367)
				(end 194.914012 -403.747986)
			)
			(xy 194.929252 -403.759416) (xy 194.966844 -403.756622)
			(arc
				(start 194.980306 -403.74316)
				(mid 194.995066 -403.707256)
				(end 194.980306 -403.671278)
			)
			(arc
				(start 194.227196 -402.918168)
				(mid 194.210633 -402.907194)
				(end 194.191128 -402.903436)
			)
			(arc
				(start 193.012822 -402.903436)
				(mid 192.993328 -402.90722)
				(end 192.976754 -402.918168)
			)
			(arc
				(start 192.808098 -403.087078)
				(mid 192.742022 -403.131229)
				(end 192.66408 -403.146768)
			)
			(arc
				(start 191.33312 -403.146768)
				(mid 191.255164 -403.131262)
				(end 191.189102 -403.087078)
			)
			(arc
				(start 190.465456 -402.363178)
				(mid 190.448922 -402.352067)
				(end 190.429388 -402.348192)
			)
			(arc
				(start 190.399162 -402.348192)
				(mid 190.363241 -402.363071)
				(end 190.348362 -402.398992)
			)
			(xy 190.348362 -402.412454) (xy 190.361062 -402.435314)
			(arc
				(start 190.372238 -402.442426)
				(mid 190.396277 -402.459256)
				(end 190.418212 -402.478748)
			)
			(arc
				(start 191.857122 -403.917658)
				(mid 191.912198 -404.00018)
				(end 191.931544 -404.09749)
			)
			(arc
				(start 191.931544 -404.206964)
				(mid 191.935494 -404.226351)
				(end 191.94653 -404.242778)
			)
			(arc
				(start 191.947546 -404.243794)
				(mid 191.963963 -404.254856)
				(end 191.98336 -404.25878)
			)
		)
		(stroke
			(width 0)
			(type solid)
		)
		(fill yes)
		(layer "In4.Cu")
		(net "AGND_HSC")
	)
	(gr_poly
		(pts
			(arc
				(start 453.286114 -30.026102)
				(mid 453.305637 -30.022201)
				(end 453.322182 -30.011116)
			)
			(arc
				(start 454.280778 -29.05252)
				(mid 454.29184 -29.036103)
				(end 454.295764 -29.016706)
			)
			(arc
				(start 454.295764 -26.473912)
				(mid 454.280885 -26.437991)
				(end 454.244964 -26.423112)
			)
			(arc
				(start 452.444866 -26.423112)
				(mid 452.425343 -26.419211)
				(end 452.408798 -26.408126)
			)
			(arc
				(start 452.08317 -26.082498)
				(mid 452.072059 -26.065964)
				(end 452.068184 -26.04643)
			)
			(arc
				(start 452.068184 -25.298654)
				(mid 452.072085 -25.279131)
				(end 452.08317 -25.262586)
			)
			(arc
				(start 452.083678 -25.262078)
				(mid 452.094789 -25.245544)
				(end 452.098664 -25.22601)
			)
			(arc
				(start 452.098664 -23.243032)
				(mid 452.091432 -23.216908)
				(end 452.07174 -23.198328)
			)
			(arc
				(start 452.07174 -23.198328)
				(mid 451.798824 -22.974242)
				(end 451.634606 -22.661626)
			)
			(xy 451.62978 -22.64537) (xy 451.602856 -22.62505) (xy 451.38086 -22.62505) (xy 451.353682 -22.646132)
			(arc
				(start 451.34911 -22.662896)
				(mid 451.179659 -22.99798)
				(end 450.887084 -23.23338)
			)
			(arc
				(start 450.887084 -23.23338)
				(mid 450.866692 -23.252032)
				(end 450.859144 -23.278592)
			)
			(arc
				(start 450.859144 -24.77897)
				(mid 450.855243 -24.798493)
				(end 450.844158 -24.815038)
			)
			(arc
				(start 450.42455 -25.234646)
				(mid 450.408016 -25.245757)
				(end 450.388482 -25.249632)
			)
			(arc
				(start 448.937126 -25.249632)
				(mid 448.917603 -25.253533)
				(end 448.901058 -25.264618)
			)
			(arc
				(start 448.09283 -26.072846)
				(mid 448.076296 -26.083957)
				(end 448.056762 -26.087832)
			)
			(arc
				(start 446.446402 -26.087832)
				(mid 446.435063 -26.089114)
				(end 446.424304 -26.092912)
			)
			(arc
				(start 446.424304 -26.092912)
				(mid 446.33947 -26.127272)
				(end 446.250822 -26.150062)
			)
			(xy 446.243202 -26.151586) (xy 446.229994 -26.158444)
			(arc
				(start 444.916052 -27.472386)
				(mid 444.899518 -27.483497)
				(end 444.879984 -27.487372)
			)
			(arc
				(start 444.847726 -27.487372)
				(mid 444.828339 -27.491322)
				(end 444.811912 -27.502358)
			)
			(arc
				(start 444.494666 -27.819604)
				(mid 444.478103 -27.830578)
				(end 444.458598 -27.834336)
			)
			(arc
				(start 440.888628 -27.834336)
				(mid 440.852781 -27.849289)
				(end 440.837828 -27.885136)
			)
			(arc
				(start 440.837828 -28.832302)
				(mid 440.852707 -28.868223)
				(end 440.888628 -28.883102)
			)
			(arc
				(start 445.131698 -28.883102)
				(mid 445.151221 -28.887003)
				(end 445.167766 -28.898088)
			)
			(arc
				(start 446.280794 -30.011116)
				(mid 446.297328 -30.022227)
				(end 446.316862 -30.026102)
			)
		)
		(stroke
			(width 0)
			(type solid)
		)
		(fill yes)
		(layer "In4.Cu")
		(net "P12V_AUX")
	)
	(gr_poly
		(pts
			(xy 201.94651 -32.368744) (xy 201.956578 -32.368318) (xy 201.975175 -32.360594) (xy 201.982578 -32.353758)
			(xy 202.26655 -32.069786) (xy 202.2734 -32.062389) (xy 202.281137 -32.043791) (xy 202.281536 -32.033718)
			(xy 202.281536 -29.308298) (xy 202.281111 -29.298229) (xy 202.273389 -29.279631) (xy 202.26655 -29.27223)
			(xy 197.917816 -24.923496) (xy 197.910969 -24.916098) (xy 197.903233 -24.8975) (xy 197.90283 -24.887428)
			(xy 197.90283 -16.676878) (xy 197.902404 -16.666809) (xy 197.894687 -16.648207) (xy 197.887844 -16.64081)
			(xy 196.819012 -15.571978) (xy 196.811618 -15.565121) (xy 196.793019 -15.55737) (xy 196.782944 -15.556992)
			(xy 194.792854 -15.556992) (xy 194.782788 -15.55656) (xy 194.764196 -15.548833) (xy 194.756786 -15.542006)
			(xy 194.4243 -15.20952) (xy 194.416892 -15.202833) (xy 194.398455 -15.195248) (xy 194.388486 -15.194788)
			(xy 191.511936 -15.194788) (xy 191.501973 -15.195274) (xy 191.483547 -15.202859) (xy 191.476122 -15.20952)
			(xy 191.45885 -15.226792) (xy 191.451738 -15.240508) (xy 191.450468 -15.248382) (xy 191.44569 -15.273947)
			(xy 191.430116 -15.323569) (xy 191.407941 -15.370614) (xy 191.379579 -15.414209) (xy 191.345554 -15.453543)
			(xy 191.306499 -15.487889) (xy 191.263139 -15.516608) (xy 191.239902 -15.52829) (xy 191.226694 -15.53464)
			(xy 191.2112 -15.559532) (xy 191.2112 -16.81607) (xy 191.211636 -16.826135) (xy 191.219368 -16.84472)
			(xy 191.226186 -16.852138) (xy 192.683892 -18.310098) (xy 192.711053 -18.337987) (xy 192.759608 -18.398843)
			(xy 192.801038 -18.464756) (xy 192.834822 -18.534896) (xy 192.860534 -18.60838) (xy 192.877852 -18.684281)
			(xy 192.886555 -18.761646) (xy 192.887092 -18.800572) (xy 192.887092 -19.14144) (xy 195.064632 -19.14144)
			(xy 195.068703 -19.085818) (xy 195.080829 -19.031381) (xy 195.100752 -18.97929) (xy 195.128048 -18.930655)
			(xy 195.162134 -18.886512) (xy 195.202283 -18.847803) (xy 195.247641 -18.815352) (xy 195.297241 -18.789851)
			(xy 195.350025 -18.771844) (xy 195.404868 -18.761714) (xy 195.460602 -18.759677) (xy 195.516039 -18.765777)
			(xy 195.569996 -18.779883) (xy 195.621325 -18.801695) (xy 195.668931 -18.830749) (xy 195.711799 -18.866424)
			(xy 195.749016 -18.907961) (xy 195.779789 -18.954474) (xy 195.803461 -19.004971) (xy 195.819529 -19.058378)
			(xy 195.827649 -19.113554) (xy 195.828158 -19.14144) (xy 195.827649 -19.169326) (xy 195.819529 -19.224502)
			(xy 195.803461 -19.277909) (xy 195.779789 -19.328406) (xy 195.749016 -19.374919) (xy 195.711799 -19.416456)
			(xy 195.668931 -19.452131) (xy 195.621325 -19.481185) (xy 195.569996 -19.502997) (xy 195.516039 -19.517103)
			(xy 195.460602 -19.523203) (xy 195.404868 -19.521166) (xy 195.350025 -19.511036) (xy 195.297241 -19.493029)
			(xy 195.247641 -19.467528) (xy 195.202283 -19.435077) (xy 195.162134 -19.396368) (xy 195.128048 -19.352225)
			(xy 195.100752 -19.30359) (xy 195.080829 -19.251499) (xy 195.068703 -19.197062) (xy 195.064632 -19.14144)
			(xy 192.887092 -19.14144) (xy 192.887092 -20.936204) (xy 192.88763 -20.946191) (xy 192.895344 -20.964623)
			(xy 192.902078 -20.972018) (xy 194.05981 -22.130004) (xy 194.086967 -22.157905) (xy 194.135545 -22.218756)
			(xy 194.177006 -22.284663) (xy 194.210827 -22.354797) (xy 194.236585 -22.428277) (xy 194.253955 -22.504178)
			(xy 194.262719 -22.581547) (xy 194.263264 -22.620478) (xy 194.263264 -27.014932) (xy 194.263743 -27.024898)
			(xy 194.271318 -27.043334) (xy 194.277996 -27.050746) (xy 199.581008 -32.353758) (xy 199.588405 -32.360608)
			(xy 199.607003 -32.368346) (xy 199.617076 -32.368744)
		)
		(stroke
			(width 0)
			(type solid)
		)
		(fill yes)
		(layer "In4.Cu")
		(net "P12V_SCM")
	)
	(gr_poly
		(pts
			(xy 421.767254 -365.227616) (xy 421.767254 -360.656886) (xy 421.329612 -360.219244) (xy 421.329612 -359.519982)
			(xy 421.907716 -358.941878) (xy 421.907716 -358.855772)
			(arc
				(start 421.80002 -358.748076)
				(mid 421.783837 -358.73717)
				(end 421.764714 -358.733344)
			)
			(arc
				(start 419.59149 -358.733344)
				(mid 419.572258 -358.737187)
				(end 419.55593 -358.748076)
			)
			(arc
				(start 419.198298 -359.105962)
				(mid 419.074522 -359.188574)
				(end 418.92855 -359.217468)
			)
			(arc
				(start 418.56152 -359.217468)
				(mid 418.544639 -359.220402)
				(end 418.52977 -359.228898)
			)
			(arc
				(start 418.52977 -359.228898)
				(mid 418.378294 -359.314895)
				(end 418.206682 -359.344722)
			)
			(arc
				(start 418.206682 -359.344722)
				(mid 417.698174 -358.836214)
				(end 418.206682 -358.327706)
			)
			(arc
				(start 418.206682 -358.327706)
				(mid 418.378292 -358.357538)
				(end 418.52977 -358.44353)
			)
			(arc
				(start 418.52977 -358.44353)
				(mid 418.544656 -358.451978)
				(end 418.56152 -358.45496)
			)
			(arc
				(start 418.749734 -358.45496)
				(mid 418.768966 -358.451117)
				(end 418.785294 -358.440228)
			)
			(arc
				(start 419.03396 -358.191308)
				(mid 419.047775 -358.165657)
				(end 419.044882 -358.136698)
			)
			(xy 419.03904 -358.122728) (xy 419.014148 -358.105964)
			(arc
				(start 417.811458 -358.105964)
				(mid 417.800646 -358.107202)
				(end 417.790376 -358.11079)
			)
			(arc
				(start 417.790376 -358.11079)
				(mid 417.576254 -358.158042)
				(end 417.362132 -358.11079)
			)
			(xy 417.351972 -358.105964)
			(arc
				(start 417.169092 -358.105964)
				(mid 417.13362 -358.12071)
				(end 417.119054 -358.156256)
			)
			(arc
				(start 417.119054 -359.786682)
				(mid 417.122897 -359.805914)
				(end 417.133786 -359.822242)
			)
			(arc
				(start 417.332922 -360.021378)
				(mid 417.349223 -360.032333)
				(end 417.368482 -360.03611)
			)
			(arc
				(start 420.552626 -360.03611)
				(mid 420.571858 -360.039953)
				(end 420.588186 -360.050842)
			)
			(arc
				(start 420.634668 -360.097324)
				(mid 420.650851 -360.10823)
				(end 420.669974 -360.112056)
			)
			(arc
				(start 420.708836 -360.112056)
				(mid 420.728039 -360.115782)
				(end 420.744396 -360.126534)
			)
			(arc
				(start 421.01643 -360.398568)
				(mid 421.027385 -360.414869)
				(end 421.031162 -360.434128)
			)
			(arc
				(start 421.031162 -364.946692)
				(mid 421.027319 -364.965924)
				(end 421.01643 -364.982252)
			)
			(arc
				(start 420.969186 -365.029496)
				(mid 420.95828 -365.045679)
				(end 420.954454 -365.064802)
			)
			(xy 420.954454 -365.316008) (xy 421.067738 -365.429292) (xy 421.565578 -365.429292)
		)
		(stroke
			(width 0)
			(type solid)
		)
		(fill yes)
		(layer "In4.Cu")
		(net "PVDD11_S3_P0_VCCS")
	)
	(gr_poly
		(pts
			(arc
				(start 124.102114 -12.795504)
				(mid 126.234222 -11.912198)
				(end 127.117348 -9.780016)
			)
			(arc
				(start 127.117348 -9.256776)
				(mid 127.111697 -9.233491)
				(end 127.096012 -9.215374)
			)
			(arc
				(start 127.096012 -9.215374)
				(mid 126.928345 -9.062058)
				(end 126.802388 -8.872982)
			)
			(xy 126.794514 -8.857234) (xy 126.76251 -8.842248)
			(arc
				(start 126.649226 -8.869426)
				(mid 126.621087 -8.887272)
				(end 126.61011 -8.918702)
			)
			(arc
				(start 126.61011 -9.780016)
				(mid 125.875535 -11.553437)
				(end 124.102114 -12.288012)
			)
			(arc
				(start 83.70189 -12.288012)
				(mid 81.928469 -11.553437)
				(end 81.193894 -9.780016)
			)
			(arc
				(start 81.193894 -3.638804)
				(mid 81.182847 -3.607429)
				(end 81.154778 -3.589528)
			)
			(xy 81.041494 -3.56235) (xy 81.00949 -3.577336)
			(arc
				(start 81.001616 -3.593084)
				(mid 80.87562 -3.782127)
				(end 80.707992 -3.935476)
			)
			(arc
				(start 80.707992 -3.935476)
				(mid 80.692292 -3.953586)
				(end 80.686656 -3.976878)
			)
			(arc
				(start 80.686656 -9.780524)
				(mid 81.569887 -11.912452)
				(end 83.70189 -12.795504)
			)
		)
		(stroke
			(width 0)
			(type solid)
		)
		(fill yes)
		(layer "In4.Cu")
		(net "GND")
	)
	(gr_poly
		(pts
			(arc
				(start 467.792054 -82.82813)
				(mid 467.983012 -81.868498)
				(end 468.526622 -81.054956)
			)
			(arc
				(start 470.85504 -78.726538)
				(mid 471.178373 -78.242681)
				(end 471.29192 -77.67193)
			)
			(arc
				(start 471.29192 -13.780008)
				(mid 470.854924 -12.725008)
				(end 469.799924 -12.288012)
			)
			(arc
				(start 458.20203 -12.288012)
				(mid 456.428609 -11.553437)
				(end 455.694034 -9.780016)
			)
			(xy 455.694034 -3.638296)
			(arc
				(start 455.693526 -3.63093)
				(mid 455.680691 -3.603937)
				(end 455.654918 -3.588766)
			)
			(xy 455.541634 -3.561842) (xy 455.509884 -3.576574) (xy 455.509884 -3.576828) (xy 455.50963 -3.576828)
			(arc
				(start 455.501756 -3.592576)
				(mid 455.377933 -3.779283)
				(end 455.213466 -3.931412)
			)
			(xy 455.212704 -3.93192)
			(arc
				(start 455.208132 -3.935222)
				(mid 455.192432 -3.953332)
				(end 455.186796 -3.976624)
			)
			(arc
				(start 455.186796 -9.780524)
				(mid 456.070027 -11.912452)
				(end 458.20203 -12.795504)
			)
			(arc
				(start 469.799924 -12.795504)
				(mid 470.496073 -13.083859)
				(end 470.784428 -13.780008)
			)
			(arc
				(start 470.784428 -77.672184)
				(mid 470.70959 -78.048688)
				(end 470.496392 -78.36789)
			)
			(arc
				(start 468.167974 -80.696308)
				(mid 467.514407 -81.674395)
				(end 467.284816 -82.82813)
			)
			(arc
				(start 467.284816 -357.040688)
				(mid 467.554494 -357.44994)
				(end 467.792054 -357.878634)
			)
		)
		(stroke
			(width 0)
			(type solid)
		)
		(fill yes)
		(layer "In4.Cu")
		(net "GND")
	)
	(gr_poly
		(pts
			(arc
				(start 256.800604 -37.135308)
				(mid 258.932532 -36.252077)
				(end 259.815584 -34.120074)
			)
			(arc
				(start 259.815584 -13.780008)
				(mid 260.103939 -13.083859)
				(end 260.800088 -12.795504)
			)
			(arc
				(start 385.601972 -12.795504)
				(mid 387.734244 -11.912288)
				(end 388.61746 -9.780016)
			)
			(arc
				(start 388.61746 -3.976878)
				(mid 388.611809 -3.953593)
				(end 388.596124 -3.935476)
			)
			(arc
				(start 388.596124 -3.935476)
				(mid 388.428347 -3.782165)
				(end 388.302246 -3.593084)
			)
			(xy 388.294372 -3.577336) (xy 388.262368 -3.56235)
			(arc
				(start 388.149084 -3.589528)
				(mid 388.120945 -3.607374)
				(end 388.109968 -3.638804)
			)
			(arc
				(start 388.109968 -9.780016)
				(mid 387.375393 -11.553437)
				(end 385.601972 -12.288012)
			)
			(arc
				(start 260.800088 -12.288012)
				(mid 259.745088 -12.725008)
				(end 259.308092 -13.780008)
			)
			(arc
				(start 259.308092 -34.120074)
				(mid 258.573517 -35.893495)
				(end 256.800096 -36.62807)
			)
			(arc
				(start 225.300032 -36.62807)
				(mid 223.526611 -35.893495)
				(end 222.792036 -34.120074)
			)
			(arc
				(start 222.792036 -13.780008)
				(mid 222.35504 -12.725008)
				(end 221.30004 -12.288012)
			)
			(xy 197.58406 -12.288012) (xy 197.36816 -12.503912) (xy 197.36816 -12.724384) (xy 197.43928 -12.795504)
			(arc
				(start 221.30004 -12.795504)
				(mid 221.996189 -13.083859)
				(end 222.284544 -13.780008)
			)
			(arc
				(start 222.284544 -34.120074)
				(mid 223.16785 -36.252182)
				(end 225.300032 -37.135308)
			)
		)
		(stroke
			(width 0)
			(type solid)
		)
		(fill yes)
		(layer "In4.Cu")
		(net "GND")
	)
	(gr_poly
		(pts
			(xy 389.38454 -153.10358) (xy 385.61645 -153.10358) (xy 385.61645 -157.001972) (xy 386.91185 -157.001972)
			(xy 386.912287 -156.974601) (xy 386.92011 -156.92042) (xy 386.935605 -156.867916) (xy 386.958454 -156.818169)
			(xy 386.988185 -156.772204) (xy 387.00583 -156.751274) (xy 387.006084 -156.75102) (xy 387.011667 -156.743931)
			(xy 387.017916 -156.727016) (xy 387.018276 -156.718) (xy 387.018276 -156.650944) (xy 387.017903 -156.641929)
			(xy 387.011667 -156.625011) (xy 387.006084 -156.617924) (xy 387.00583 -156.617924) (xy 387.00583 -156.61767)
			(xy 386.988215 -156.596718) (xy 386.958498 -156.550752) (xy 386.935657 -156.501009) (xy 386.920161 -156.448512)
			(xy 386.912327 -156.39434) (xy 386.91185 -156.366972) (xy 386.912354 -156.339204) (xy 386.920393 -156.284252)
			(xy 386.936312 -156.231046) (xy 386.959775 -156.180709) (xy 386.990286 -156.134304) (xy 387.00837 -156.113226)
			(xy 387.014252 -156.106038) (xy 387.020913 -156.088721) (xy 387.021324 -156.079444) (xy 387.021324 -156.01188)
			(xy 387.020905 -156.002605) (xy 387.014247 -155.985287) (xy 387.00837 -155.978098) (xy 386.990305 -155.957004)
			(xy 386.959797 -155.910601) (xy 386.936331 -155.860268) (xy 386.920405 -155.807066) (xy 386.912353 -155.752119)
			(xy 386.91185 -155.724352) (xy 386.912334 -155.696982) (xy 386.920146 -155.642803) (xy 386.93563 -155.5903)
			(xy 386.958468 -155.540553) (xy 386.98819 -155.494586) (xy 387.00583 -155.473654) (xy 387.006084 -155.4734)
			(xy 387.011675 -155.466316) (xy 387.017919 -155.449397) (xy 387.018276 -155.44038) (xy 387.018276 -155.373324)
			(xy 387.017912 -155.364308) (xy 387.01167 -155.34739) (xy 387.006084 -155.340304) (xy 387.00583 -155.340304)
			(xy 387.00583 -155.34005) (xy 386.988206 -155.319106) (xy 386.95849 -155.273137) (xy 386.935651 -155.223393)
			(xy 386.920157 -155.170894) (xy 386.912326 -155.11672) (xy 386.91185 -155.089352) (xy 386.912358 -155.060613)
			(xy 386.920986 -155.003785) (xy 386.938041 -154.948895) (xy 386.963136 -154.897183) (xy 386.995703 -154.849821)
			(xy 387.014974 -154.828494) (xy 387.021578 -154.821636) (xy 387.02869 -154.803602) (xy 387.02869 -154.714702)
			(xy 387.021578 -154.696668) (xy 387.014974 -154.68981) (xy 386.995686 -154.668497) (xy 386.963121 -154.621132)
			(xy 386.938031 -154.569417) (xy 386.920985 -154.514523) (xy 386.912368 -154.457692) (xy 386.91185 -154.428952)
			(xy 386.912334 -154.401582) (xy 386.920146 -154.347403) (xy 386.93563 -154.2949) (xy 386.958468 -154.245153)
			(xy 386.98819 -154.199186) (xy 387.00583 -154.178254) (xy 387.006084 -154.178) (xy 387.011675 -154.170916)
			(xy 387.017919 -154.153997) (xy 387.018276 -154.14498) (xy 387.018276 -154.077924) (xy 387.017912 -154.068908)
			(xy 387.01167 -154.05199) (xy 387.006084 -154.044904) (xy 387.00583 -154.044904) (xy 387.00583 -154.04465)
			(xy 386.988206 -154.023706) (xy 386.95849 -153.977737) (xy 386.935651 -153.927993) (xy 386.920157 -153.875494)
			(xy 386.912326 -153.82132) (xy 386.91185 -153.793952) (xy 386.912333 -153.766701) (xy 386.920095 -153.712756)
			(xy 386.935454 -153.660464) (xy 386.958098 -153.610889) (xy 386.987565 -153.565041) (xy 387.023257 -153.523852)
			(xy 387.064446 -153.488162) (xy 387.110294 -153.458695) (xy 387.159869 -153.436052) (xy 387.212162 -153.420694)
			(xy 387.266107 -153.412933) (xy 387.293358 -153.412444) (xy 387.320728 -153.412924) (xy 387.374907 -153.420737)
			(xy 387.42741 -153.436222) (xy 387.477157 -153.459061) (xy 387.523124 -153.488783) (xy 387.544056 -153.506424)
			(xy 387.54431 -153.506678) (xy 387.551383 -153.512284) (xy 387.56831 -153.518517) (xy 387.57733 -153.51887)
			(xy 387.644386 -153.51887) (xy 387.653403 -153.518513) (xy 387.67032 -153.512266) (xy 387.677406 -153.506678)
			(xy 387.677406 -153.506424) (xy 387.67766 -153.506424) (xy 387.698599 -153.488794) (xy 387.74457 -153.45908)
			(xy 387.794315 -153.436242) (xy 387.846815 -153.420749) (xy 387.900989 -153.412919) (xy 387.928358 -153.412444)
			(xy 387.955606 -153.413017) (xy 388.009548 -153.420767) (xy 388.061838 -153.436114) (xy 388.111412 -153.458747)
			(xy 388.15726 -153.488204) (xy 388.19845 -153.523887) (xy 388.234142 -153.565068) (xy 388.26361 -153.610909)
			(xy 388.286254 -153.660477) (xy 388.301614 -153.712764) (xy 388.309376 -153.766704) (xy 388.309866 -153.793952)
			(xy 388.30938 -153.821322) (xy 388.301568 -153.8755) (xy 388.286084 -153.928003) (xy 388.263247 -153.977751)
			(xy 388.233526 -154.023718) (xy 388.215886 -154.04465) (xy 388.215632 -154.044904) (xy 388.21003 -154.051979)
			(xy 388.203794 -154.068905) (xy 388.20344 -154.077924) (xy 388.20344 -154.14498) (xy 388.203798 -154.153997)
			(xy 388.210044 -154.170914) (xy 388.215632 -154.178) (xy 388.215886 -154.178) (xy 388.215886 -154.178254)
			(xy 388.233515 -154.199194) (xy 388.263229 -154.245165) (xy 388.286067 -154.29491) (xy 388.30156 -154.347409)
			(xy 388.309391 -154.401583) (xy 388.309866 -154.428952) (xy 388.309356 -154.457691) (xy 388.300728 -154.514518)
			(xy 388.283673 -154.569409) (xy 388.258579 -154.62112) (xy 388.226013 -154.668483) (xy 388.206742 -154.68981)
			(xy 388.200138 -154.696668) (xy 388.193026 -154.714702) (xy 388.193026 -154.803602) (xy 388.200138 -154.821636)
			(xy 388.206742 -154.828494) (xy 388.226034 -154.849803) (xy 388.258598 -154.897169) (xy 388.283687 -154.948886)
			(xy 388.300732 -155.003781) (xy 388.309349 -155.060612) (xy 388.309866 -155.089352) (xy 388.30938 -155.116722)
			(xy 388.301568 -155.1709) (xy 388.286084 -155.223403) (xy 388.263247 -155.273151) (xy 388.233526 -155.319118)
			(xy 388.215886 -155.34005) (xy 388.215632 -155.340304) (xy 388.21003 -155.347379) (xy 388.203794 -155.364305)
			(xy 388.20344 -155.373324) (xy 388.20344 -155.44038) (xy 388.203798 -155.449397) (xy 388.210044 -155.466314)
			(xy 388.215632 -155.4734) (xy 388.215886 -155.4734) (xy 388.215886 -155.473654) (xy 388.233515 -155.494594)
			(xy 388.263229 -155.540565) (xy 388.286067 -155.59031) (xy 388.30156 -155.642809) (xy 388.309391 -155.696983)
			(xy 388.309866 -155.724352) (xy 388.309372 -155.752121) (xy 388.30133 -155.807073) (xy 388.285408 -155.860279)
			(xy 388.261943 -155.910615) (xy 388.231431 -155.95702) (xy 388.213346 -155.978098) (xy 388.207444 -155.985271)
			(xy 388.200797 -156.0026) (xy 388.200392 -156.01188) (xy 388.200392 -156.079444) (xy 388.200867 -156.088712)
			(xy 388.207488 -156.10603) (xy 388.213346 -156.113226) (xy 388.231425 -156.134308) (xy 388.261931 -156.180715)
			(xy 388.285393 -156.231051) (xy 388.301316 -156.284255) (xy 388.309365 -156.339204) (xy 388.309866 -156.366972)
			(xy 388.309392 -156.394342) (xy 388.301577 -156.448521) (xy 388.28609 -156.501024) (xy 388.26325 -156.550771)
			(xy 388.233527 -156.596738) (xy 388.215886 -156.61767) (xy 388.215632 -156.617924) (xy 388.210021 -156.624994)
			(xy 388.203791 -156.641924) (xy 388.20344 -156.650944) (xy 388.20344 -156.718) (xy 388.203789 -156.727018)
			(xy 388.210041 -156.743935) (xy 388.215632 -156.75102) (xy 388.215886 -156.75102) (xy 388.215886 -156.751274)
			(xy 388.233524 -156.772207) (xy 388.263237 -156.818179) (xy 388.286073 -156.867926) (xy 388.301564 -156.920427)
			(xy 388.309392 -156.974603) (xy 388.309866 -157.001972) (xy 388.309419 -157.029226) (xy 388.301664 -157.08318)
			(xy 388.28631 -157.13548) (xy 388.263667 -157.185063) (xy 388.234198 -157.230919) (xy 388.198503 -157.272113)
			(xy 388.157307 -157.307807) (xy 388.111451 -157.337274) (xy 388.061867 -157.359915) (xy 388.009566 -157.375267)
			(xy 387.955612 -157.38302) (xy 387.928358 -157.38348) (xy 387.900989 -157.382985) (xy 387.846811 -157.375175)
			(xy 387.794308 -157.359693) (xy 387.74456 -157.336857) (xy 387.698592 -157.307139) (xy 387.67766 -157.2895)
			(xy 387.677406 -157.289246) (xy 387.670327 -157.283649) (xy 387.653404 -157.27741) (xy 387.644386 -157.277054)
			(xy 387.57733 -157.277054) (xy 387.568313 -157.277414) (xy 387.551396 -157.283658) (xy 387.54431 -157.289246)
			(xy 387.54431 -157.2895) (xy 387.544056 -157.2895) (xy 387.523114 -157.307126) (xy 387.477144 -157.33684)
			(xy 387.427399 -157.359678) (xy 387.3749 -157.375173) (xy 387.320726 -157.383004) (xy 387.293358 -157.38348)
			(xy 387.266104 -157.383061) (xy 387.212153 -157.375298) (xy 387.159855 -157.359936) (xy 387.110276 -157.337288)
			(xy 387.064424 -157.307815) (xy 387.023234 -157.272117) (xy 386.987543 -157.23092) (xy 386.958078 -157.185063)
			(xy 386.935439 -157.135479) (xy 386.920087 -157.083179) (xy 386.912334 -157.029226) (xy 386.91185 -157.001972)
			(xy 385.61645 -157.001972) (xy 385.61645 -158.25216) (xy 389.38454 -158.25216)
		)
		(stroke
			(width 0)
			(type solid)
		)
		(fill yes)
		(layer "In4.Cu")
		(net "GND")
	)
	(gr_poly
		(pts
			(xy 175.281336 -366.376966) (xy 175.292758 -366.376515) (xy 175.313396 -366.366738) (xy 175.32096 -366.35817)
			(xy 175.377856 -366.287558) (xy 175.38319 -366.265206) (xy 175.38065 -366.253776) (xy 175.376599 -366.23383)
			(xy 175.372275 -366.193356) (xy 175.372014 -366.173004) (xy 175.372552 -366.144474) (xy 175.381061 -366.088053)
			(xy 175.397874 -366.033527) (xy 175.422617 -365.982111) (xy 175.454738 -365.934952) (xy 175.493522 -365.8931)
			(xy 175.538104 -365.857488) (xy 175.587491 -365.828909) (xy 175.613822 -365.817912) (xy 175.626776 -365.812832)
			(xy 175.643794 -365.791242) (xy 175.659034 -365.675418) (xy 175.648112 -365.650018) (xy 175.636936 -365.641636)
			(xy 175.613344 -365.623531) (xy 175.571543 -365.581235) (xy 175.536817 -365.532961) (xy 175.510007 -365.479881)
			(xy 175.491764 -365.423282) (xy 175.482531 -365.364537) (xy 175.481996 -365.334804) (xy 175.482482 -365.307553)
			(xy 175.490238 -365.253605) (xy 175.505593 -365.20131) (xy 175.528235 -365.151733) (xy 175.557701 -365.105883)
			(xy 175.593392 -365.064692) (xy 175.634583 -365.029001) (xy 175.680433 -364.999535) (xy 175.73001 -364.976893)
			(xy 175.782305 -364.961538) (xy 175.836253 -364.953782) (xy 175.890755 -364.953782) (xy 175.944703 -364.961538)
			(xy 175.996998 -364.976893) (xy 176.046575 -364.999535) (xy 176.092425 -365.029001) (xy 176.133616 -365.064692)
			(xy 176.169307 -365.105883) (xy 176.198773 -365.151733) (xy 176.221415 -365.20131) (xy 176.23677 -365.253605)
			(xy 176.244526 -365.307553) (xy 176.245012 -365.334804) (xy 176.244473 -365.363334) (xy 176.235964 -365.419755)
			(xy 176.219151 -365.474282) (xy 176.194408 -365.525698) (xy 176.162288 -365.572858) (xy 176.123505 -365.614711)
			(xy 176.078924 -365.650325) (xy 176.029538 -365.678906) (xy 176.003204 -365.689896) (xy 175.99025 -365.694976)
			(xy 175.973232 -365.716566) (xy 175.957992 -365.83239) (xy 175.968914 -365.85779) (xy 175.98009 -365.866172)
			(xy 176.00227 -365.883188) (xy 176.041931 -365.922584) (xy 176.059084 -365.944658) (xy 176.067212 -365.955326)
			(xy 176.091088 -365.965994) (xy 176.203356 -365.956342) (xy 176.2252 -365.941864) (xy 176.231042 -365.929926)
			(xy 176.243331 -365.906726) (xy 176.273321 -365.863636) (xy 176.308938 -365.825067) (xy 176.349508 -365.791748)
			(xy 176.394265 -365.764308) (xy 176.442363 -365.743266) (xy 176.492893 -365.72902) (xy 176.544898 -365.72184)
			(xy 176.571148 -365.721392) (xy 176.598397 -365.721881) (xy 176.65234 -365.729643) (xy 176.704629 -365.745002)
			(xy 176.7542 -365.767646) (xy 176.800044 -365.797114) (xy 176.841229 -365.832805) (xy 176.876915 -365.873994)
			(xy 176.906377 -365.919842) (xy 176.929014 -365.969416) (xy 176.944367 -366.021707) (xy 176.952122 -366.075651)
			(xy 176.952656 -366.1029) (xy 176.952317 -366.126112) (xy 176.946685 -366.172192) (xy 176.935492 -366.217245)
			(xy 176.92751 -366.239044) (xy 176.922938 -366.250982) (xy 176.925986 -366.27562) (xy 176.980596 -366.354868)
			(xy 176.988119 -366.364768) (xy 177.010088 -366.376354) (xy 177.022506 -366.376966) (xy 178.671474 -366.376966)
			(xy 178.681471 -366.376473) (xy 178.699952 -366.36884) (xy 178.71414 -366.354751) (xy 178.718464 -366.345724)
			(xy 178.724306 -366.331246) (xy 178.718464 -366.301274) (xy 177.025808 -364.608618) (xy 177.018411 -364.601768)
			(xy 176.999813 -364.594028) (xy 176.98974 -364.593632) (xy 172.973492 -364.593632) (xy 172.94098 -364.593176)
			(xy 172.876365 -364.585897) (xy 172.81297 -364.57143) (xy 172.751593 -364.549958) (xy 172.693006 -364.521751)
			(xy 172.637944 -364.487163) (xy 172.5871 -364.446629) (xy 172.56379 -364.42396) (xy 168.82237 -360.68254)
			(xy 168.814941 -360.675773) (xy 168.796345 -360.6682) (xy 168.786302 -360.667808) (xy 158.30677 -360.667808)
			(xy 158.296767 -360.668301) (xy 158.278287 -360.675967) (xy 158.264145 -360.690119) (xy 158.256494 -360.708605)
			(xy 158.25597 -360.718608) (xy 158.25597 -361.19308) (xy 158.256454 -361.203093) (xy 158.264109 -361.221596)
			(xy 158.278262 -361.235763) (xy 158.296758 -361.243436) (xy 158.30677 -361.24388) (xy 165.563804 -361.24388)
			(xy 165.573832 -361.243432) (xy 165.592392 -361.235843) (xy 165.599872 -361.229148) (xy 165.706044 -361.122976)
			(xy 165.729344 -361.100296) (xy 165.780184 -361.059752) (xy 165.835245 -361.025159) (xy 165.893835 -360.99695)
			(xy 165.955215 -360.97548) (xy 166.018613 -360.961021) (xy 166.083233 -360.953754) (xy 166.115746 -360.953304)
			(xy 166.150758 -360.953835) (xy 166.220272 -360.962281) (xy 166.288261 -360.979043) (xy 166.353734 -361.003877)
			(xy 166.415737 -361.036422) (xy 166.473365 -361.076203) (xy 166.525778 -361.122639) (xy 166.572212 -361.175054)
			(xy 166.61199 -361.232684) (xy 166.644532 -361.294688) (xy 166.669364 -361.360162) (xy 166.686124 -361.428152)
			(xy 166.694566 -361.497666) (xy 166.69512 -361.532678) (xy 166.694618 -361.567559) (xy 166.686273 -361.636818)
			(xy 166.669665 -361.704574) (xy 166.645036 -361.769842) (xy 166.612741 -361.831677) (xy 166.57325 -361.889184)
			(xy 166.550594 -361.91571) (xy 166.544824 -361.922868) (xy 166.538324 -361.940053) (xy 166.537894 -361.949238)
			(xy 166.537894 -361.979718) (xy 166.53828 -361.988911) (xy 166.544791 -362.006105) (xy 166.550594 -362.013246)
			(xy 166.573245 -362.039773) (xy 166.612709 -362.097292) (xy 166.644986 -362.159132) (xy 166.669608 -362.224398)
			(xy 166.68622 -362.292147) (xy 166.694582 -362.3614) (xy 166.69512 -362.396278) (xy 166.694593 -362.431294)
			(xy 166.686154 -362.500814) (xy 166.669398 -362.568811) (xy 166.644568 -362.634293) (xy 166.612026 -362.696304)
			(xy 166.572247 -362.75394) (xy 166.52581 -362.806362) (xy 166.473394 -362.852805) (xy 166.415762 -362.89259)
			(xy 166.353755 -362.92514) (xy 166.288276 -362.949978) (xy 166.220281 -362.966742) (xy 166.150762 -362.975189)
			(xy 166.115746 -362.975652) (xy 166.083235 -362.975194) (xy 166.018622 -362.96791) (xy 165.95523 -362.953439)
			(xy 165.893856 -362.931964) (xy 165.835271 -362.903755) (xy 165.780213 -362.869165) (xy 165.729371 -362.828631)
			(xy 165.706044 -362.80598) (xy 165.599872 -362.699808) (xy 165.592446 -362.693034) (xy 165.573849 -362.685449)
			(xy 165.563804 -362.685076) (xy 158.30677 -362.685076) (xy 158.296765 -362.685569) (xy 158.278279 -362.693233)
			(xy 158.264129 -362.707384) (xy 158.256468 -362.72587) (xy 158.25597 -362.735876) (xy 158.25597 -363.708188)
			(xy 170.730926 -363.708188) (xy 170.731412 -363.680937) (xy 170.739168 -363.626989) (xy 170.754523 -363.574694)
			(xy 170.777165 -363.525117) (xy 170.806631 -363.479267) (xy 170.842322 -363.438076) (xy 170.883513 -363.402385)
			(xy 170.929363 -363.372919) (xy 170.97894 -363.350277) (xy 171.031235 -363.334922) (xy 171.085183 -363.327166)
			(xy 171.139685 -363.327166) (xy 171.193633 -363.334922) (xy 171.245928 -363.350277) (xy 171.295505 -363.372919)
			(xy 171.341355 -363.402385) (xy 171.382546 -363.438076) (xy 171.418237 -363.479267) (xy 171.447703 -363.525117)
			(xy 171.470345 -363.574694) (xy 171.4857 -363.626989) (xy 171.493456 -363.680937) (xy 171.493942 -363.708188)
			(xy 171.493571 -363.732446) (xy 171.487408 -363.780568) (xy 171.475193 -363.827521) (xy 171.46651 -363.850174)
			(xy 171.461783 -363.862923) (xy 171.458616 -363.889922) (xy 171.462692 -363.916798) (xy 171.473723 -363.941643)
			(xy 171.490924 -363.962692) (xy 171.513074 -363.97845) (xy 171.5386 -363.987798) (xy 171.552108 -363.989366)
			(xy 171.580275 -363.99237) (xy 171.635365 -364.005537) (xy 171.687901 -364.026709) (xy 171.736726 -364.055421)
			(xy 171.780768 -364.091039) (xy 171.819055 -364.13278) (xy 171.850746 -364.179727) (xy 171.875144 -364.230845)
			(xy 171.891711 -364.285009) (xy 171.900082 -364.341029) (xy 171.900596 -364.36935) (xy 171.90011 -364.396601)
			(xy 171.892354 -364.450549) (xy 171.876999 -364.502844) (xy 171.854357 -364.552421) (xy 171.824891 -364.598271)
			(xy 171.7892 -364.639462) (xy 171.748009 -364.675153) (xy 171.702159 -364.704619) (xy 171.652582 -364.727261)
			(xy 171.600287 -364.742616) (xy 171.546339 -364.750372) (xy 171.491837 -364.750372) (xy 171.437889 -364.742616)
			(xy 171.385594 -364.727261) (xy 171.336017 -364.704619) (xy 171.290167 -364.675153) (xy 171.248976 -364.639462)
			(xy 171.213285 -364.598271) (xy 171.183819 -364.552421) (xy 171.161177 -364.502844) (xy 171.145822 -364.450549)
			(xy 171.138066 -364.396601) (xy 171.13758 -364.36935) (xy 171.137961 -364.345093) (xy 171.14412 -364.296971)
			(xy 171.15633 -364.250018) (xy 171.165012 -364.227364) (xy 171.169676 -364.214594) (xy 171.172849 -364.187606)
			(xy 171.168781 -364.160738) (xy 171.15776 -364.135898) (xy 171.14057 -364.114852) (xy 171.118432 -364.099094)
			(xy 171.092917 -364.089743) (xy 171.079414 -364.088172) (xy 171.051232 -364.085294) (xy 170.996135 -364.072113)
			(xy 170.943595 -364.050926) (xy 170.894767 -364.0222) (xy 170.850725 -363.986568) (xy 170.812439 -363.944812)
			(xy 170.780752 -363.897852) (xy 170.756359 -363.846721) (xy 170.739799 -363.792544) (xy 170.731435 -363.736514)
			(xy 170.730926 -363.708188) (xy 158.25597 -363.708188) (xy 158.25597 -364.508288) (xy 158.25639 -364.51836)
			(xy 158.264098 -364.53697) (xy 158.270956 -364.544356) (xy 160.08858 -366.36198) (xy 160.095982 -366.368816)
			(xy 160.11458 -366.376524) (xy 160.124648 -366.376966)
		)
		(stroke
			(width 0)
			(type solid)
		)
		(fill yes)
		(layer "In4.Cu")
		(net "GND")
	)
	(gr_poly
		(pts
			(xy 71.350632 -26.34615) (xy 71.360698 -26.34572) (xy 71.37929 -26.337991) (xy 71.3867 -26.331164)
			(xy 73.042018 -24.675846) (xy 73.048865 -24.668449) (xy 73.056593 -24.649849) (xy 73.057004 -24.639778)
			(xy 73.057004 -19.427444) (xy 73.056571 -19.417378) (xy 73.048842 -19.398788) (xy 73.042018 -19.391376)
			(xy 70.497446 -16.846804) (xy 70.49389 -16.843756) (xy 70.493636 -16.843502) (xy 70.471538 -16.824198)
			(xy 70.471284 -16.824198) (xy 70.446392 -16.800068) (xy 68.455032 -14.808708) (xy 68.427873 -14.780818)
			(xy 68.379323 -14.71996) (xy 68.337897 -14.654046) (xy 68.304116 -14.583906) (xy 68.278406 -14.510423)
			(xy 68.26109 -14.434522) (xy 68.252387 -14.35716) (xy 68.251832 -14.318234) (xy 68.251832 -13.140436)
			(xy 68.251331 -13.130108) (xy 68.243198 -13.111119) (xy 68.228291 -13.096817) (xy 68.218812 -13.092684)
			(xy 68.114672 -13.053822) (xy 68.083938 -13.061696) (xy 68.073524 -13.073634) (xy 68.04673 -13.103688)
			(xy 67.988553 -13.15936) (xy 67.92559 -13.209554) (xy 67.858352 -13.253861) (xy 67.82308 -13.273278)
			(xy 67.813809 -13.278728) (xy 67.800642 -13.295706) (xy 67.79768 -13.306044) (xy 67.787278 -13.347142)
			(xy 67.759673 -13.427305) (xy 67.724562 -13.504477) (xy 67.682265 -13.577955) (xy 67.633164 -13.647073)
			(xy 67.577707 -13.711203) (xy 67.516397 -13.769762) (xy 67.44979 -13.822219) (xy 67.378493 -13.868097)
			(xy 67.303152 -13.90698) (xy 67.224451 -13.938514) (xy 67.143106 -13.962413) (xy 67.059856 -13.978459)
			(xy 66.975456 -13.986508) (xy 66.933064 -13.987018) (xy 66.894774 -13.98661) (xy 66.818479 -13.980007)
			(xy 66.743036 -13.96686) (xy 66.669004 -13.947269) (xy 66.632836 -13.934694) (xy 66.624398 -13.932052)
			(xy 66.60673 -13.932052) (xy 66.598292 -13.934694) (xy 66.562114 -13.947239) (xy 66.488082 -13.966817)
			(xy 66.412643 -13.979967) (xy 66.336352 -13.98659) (xy 66.298064 -13.987018) (xy 66.254268 -13.9865)
			(xy 66.167098 -13.977897) (xy 66.081199 -13.960757) (xy 65.997403 -13.935249) (xy 65.916523 -13.901618)
			(xy 65.877694 -13.881354) (xy 65.866228 -13.875936) (xy 65.8409 -13.875936) (xy 65.829434 -13.881354)
			(xy 65.79059 -13.901586) (xy 65.709706 -13.935193) (xy 65.625912 -13.960696) (xy 65.54002 -13.977848)
			(xy 65.452858 -13.986484) (xy 65.409064 -13.987018) (xy 65.365268 -13.9865) (xy 65.278098 -13.977897)
			(xy 65.192199 -13.960757) (xy 65.108403 -13.935249) (xy 65.027523 -13.901618) (xy 64.988694 -13.881354)
			(xy 64.977228 -13.875936) (xy 64.9519 -13.875936) (xy 64.940434 -13.881354) (xy 64.90159 -13.901586)
			(xy 64.820706 -13.935193) (xy 64.736912 -13.960696) (xy 64.65102 -13.977848) (xy 64.563858 -13.986484)
			(xy 64.520064 -13.987018) (xy 64.476268 -13.9865) (xy 64.389098 -13.977897) (xy 64.303199 -13.960757)
			(xy 64.219403 -13.935249) (xy 64.138523 -13.901618) (xy 64.099694 -13.881354) (xy 64.088228 -13.875936)
			(xy 64.0629 -13.875936) (xy 64.051434 -13.881354) (xy 64.01259 -13.901586) (xy 63.931706 -13.935193)
			(xy 63.847912 -13.960696) (xy 63.76202 -13.977848) (xy 63.674858 -13.986484) (xy 63.631064 -13.987018)
			(xy 63.590765 -13.986565) (xy 63.510499 -13.979268) (xy 63.431222 -13.964739) (xy 63.353585 -13.943095)
			(xy 63.278225 -13.914515) (xy 63.20576 -13.879233) (xy 63.136785 -13.837538) (xy 63.071866 -13.789773)
			(xy 63.011536 -13.73633) (xy 62.956289 -13.677646) (xy 62.906579 -13.614204) (xy 62.884304 -13.580618)
			(xy 62.874906 -13.566394) (xy 62.843664 -13.55471) (xy 62.733682 -13.587222) (xy 62.723365 -13.590829)
			(xy 62.706911 -13.60518) (xy 62.69791 -13.625071) (xy 62.69736 -13.63599) (xy 62.69736 -13.685266)
			(xy 62.697797 -13.69533) (xy 62.705535 -13.713911) (xy 62.712346 -13.721334) (xy 64.615568 -15.624556)
			(xy 64.622409 -15.631956) (xy 64.630128 -15.650555) (xy 64.630554 -15.660624) (xy 64.630554 -18.518562)
			(xy 67.655436 -18.518562) (xy 67.655436 -18.433866) (xy 67.663487 -18.349552) (xy 67.679516 -18.266386)
			(xy 67.703377 -18.185119) (xy 67.734856 -18.106489) (xy 67.773667 -18.031208) (xy 67.819457 -17.959956)
			(xy 67.871813 -17.89338) (xy 67.930261 -17.832082) (xy 67.994271 -17.776617) (xy 68.063263 -17.727488)
			(xy 68.136613 -17.685139) (xy 68.213656 -17.649955) (xy 68.293695 -17.622253) (xy 68.376004 -17.602285)
			(xy 68.459839 -17.590232) (xy 68.54444 -17.586202) (xy 68.629041 -17.590232) (xy 68.712876 -17.602285)
			(xy 68.795185 -17.622253) (xy 68.875224 -17.649955) (xy 68.952267 -17.685139) (xy 69.025617 -17.727488)
			(xy 69.094609 -17.776617) (xy 69.158619 -17.832082) (xy 69.217067 -17.89338) (xy 69.269423 -17.959956)
			(xy 69.315213 -18.031208) (xy 69.354024 -18.106489) (xy 69.385503 -18.185119) (xy 69.409364 -18.266386)
			(xy 69.425393 -18.349552) (xy 69.433444 -18.433866) (xy 69.433948 -18.476214) (xy 69.433444 -18.518562)
			(xy 69.425393 -18.602876) (xy 69.409364 -18.686042) (xy 69.385503 -18.767309) (xy 69.354024 -18.845939)
			(xy 69.315213 -18.92122) (xy 69.269423 -18.992472) (xy 69.217067 -19.059048) (xy 69.158619 -19.120346)
			(xy 69.094609 -19.175811) (xy 69.025617 -19.22494) (xy 68.952267 -19.267289) (xy 68.875224 -19.302473)
			(xy 68.795185 -19.330175) (xy 68.712876 -19.350143) (xy 68.629041 -19.362196) (xy 68.54444 -19.366227)
			(xy 68.459839 -19.362196) (xy 68.376004 -19.350143) (xy 68.293695 -19.330175) (xy 68.213656 -19.302473)
			(xy 68.136613 -19.267289) (xy 68.063263 -19.22494) (xy 67.994271 -19.175811) (xy 67.930261 -19.120346)
			(xy 67.871813 -19.059048) (xy 67.819457 -18.992472) (xy 67.773667 -18.92122) (xy 67.734856 -18.845939)
			(xy 67.703377 -18.767309) (xy 67.679516 -18.686042) (xy 67.663487 -18.602876) (xy 67.655436 -18.518562)
			(xy 64.630554 -18.518562) (xy 64.630554 -21.0881) (xy 69.020483 -21.0881) (xy 69.024513 -21.003501)
			(xy 69.036566 -20.919669) (xy 69.056533 -20.837362) (xy 69.084233 -20.757325) (xy 69.119415 -20.680284)
			(xy 69.161761 -20.606935) (xy 69.210887 -20.537944) (xy 69.266349 -20.473935) (xy 69.327643 -20.415488)
			(xy 69.394216 -20.363131) (xy 69.465464 -20.317339) (xy 69.540742 -20.278527) (xy 69.619368 -20.247046)
			(xy 69.700631 -20.223181) (xy 69.783794 -20.207149) (xy 69.868105 -20.199094) (xy 69.910452 -20.198588)
			(xy 69.952896 -20.19906) (xy 70.037397 -20.207152) (xy 70.120743 -20.223257) (xy 70.202175 -20.247229)
			(xy 70.280954 -20.278849) (xy 70.318884 -20.297902) (xy 70.330048 -20.302883) (xy 70.354456 -20.302883)
			(xy 70.36562 -20.297902) (xy 70.403559 -20.278868) (xy 70.482336 -20.247249) (xy 70.563766 -20.223278)
			(xy 70.64711 -20.207174) (xy 70.731609 -20.199083) (xy 70.774052 -20.198588) (xy 70.816403 -20.199082)
			(xy 70.90072 -20.207129) (xy 70.983892 -20.223155) (xy 71.065163 -20.247014) (xy 71.143798 -20.278491)
			(xy 71.219084 -20.317301) (xy 71.290341 -20.363091) (xy 71.356922 -20.415448) (xy 71.418225 -20.473896)
			(xy 71.473694 -20.537908) (xy 71.522826 -20.606902) (xy 71.565178 -20.680254) (xy 71.600365 -20.757301)
			(xy 71.628069 -20.837343) (xy 71.648039 -20.919656) (xy 71.660094 -21.003495) (xy 71.664124 -21.0881)
			(xy 71.660094 -21.172705) (xy 71.648039 -21.256544) (xy 71.628069 -21.338857) (xy 71.600365 -21.418899)
			(xy 71.565178 -21.495946) (xy 71.522826 -21.569298) (xy 71.473694 -21.638292) (xy 71.418225 -21.702304)
			(xy 71.356922 -21.760752) (xy 71.290341 -21.813109) (xy 71.219084 -21.858899) (xy 71.143798 -21.897709)
			(xy 71.065163 -21.929186) (xy 70.983892 -21.953045) (xy 70.90072 -21.969071) (xy 70.816403 -21.977118)
			(xy 70.774052 -21.977604) (xy 70.731608 -21.977131) (xy 70.647107 -21.969039) (xy 70.563761 -21.952935)
			(xy 70.482329 -21.928963) (xy 70.40355 -21.897343) (xy 70.36562 -21.87829) (xy 70.354456 -21.873309)
			(xy 70.330048 -21.873309) (xy 70.318884 -21.87829) (xy 70.280962 -21.897359) (xy 70.20218 -21.928972)
			(xy 70.120745 -21.952935) (xy 70.037398 -21.969031) (xy 69.952896 -21.977114) (xy 69.910452 -21.977604)
			(xy 69.868105 -21.977106) (xy 69.783794 -21.969051) (xy 69.700631 -21.953019) (xy 69.619368 -21.929154)
			(xy 69.540742 -21.897673) (xy 69.465464 -21.858861) (xy 69.394216 -21.813069) (xy 69.327643 -21.760712)
			(xy 69.266349 -21.702265) (xy 69.210887 -21.638256) (xy 69.161761 -21.569265) (xy 69.119415 -21.495916)
			(xy 69.084233 -21.418875) (xy 69.056533 -21.338838) (xy 69.036566 -21.256531) (xy 69.024513 -21.172699)
			(xy 69.020483 -21.0881) (xy 64.630554 -21.0881) (xy 64.630554 -25.193244) (xy 70.553324 -25.193244)
			(xy 70.557395 -25.137622) (xy 70.569521 -25.083185) (xy 70.589444 -25.031094) (xy 70.61674 -24.982459)
			(xy 70.650826 -24.938316) (xy 70.690975 -24.899607) (xy 70.736333 -24.867156) (xy 70.785933 -24.841655)
			(xy 70.838717 -24.823648) (xy 70.89356 -24.813518) (xy 70.949294 -24.811481) (xy 71.004731 -24.817581)
			(xy 71.058688 -24.831687) (xy 71.110017 -24.853499) (xy 71.157623 -24.882553) (xy 71.200491 -24.918228)
			(xy 71.237708 -24.959765) (xy 71.268481 -25.006278) (xy 71.292153 -25.056775) (xy 71.308221 -25.110182)
			(xy 71.316341 -25.165358) (xy 71.31685 -25.193244) (xy 71.316341 -25.22113) (xy 71.308221 -25.276306)
			(xy 71.292153 -25.329713) (xy 71.268481 -25.38021) (xy 71.237708 -25.426723) (xy 71.200491 -25.46826)
			(xy 71.157623 -25.503935) (xy 71.110017 -25.532989) (xy 71.058688 -25.554801) (xy 71.004731 -25.568907)
			(xy 70.949294 -25.575007) (xy 70.89356 -25.57297) (xy 70.838717 -25.56284) (xy 70.785933 -25.544833)
			(xy 70.736333 -25.519332) (xy 70.690975 -25.486881) (xy 70.650826 -25.448172) (xy 70.61674 -25.404029)
			(xy 70.589444 -25.355394) (xy 70.569521 -25.303303) (xy 70.557395 -25.248866) (xy 70.553324 -25.193244)
			(xy 64.630554 -25.193244) (xy 64.630554 -25.74671) (xy 64.63098 -25.756778) (xy 64.638703 -25.775375)
			(xy 64.64554 -25.782778) (xy 65.193926 -26.331164) (xy 65.201324 -26.33801) (xy 65.219923 -26.345741)
			(xy 65.229994 -26.34615)
		)
		(stroke
			(width 0)
			(type solid)
		)
		(fill yes)
		(layer "In4.Cu")
		(net "P12V_OCP_V3_2")
	)
	(gr_poly
		(pts
			(xy 372.08206 -162.59302) (xy 365.671608 -162.59302) (xy 365.671608 -164.53358) (xy 366.362996 -164.53358)
			(xy 366.363451 -164.506209) (xy 366.371272 -164.45203) (xy 366.386764 -164.399527) (xy 366.409608 -164.34978)
			(xy 366.439334 -164.303814) (xy 366.456976 -164.282882) (xy 366.45723 -164.282628) (xy 366.462814 -164.27554)
			(xy 366.469061 -164.258624) (xy 366.469422 -164.249608) (xy 366.469422 -164.182552) (xy 366.469035 -164.173538)
			(xy 366.462808 -164.156621) (xy 366.45723 -164.149532) (xy 366.456976 -164.149532) (xy 366.456976 -164.149278)
			(xy 366.439356 -164.12833) (xy 366.409642 -164.082361) (xy 366.386803 -164.032618) (xy 366.371307 -163.980121)
			(xy 366.363473 -163.925948) (xy 366.362996 -163.89858) (xy 366.363459 -163.871328) (xy 366.371219 -163.817379)
			(xy 366.386576 -163.765084) (xy 366.40922 -163.715506) (xy 366.438689 -163.669656) (xy 366.474383 -163.628466)
			(xy 366.515575 -163.592775) (xy 366.561427 -163.563309) (xy 366.611006 -163.540668) (xy 366.663303 -163.525313)
			(xy 366.717252 -163.517557) (xy 366.744504 -163.517072) (xy 366.771875 -163.517518) (xy 366.826056 -163.525338)
			(xy 366.87856 -163.540831) (xy 366.928306 -163.563677) (xy 366.974272 -163.593408) (xy 366.995202 -163.611052)
			(xy 366.995456 -163.611306) (xy 367.002551 -163.616881) (xy 367.019461 -163.623134) (xy 367.028476 -163.623498)
			(xy 367.095532 -163.623498) (xy 367.10455 -163.623157) (xy 367.121467 -163.616898) (xy 367.128552 -163.611306)
			(xy 367.128552 -163.611052) (xy 367.128806 -163.611052) (xy 367.149732 -163.593405) (xy 367.195705 -163.563692)
			(xy 367.245454 -163.540857) (xy 367.297957 -163.525368) (xy 367.352134 -163.517544) (xy 367.379504 -163.517072)
			(xy 367.408516 -163.517609) (xy 367.465873 -163.526378) (xy 367.521242 -163.543729) (xy 367.573346 -163.569262)
			(xy 367.620984 -163.602388) (xy 367.642394 -163.621974) (xy 367.649252 -163.628832) (xy 367.667286 -163.635944)
			(xy 367.757202 -163.635944) (xy 367.775236 -163.628832) (xy 367.782094 -163.621974) (xy 367.803503 -163.602389)
			(xy 367.851147 -163.569273) (xy 367.903252 -163.543745) (xy 367.958618 -163.526392) (xy 368.015973 -163.517613)
			(xy 368.044984 -163.517072) (xy 368.072355 -163.51753) (xy 368.126535 -163.525347) (xy 368.179039 -163.540837)
			(xy 368.228786 -163.563681) (xy 368.274751 -163.593409) (xy 368.295682 -163.611052) (xy 368.295936 -163.611306)
			(xy 368.303036 -163.616873) (xy 368.319943 -163.623131) (xy 368.328956 -163.623498) (xy 368.396012 -163.623498)
			(xy 368.405029 -163.623147) (xy 368.421946 -163.616895) (xy 368.429032 -163.611306) (xy 368.429032 -163.611052)
			(xy 368.429286 -163.611052) (xy 368.450219 -163.593411) (xy 368.496187 -163.563687) (xy 368.545933 -163.540841)
			(xy 368.598435 -163.525345) (xy 368.652613 -163.517516) (xy 368.707355 -163.517516) (xy 368.761533 -163.525345)
			(xy 368.814035 -163.540841) (xy 368.863781 -163.563687) (xy 368.909749 -163.593411) (xy 368.930682 -163.611052)
			(xy 368.930936 -163.611306) (xy 368.938036 -163.616873) (xy 368.954943 -163.623131) (xy 368.963956 -163.623498)
			(xy 369.031012 -163.623498) (xy 369.040029 -163.623147) (xy 369.056946 -163.616895) (xy 369.064032 -163.611306)
			(xy 369.064032 -163.611052) (xy 369.064286 -163.611052) (xy 369.085219 -163.593411) (xy 369.131187 -163.563687)
			(xy 369.180933 -163.540841) (xy 369.233435 -163.525345) (xy 369.287613 -163.517516) (xy 369.342355 -163.517516)
			(xy 369.396533 -163.525345) (xy 369.449035 -163.540841) (xy 369.498781 -163.563687) (xy 369.544749 -163.593411)
			(xy 369.565682 -163.611052) (xy 369.565936 -163.611306) (xy 369.573036 -163.616873) (xy 369.589943 -163.623131)
			(xy 369.598956 -163.623498) (xy 369.666012 -163.623498) (xy 369.675029 -163.623147) (xy 369.691946 -163.616895)
			(xy 369.699032 -163.611306) (xy 369.699032 -163.611052) (xy 369.699286 -163.611052) (xy 369.720219 -163.593414)
			(xy 369.766191 -163.5637) (xy 369.815938 -163.540863) (xy 369.868439 -163.525372) (xy 369.922615 -163.517545)
			(xy 369.949984 -163.517072) (xy 369.977558 -163.517558) (xy 370.032129 -163.525508) (xy 370.084988 -163.54123)
			(xy 370.135034 -163.564396) (xy 370.181224 -163.594524) (xy 370.222597 -163.630987) (xy 370.240814 -163.651692)
			(xy 370.248365 -163.659773) (xy 370.268379 -163.669124) (xy 370.279422 -163.669726) (xy 370.357146 -163.669726)
			(xy 370.368195 -163.669151) (xy 370.388218 -163.659793) (xy 370.395754 -163.651692) (xy 370.413984 -163.630998)
			(xy 370.455349 -163.594527) (xy 370.501535 -163.564393) (xy 370.551579 -163.541224) (xy 370.604438 -163.525504)
			(xy 370.65901 -163.51756) (xy 370.686584 -163.517072) (xy 370.713834 -163.517593) (xy 370.767779 -163.525347)
			(xy 370.820072 -163.540699) (xy 370.869648 -163.563337) (xy 370.915497 -163.592799) (xy 370.956687 -163.628487)
			(xy 370.992379 -163.669674) (xy 371.021846 -163.71552) (xy 371.044488 -163.765094) (xy 371.059845 -163.817385)
			(xy 371.067604 -163.87133) (xy 371.068092 -163.89858) (xy 371.067616 -163.92595) (xy 371.059801 -163.980129)
			(xy 371.044314 -164.032632) (xy 371.021475 -164.082379) (xy 370.991752 -164.128346) (xy 370.974112 -164.149278)
			(xy 370.973858 -164.149532) (xy 370.968289 -164.15663) (xy 370.962033 -164.173538) (xy 370.961666 -164.182552)
			(xy 370.961666 -164.249608) (xy 370.962026 -164.258624) (xy 370.968272 -164.275541) (xy 370.973858 -164.282628)
			(xy 370.974112 -164.282628) (xy 370.974112 -164.282882) (xy 370.991758 -164.303808) (xy 371.021468 -164.349783)
			(xy 371.044303 -164.399532) (xy 371.059792 -164.452034) (xy 371.067619 -164.50621) (xy 371.068092 -164.53358)
			(xy 371.068092 -164.533834) (xy 371.067564 -164.561813) (xy 371.059376 -164.617169) (xy 371.043194 -164.670737)
			(xy 371.019366 -164.721369) (xy 370.988402 -164.76798) (xy 370.970048 -164.789104) (xy 370.963698 -164.796216)
			(xy 370.95684 -164.81425) (xy 370.958364 -164.90315) (xy 370.965984 -164.92093) (xy 370.972588 -164.927788)
			(xy 370.992762 -164.949287) (xy 371.026905 -164.997347) (xy 371.053251 -165.050087) (xy 371.071172 -165.106251)
			(xy 371.080242 -165.164503) (xy 371.080792 -165.19398) (xy 371.080326 -165.221233) (xy 371.072571 -165.275185)
			(xy 371.057217 -165.327484) (xy 371.034576 -165.377065) (xy 371.005108 -165.422919) (xy 370.969415 -165.464112)
			(xy 370.928222 -165.499806) (xy 370.882368 -165.529274) (xy 370.832787 -165.551916) (xy 370.780489 -165.567271)
			(xy 370.726537 -165.575026) (xy 370.699284 -165.575488) (xy 370.671711 -165.574969) (xy 370.617141 -165.567028)
			(xy 370.564282 -165.551314) (xy 370.514235 -165.528154) (xy 370.468044 -165.49803) (xy 370.426671 -165.461571)
			(xy 370.408454 -165.440868) (xy 370.400923 -165.432767) (xy 370.380893 -165.423428) (xy 370.369846 -165.422834)
			(xy 370.292122 -165.422834) (xy 370.281073 -165.423403) (xy 370.261051 -165.432767) (xy 370.253514 -165.440868)
			(xy 370.235292 -165.461569) (xy 370.193926 -165.498042) (xy 370.147739 -165.528176) (xy 370.097693 -165.551344)
			(xy 370.044832 -165.567062) (xy 369.990258 -165.575002) (xy 369.962684 -165.575488) (xy 369.935313 -165.575034)
			(xy 369.881134 -165.567214) (xy 369.82863 -165.551722) (xy 369.778884 -165.528878) (xy 369.732917 -165.49915)
			(xy 369.711986 -165.481508) (xy 369.711732 -165.481254) (xy 369.704644 -165.475669) (xy 369.687728 -165.469423)
			(xy 369.678712 -165.469062) (xy 369.611656 -165.469062) (xy 369.602643 -165.469454) (xy 369.585726 -165.475678)
			(xy 369.578636 -165.481254) (xy 369.578636 -165.481508) (xy 369.578382 -165.481508) (xy 369.557449 -165.499149)
			(xy 369.511481 -165.528873) (xy 369.461735 -165.551719) (xy 369.409233 -165.567215) (xy 369.355055 -165.575044)
			(xy 369.300313 -165.575044) (xy 369.246135 -165.567215) (xy 369.193633 -165.551719) (xy 369.143887 -165.528873)
			(xy 369.097919 -165.499149) (xy 369.076986 -165.481508) (xy 369.076732 -165.481254) (xy 369.069644 -165.475669)
			(xy 369.052728 -165.469423) (xy 369.043712 -165.469062) (xy 368.976656 -165.469062) (xy 368.967643 -165.469454)
			(xy 368.950726 -165.475678) (xy 368.943636 -165.481254) (xy 368.943636 -165.481508) (xy 368.943382 -165.481508)
			(xy 368.922449 -165.499149) (xy 368.876481 -165.528873) (xy 368.826735 -165.551719) (xy 368.774233 -165.567215)
			(xy 368.720055 -165.575044) (xy 368.665313 -165.575044) (xy 368.611135 -165.567215) (xy 368.558633 -165.551719)
			(xy 368.508887 -165.528873) (xy 368.462919 -165.499149) (xy 368.441986 -165.481508) (xy 368.441732 -165.481254)
			(xy 368.434644 -165.475669) (xy 368.417728 -165.469423) (xy 368.408712 -165.469062) (xy 368.341656 -165.469062)
			(xy 368.332643 -165.469454) (xy 368.315726 -165.475678) (xy 368.308636 -165.481254) (xy 368.308636 -165.481508)
			(xy 368.308382 -165.481508) (xy 368.287431 -165.499123) (xy 368.241463 -165.528838) (xy 368.19172 -165.551679)
			(xy 368.139224 -165.567176) (xy 368.085052 -165.57501) (xy 368.057684 -165.575488) (xy 368.028671 -165.57497)
			(xy 367.971313 -165.566198) (xy 367.915943 -165.548843) (xy 367.86384 -165.523305) (xy 367.816203 -165.490174)
			(xy 367.794794 -165.470586) (xy 367.787936 -165.463728) (xy 367.769902 -165.456616) (xy 367.679986 -165.456616)
			(xy 367.661952 -165.463728) (xy 367.655094 -165.470586) (xy 367.633699 -165.490187) (xy 367.58605 -165.523298)
			(xy 367.533941 -165.548822) (xy 367.478572 -165.566172) (xy 367.421216 -165.574948) (xy 367.392204 -165.575488)
			(xy 367.364834 -165.575023) (xy 367.310654 -165.567205) (xy 367.258151 -165.551716) (xy 367.208404 -165.528874)
			(xy 367.162438 -165.499149) (xy 367.141506 -165.481508) (xy 367.141252 -165.481254) (xy 367.134159 -165.475677)
			(xy 367.117247 -165.469426) (xy 367.108232 -165.469062) (xy 367.041176 -165.469062) (xy 367.032159 -165.469416)
			(xy 367.015242 -165.475666) (xy 367.008156 -165.481254) (xy 367.008156 -165.481508) (xy 367.007902 -165.481508)
			(xy 366.986981 -165.499161) (xy 366.941005 -165.52887) (xy 366.891255 -165.551704) (xy 366.838752 -165.567191)
			(xy 366.784574 -165.575016) (xy 366.757204 -165.575488) (xy 366.72995 -165.575041) (xy 366.675998 -165.567284)
			(xy 366.623698 -165.551927) (xy 366.574117 -165.529284) (xy 366.528263 -165.499814) (xy 366.48707 -165.464119)
			(xy 366.451376 -165.422924) (xy 366.421908 -165.377069) (xy 366.399267 -165.327487) (xy 366.383913 -165.275187)
			(xy 366.376158 -165.221234) (xy 366.375696 -165.19398) (xy 366.375696 -165.193726) (xy 366.376202 -165.165746)
			(xy 366.384396 -165.110389) (xy 366.400583 -165.056821) (xy 366.424416 -165.006189) (xy 366.455384 -164.959579)
			(xy 366.47374 -164.938456) (xy 366.48009 -164.931344) (xy 366.486948 -164.91331) (xy 366.485424 -164.82441)
			(xy 366.477804 -164.80663) (xy 366.4712 -164.799772) (xy 366.451022 -164.778276) (xy 366.416876 -164.730217)
			(xy 366.390529 -164.677477) (xy 366.372609 -164.621311) (xy 366.363543 -164.563057) (xy 366.362996 -164.53358)
			(xy 365.671608 -164.53358) (xy 365.671608 -166.54526) (xy 372.08206 -166.54526)
		)
		(stroke
			(width 0)
			(type solid)
		)
		(fill yes)
		(layer "In4.Cu")
		(net "GND")
	)
	(gr_poly
		(pts
			(xy 172.083476 -388.564628) (xy 172.093438 -388.564141) (xy 172.111862 -388.556554) (xy 172.11929 -388.549896)
			(xy 172.849032 -387.820154) (xy 172.874956 -387.795035) (xy 172.932069 -387.750889) (xy 172.994324 -387.71435)
			(xy 173.060714 -387.686008) (xy 173.130163 -387.666323) (xy 173.16577 -387.660388) (xy 173.175184 -387.658609)
			(xy 173.191788 -387.649082) (xy 173.203722 -387.634114) (xy 173.206918 -387.625082) (xy 173.215317 -387.599465)
			(xy 173.238319 -387.550709) (xy 173.267955 -387.505676) (xy 173.303633 -387.465262) (xy 173.344645 -387.430272)
			(xy 173.390174 -387.401403) (xy 173.439312 -387.379229) (xy 173.491082 -387.364192) (xy 173.544453 -387.356592)
			(xy 173.571408 -387.356096) (xy 173.598027 -387.356559) (xy 173.650749 -387.363961) (xy 173.701931 -387.378619)
			(xy 173.750577 -387.400249) (xy 173.795745 -387.428432) (xy 173.836557 -387.462619) (xy 173.87222 -387.502148)
			(xy 173.902043 -387.54625) (xy 173.925445 -387.59407) (xy 173.93412 -387.61924) (xy 173.9392 -387.634734)
			(xy 173.96587 -387.654292) (xy 174.463456 -387.654292) (xy 174.473447 -387.653762) (xy 174.49189 -387.646059)
			(xy 174.49927 -387.639306) (xy 184.308242 -377.830334) (xy 184.315084 -377.822935) (xy 184.322804 -377.804336)
			(xy 184.323228 -377.794266) (xy 184.323228 -370.09705) (xy 184.322797 -370.086983) (xy 184.315073 -370.068389)
			(xy 184.308242 -370.060982) (xy 183.702452 -369.455192) (xy 183.695045 -369.4485) (xy 183.676609 -369.440901)
			(xy 183.666638 -369.44046) (xy 179.372514 -369.44046) (xy 179.362553 -369.440949) (xy 179.34413 -369.448537)
			(xy 179.3367 -369.455192) (xy 176.7586 -372.033292) (xy 176.735808 -372.055488) (xy 176.686075 -372.095169)
			(xy 176.632212 -372.129031) (xy 176.574895 -372.156648) (xy 176.514847 -372.177673) (xy 176.452821 -372.191842)
			(xy 176.389599 -372.198977) (xy 176.357788 -372.199408) (xy 172.758354 -372.199408) (xy 172.74839 -372.199891)
			(xy 172.729962 -372.207474) (xy 172.72254 -372.21414) (xy 172.036486 -372.900194) (xy 172.029629 -372.907588)
			(xy 172.021879 -372.926187) (xy 172.0215 -372.936262) (xy 172.0215 -376.49658) (xy 173.226991 -376.49658)
			(xy 173.230998 -376.311676) (xy 173.243011 -376.127118) (xy 173.263007 -375.943254) (xy 173.290949 -375.76043)
			(xy 173.326785 -375.578987) (xy 173.370447 -375.399266) (xy 173.421854 -375.221606) (xy 173.480908 -375.04634)
			(xy 173.547499 -374.873796) (xy 173.621502 -374.704299) (xy 173.702778 -374.538167) (xy 173.791174 -374.375711)
			(xy 173.886525 -374.217237) (xy 173.988651 -374.063042) (xy 174.09736 -373.913416) (xy 174.212449 -373.76864)
			(xy 174.333702 -373.628985) (xy 174.460891 -373.494714) (xy 174.593776 -373.366078) (xy 174.73211 -373.243319)
			(xy 174.875631 -373.126669) (xy 175.02407 -373.016345) (xy 175.17715 -372.912554) (xy 175.334581 -372.815492)
			(xy 175.49607 -372.725342) (xy 175.661312 -372.642271) (xy 175.829998 -372.566436) (xy 176.00181 -372.49798)
			(xy 176.176426 -372.43703) (xy 176.353519 -372.383703) (xy 176.532756 -372.338096) (xy 176.7138 -372.300297)
			(xy 176.896311 -372.270376) (xy 177.079948 -372.248389) (xy 177.264364 -372.234377) (xy 177.449214 -372.228367)
			(xy 177.634151 -372.230371) (xy 177.818828 -372.240384) (xy 178.002898 -372.258387) (xy 178.186014 -372.284348)
			(xy 178.367835 -372.318216) (xy 178.548018 -372.359928) (xy 178.726224 -372.409407) (xy 178.90212 -372.466559)
			(xy 179.075375 -372.531277) (xy 179.245664 -372.60344) (xy 179.412667 -372.682911) (xy 179.576071 -372.769542)
			(xy 179.735568 -372.863171) (xy 179.89086 -372.96362) (xy 180.041655 -373.070703) (xy 180.18767 -373.184217)
			(xy 180.32863 -373.303949) (xy 180.464271 -373.429676) (xy 180.594339 -373.56116) (xy 180.718589 -373.698156)
			(xy 180.836787 -373.840405) (xy 180.948713 -373.98764) (xy 181.054156 -374.139586) (xy 181.152917 -374.295957)
			(xy 181.244812 -374.45646) (xy 181.329668 -374.620792) (xy 181.407326 -374.788647) (xy 181.477639 -374.959707)
			(xy 181.540476 -375.133653) (xy 181.59572 -375.310158) (xy 181.643265 -375.48889) (xy 181.683023 -375.669514)
			(xy 181.71492 -375.851691) (xy 181.738895 -376.035078) (xy 181.754903 -376.219332) (xy 181.762915 -376.404106)
			(xy 181.763416 -376.49658) (xy 181.762915 -376.589054) (xy 181.754903 -376.773828) (xy 181.738895 -376.958082)
			(xy 181.71492 -377.141469) (xy 181.683023 -377.323646) (xy 181.643265 -377.50427) (xy 181.59572 -377.683002)
			(xy 181.540476 -377.859507) (xy 181.477639 -378.033453) (xy 181.407326 -378.204513) (xy 181.329668 -378.372368)
			(xy 181.244812 -378.5367) (xy 181.152917 -378.697203) (xy 181.054156 -378.853574) (xy 180.948713 -379.00552)
			(xy 180.836787 -379.152755) (xy 180.718589 -379.295004) (xy 180.594339 -379.432) (xy 180.464271 -379.563484)
			(xy 180.32863 -379.689211) (xy 180.18767 -379.808943) (xy 180.041655 -379.922457) (xy 179.89086 -380.02954)
			(xy 179.735568 -380.129989) (xy 179.576071 -380.223618) (xy 179.412667 -380.310249) (xy 179.245664 -380.38972)
			(xy 179.075375 -380.461883) (xy 178.90212 -380.526601) (xy 178.726224 -380.583753) (xy 178.548018 -380.633232)
			(xy 178.367835 -380.674944) (xy 178.186014 -380.708812) (xy 178.002898 -380.734773) (xy 177.818828 -380.752776)
			(xy 177.634151 -380.762789) (xy 177.449214 -380.764793) (xy 177.264364 -380.758783) (xy 177.079948 -380.744771)
			(xy 176.896311 -380.722784) (xy 176.7138 -380.692863) (xy 176.532756 -380.655064) (xy 176.353519 -380.609457)
			(xy 176.176426 -380.55613) (xy 176.00181 -380.49518) (xy 175.829998 -380.426724) (xy 175.661312 -380.350889)
			(xy 175.49607 -380.267818) (xy 175.334581 -380.177668) (xy 175.17715 -380.080606) (xy 175.02407 -379.976815)
			(xy 174.875631 -379.866491) (xy 174.73211 -379.749841) (xy 174.593776 -379.627082) (xy 174.460891 -379.498446)
			(xy 174.333702 -379.364175) (xy 174.212449 -379.22452) (xy 174.09736 -379.079744) (xy 173.988651 -378.930118)
			(xy 173.886525 -378.775923) (xy 173.791174 -378.617449) (xy 173.702778 -378.454993) (xy 173.621502 -378.288861)
			(xy 173.547499 -378.119364) (xy 173.480908 -377.94682) (xy 173.421854 -377.771554) (xy 173.370447 -377.593894)
			(xy 173.326785 -377.414173) (xy 173.290949 -377.23273) (xy 173.263007 -377.049906) (xy 173.243011 -376.866042)
			(xy 173.230998 -376.681484) (xy 173.226991 -376.49658) (xy 172.0215 -376.49658) (xy 172.0215 -380.905258)
			(xy 172.021066 -380.915323) (xy 172.013337 -380.933913) (xy 172.006514 -380.941326) (xy 170.433746 -382.514094)
			(xy 170.426894 -382.52149) (xy 170.41915 -382.540088) (xy 170.41876 -382.550162) (xy 170.41876 -383.949194)
			(xy 170.419184 -383.959263) (xy 170.426903 -383.977864) (xy 170.433746 -383.985262) (xy 170.712384 -384.2639)
			(xy 170.734581 -384.286692) (xy 170.774262 -384.336425) (xy 170.808124 -384.390288) (xy 170.835742 -384.447604)
			(xy 170.856767 -384.507653) (xy 170.870936 -384.569678) (xy 170.878071 -384.6329) (xy 170.8785 -384.664712)
			(xy 170.8785 -386.010404) (xy 170.98848 -386.010404) (xy 170.992551 -385.954782) (xy 171.004677 -385.900345)
			(xy 171.0246 -385.848254) (xy 171.051896 -385.799619) (xy 171.085982 -385.755476) (xy 171.126131 -385.716767)
			(xy 171.171489 -385.684316) (xy 171.221089 -385.658815) (xy 171.273873 -385.640808) (xy 171.328716 -385.630678)
			(xy 171.38445 -385.628641) (xy 171.439887 -385.634741) (xy 171.493844 -385.648847) (xy 171.545173 -385.670659)
			(xy 171.592779 -385.699713) (xy 171.635647 -385.735388) (xy 171.672864 -385.776925) (xy 171.703637 -385.823438)
			(xy 171.727309 -385.873935) (xy 171.743377 -385.927342) (xy 171.751497 -385.982518) (xy 171.752006 -386.010404)
			(xy 171.751497 -386.03829) (xy 171.743377 -386.093466) (xy 171.727309 -386.146873) (xy 171.724842 -386.152136)
			(xy 172.518322 -386.152136) (xy 172.522393 -386.096514) (xy 172.534519 -386.042077) (xy 172.554442 -385.989986)
			(xy 172.581738 -385.941351) (xy 172.615824 -385.897208) (xy 172.655973 -385.858499) (xy 172.701331 -385.826048)
			(xy 172.750931 -385.800547) (xy 172.803715 -385.78254) (xy 172.858558 -385.77241) (xy 172.914292 -385.770373)
			(xy 172.969729 -385.776473) (xy 173.023686 -385.790579) (xy 173.075015 -385.812391) (xy 173.122621 -385.841445)
			(xy 173.165489 -385.87712) (xy 173.202706 -385.918657) (xy 173.233479 -385.96517) (xy 173.2398 -385.978654)
			(xy 174.400462 -385.978654) (xy 174.404533 -385.923032) (xy 174.416659 -385.868595) (xy 174.436582 -385.816504)
			(xy 174.463878 -385.767869) (xy 174.497964 -385.723726) (xy 174.538113 -385.685017) (xy 174.583471 -385.652566)
			(xy 174.633071 -385.627065) (xy 174.685855 -385.609058) (xy 174.740698 -385.598928) (xy 174.796432 -385.596891)
			(xy 174.851869 -385.602991) (xy 174.905826 -385.617097) (xy 174.957155 -385.638909) (xy 175.004761 -385.667963)
			(xy 175.047629 -385.703638) (xy 175.084846 -385.745175) (xy 175.115619 -385.791688) (xy 175.139291 -385.842185)
			(xy 175.155359 -385.895592) (xy 175.163479 -385.950768) (xy 175.163988 -385.978654) (xy 175.163479 -386.00654)
			(xy 175.155359 -386.061716) (xy 175.139291 -386.115123) (xy 175.115619 -386.16562) (xy 175.084846 -386.212133)
			(xy 175.047629 -386.25367) (xy 175.004761 -386.289345) (xy 174.957155 -386.318399) (xy 174.905826 -386.340211)
			(xy 174.851869 -386.354317) (xy 174.796432 -386.360417) (xy 174.740698 -386.35838) (xy 174.685855 -386.34825)
			(xy 174.633071 -386.330243) (xy 174.583471 -386.304742) (xy 174.538113 -386.272291) (xy 174.497964 -386.233582)
			(xy 174.463878 -386.189439) (xy 174.436582 -386.140804) (xy 174.416659 -386.088713) (xy 174.404533 -386.034276)
			(xy 174.400462 -385.978654) (xy 173.2398 -385.978654) (xy 173.257151 -386.015667) (xy 173.273219 -386.069074)
			(xy 173.281339 -386.12425) (xy 173.281848 -386.152136) (xy 173.281339 -386.180022) (xy 173.273219 -386.235198)
			(xy 173.257151 -386.288605) (xy 173.233479 -386.339102) (xy 173.202706 -386.385615) (xy 173.165489 -386.427152)
			(xy 173.122621 -386.462827) (xy 173.075015 -386.491881) (xy 173.023686 -386.513693) (xy 172.969729 -386.527799)
			(xy 172.914292 -386.533899) (xy 172.858558 -386.531862) (xy 172.803715 -386.521732) (xy 172.750931 -386.503725)
			(xy 172.701331 -386.478224) (xy 172.655973 -386.445773) (xy 172.615824 -386.407064) (xy 172.581738 -386.362921)
			(xy 172.554442 -386.314286) (xy 172.534519 -386.262195) (xy 172.522393 -386.207758) (xy 172.518322 -386.152136)
			(xy 171.724842 -386.152136) (xy 171.703637 -386.19737) (xy 171.672864 -386.243883) (xy 171.635647 -386.28542)
			(xy 171.592779 -386.321095) (xy 171.545173 -386.350149) (xy 171.493844 -386.371961) (xy 171.439887 -386.386067)
			(xy 171.38445 -386.392167) (xy 171.328716 -386.39013) (xy 171.273873 -386.38) (xy 171.221089 -386.361993)
			(xy 171.171489 -386.336492) (xy 171.126131 -386.304041) (xy 171.085982 -386.265332) (xy 171.051896 -386.221189)
			(xy 171.0246 -386.172554) (xy 171.004677 -386.120463) (xy 170.992551 -386.066026) (xy 170.98848 -386.010404)
			(xy 170.8785 -386.010404) (xy 170.8785 -386.355082) (xy 170.90263 -386.38353) (xy 170.921172 -386.386324)
			(xy 170.947769 -386.390993) (xy 170.99939 -386.406843) (xy 171.048261 -386.429811) (xy 171.093407 -386.459438)
			(xy 171.133926 -386.495134) (xy 171.169008 -386.536184) (xy 171.197954 -386.58177) (xy 171.220185 -386.630981)
			(xy 171.228881 -386.660898) (xy 173.271178 -386.660898) (xy 173.275249 -386.605276) (xy 173.287375 -386.550839)
			(xy 173.307298 -386.498748) (xy 173.334594 -386.450113) (xy 173.36868 -386.40597) (xy 173.408829 -386.367261)
			(xy 173.454187 -386.33481) (xy 173.503787 -386.309309) (xy 173.556571 -386.291302) (xy 173.611414 -386.281172)
			(xy 173.667148 -386.279135) (xy 173.722585 -386.285235) (xy 173.776542 -386.299341) (xy 173.827871 -386.321153)
			(xy 173.875477 -386.350207) (xy 173.918345 -386.385882) (xy 173.955562 -386.427419) (xy 173.986335 -386.473932)
			(xy 174.010007 -386.524429) (xy 174.026075 -386.577836) (xy 174.034195 -386.633012) (xy 174.034704 -386.660898)
			(xy 174.034195 -386.688784) (xy 174.026075 -386.74396) (xy 174.010007 -386.797367) (xy 173.986335 -386.847864)
			(xy 173.955562 -386.894377) (xy 173.918345 -386.935914) (xy 173.875477 -386.971589) (xy 173.827871 -387.000643)
			(xy 173.776542 -387.022455) (xy 173.722585 -387.036561) (xy 173.667148 -387.042661) (xy 173.611414 -387.040624)
			(xy 173.556571 -387.030494) (xy 173.503787 -387.012487) (xy 173.454187 -386.986986) (xy 173.408829 -386.954535)
			(xy 173.36868 -386.915826) (xy 173.334594 -386.871683) (xy 173.307298 -386.823048) (xy 173.287375 -386.770957)
			(xy 173.275249 -386.71652) (xy 173.271178 -386.660898) (xy 171.228881 -386.660898) (xy 171.235258 -386.682834)
			(xy 171.24287 -386.736294) (xy 171.242871 -386.790293) (xy 171.23526 -386.843754) (xy 171.22019 -386.895607)
			(xy 171.19796 -386.944819) (xy 171.169016 -386.990406) (xy 171.133935 -387.031458) (xy 171.093417 -387.067154)
			(xy 171.048272 -387.096783) (xy 170.999402 -387.119753) (xy 170.947781 -387.135604) (xy 170.921172 -387.140196)
			(xy 170.90263 -387.14299) (xy 170.8785 -387.171438) (xy 170.8785 -387.226302) (xy 170.904408 -387.255258)
			(xy 170.923712 -387.25729) (xy 170.954525 -387.261049) (xy 171.014987 -387.275111) (xy 171.073287 -387.29643)
			(xy 171.128557 -387.324688) (xy 171.179976 -387.359467) (xy 171.226777 -387.400247) (xy 171.268265 -387.446422)
			(xy 171.303822 -387.497305) (xy 171.332918 -387.552139) (xy 171.355122 -387.610108) (xy 171.370102 -387.670349)
			(xy 171.377635 -387.731966) (xy 171.378118 -387.763004) (xy 171.377679 -387.793117) (xy 171.370573 -387.852922)
			(xy 171.356451 -387.911468) (xy 171.335509 -387.967935) (xy 171.308041 -388.021532) (xy 171.274432 -388.071507)
			(xy 171.235153 -388.117161) (xy 171.190754 -388.157854) (xy 171.166536 -388.175754) (xy 171.157114 -388.183416)
			(xy 171.146121 -388.205029) (xy 171.145454 -388.217156) (xy 171.145454 -388.299452) (xy 171.146066 -388.311595)
			(xy 171.157059 -388.333241) (xy 171.166536 -388.340854) (xy 171.19229 -388.359967) (xy 171.239246 -388.403651)
			(xy 171.280337 -388.452892) (xy 171.314912 -388.506909) (xy 171.329096 -388.535672) (xy 171.333613 -388.544129)
			(xy 171.347658 -388.55716) (xy 171.365491 -388.564165) (xy 171.37507 -388.564628)
		)
		(stroke
			(width 0)
			(type solid)
		)
		(fill yes)
		(layer "In4.Cu")
		(net "P1V8_CPU1_RT_1D")
	)
	(gr_poly
		(pts
			(xy 278.25319 -381.468122) (xy 278.25319 -375.210832)
			(arc
				(start 277.75408 -374.711722)
				(mid 277.750179 -374.692199)
				(end 277.739094 -374.675654)
			)
			(arc
				(start 275.965666 -372.902226)
				(mid 275.949132 -372.891115)
				(end 275.929598 -372.88724)
			)
			(xy 274.329652 -372.88724) (xy 274.296886 -372.854474) (xy 273.90852 -372.854474) (xy 273.027902 -371.973856)
			(xy 237.102142 -371.973856) (xy 236.70387 -372.372128) (xy 236.70387 -373.351298) (xy 236.70387 -381.177038)
			(xy 237.095792 -381.56896) (xy 237.676182 -381.56896)
			(arc
				(start 242.373658 -381.56896)
				(mid 242.393181 -381.565059)
				(end 242.409726 -381.553974)
			)
			(xy 242.54206 -381.42164) (xy 242.54968 -381.400558)
			(arc
				(start 242.54841 -381.389128)
				(mid 242.545526 -381.347517)
				(end 242.5446 -381.305816)
			)
			(arc
				(start 242.5446 -381.305816)
				(mid 242.561582 -381.132835)
				(end 242.61191 -380.966472)
			)
			(xy 242.61572 -380.957074)
			(arc
				(start 242.61572 -380.868682)
				(mid 242.619621 -380.849159)
				(end 242.630706 -380.832614)
			)
			(arc
				(start 242.709954 -380.753366)
				(mid 242.726488 -380.742255)
				(end 242.746022 -380.73838)
			)
			(xy 242.748816 -380.73838)
			(arc
				(start 242.763802 -380.721108)
				(mid 243.065936 -380.496098)
				(end 243.434108 -380.416308)
			)
			(arc
				(start 243.434108 -380.416308)
				(mid 243.635821 -380.439481)
				(end 243.827046 -380.507748)
			)
			(arc
				(start 243.827046 -380.507748)
				(mid 243.855255 -380.512748)
				(end 243.881656 -380.501652)
			)
			(arc
				(start 243.881656 -380.501652)
				(mid 244.085185 -380.3867)
				(end 244.315488 -380.346712)
			)
			(arc
				(start 244.719602 -380.346712)
				(mid 245.018076 -380.414768)
				(end 245.25732 -380.605792)
			)
			(xy 245.264686 -380.61519)
			(arc
				(start 245.269004 -380.618746)
				(mid 245.508358 -380.925875)
				(end 245.593616 -381.305816)
			)
			(arc
				(start 245.593616 -381.305816)
				(mid 245.588841 -381.397877)
				(end 245.574566 -381.48895)
			)
			(arc
				(start 245.574566 -381.48895)
				(mid 245.580408 -381.524976)
				(end 245.608856 -381.547878)
			)
			(xy 245.613174 -381.549148) (xy 245.619016 -381.550926)
			(arc
				(start 245.675658 -381.56896)
				(mid 245.683308 -381.570814)
				(end 245.691152 -381.5715)
			)
			(arc
				(start 248.312178 -381.5715)
				(mid 248.331701 -381.567599)
				(end 248.348246 -381.556514)
			)
			(xy 248.477532 -381.427228) (xy 248.485152 -381.405892)
			(arc
				(start 248.483882 -381.394462)
				(mid 248.480613 -381.350193)
				(end 248.479564 -381.305816)
			)
			(arc
				(start 248.479564 -381.305816)
				(mid 248.485227 -381.205607)
				(end 248.50217 -381.10668)
			)
			(xy 248.50344 -381.101092)
			(arc
				(start 248.50344 -380.881382)
				(mid 248.507341 -380.861859)
				(end 248.518426 -380.845314)
			)
			(arc
				(start 248.645934 -380.717806)
				(mid 248.662468 -380.706695)
				(end 248.682002 -380.70282)
			)
			(xy 248.703592 -380.70282) (xy 248.722642 -380.694692)
			(arc
				(start 248.729754 -380.687326)
				(mid 249.021873 -380.486847)
				(end 249.369072 -380.416308)
			)
			(arc
				(start 249.369072 -380.416308)
				(mid 249.570785 -380.439481)
				(end 249.76201 -380.507748)
			)
			(arc
				(start 249.76201 -380.507748)
				(mid 249.790219 -380.512748)
				(end 249.81662 -380.501652)
			)
			(arc
				(start 249.81662 -380.501652)
				(mid 250.020149 -380.3867)
				(end 250.250452 -380.346712)
			)
			(arc
				(start 250.674632 -380.346712)
				(mid 250.937383 -380.399106)
				(end 251.160026 -380.548134)
			)
			(arc
				(start 251.31522 -380.703328)
				(mid 251.323137 -380.713669)
				(end 251.328174 -380.72568)
			)
			(xy 251.33554 -380.75235)
			(arc
				(start 251.341636 -380.760224)
				(mid 251.480565 -381.017447)
				(end 251.52858 -381.305816)
			)
			(arc
				(start 251.52858 -381.305816)
				(mid 251.525985 -381.373961)
				(end 251.518166 -381.441706)
			)
			(xy 251.516388 -381.452628) (xy 251.522484 -381.473964)
			(arc
				(start 251.579888 -381.54102)
				(mid 251.597243 -381.554143)
				(end 251.618496 -381.5588)
			)
			(arc
				(start 254.248158 -381.5588)
				(mid 254.267681 -381.554899)
				(end 254.284226 -381.543814)
			)
			(xy 254.41148 -381.41656) (xy 254.4191 -381.395732)
			(arc
				(start 254.418084 -381.384302)
				(mid 254.415437 -381.345098)
				(end 254.414528 -381.305816)
			)
			(arc
				(start 254.414528 -381.305816)
				(mid 254.416827 -381.242152)
				(end 254.423672 -381.178816)
			)
			(xy 254.42418 -381.175006)
			(arc
				(start 254.42418 -381.010922)
				(mid 254.420279 -380.991399)
				(end 254.409194 -380.974854)
			)
			(xy 254.40386 -380.96952) (xy 254.569976 -380.803404)
			(arc
				(start 254.572516 -380.799594)
				(mid 254.891115 -380.517948)
				(end 255.304036 -380.416308)
			)
			(arc
				(start 255.304036 -380.416308)
				(mid 255.505749 -380.439481)
				(end 255.696974 -380.507748)
			)
			(arc
				(start 255.696974 -380.507748)
				(mid 255.725183 -380.512748)
				(end 255.751584 -380.501652)
			)
			(arc
				(start 255.751584 -380.501652)
				(mid 255.955113 -380.3867)
				(end 256.185416 -380.346712)
			)
			(arc
				(start 256.58953 -380.346712)
				(mid 256.888004 -380.414768)
				(end 257.127248 -380.605792)
			)
			(xy 257.134614 -380.61519)
			(arc
				(start 257.138932 -380.618746)
				(mid 257.378286 -380.925875)
				(end 257.463544 -381.305816)
			)
			(arc
				(start 257.463544 -381.305816)
				(mid 257.457432 -381.409912)
				(end 257.43916 -381.512572)
			)
			(xy 257.436112 -381.525526) (xy 257.443224 -381.550672)
			(arc
				(start 257.482086 -381.589534)
				(mid 257.498503 -381.600596)
				(end 257.5179 -381.60452)
			)
			(arc
				(start 260.090158 -381.60452)
				(mid 260.109681 -381.600619)
				(end 260.126226 -381.589534)
			)
			(xy 260.343142 -381.372618) (xy 260.350762 -381.35306) (xy 260.350254 -381.342392)
			(arc
				(start 260.349492 -381.305816)
				(mid 260.353823 -381.218141)
				(end 260.366764 -381.131318)
			)
			(xy 260.36778 -381.126238)
			(arc
				(start 260.36778 -380.990602)
				(mid 260.371681 -380.971079)
				(end 260.382766 -380.954534)
			)
			(xy 260.458966 -380.878334)
			(arc
				(start 260.462268 -380.872238)
				(mid 260.78866 -380.538681)
				(end 261.239 -380.416308)
			)
			(arc
				(start 261.239 -380.416308)
				(mid 261.440713 -380.439481)
				(end 261.631938 -380.507748)
			)
			(arc
				(start 261.631938 -380.507748)
				(mid 261.660147 -380.512748)
				(end 261.686548 -380.501652)
			)
			(arc
				(start 261.686548 -380.501652)
				(mid 261.890077 -380.3867)
				(end 262.12038 -380.346712)
			)
			(arc
				(start 262.524494 -380.346712)
				(mid 262.822968 -380.414768)
				(end 263.062212 -380.605792)
			)
			(xy 263.069578 -380.61519)
			(arc
				(start 263.073896 -380.618746)
				(mid 263.31325 -380.925875)
				(end 263.398508 -381.305816)
			)
			(arc
				(start 263.398508 -381.305816)
				(mid 263.3962 -381.369352)
				(end 263.389364 -381.432562)
			)
			(xy 263.38784 -381.443738) (xy 263.393936 -381.464566)
			(arc
				(start 263.451594 -381.531114)
				(mid 263.468869 -381.544034)
				(end 263.489948 -381.54864)
			)
			(arc
				(start 266.099798 -381.54864)
				(mid 266.119321 -381.544739)
				(end 266.135866 -381.533654)
			)
			(xy 266.279122 -381.390398) (xy 266.286742 -381.370078) (xy 266.28598 -381.359156)
			(arc
				(start 266.284456 -381.305816)
				(mid 266.291487 -381.194449)
				(end 266.312396 -381.084836)
			)
			(xy 266.31392 -381.07874)
			(arc
				(start 266.31392 -380.990602)
				(mid 266.317821 -380.971079)
				(end 266.328906 -380.954534)
			)
			(xy 266.38123 -380.90221)
			(arc
				(start 266.384786 -380.895098)
				(mid 266.71243 -380.545356)
				(end 267.173964 -380.416308)
			)
			(arc
				(start 267.173964 -380.416308)
				(mid 267.375677 -380.439481)
				(end 267.566902 -380.507748)
			)
			(arc
				(start 267.566902 -380.507748)
				(mid 267.595111 -380.512748)
				(end 267.621512 -380.501652)
			)
			(arc
				(start 267.621512 -380.501652)
				(mid 267.825041 -380.3867)
				(end 268.055344 -380.346712)
			)
			(arc
				(start 268.459458 -380.346712)
				(mid 268.757932 -380.414768)
				(end 268.997176 -380.605792)
			)
			(xy 269.004542 -380.61519)
			(arc
				(start 269.00886 -380.618746)
				(mid 269.248214 -380.925875)
				(end 269.333472 -381.305816)
			)
			(arc
				(start 269.333472 -381.305816)
				(mid 269.327631 -381.407836)
				(end 269.310104 -381.508508)
			)
			(xy 269.307056 -381.521462) (xy 269.314168 -381.546608)
			(arc
				(start 269.324074 -381.556514)
				(mid 269.340608 -381.567625)
				(end 269.360142 -381.5715)
			)
			(arc
				(start 272.023078 -381.5715)
				(mid 272.042601 -381.567599)
				(end 272.059146 -381.556514)
			)
			(xy 272.21434 -381.40132) (xy 272.22196 -381.382778)
			(arc
				(start 272.22196 -381.372872)
				(mid 272.220062 -381.339368)
				(end 272.21942 -381.305816)
			)
			(arc
				(start 272.21942 -381.305816)
				(mid 272.219964 -381.273156)
				(end 272.221706 -381.240538)
			)
			(xy 272.22196 -381.238506)
			(arc
				(start 272.22196 -380.990602)
				(mid 272.225861 -380.971079)
				(end 272.236946 -380.954534)
			)
			(xy 272.34642 -380.84506)
			(arc
				(start 272.353532 -380.835916)
				(mid 272.676872 -380.528255)
				(end 273.108928 -380.416308)
			)
			(arc
				(start 273.108928 -380.416308)
				(mid 273.310641 -380.439481)
				(end 273.501866 -380.507748)
			)
			(arc
				(start 273.501866 -380.507748)
				(mid 273.530075 -380.512748)
				(end 273.556476 -380.501652)
			)
			(arc
				(start 273.556476 -380.501652)
				(mid 273.760005 -380.3867)
				(end 273.990308 -380.346712)
			)
			(arc
				(start 274.394422 -380.346712)
				(mid 274.692896 -380.414768)
				(end 274.93214 -380.605792)
			)
			(xy 274.939506 -380.61519)
			(arc
				(start 274.943824 -380.618746)
				(mid 275.183178 -380.925875)
				(end 275.268436 -381.305816)
			)
			(arc
				(start 275.268436 -381.305816)
				(mid 275.261824 -381.414321)
				(end 275.24202 -381.521208)
			)
			(xy 275.238972 -381.5334) (xy 275.244814 -381.558038) (xy 275.251418 -381.565404)
			(arc
				(start 275.257768 -381.581914)
				(mid 275.276413 -381.605698)
				(end 275.305266 -381.61468)
			)
			(xy 277.565358 -381.61468) (xy 277.5712 -381.620522) (xy 278.10079 -381.620522)
		)
		(stroke
			(width 0)
			(type solid)
		)
		(fill yes)
		(layer "In4.Cu")
		(net "P12V_AUX")
	)
	(gr_poly
		(pts
			(xy 22.774148 -353.278694) (xy 22.75332 -353.257866) (xy 22.75332 -353.23653) (xy 24.596344 -351.393506)
			(xy 24.596344 -349.676466) (xy 24.596889 -349.666482) (xy 24.604616 -349.648063) (xy 24.61133 -349.640652)
			(xy 25.560782 -348.6912) (xy 25.56763 -348.683802) (xy 25.575367 -348.665204) (xy 25.575768 -348.655132)
			(xy 25.575768 -346.273882) (xy 25.575263 -346.264074) (xy 25.567806 -346.245925) (xy 25.56129 -346.238576)
			(xy 25.505156 -346.180664) (xy 25.486868 -346.17279) (xy 25.476962 -346.172282) (xy 25.449639 -346.170983)
			(xy 25.39579 -346.16137) (xy 25.343926 -346.143987) (xy 25.295162 -346.119207) (xy 25.250545 -346.087562)
			(xy 25.211035 -346.049733) (xy 25.177481 -346.006534) (xy 25.150604 -345.958892) (xy 25.130983 -345.907833)
			(xy 25.119039 -345.854453) (xy 25.115029 -345.799901) (xy 25.119039 -345.745348) (xy 25.130983 -345.691968)
			(xy 25.150604 -345.640909) (xy 25.17748 -345.593267) (xy 25.211034 -345.550067) (xy 25.250544 -345.512239)
			(xy 25.295161 -345.480594) (xy 25.343925 -345.455813) (xy 25.395789 -345.43843) (xy 25.449638 -345.428817)
			(xy 25.476962 -345.427554) (xy 25.486868 -345.427046) (xy 25.505156 -345.419172) (xy 25.56129 -345.36126)
			(xy 25.567835 -345.353931) (xy 25.575283 -345.335768) (xy 25.575768 -345.325954) (xy 25.575768 -341.686896)
			(xy 25.575229 -341.67691) (xy 25.567511 -341.658481) (xy 25.560782 -341.651082) (xy 15.862554 -331.952854)
			(xy 15.855156 -331.946009) (xy 15.836557 -331.938283) (xy 15.826486 -331.937868) (xy 15.0241 -331.937868)
			(xy 15.016918 -331.938112) (xy 15.003119 -331.942103) (xy 14.996922 -331.945742) (xy 14.969678 -331.962412)
			(xy 14.911871 -331.989572) (xy 14.851119 -332.009284) (xy 14.788378 -332.021236) (xy 14.724634 -332.025241)
			(xy 14.66089 -332.021236) (xy 14.598149 -332.009284) (xy 14.537397 -331.989572) (xy 14.47959 -331.962412)
			(xy 14.452346 -331.945742) (xy 14.446146 -331.942108) (xy 14.43235 -331.938111) (xy 14.425168 -331.937868)
			(xy 8.383016 -331.937868) (xy 8.372966 -331.938374) (xy 8.354406 -331.946096) (xy 8.346948 -331.952854)
			(xy 8.105648 -332.194154) (xy 8.098805 -332.201553) (xy 8.091083 -332.220152) (xy 8.090662 -332.230222)
			(xy 8.090662 -333.9338) (xy 14.277876 -340.121014) (xy 22.606322 -340.121014) (xy 22.606327 -340.066519)
			(xy 22.614086 -340.01258) (xy 22.629444 -339.960294) (xy 22.652085 -339.910726) (xy 22.681551 -339.864884)
			(xy 22.71724 -339.823702) (xy 22.758427 -339.788019) (xy 22.804273 -339.75856) (xy 22.853845 -339.735925)
			(xy 22.906133 -339.720575) (xy 22.960073 -339.712823) (xy 23.014568 -339.712826) (xy 23.068508 -339.720584)
			(xy 23.120794 -339.735939) (xy 23.170363 -339.758579) (xy 23.216206 -339.788043) (xy 23.257389 -339.823731)
			(xy 23.293074 -339.864917) (xy 23.322534 -339.910762) (xy 23.345171 -339.960333) (xy 23.360522 -340.01262)
			(xy 23.368276 -340.066561) (xy 23.368762 -340.093808) (xy 23.36832 -340.119399) (xy 23.361443 -340.170118)
			(xy 23.355046 -340.1949) (xy 23.351598 -340.209641) (xy 23.352515 -340.239885) (xy 23.362246 -340.268535)
			(xy 23.379938 -340.293082) (xy 23.404041 -340.311373) (xy 23.432442 -340.321807) (xy 23.462654 -340.323468)
			(xy 23.477474 -340.320376) (xy 23.499973 -340.315158) (xy 23.54582 -340.309553) (xy 23.568914 -340.3092)
			(xy 23.596164 -340.309693) (xy 23.650109 -340.317451) (xy 23.7024 -340.332807) (xy 23.751974 -340.355449)
			(xy 23.797821 -340.384915) (xy 23.839009 -340.420606) (xy 23.874697 -340.461795) (xy 23.904161 -340.507644)
			(xy 23.9268 -340.557219) (xy 23.942153 -340.609512) (xy 23.949908 -340.663457) (xy 23.949907 -340.717957)
			(xy 23.94215 -340.771901) (xy 23.926795 -340.824193) (xy 23.904155 -340.873768) (xy 23.874689 -340.919616)
			(xy 23.838999 -340.960803) (xy 23.797811 -340.996493) (xy 23.751963 -341.025957) (xy 23.702388 -341.048597)
			(xy 23.650096 -341.063952) (xy 23.596151 -341.071708) (xy 23.541651 -341.071708) (xy 23.487706 -341.063952)
			(xy 23.435414 -341.048598) (xy 23.385839 -341.025958) (xy 23.33999 -340.996494) (xy 23.298802 -340.960804)
			(xy 23.263111 -340.919617) (xy 23.233646 -340.873769) (xy 23.211005 -340.824195) (xy 23.19565 -340.771903)
			(xy 23.187893 -340.717958) (xy 23.187406 -340.690708) (xy 23.187832 -340.665116) (xy 23.194719 -340.614398)
			(xy 23.201122 -340.589616) (xy 23.204577 -340.574881) (xy 23.203639 -340.544645) (xy 23.193898 -340.516005)
			(xy 23.176205 -340.491468) (xy 23.152109 -340.473179) (xy 23.123717 -340.462738) (xy 23.093513 -340.461059)
			(xy 23.078694 -340.46414) (xy 23.056196 -340.469364) (xy 23.010348 -340.474965) (xy 22.987254 -340.475316)
			(xy 22.960007 -340.474773) (xy 22.906068 -340.467011) (xy 22.853782 -340.451652) (xy 22.804214 -340.429008)
			(xy 22.758374 -340.399541) (xy 22.717193 -340.363851) (xy 22.681511 -340.322663) (xy 22.652053 -340.276816)
			(xy 22.62942 -340.227244) (xy 22.614072 -340.174955) (xy 22.606322 -340.121014) (xy 14.277876 -340.121014)
			(xy 14.68882 -340.531958) (xy 14.68882 -341.77478) (xy 14.841728 -341.927688) (xy 23.224996 -341.927688)
			(xy 23.229067 -341.872066) (xy 23.241193 -341.817629) (xy 23.261116 -341.765538) (xy 23.288412 -341.716903)
			(xy 23.322498 -341.67276) (xy 23.362647 -341.634051) (xy 23.408005 -341.6016) (xy 23.457605 -341.576099)
			(xy 23.510389 -341.558092) (xy 23.565232 -341.547962) (xy 23.620966 -341.545925) (xy 23.676403 -341.552025)
			(xy 23.73036 -341.566131) (xy 23.781689 -341.587943) (xy 23.829295 -341.616997) (xy 23.872163 -341.652672)
			(xy 23.90938 -341.694209) (xy 23.940153 -341.740722) (xy 23.963825 -341.791219) (xy 23.979893 -341.844626)
			(xy 23.988013 -341.899802) (xy 23.988522 -341.927688) (xy 23.988013 -341.955574) (xy 23.979893 -342.01075)
			(xy 23.963825 -342.064157) (xy 23.940153 -342.114654) (xy 23.90938 -342.161167) (xy 23.872163 -342.202704)
			(xy 23.829295 -342.238379) (xy 23.781689 -342.267433) (xy 23.73036 -342.289245) (xy 23.676403 -342.303351)
			(xy 23.620966 -342.309451) (xy 23.565232 -342.307414) (xy 23.510389 -342.297284) (xy 23.457605 -342.279277)
			(xy 23.408005 -342.253776) (xy 23.362647 -342.221325) (xy 23.322498 -342.182616) (xy 23.288412 -342.138473)
			(xy 23.261116 -342.089838) (xy 23.241193 -342.037747) (xy 23.229067 -341.98331) (xy 23.224996 -341.927688)
			(xy 14.841728 -341.927688) (xy 15.89024 -342.9762) (xy 22.10586 -342.9762) (xy 22.110027 -342.920586)
			(xy 22.122437 -342.866215) (xy 22.142812 -342.8143) (xy 22.170697 -342.766002) (xy 22.205469 -342.7224)
			(xy 22.246351 -342.684467) (xy 22.29243 -342.653051) (xy 22.342676 -342.628853) (xy 22.395968 -342.612415)
			(xy 22.451115 -342.604103) (xy 22.479 -342.603582) (xy 22.506341 -342.604043) (xy 22.560437 -342.612024)
			(xy 22.612785 -342.62783) (xy 22.662259 -342.65112) (xy 22.707795 -342.681394) (xy 22.728428 -342.69934)
			(xy 22.73554 -342.705944) (xy 22.752812 -342.712548) (xy 22.840188 -342.712548) (xy 22.85746 -342.705944)
			(xy 22.864572 -342.69934) (xy 22.885197 -342.681388) (xy 22.930743 -342.651131) (xy 22.98022 -342.627852)
			(xy 23.032567 -342.612049) (xy 23.08666 -342.604062) (xy 23.114 -342.603582) (xy 23.141885 -342.604103)
			(xy 23.197032 -342.612415) (xy 23.250324 -342.628853) (xy 23.30057 -342.653051) (xy 23.346649 -342.684467)
			(xy 23.387531 -342.7224) (xy 23.422303 -342.766002) (xy 23.450188 -342.8143) (xy 23.470563 -342.866215)
			(xy 23.482973 -342.920586) (xy 23.487141 -342.9762) (xy 23.482973 -343.031814) (xy 23.470563 -343.086185)
			(xy 23.450188 -343.1381) (xy 23.422303 -343.186398) (xy 23.387531 -343.23) (xy 23.346649 -343.267933)
			(xy 23.30057 -343.299349) (xy 23.250324 -343.323547) (xy 23.197032 -343.339985) (xy 23.141885 -343.348297)
			(xy 23.114 -343.348818) (xy 23.086659 -343.348357) (xy 23.032563 -343.340376) (xy 22.980215 -343.32457)
			(xy 22.930741 -343.30128) (xy 22.885205 -343.271006) (xy 22.864572 -343.25306) (xy 22.85746 -343.246456)
			(xy 22.840188 -343.239852) (xy 22.752812 -343.239852) (xy 22.73554 -343.246456) (xy 22.728428 -343.25306)
			(xy 22.707803 -343.271012) (xy 22.662257 -343.301269) (xy 22.61278 -343.324548) (xy 22.560433 -343.340351)
			(xy 22.50634 -343.348338) (xy 22.479 -343.348818) (xy 22.451115 -343.348297) (xy 22.395968 -343.339985)
			(xy 22.342676 -343.323547) (xy 22.29243 -343.299349) (xy 22.246351 -343.267933) (xy 22.205469 -343.23)
			(xy 22.170697 -343.186398) (xy 22.142812 -343.1381) (xy 22.122437 -343.086185) (xy 22.110027 -343.031814)
			(xy 22.10586 -342.9762) (xy 15.89024 -342.9762) (xy 17.076166 -344.162126) (xy 17.098331 -344.184938)
			(xy 17.137972 -344.234681) (xy 17.171795 -344.28855) (xy 17.199375 -344.345866) (xy 17.220365 -344.40591)
			(xy 17.234502 -344.467926) (xy 17.241607 -344.531134) (xy 17.242028 -344.562938) (xy 17.242028 -346.043504)
			(xy 17.242623 -346.054513) (xy 17.251904 -346.074487) (xy 17.268654 -346.088789) (xy 17.279112 -346.092272)
			(xy 17.389602 -346.123514) (xy 17.421352 -346.111322) (xy 17.430242 -346.09659) (xy 17.472339 -346.029141)
			(xy 17.562186 -345.897944) (xy 17.658291 -345.771258) (xy 17.760427 -345.649383) (xy 17.868353 -345.532605)
			(xy 17.981816 -345.421199) (xy 18.100549 -345.315427) (xy 18.224272 -345.215537) (xy 18.352694 -345.121766)
			(xy 18.485512 -345.034333) (xy 18.622415 -344.953445) (xy 18.76308 -344.879292) (xy 18.907175 -344.812048)
			(xy 19.054362 -344.751872) (xy 19.204295 -344.698905) (xy 19.35662 -344.653272) (xy 19.510978 -344.61508)
			(xy 19.667008 -344.58442) (xy 19.824341 -344.561363) (xy 19.982607 -344.545964) (xy 20.141433 -344.538259)
			(xy 20.22094 -344.537792) (xy 20.301376 -344.538286) (xy 20.462055 -344.546179) (xy 20.622153 -344.561948)
			(xy 20.781285 -344.585553) (xy 20.939067 -344.616937) (xy 21.095118 -344.656026) (xy 21.249064 -344.702725)
			(xy 21.400533 -344.756921) (xy 21.54916 -344.818485) (xy 21.694587 -344.887267) (xy 21.836464 -344.963102)
			(xy 21.974449 -345.045807) (xy 22.10821 -345.135183) (xy 22.237424 -345.231015) (xy 22.36178 -345.333071)
			(xy 22.480979 -345.441107) (xy 22.594733 -345.554861) (xy 22.702769 -345.67406) (xy 22.804825 -345.798416)
			(xy 22.900657 -345.92763) (xy 22.990033 -346.061391) (xy 23.072738 -346.199376) (xy 23.148573 -346.341253)
			(xy 23.217355 -346.48668) (xy 23.278919 -346.635307) (xy 23.333115 -346.786776) (xy 23.379814 -346.940722)
			(xy 23.418903 -347.096773) (xy 23.450287 -347.254555) (xy 23.473892 -347.413687) (xy 23.489661 -347.573785)
			(xy 23.497554 -347.734464) (xy 23.497554 -347.895336) (xy 23.489661 -348.056015) (xy 23.473892 -348.216113)
			(xy 23.450287 -348.375245) (xy 23.45014 -348.375986) (xy 24.536146 -348.375986) (xy 24.536641 -348.348075)
			(xy 24.544777 -348.29285) (xy 24.560872 -348.2394) (xy 24.584584 -348.188865) (xy 24.615406 -348.142325)
			(xy 24.633682 -348.121224) (xy 24.640032 -348.114112) (xy 24.646636 -348.09684) (xy 24.646636 -348.009718)
			(xy 24.640032 -347.992446) (xy 24.633682 -347.985334) (xy 24.615396 -347.964241) (xy 24.58457 -347.917701)
			(xy 24.560857 -347.867164) (xy 24.544762 -347.813712) (xy 24.53663 -347.758484) (xy 24.536146 -347.730572)
			(xy 24.536632 -347.703321) (xy 24.544388 -347.649373) (xy 24.559743 -347.597078) (xy 24.582385 -347.547501)
			(xy 24.611851 -347.501651) (xy 24.647542 -347.46046) (xy 24.688733 -347.424769) (xy 24.734583 -347.395303)
			(xy 24.78416 -347.372661) (xy 24.836455 -347.357306) (xy 24.890403 -347.34955) (xy 24.944905 -347.34955)
			(xy 24.998853 -347.357306) (xy 25.051148 -347.372661) (xy 25.100725 -347.395303) (xy 25.146575 -347.424769)
			(xy 25.187766 -347.46046) (xy 25.223457 -347.501651) (xy 25.252923 -347.547501) (xy 25.275565 -347.597078)
			(xy 25.29092 -347.649373) (xy 25.298676 -347.703321) (xy 25.299162 -347.730572) (xy 25.298699 -347.758484)
			(xy 25.290555 -347.81371) (xy 25.274452 -347.867161) (xy 25.250733 -347.917695) (xy 25.219905 -347.964234)
			(xy 25.201626 -347.985334) (xy 25.195276 -347.992446) (xy 25.188672 -348.009718) (xy 25.188672 -348.09684)
			(xy 25.195276 -348.114112) (xy 25.201626 -348.121224) (xy 25.219894 -348.142332) (xy 25.250722 -348.188868)
			(xy 25.274439 -348.239401) (xy 25.290538 -348.29285) (xy 25.298675 -348.348075) (xy 25.299162 -348.375986)
			(xy 25.298676 -348.403237) (xy 25.29092 -348.457185) (xy 25.275565 -348.50948) (xy 25.252923 -348.559057)
			(xy 25.223457 -348.604907) (xy 25.187766 -348.646098) (xy 25.146575 -348.681789) (xy 25.100725 -348.711255)
			(xy 25.051148 -348.733897) (xy 24.998853 -348.749252) (xy 24.944905 -348.757008) (xy 24.890403 -348.757008)
			(xy 24.836455 -348.749252) (xy 24.78416 -348.733897) (xy 24.734583 -348.711255) (xy 24.688733 -348.681789)
			(xy 24.647542 -348.646098) (xy 24.611851 -348.604907) (xy 24.582385 -348.559057) (xy 24.559743 -348.50948)
			(xy 24.544388 -348.457185) (xy 24.536632 -348.403237) (xy 24.536146 -348.375986) (xy 23.45014 -348.375986)
			(xy 23.418903 -348.533027) (xy 23.379814 -348.689078) (xy 23.333115 -348.843024) (xy 23.278919 -348.994493)
			(xy 23.217355 -349.14312) (xy 23.148573 -349.288547) (xy 23.072738 -349.430424) (xy 22.990033 -349.568409)
			(xy 22.900657 -349.70217) (xy 22.804825 -349.831384) (xy 22.702769 -349.95574) (xy 22.594733 -350.074939)
			(xy 22.480979 -350.188693) (xy 22.36178 -350.296729) (xy 22.237424 -350.398785) (xy 22.10821 -350.494617)
			(xy 21.974449 -350.583993) (xy 21.836464 -350.666698) (xy 21.694587 -350.742533) (xy 21.54916 -350.811315)
			(xy 21.400533 -350.872879) (xy 21.249064 -350.927075) (xy 21.095118 -350.973774) (xy 20.939067 -351.012863)
			(xy 20.781285 -351.044247) (xy 20.622153 -351.067852) (xy 20.462055 -351.083621) (xy 20.301376 -351.091514)
			(xy 20.22094 -351.092008) (xy 20.141433 -351.091537) (xy 19.982605 -351.083839) (xy 19.824337 -351.068446)
			(xy 19.667002 -351.045394) (xy 19.510971 -351.014739) (xy 19.35661 -350.976551) (xy 19.204283 -350.930921)
			(xy 19.054348 -350.877957) (xy 18.907159 -350.817782) (xy 18.763062 -350.750539) (xy 18.622396 -350.676386)
			(xy 18.485492 -350.595498) (xy 18.352672 -350.508064) (xy 18.22425 -350.414291) (xy 18.100528 -350.314399)
			(xy 17.981796 -350.208624) (xy 17.868334 -350.097215) (xy 17.76041 -349.980433) (xy 17.658277 -349.858554)
			(xy 17.562176 -349.731865) (xy 17.472333 -349.600664) (xy 17.430242 -349.53321) (xy 17.421352 -349.518478)
			(xy 17.389602 -349.506286) (xy 17.279112 -349.537528) (xy 17.268647 -349.541011) (xy 17.251863 -349.555283)
			(xy 17.242618 -349.57528) (xy 17.242028 -349.586296) (xy 17.242028 -351.066608) (xy 17.242567 -351.076594)
			(xy 17.250286 -351.095022) (xy 17.257014 -351.102422) (xy 19.391122 -353.23653) (xy 19.955764 -353.801172)
			(xy 22.25167 -353.801172)
		)
		(stroke
			(width 0)
			(type solid)
		)
		(fill yes)
		(layer "In4.Cu")
		(net "P3V3_AUX")
	)
	(gr_poly
		(pts
			(xy 442.067188 -374.13946) (xy 442.076105 -374.13906) (xy 442.09286 -374.132942) (xy 442.099954 -374.127522)
			(xy 442.121274 -374.110262) (xy 442.168703 -374.082713) (xy 442.220205 -374.063843) (xy 442.274206 -374.054229)
			(xy 442.30163 -374.053608) (xy 454.91527 -374.053608) (xy 454.925232 -374.053121) (xy 454.943656 -374.045533)
			(xy 454.951084 -374.038876) (xy 455.082148 -373.907812) (xy 455.088829 -373.900401) (xy 455.096408 -373.881965)
			(xy 455.09688 -373.871998) (xy 455.09688 -338.792312) (xy 455.097337 -338.76772) (xy 455.105031 -338.719143)
			(xy 455.120232 -338.672368) (xy 455.142566 -338.628549) (xy 455.171482 -338.588763) (xy 455.188574 -338.571078)
			(xy 465.97951 -327.780142) (xy 465.98631 -327.772793) (xy 465.99402 -327.754331) (xy 465.994496 -327.744328)
			(xy 465.994496 -168.056052) (xy 465.993968 -168.04606) (xy 465.986267 -168.027615) (xy 465.97951 -168.020238)
			(xy 465.830666 -167.871394) (xy 465.827231 -167.867777) (xy 465.821726 -167.859461) (xy 465.819744 -167.854884)
			(xy 465.808568 -167.828214) (xy 465.801456 -167.821102) (xy 464.82889 -166.848536) (xy 464.82152 -166.841792)
			(xy 464.803058 -166.834197) (xy 464.793076 -166.833804) (xy 458.61478 -166.833804) (xy 458.59019 -166.833345)
			(xy 458.541615 -166.825646) (xy 458.494844 -166.81044) (xy 458.451028 -166.788103) (xy 458.411248 -166.759184)
			(xy 458.393546 -166.74211) (xy 455.40803 -163.756594) (xy 455.390952 -163.738893) (xy 455.36202 -163.699118)
			(xy 455.339674 -163.655304) (xy 455.324465 -163.60853) (xy 455.316769 -163.559952) (xy 455.316336 -163.53536)
			(xy 455.316336 -139.886944) (xy 455.312857 -139.885996) (xy 455.305718 -139.884976) (xy 455.302112 -139.884912)
			(xy 452.49211 -139.884912) (xy 452.482039 -139.884491) (xy 452.46343 -139.876781) (xy 452.456042 -139.869926)
			(xy 452.349362 -139.763246) (xy 452.341964 -139.756401) (xy 452.323365 -139.748673) (xy 452.313294 -139.74826)
			(xy 450.782182 -139.74826) (xy 450.772115 -139.748688) (xy 450.753521 -139.756414) (xy 450.746114 -139.763246)
			(xy 450.247766 -140.261594) (xy 450.240911 -140.268989) (xy 450.233164 -140.287588) (xy 450.23278 -140.297662)
			(xy 450.23278 -141.0589) (xy 450.233086 -141.067388) (xy 450.238636 -141.083431) (xy 450.249151 -141.096758)
			(xy 450.256148 -141.101572) (xy 450.338698 -141.154912) (xy 450.364606 -141.15669) (xy 450.37629 -141.151356)
			(xy 450.409474 -141.137003) (xy 450.478881 -141.116754) (xy 450.550452 -141.10652) (xy 450.586602 -141.10589)
			(xy 450.618563 -141.106392) (xy 450.681981 -141.114404) (xy 450.743895 -141.130301) (xy 450.803328 -141.153832)
			(xy 450.859344 -141.184627) (xy 450.911058 -141.2222) (xy 450.957655 -141.265958) (xy 450.9984 -141.315211)
			(xy 451.032651 -141.369182) (xy 451.059868 -141.42702) (xy 451.079621 -141.487814) (xy 451.091599 -141.550604)
			(xy 451.095613 -141.6144) (xy 451.091599 -141.678196) (xy 451.079621 -141.740986) (xy 451.059868 -141.80178)
			(xy 451.032651 -141.859618) (xy 450.9984 -141.913589) (xy 450.957655 -141.962842) (xy 450.911058 -142.0066)
			(xy 450.859344 -142.044173) (xy 450.803328 -142.074968) (xy 450.743895 -142.098499) (xy 450.681981 -142.114396)
			(xy 450.618563 -142.122408) (xy 450.586602 -142.122906) (xy 450.550449 -142.122295) (xy 450.478869 -142.11209)
			(xy 450.409461 -142.091828) (xy 450.37629 -142.07744) (xy 450.364606 -142.072106) (xy 450.338698 -142.073884)
			(xy 450.256148 -142.127224) (xy 450.249191 -142.13208) (xy 450.238705 -142.145406) (xy 450.233125 -142.161419)
			(xy 450.23278 -142.169896) (xy 450.23278 -146.712178) (xy 450.235828 -146.724116) (xy 450.238622 -146.729704)
			(xy 450.250178 -146.752435) (xy 450.266561 -146.800719) (xy 450.274895 -146.851022) (xy 450.275452 -146.876516)
			(xy 450.275452 -164.86759) (xy 450.275926 -164.877557) (xy 450.2835 -164.895997) (xy 450.290184 -164.903404)
			(xy 455.823574 -170.436794) (xy 455.830424 -170.444191) (xy 455.838165 -170.462789) (xy 455.83856 -170.472862)
			(xy 455.83856 -172.452538) (xy 455.838992 -172.462604) (xy 455.846722 -172.481193) (xy 455.853546 -172.488606)
			(xy 459.876398 -176.511458) (xy 459.88351 -176.515014) (xy 459.896718 -176.522126) (xy 459.908184 -176.527544)
			(xy 459.933512 -176.527544) (xy 459.944978 -176.522126) (xy 459.983822 -176.501895) (xy 460.064707 -176.46829)
			(xy 460.148501 -176.442789) (xy 460.234393 -176.425638) (xy 460.321554 -176.417004) (xy 460.365348 -176.416462)
			(xy 460.40645 -176.416939) (xy 460.488302 -176.424528) (xy 460.569105 -176.439636) (xy 460.648169 -176.462135)
			(xy 460.72482 -176.491833) (xy 460.798404 -176.528476) (xy 460.868294 -176.571752) (xy 460.933892 -176.621291)
			(xy 460.994641 -176.676672) (xy 461.05002 -176.737421) (xy 461.099558 -176.803021) (xy 461.142833 -176.872912)
			(xy 461.179475 -176.946496) (xy 461.209171 -177.023148) (xy 461.231668 -177.102213) (xy 461.246775 -177.183016)
			(xy 461.254362 -177.264868) (xy 461.254856 -177.30597) (xy 461.254447 -177.34426) (xy 461.247841 -177.420554)
			(xy 461.234692 -177.495996) (xy 461.215099 -177.570027) (xy 461.202532 -177.606198) (xy 461.199884 -177.614636)
			(xy 461.199874 -177.632308) (xy 461.202532 -177.640742) (xy 461.215076 -177.67692) (xy 461.234653 -177.750952)
			(xy 461.247801 -177.826392) (xy 461.254422 -177.902682) (xy 461.254856 -177.94097) (xy 461.254447 -177.97926)
			(xy 461.247841 -178.055554) (xy 461.234692 -178.130996) (xy 461.215099 -178.205027) (xy 461.202532 -178.241198)
			(xy 461.199884 -178.249636) (xy 461.199874 -178.267308) (xy 461.202532 -178.275742) (xy 461.215076 -178.31192)
			(xy 461.234653 -178.385952) (xy 461.247801 -178.461392) (xy 461.254422 -178.537682) (xy 461.254856 -178.57597)
			(xy 461.254447 -178.61426) (xy 461.247841 -178.690554) (xy 461.234692 -178.765996) (xy 461.215099 -178.840027)
			(xy 461.202532 -178.876198) (xy 461.199884 -178.884636) (xy 461.199874 -178.902308) (xy 461.202532 -178.910742)
			(xy 461.215076 -178.94692) (xy 461.234653 -179.020952) (xy 461.247801 -179.096392) (xy 461.254422 -179.172682)
			(xy 461.254856 -179.21097) (xy 461.254447 -179.24926) (xy 461.247841 -179.325554) (xy 461.234692 -179.400996)
			(xy 461.215099 -179.475027) (xy 461.202532 -179.511198) (xy 461.199884 -179.519636) (xy 461.199874 -179.537308)
			(xy 461.202532 -179.545742) (xy 461.215076 -179.58192) (xy 461.234653 -179.655952) (xy 461.247801 -179.731392)
			(xy 461.254422 -179.807682) (xy 461.254856 -179.84597) (xy 461.254361 -179.888435) (xy 461.246271 -179.972978)
			(xy 461.23017 -180.056368) (xy 461.206205 -180.137846) (xy 461.190848 -180.17744) (xy 461.18907 -180.181758)
			(xy 461.187292 -180.190902) (xy 461.187292 -180.210968) (xy 461.189578 -180.221382) (xy 461.19161 -180.226208)
			(xy 461.20907 -180.267881) (xy 461.236422 -180.354) (xy 461.254905 -180.442447) (xy 461.264327 -180.532313)
			(xy 461.265016 -180.57749) (xy 461.265016 -180.58511) (xy 461.26438 -180.62276) (xy 461.257542 -180.697756)
			(xy 461.244397 -180.771907) (xy 461.225038 -180.844684) (xy 461.212692 -180.880258) (xy 461.210056 -180.888696)
			(xy 461.210066 -180.90636) (xy 461.212692 -180.914802) (xy 461.225237 -180.950979) (xy 461.244816 -181.025012)
			(xy 461.257966 -181.100451) (xy 461.26459 -181.176742) (xy 461.265016 -181.21503) (xy 461.264608 -181.25332)
			(xy 461.258005 -181.329615) (xy 461.24486 -181.405058) (xy 461.225269 -181.47909) (xy 461.212692 -181.515258)
			(xy 461.210056 -181.523696) (xy 461.210066 -181.54136) (xy 461.212692 -181.549802) (xy 461.225237 -181.585979)
			(xy 461.244816 -181.660012) (xy 461.257966 -181.735451) (xy 461.26459 -181.811742) (xy 461.265016 -181.85003)
			(xy 461.264579 -181.889387) (xy 461.257622 -181.967793) (xy 461.243763 -182.045278) (xy 461.223111 -182.121235)
			(xy 461.195829 -182.19507) (xy 461.16213 -182.266206) (xy 461.142588 -182.300372) (xy 461.139286 -182.306214)
			(xy 461.133952 -182.325264) (xy 461.132174 -182.338726) (xy 461.132174 -323.904864) (xy 461.131739 -323.914928)
			(xy 461.124005 -323.933514) (xy 461.117188 -323.940932) (xy 461.010254 -324.047866) (xy 461.003448 -324.055212)
			(xy 460.995731 -324.073675) (xy 460.995268 -324.08368) (xy 460.995268 -325.185024) (xy 460.994723 -325.218302)
			(xy 460.986036 -325.284288) (xy 460.968814 -325.348577) (xy 460.943351 -325.41007) (xy 460.910082 -325.467714)
			(xy 460.869577 -325.520525) (xy 460.846424 -325.544434) (xy 460.487014 -325.903844) (xy 460.463115 -325.92701)
			(xy 460.41031 -325.967533) (xy 460.352667 -326.000813) (xy 460.291172 -326.026282) (xy 460.226877 -326.043504)
			(xy 460.160885 -326.052182) (xy 460.127604 -326.052688) (xy 460.114396 -326.052688) (xy 460.083535 -326.051431)
			(xy 460.022438 -326.042357) (xy 459.96289 -326.025947) (xy 459.90577 -326.002443) (xy 459.851918 -325.972192)
			(xy 459.802128 -325.935638) (xy 459.757134 -325.893321) (xy 459.717599 -325.845864) (xy 459.684106 -325.793966)
			(xy 459.657147 -325.738393) (xy 459.63712 -325.679962) (xy 459.630272 -325.649844) (xy 459.627224 -325.636128)
			(xy 459.608428 -325.615554) (xy 459.509368 -325.586344) (xy 459.500534 -325.58411) (xy 459.482368 -325.585356)
			(xy 459.465787 -325.592881) (xy 459.459076 -325.599044) (xy 449.123308 -335.934812) (xy 449.116463 -335.942211)
			(xy 449.108731 -335.960809) (xy 449.108322 -335.97088) (xy 449.108322 -369.110514) (xy 452.20509 -369.110514)
			(xy 452.205576 -369.078419) (xy 452.213663 -369.01474) (xy 452.229699 -368.952585) (xy 452.253428 -368.892942)
			(xy 452.284472 -368.836758) (xy 452.32234 -368.784927) (xy 452.344028 -368.761264) (xy 452.350227 -368.754133)
			(xy 452.357379 -368.736658) (xy 452.357998 -368.727228) (xy 452.358252 -368.69624) (xy 452.358002 -368.686792)
			(xy 452.351466 -368.669071) (xy 452.345552 -368.661696) (xy 452.325448 -368.638391) (xy 452.290433 -368.587772)
			(xy 452.261785 -368.533295) (xy 452.239922 -368.475759) (xy 452.225166 -368.416004) (xy 452.217732 -368.354905)
			(xy 452.217282 -368.32413) (xy 452.217718 -368.293558) (xy 452.22506 -368.232857) (xy 452.239631 -368.173476)
			(xy 452.26122 -368.11627) (xy 452.289515 -368.062068) (xy 452.306436 -368.036602) (xy 452.311898 -368.027789)
			(xy 452.315963 -368.007476) (xy 452.311722 -367.9872) (xy 452.306182 -367.978436) (xy 452.288571 -367.952649)
			(xy 452.259102 -367.897591) (xy 452.236595 -367.83934) (xy 452.221388 -367.778772) (xy 452.21371 -367.716798)
			(xy 452.213218 -367.685574) (xy 452.213632 -367.654841) (xy 452.221044 -367.593825) (xy 452.235756 -367.534147)
			(xy 452.257555 -367.476677) (xy 452.286122 -367.422254) (xy 452.321041 -367.371671) (xy 452.361802 -367.325665)
			(xy 452.407812 -367.284909) (xy 452.458398 -367.249995) (xy 452.512824 -367.221434) (xy 452.570296 -367.199641)
			(xy 452.629976 -367.184934) (xy 452.690993 -367.177529) (xy 452.721726 -367.177066) (xy 452.751317 -367.177506)
			(xy 452.810098 -367.184372) (xy 452.867687 -367.198009) (xy 452.923306 -367.218232) (xy 452.976204 -367.244769)
			(xy 453.025668 -367.277262) (xy 453.048624 -367.295938) (xy 453.055695 -367.301392) (xy 453.072467 -367.307489)
			(xy 453.08139 -367.307876) (xy 453.111616 -367.307622) (xy 453.120565 -367.307208) (xy 453.137349 -367.300978)
			(xy 453.144382 -367.29543) (xy 453.167493 -367.276235) (xy 453.217396 -367.242782) (xy 453.270892 -367.215441)
			(xy 453.327237 -367.194594) (xy 453.385646 -367.18053) (xy 453.445305 -367.173445) (xy 453.475344 -367.173002)
			(xy 453.506076 -367.173414) (xy 453.567092 -367.180828) (xy 453.62677 -367.195542) (xy 453.684239 -367.217342)
			(xy 453.738661 -367.245909) (xy 453.789244 -367.280829) (xy 453.835248 -367.32159) (xy 453.876005 -367.367599)
			(xy 453.910918 -367.418185) (xy 453.93948 -367.47261) (xy 453.961274 -367.530082) (xy 453.975982 -367.589761)
			(xy 453.983389 -367.650778) (xy 453.983852 -367.68151) (xy 453.983373 -367.712206) (xy 453.975973 -367.773151)
			(xy 453.961283 -367.83276) (xy 453.939516 -367.890164) (xy 453.91099 -367.944527) (xy 453.893936 -367.970054)
			(xy 453.888452 -367.9788) (xy 453.884324 -367.999008) (xy 453.888459 -368.019215) (xy 453.893936 -368.027966)
			(xy 453.91099 -368.053492) (xy 453.939498 -368.107863) (xy 453.961258 -368.165268) (xy 453.975954 -368.224874)
			(xy 453.983374 -368.285815) (xy 453.983852 -368.31651) (xy 453.983371 -368.347941) (xy 453.975582 -368.410319)
			(xy 453.960173 -368.471264) (xy 453.937379 -368.529848) (xy 453.907546 -368.585181) (xy 453.871128 -368.63642)
			(xy 453.850248 -368.659918) (xy 453.843644 -368.667284) (xy 453.836786 -368.685318) (xy 453.838818 -368.775488)
			(xy 453.846438 -368.793268) (xy 453.853296 -368.80038) (xy 453.87645 -368.824288) (xy 453.916956 -368.877098)
			(xy 453.950226 -368.934743) (xy 453.975689 -368.996236) (xy 453.99291 -369.060525) (xy 454.001596 -369.126512)
			(xy 454.00214 -369.15979) (xy 454.001683 -369.19141) (xy 453.993858 -369.254164) (xy 453.978316 -369.315464)
			(xy 453.955297 -369.374366) (xy 453.925154 -369.42996) (xy 453.907144 -369.455954) (xy 453.902262 -369.463413)
			(xy 453.897466 -369.480571) (xy 453.897746 -369.489482) (xy 453.900032 -369.519454) (xy 453.9011 -369.528235)
			(xy 453.908371 -369.544346) (xy 453.914256 -369.55095) (xy 453.93687 -369.574796) (xy 453.97644 -369.627266)
			(xy 454.008918 -369.684398) (xy 454.033762 -369.745239) (xy 454.050559 -369.808775) (xy 454.059028 -369.873945)
			(xy 454.059544 -369.906804) (xy 454.059048 -369.937534) (xy 454.05164 -369.998545) (xy 454.036932 -370.058219)
			(xy 454.015138 -370.115684) (xy 453.986578 -370.170104) (xy 453.951666 -370.220685) (xy 453.910912 -370.266689)
			(xy 453.86491 -370.307446) (xy 453.814332 -370.342361) (xy 453.759914 -370.370925) (xy 453.702449 -370.392722)
			(xy 453.642776 -370.407434) (xy 453.581766 -370.414846) (xy 453.551036 -370.415312) (xy 453.518147 -370.414782)
			(xy 453.45292 -370.406294) (xy 453.389332 -370.389468) (xy 453.328443 -370.364584) (xy 453.27127 -370.332057)
			(xy 453.218768 -370.292432) (xy 453.194928 -370.26977) (xy 453.187884 -370.263379) (xy 453.170382 -370.255957)
			(xy 453.160892 -370.255292) (xy 453.130158 -370.254276) (xy 453.120661 -370.254415) (xy 453.102787 -370.260802)
			(xy 453.09536 -370.266722) (xy 453.072213 -370.286181) (xy 453.022108 -370.320039) (xy 452.968342 -370.347717)
			(xy 452.911673 -370.368826) (xy 452.852902 -370.383067) (xy 452.792856 -370.390239) (xy 452.76262 -370.390674)
			(xy 452.731887 -370.390243) (xy 452.670869 -370.382836) (xy 452.611189 -370.368128) (xy 452.553717 -370.346333)
			(xy 452.499291 -370.317769) (xy 452.448706 -370.282852) (xy 452.402698 -370.242092) (xy 452.36194 -370.196083)
			(xy 452.327024 -370.145497) (xy 452.298461 -370.09107) (xy 452.276668 -370.033598) (xy 452.261961 -369.973917)
			(xy 452.254556 -369.912899) (xy 452.254112 -369.882166) (xy 452.254665 -369.848445) (xy 452.263583 -369.781596)
			(xy 452.281258 -369.716512) (xy 452.30738 -369.654335) (xy 452.34149 -369.596156) (xy 452.361808 -369.569238)
			(xy 452.367084 -369.561711) (xy 452.372424 -369.544137) (xy 452.372222 -369.534948) (xy 452.370444 -369.504468)
			(xy 452.369436 -369.49522) (xy 452.361758 -369.478292) (xy 452.355458 -369.471448) (xy 452.332058 -369.447527)
			(xy 452.291148 -369.39457) (xy 452.257537 -369.336704) (xy 452.231807 -369.274929) (xy 452.214402 -369.210314)
			(xy 452.205623 -369.143973) (xy 452.20509 -369.110514) (xy 449.108322 -369.110514) (xy 449.108322 -371.105176)
			(xy 449.107886 -371.115241) (xy 449.100154 -371.133827) (xy 449.093336 -371.141244) (xy 448.959986 -371.274594)
			(xy 448.952587 -371.281439) (xy 448.933989 -371.289169) (xy 448.923918 -371.28958) (xy 448.410838 -371.28958)
			(xy 448.403965 -371.289775) (xy 448.390705 -371.293385) (xy 448.384676 -371.296692) (xy 448.354992 -371.313803)
			(xy 448.292006 -371.340769) (xy 448.225968 -371.359028) (xy 448.158076 -371.368249) (xy 448.123818 -371.368828)
			(xy 448.089561 -371.36825) (xy 448.02167 -371.359019) (xy 447.955633 -371.34076) (xy 447.892642 -371.313805)
			(xy 447.86296 -371.296692) (xy 447.856934 -371.293381) (xy 447.843671 -371.289775) (xy 447.836798 -371.28958)
			(xy 443.62497 -371.28958) (xy 443.614984 -371.290122) (xy 443.596558 -371.297841) (xy 443.589156 -371.304566)
			(xy 443.567058 -371.326664) (xy 443.549345 -371.343714) (xy 443.509555 -371.372589) (xy 443.465737 -371.394881)
			(xy 443.418969 -371.410039) (xy 443.370406 -371.417691) (xy 443.345824 -371.418104) (xy 438.080404 -371.418104)
			(xy 438.070416 -371.418641) (xy 438.051984 -371.426354) (xy 438.04459 -371.43309) (xy 438.043066 -371.434614)
			(xy 438.036215 -371.44201) (xy 438.028475 -371.460609) (xy 438.02808 -371.470682) (xy 438.02808 -372.795038)
			(xy 438.029096 -372.799864) (xy 438.034085 -372.826893) (xy 438.039428 -372.8816) (xy 438.039764 -372.909084)
			(xy 438.039426 -372.936567) (xy 438.034081 -372.991274) (xy 438.029096 -373.018304) (xy 438.02808 -373.02313)
			(xy 438.02808 -373.42572) (xy 438.028506 -373.435789) (xy 438.036223 -373.45439) (xy 438.043066 -373.461788)
			(xy 438.65419 -374.072912) (xy 438.665378 -374.084252) (xy 438.686601 -374.108015) (xy 438.696608 -374.12041)
			(xy 438.704237 -374.128927) (xy 438.724816 -374.138824) (xy 438.736232 -374.13946)
		)
		(stroke
			(width 0)
			(type solid)
		)
		(fill yes)
		(layer "In4.Cu")
		(net "P5V_AUX")
	)
	(gr_poly
		(pts
			(xy 169.124122 -58.426096) (xy 169.13419 -58.425669) (xy 169.152789 -58.417948) (xy 169.16019 -58.41111)
			(xy 170.071034 -57.500266) (xy 170.077882 -57.492869) (xy 170.085615 -57.47427) (xy 170.08602 -57.464198)
			(xy 170.08602 -38.017196) (xy 170.085597 -38.007126) (xy 170.077884 -37.98852) (xy 170.071034 -37.981128)
			(xy 169.070528 -36.980622) (xy 169.063127 -36.973785) (xy 169.044528 -36.966073) (xy 169.03446 -36.965636)
			(xy 162.535362 -36.965636) (xy 162.525296 -36.966067) (xy 162.506704 -36.973795) (xy 162.499294 -36.980622)
			(xy 161.946844 -37.533072) (xy 161.940004 -37.540472) (xy 161.932289 -37.559071) (xy 161.931858 -37.56914)
			(xy 161.931858 -40.2082) (xy 162.333686 -40.2082) (xy 162.334188 -40.176239) (xy 162.342199 -40.112821)
			(xy 162.358096 -40.050907) (xy 162.381628 -39.991474) (xy 162.412422 -39.935459) (xy 162.449995 -39.883744)
			(xy 162.493752 -39.837147) (xy 162.543005 -39.796402) (xy 162.596976 -39.762151) (xy 162.654815 -39.734934)
			(xy 162.715608 -39.715181) (xy 162.778398 -39.703203) (xy 162.842194 -39.69919) (xy 162.90599 -39.703203)
			(xy 162.96878 -39.715181) (xy 163.029573 -39.734934) (xy 163.087412 -39.762151) (xy 163.141383 -39.796402)
			(xy 163.190636 -39.837147) (xy 163.234393 -39.883744) (xy 163.271966 -39.935459) (xy 163.30276 -39.991474)
			(xy 163.326292 -40.050907) (xy 163.342189 -40.112821) (xy 163.3502 -40.176239) (xy 163.350702 -40.2082)
			(xy 163.350232 -40.238395) (xy 163.343073 -40.298359) (xy 163.328867 -40.357053) (xy 163.307813 -40.413654)
			(xy 163.280209 -40.467366) (xy 163.246441 -40.517432) (xy 163.206985 -40.56315) (xy 163.162396 -40.603877)
			(xy 163.113299 -40.63904) (xy 163.08705 -40.65397) (xy 163.075874 -40.660066) (xy 163.062412 -40.680132)
			(xy 163.05022 -40.787828) (xy 163.05911 -40.810688) (xy 163.068508 -40.81907) (xy 163.076422 -40.826193)
			(xy 163.091545 -40.841187) (xy 163.098734 -40.849042) (xy 163.1061 -40.856916) (xy 163.12515 -40.865552)
			(xy 163.221416 -40.866822) (xy 163.24072 -40.858694) (xy 163.248086 -40.85082) (xy 163.266157 -40.832314)
			(xy 163.306445 -40.799875) (xy 163.350748 -40.773179) (xy 163.398253 -40.752717) (xy 163.448088 -40.738863)
			(xy 163.499338 -40.731871) (xy 163.5252 -40.73144) (xy 163.552455 -40.73183) (xy 163.606409 -40.739587)
			(xy 163.658711 -40.754944) (xy 163.708294 -40.777588) (xy 163.75415 -40.807058) (xy 163.795346 -40.842754)
			(xy 163.831042 -40.88395) (xy 163.860512 -40.929806) (xy 163.883156 -40.979389) (xy 163.898513 -41.031691)
			(xy 163.90627 -41.085645) (xy 163.90627 -41.140155) (xy 163.898513 -41.194109) (xy 163.883156 -41.246411)
			(xy 163.860512 -41.295994) (xy 163.831042 -41.34185) (xy 163.795346 -41.383046) (xy 163.75415 -41.418742)
			(xy 163.708294 -41.448212) (xy 163.658711 -41.470856) (xy 163.606409 -41.486213) (xy 163.552455 -41.49397)
			(xy 163.5252 -41.494456) (xy 163.498588 -41.493979) (xy 163.445881 -41.486587) (xy 163.394715 -41.471935)
			(xy 163.346085 -41.450306) (xy 163.300938 -41.422121) (xy 163.260151 -41.387929) (xy 163.24199 -41.368472)
			(xy 163.234624 -41.360598) (xy 163.215574 -41.351962) (xy 163.119308 -41.350692) (xy 163.100004 -41.35882)
			(xy 163.092638 -41.366694) (xy 163.074558 -41.385191) (xy 163.034271 -41.41763) (xy 162.98997 -41.444327)
			(xy 162.942467 -41.464791) (xy 162.892634 -41.478647) (xy 162.841386 -41.485641) (xy 162.815524 -41.486074)
			(xy 162.78827 -41.485622) (xy 162.734317 -41.477868) (xy 162.682017 -41.462513) (xy 162.632435 -41.439871)
			(xy 162.58658 -41.410402) (xy 162.545386 -41.374707) (xy 162.509692 -41.333512) (xy 162.480224 -41.287657)
			(xy 162.457584 -41.238074) (xy 162.44223 -41.185773) (xy 162.434477 -41.13182) (xy 162.434016 -41.104566)
			(xy 162.434561 -41.075775) (xy 162.443237 -41.018851) (xy 162.460373 -40.963878) (xy 162.485578 -40.912106)
			(xy 162.51828 -40.864711) (xy 162.557735 -40.822772) (xy 162.580066 -40.804592) (xy 162.589972 -40.796718)
			(xy 162.599878 -40.77462) (xy 162.59429 -40.666416) (xy 162.582098 -40.645334) (xy 162.57143 -40.638476)
			(xy 162.544536 -40.62098) (xy 162.494945 -40.580269) (xy 162.450873 -40.53364) (xy 162.413021 -40.481834)
			(xy 162.38199 -40.425676) (xy 162.358274 -40.366059) (xy 162.342251 -40.303931) (xy 162.334175 -40.24028)
			(xy 162.333686 -40.2082) (xy 161.931858 -40.2082) (xy 161.931858 -42.209423) (xy 163.017194 -42.209423)
			(xy 163.017194 -42.145501) (xy 163.025205 -42.082083) (xy 163.041102 -42.020169) (xy 163.064634 -41.960736)
			(xy 163.095428 -41.904721) (xy 163.133001 -41.853006) (xy 163.176758 -41.806409) (xy 163.226011 -41.765664)
			(xy 163.279982 -41.731413) (xy 163.337821 -41.704196) (xy 163.398614 -41.684443) (xy 163.461404 -41.672465)
			(xy 163.5252 -41.668452) (xy 163.588996 -41.672465) (xy 163.651786 -41.684443) (xy 163.712579 -41.704196)
			(xy 163.770418 -41.731413) (xy 163.824389 -41.765664) (xy 163.873642 -41.806409) (xy 163.917399 -41.853006)
			(xy 163.954972 -41.904721) (xy 163.985766 -41.960736) (xy 164.009298 -42.020169) (xy 164.025195 -42.082083)
			(xy 164.033206 -42.145501) (xy 164.033708 -42.177462) (xy 164.033206 -42.209423) (xy 164.025195 -42.272841)
			(xy 164.009298 -42.334755) (xy 163.985766 -42.394188) (xy 163.954972 -42.450203) (xy 163.917399 -42.501918)
			(xy 163.873642 -42.548515) (xy 163.824389 -42.58926) (xy 163.770418 -42.623511) (xy 163.712579 -42.650728)
			(xy 163.651786 -42.670481) (xy 163.588996 -42.682459) (xy 163.5252 -42.686473) (xy 163.461404 -42.682459)
			(xy 163.398614 -42.670481) (xy 163.337821 -42.650728) (xy 163.279982 -42.623511) (xy 163.226011 -42.58926)
			(xy 163.176758 -42.548515) (xy 163.133001 -42.501918) (xy 163.095428 -42.450203) (xy 163.064634 -42.394188)
			(xy 163.041102 -42.334755) (xy 163.025205 -42.272841) (xy 163.017194 -42.209423) (xy 161.931858 -42.209423)
			(xy 161.931858 -43.024552) (xy 162.412424 -43.024552) (xy 162.416495 -42.96893) (xy 162.428621 -42.914493)
			(xy 162.448544 -42.862402) (xy 162.47584 -42.813767) (xy 162.509926 -42.769624) (xy 162.550075 -42.730915)
			(xy 162.595433 -42.698464) (xy 162.645033 -42.672963) (xy 162.697817 -42.654956) (xy 162.75266 -42.644826)
			(xy 162.808394 -42.642789) (xy 162.863831 -42.648889) (xy 162.917788 -42.662995) (xy 162.969117 -42.684807)
			(xy 163.016723 -42.713861) (xy 163.059591 -42.749536) (xy 163.096808 -42.791073) (xy 163.127581 -42.837586)
			(xy 163.151253 -42.888083) (xy 163.167321 -42.94149) (xy 163.175441 -42.996666) (xy 163.17595 -43.024552)
			(xy 163.175441 -43.052438) (xy 163.167321 -43.107614) (xy 163.151253 -43.161021) (xy 163.127581 -43.211518)
			(xy 163.096808 -43.258031) (xy 163.059591 -43.299568) (xy 163.016723 -43.335243) (xy 162.969117 -43.364297)
			(xy 162.917788 -43.386109) (xy 162.863831 -43.400215) (xy 162.808394 -43.406315) (xy 162.75266 -43.404278)
			(xy 162.697817 -43.394148) (xy 162.645033 -43.376141) (xy 162.595433 -43.35064) (xy 162.550075 -43.318189)
			(xy 162.509926 -43.27948) (xy 162.47584 -43.235337) (xy 162.448544 -43.186702) (xy 162.428621 -43.134611)
			(xy 162.416495 -43.080174) (xy 162.412424 -43.024552) (xy 161.931858 -43.024552) (xy 161.931858 -44.306998)
			(xy 165.816786 -44.306998) (xy 165.820857 -44.251376) (xy 165.832983 -44.196939) (xy 165.852906 -44.144848)
			(xy 165.880202 -44.096213) (xy 165.914288 -44.05207) (xy 165.954437 -44.013361) (xy 165.999795 -43.98091)
			(xy 166.049395 -43.955409) (xy 166.102179 -43.937402) (xy 166.157022 -43.927272) (xy 166.212756 -43.925235)
			(xy 166.268193 -43.931335) (xy 166.32215 -43.945441) (xy 166.373479 -43.967253) (xy 166.421085 -43.996307)
			(xy 166.463953 -44.031982) (xy 166.50117 -44.073519) (xy 166.531943 -44.120032) (xy 166.555615 -44.170529)
			(xy 166.571683 -44.223936) (xy 166.579803 -44.279112) (xy 166.580312 -44.306998) (xy 166.579803 -44.334884)
			(xy 166.571683 -44.39006) (xy 166.555615 -44.443467) (xy 166.531943 -44.493964) (xy 166.50117 -44.540477)
			(xy 166.463953 -44.582014) (xy 166.421085 -44.617689) (xy 166.373479 -44.646743) (xy 166.32215 -44.668555)
			(xy 166.268193 -44.682661) (xy 166.212756 -44.688761) (xy 166.157022 -44.686724) (xy 166.102179 -44.676594)
			(xy 166.049395 -44.658587) (xy 165.999795 -44.633086) (xy 165.954437 -44.600635) (xy 165.914288 -44.561926)
			(xy 165.880202 -44.517783) (xy 165.852906 -44.469148) (xy 165.832983 -44.417057) (xy 165.820857 -44.36262)
			(xy 165.816786 -44.306998) (xy 161.931858 -44.306998) (xy 161.931858 -44.958762) (xy 164.575996 -44.958762)
			(xy 164.580067 -44.90314) (xy 164.592193 -44.848703) (xy 164.612116 -44.796612) (xy 164.639412 -44.747977)
			(xy 164.673498 -44.703834) (xy 164.713647 -44.665125) (xy 164.759005 -44.632674) (xy 164.808605 -44.607173)
			(xy 164.861389 -44.589166) (xy 164.916232 -44.579036) (xy 164.971966 -44.576999) (xy 165.027403 -44.583099)
			(xy 165.08136 -44.597205) (xy 165.132689 -44.619017) (xy 165.180295 -44.648071) (xy 165.223163 -44.683746)
			(xy 165.26038 -44.725283) (xy 165.291153 -44.771796) (xy 165.314825 -44.822293) (xy 165.330893 -44.8757)
			(xy 165.339013 -44.930876) (xy 165.339522 -44.958762) (xy 165.339013 -44.986648) (xy 165.330893 -45.041824)
			(xy 165.314825 -45.095231) (xy 165.291153 -45.145728) (xy 165.26038 -45.192241) (xy 165.223163 -45.233778)
			(xy 165.180295 -45.269453) (xy 165.132689 -45.298507) (xy 165.08136 -45.320319) (xy 165.027403 -45.334425)
			(xy 164.971966 -45.340525) (xy 164.916232 -45.338488) (xy 164.861389 -45.328358) (xy 164.808605 -45.310351)
			(xy 164.759005 -45.28485) (xy 164.713647 -45.252399) (xy 164.673498 -45.21369) (xy 164.639412 -45.169547)
			(xy 164.612116 -45.120912) (xy 164.592193 -45.068821) (xy 164.580067 -45.014384) (xy 164.575996 -44.958762)
			(xy 161.931858 -44.958762) (xy 161.931858 -45.710348) (xy 165.657782 -45.710348) (xy 165.661853 -45.654726)
			(xy 165.673979 -45.600289) (xy 165.693902 -45.548198) (xy 165.721198 -45.499563) (xy 165.755284 -45.45542)
			(xy 165.795433 -45.416711) (xy 165.840791 -45.38426) (xy 165.890391 -45.358759) (xy 165.943175 -45.340752)
			(xy 165.998018 -45.330622) (xy 166.053752 -45.328585) (xy 166.109189 -45.334685) (xy 166.163146 -45.348791)
			(xy 166.214475 -45.370603) (xy 166.262081 -45.399657) (xy 166.304949 -45.435332) (xy 166.342166 -45.476869)
			(xy 166.372939 -45.523382) (xy 166.396611 -45.573879) (xy 166.412679 -45.627286) (xy 166.420799 -45.682462)
			(xy 166.421308 -45.710348) (xy 166.420799 -45.738234) (xy 166.412679 -45.79341) (xy 166.396611 -45.846817)
			(xy 166.372939 -45.897314) (xy 166.342166 -45.943827) (xy 166.304949 -45.985364) (xy 166.262081 -46.021039)
			(xy 166.214475 -46.050093) (xy 166.163146 -46.071905) (xy 166.109189 -46.086011) (xy 166.053752 -46.092111)
			(xy 165.998018 -46.090074) (xy 165.943175 -46.079944) (xy 165.890391 -46.061937) (xy 165.840791 -46.036436)
			(xy 165.795433 -46.003985) (xy 165.755284 -45.965276) (xy 165.721198 -45.921133) (xy 165.693902 -45.872498)
			(xy 165.673979 -45.820407) (xy 165.661853 -45.76597) (xy 165.657782 -45.710348) (xy 161.931858 -45.710348)
			(xy 161.931858 -46.213268) (xy 164.685216 -46.213268) (xy 164.689287 -46.157646) (xy 164.701413 -46.103209)
			(xy 164.721336 -46.051118) (xy 164.748632 -46.002483) (xy 164.782718 -45.95834) (xy 164.822867 -45.919631)
			(xy 164.868225 -45.88718) (xy 164.917825 -45.861679) (xy 164.970609 -45.843672) (xy 165.025452 -45.833542)
			(xy 165.081186 -45.831505) (xy 165.136623 -45.837605) (xy 165.19058 -45.851711) (xy 165.241909 -45.873523)
			(xy 165.289515 -45.902577) (xy 165.332383 -45.938252) (xy 165.3696 -45.979789) (xy 165.400373 -46.026302)
			(xy 165.424045 -46.076799) (xy 165.440113 -46.130206) (xy 165.448233 -46.185382) (xy 165.448742 -46.213268)
			(xy 165.448233 -46.241154) (xy 165.440113 -46.29633) (xy 165.424045 -46.349737) (xy 165.400373 -46.400234)
			(xy 165.3696 -46.446747) (xy 165.332383 -46.488284) (xy 165.289515 -46.523959) (xy 165.241909 -46.553013)
			(xy 165.19058 -46.574825) (xy 165.136623 -46.588931) (xy 165.081186 -46.595031) (xy 165.025452 -46.592994)
			(xy 164.970609 -46.582864) (xy 164.917825 -46.564857) (xy 164.868225 -46.539356) (xy 164.822867 -46.506905)
			(xy 164.782718 -46.468196) (xy 164.748632 -46.424053) (xy 164.721336 -46.375418) (xy 164.701413 -46.323327)
			(xy 164.689287 -46.26889) (xy 164.685216 -46.213268) (xy 161.931858 -46.213268) (xy 161.931858 -47.639478)
			(xy 162.502596 -47.639478) (xy 162.503117 -47.611721) (xy 162.51114 -47.55679) (xy 162.527042 -47.503603)
			(xy 162.550488 -47.453284) (xy 162.580981 -47.406895) (xy 162.617878 -47.365418) (xy 162.660398 -47.329728)
			(xy 162.707644 -47.300581) (xy 162.758616 -47.278591) (xy 162.785298 -47.270924) (xy 162.796474 -47.26813)
			(xy 162.813746 -47.253144) (xy 162.855402 -47.16018) (xy 162.854894 -47.13732) (xy 162.84956 -47.126906)
			(xy 162.836697 -47.100082) (xy 162.818476 -47.043456) (xy 162.809243 -46.984691) (xy 162.808666 -46.954948)
			(xy 162.809152 -46.927697) (xy 162.816908 -46.873749) (xy 162.832263 -46.821454) (xy 162.854905 -46.771877)
			(xy 162.884371 -46.726027) (xy 162.920062 -46.684836) (xy 162.961253 -46.649145) (xy 163.007103 -46.619679)
			(xy 163.05668 -46.597037) (xy 163.108975 -46.581682) (xy 163.162923 -46.573926) (xy 163.217425 -46.573926)
			(xy 163.271373 -46.581682) (xy 163.323668 -46.597037) (xy 163.373245 -46.619679) (xy 163.419095 -46.649145)
			(xy 163.460286 -46.684836) (xy 163.495977 -46.726027) (xy 163.525443 -46.771877) (xy 163.548085 -46.821454)
			(xy 163.56344 -46.873749) (xy 163.571196 -46.927697) (xy 163.571682 -46.954948) (xy 163.5712 -46.982706)
			(xy 163.563173 -47.037639) (xy 163.547266 -47.090828) (xy 163.523816 -47.141149) (xy 163.493318 -47.187538)
			(xy 163.456416 -47.229015) (xy 163.413891 -47.264703) (xy 163.36664 -47.293849) (xy 163.315664 -47.315837)
			(xy 163.28898 -47.323502) (xy 163.277804 -47.326296) (xy 163.260532 -47.341282) (xy 163.218876 -47.434246)
			(xy 163.219384 -47.457106) (xy 163.224718 -47.46752) (xy 163.237588 -47.494341) (xy 163.255807 -47.550969)
			(xy 163.265037 -47.609735) (xy 163.265612 -47.639478) (xy 163.265126 -47.666729) (xy 163.25737 -47.720677)
			(xy 163.242015 -47.772972) (xy 163.219373 -47.822549) (xy 163.189907 -47.868399) (xy 163.154216 -47.90959)
			(xy 163.113025 -47.945281) (xy 163.067175 -47.974747) (xy 163.017598 -47.997389) (xy 162.965303 -48.012744)
			(xy 162.911355 -48.0205) (xy 162.856853 -48.0205) (xy 162.802905 -48.012744) (xy 162.75061 -47.997389)
			(xy 162.701033 -47.974747) (xy 162.655183 -47.945281) (xy 162.613992 -47.90959) (xy 162.578301 -47.868399)
			(xy 162.548835 -47.822549) (xy 162.526193 -47.772972) (xy 162.510838 -47.720677) (xy 162.503082 -47.666729)
			(xy 162.502596 -47.639478) (xy 161.931858 -47.639478) (xy 161.931858 -51.285902) (xy 162.94354 -51.285902)
			(xy 162.944081 -51.257164) (xy 162.952702 -51.200338) (xy 162.969749 -51.145448) (xy 162.994836 -51.093736)
			(xy 163.027396 -51.046372) (xy 163.046664 -51.025044) (xy 163.053268 -51.017932) (xy 163.06038 -51.000406)
			(xy 163.06038 -50.910998) (xy 163.053268 -50.893472) (xy 163.046664 -50.88636) (xy 163.027399 -50.865028)
			(xy 162.994831 -50.817668) (xy 162.969737 -50.765958) (xy 162.952685 -50.711068) (xy 162.944061 -50.654241)
			(xy 162.94354 -50.625502) (xy 162.944026 -50.598251) (xy 162.951782 -50.544303) (xy 162.967137 -50.492008)
			(xy 162.989779 -50.442431) (xy 163.019245 -50.396581) (xy 163.054936 -50.35539) (xy 163.096127 -50.319699)
			(xy 163.141977 -50.290233) (xy 163.191554 -50.267591) (xy 163.243849 -50.252236) (xy 163.297797 -50.24448)
			(xy 163.352299 -50.24448) (xy 163.406247 -50.252236) (xy 163.458542 -50.267591) (xy 163.508119 -50.290233)
			(xy 163.553969 -50.319699) (xy 163.59516 -50.35539) (xy 163.630851 -50.396581) (xy 163.660317 -50.442431)
			(xy 163.682959 -50.492008) (xy 163.698314 -50.544303) (xy 163.70607 -50.598251) (xy 163.706556 -50.625502)
			(xy 163.706019 -50.65424) (xy 163.697397 -50.711066) (xy 163.680349 -50.765956) (xy 163.655261 -50.817668)
			(xy 163.6227 -50.865032) (xy 163.603432 -50.88636) (xy 163.596828 -50.893472) (xy 163.589716 -50.910998)
			(xy 163.589716 -51.000406) (xy 163.596828 -51.017932) (xy 163.603432 -51.025044) (xy 163.622699 -51.046375)
			(xy 163.655267 -51.093735) (xy 163.68036 -51.145446) (xy 163.697412 -51.200336) (xy 163.706035 -51.257163)
			(xy 163.706556 -51.285902) (xy 163.70607 -51.313153) (xy 163.698314 -51.367101) (xy 163.682959 -51.419396)
			(xy 163.660317 -51.468973) (xy 163.630851 -51.514823) (xy 163.59516 -51.556014) (xy 163.553969 -51.591705)
			(xy 163.508119 -51.621171) (xy 163.458542 -51.643813) (xy 163.406247 -51.659168) (xy 163.352299 -51.666924)
			(xy 163.297797 -51.666924) (xy 163.243849 -51.659168) (xy 163.191554 -51.643813) (xy 163.141977 -51.621171)
			(xy 163.096127 -51.591705) (xy 163.054936 -51.556014) (xy 163.019245 -51.514823) (xy 162.989779 -51.468973)
			(xy 162.967137 -51.419396) (xy 162.951782 -51.367101) (xy 162.944026 -51.313153) (xy 162.94354 -51.285902)
			(xy 161.931858 -51.285902) (xy 161.931858 -58.001662) (xy 161.932294 -58.011726) (xy 161.940031 -58.030309)
			(xy 161.946844 -58.03773) (xy 162.320224 -58.41111) (xy 162.327619 -58.417963) (xy 162.346219 -58.425702)
			(xy 162.356292 -58.426096)
		)
		(stroke
			(width 0)
			(type solid)
		)
		(fill yes)
		(layer "In4.Cu")
		(net "P3V3_M2_0")
	)
	(gr_poly
		(pts
			(xy 217.77071 -401.657312) (xy 217.780738 -401.656864) (xy 217.799299 -401.649276) (xy 217.806778 -401.64258)
			(xy 218.2876 -401.161758) (xy 218.294387 -401.154337) (xy 218.302002 -401.13574) (xy 218.302332 -401.12569)
			(xy 218.302332 -400.34718) (xy 218.302784 -400.327161) (xy 218.310589 -400.287891) (xy 218.325914 -400.250903)
			(xy 218.348168 -400.21762) (xy 218.362022 -400.203162) (xy 218.75242 -399.812764) (xy 218.766903 -399.798958)
			(xy 218.800195 -399.776771) (xy 218.83718 -399.761517) (xy 218.876433 -399.753784) (xy 218.896438 -399.753328)
			(xy 226.764596 -399.753328) (xy 226.776662 -399.75265) (xy 226.798134 -399.741636) (xy 226.805744 -399.732246)
			(xy 226.822734 -399.709748) (xy 226.862244 -399.669535) (xy 226.907243 -399.635575) (xy 226.95675 -399.608609)
			(xy 227.009687 -399.589224) (xy 227.064901 -399.577842) (xy 227.093018 -399.575782) (xy 227.108004 -399.57502)
			(xy 227.132134 -399.557494) (xy 227.170742 -399.456656) (xy 227.17385 -399.447371) (xy 227.173534 -399.427811)
			(xy 227.165899 -399.4098) (xy 227.159312 -399.402554) (xy 226.839526 -399.083022) (xy 226.825724 -399.068523)
			(xy 226.803488 -399.035244) (xy 226.788165 -398.998269) (xy 226.780343 -398.959016) (xy 226.779836 -398.939004)
			(xy 226.779836 -394.042138) (xy 226.779397 -394.032106) (xy 226.771825 -394.013529) (xy 226.765104 -394.00607)
			(xy 226.458272 -393.699238) (xy 226.450874 -393.692392) (xy 226.432275 -393.684661) (xy 226.422204 -393.684252)
			(xy 218.259406 -393.684252) (xy 218.249336 -393.684675) (xy 218.230735 -393.692394) (xy 218.223338 -393.699238)
			(xy 218.15806 -393.764516) (xy 218.151289 -393.771943) (xy 218.143708 -393.79054) (xy 218.143328 -393.800584)
			(xy 218.143328 -398.305789) (xy 218.781878 -398.305789) (xy 218.785609 -398.252536) (xy 218.796728 -398.200322)
			(xy 218.815016 -398.150169) (xy 218.840117 -398.103054) (xy 218.871541 -398.059899) (xy 218.908674 -398.021545)
			(xy 218.929458 -398.004792) (xy 218.938229 -397.997239) (xy 218.948405 -397.976473) (xy 218.949016 -397.964914)
			(xy 218.949016 -397.88465) (xy 218.948411 -397.873087) (xy 218.93824 -397.852316) (xy 218.929458 -397.844772)
			(xy 218.908657 -397.82804) (xy 218.871527 -397.789684) (xy 218.840105 -397.746527) (xy 218.815007 -397.699411)
			(xy 218.796721 -397.649256) (xy 218.785606 -397.597042) (xy 218.781878 -397.543789) (xy 218.785609 -397.490536)
			(xy 218.796728 -397.438322) (xy 218.815016 -397.388169) (xy 218.840117 -397.341054) (xy 218.871541 -397.297899)
			(xy 218.908674 -397.259545) (xy 218.929458 -397.242792) (xy 218.938229 -397.235239) (xy 218.948405 -397.214473)
			(xy 218.949016 -397.202914) (xy 218.949016 -397.12265) (xy 218.948411 -397.111087) (xy 218.93824 -397.090316)
			(xy 218.929458 -397.082772) (xy 218.908657 -397.06604) (xy 218.871527 -397.027684) (xy 218.840105 -396.984527)
			(xy 218.815007 -396.937411) (xy 218.796721 -396.887256) (xy 218.785606 -396.835042) (xy 218.781878 -396.781789)
			(xy 218.785609 -396.728536) (xy 218.796728 -396.676322) (xy 218.815016 -396.626169) (xy 218.840117 -396.579054)
			(xy 218.871541 -396.535899) (xy 218.908674 -396.497545) (xy 218.929458 -396.480792) (xy 218.938229 -396.473239)
			(xy 218.948405 -396.452473) (xy 218.949016 -396.440914) (xy 218.949016 -396.36065) (xy 218.948411 -396.349087)
			(xy 218.93824 -396.328316) (xy 218.929458 -396.320772) (xy 218.908657 -396.30404) (xy 218.871527 -396.265684)
			(xy 218.840105 -396.222527) (xy 218.815007 -396.175411) (xy 218.796721 -396.125256) (xy 218.785606 -396.073042)
			(xy 218.781878 -396.019789) (xy 218.785609 -395.966536) (xy 218.796728 -395.914322) (xy 218.815016 -395.864169)
			(xy 218.840117 -395.817054) (xy 218.871541 -395.773899) (xy 218.908674 -395.735545) (xy 218.929458 -395.718792)
			(xy 218.938229 -395.711239) (xy 218.948405 -395.690473) (xy 218.949016 -395.678914) (xy 218.949016 -395.59865)
			(xy 218.948411 -395.587087) (xy 218.93824 -395.566316) (xy 218.929458 -395.558772) (xy 218.906952 -395.540607)
			(xy 218.86722 -395.498581) (xy 218.834285 -395.45104) (xy 218.808901 -395.399074) (xy 218.791649 -395.343872)
			(xy 218.782925 -395.286699) (xy 218.782392 -395.257782) (xy 218.782861 -395.23053) (xy 218.79062 -395.176582)
			(xy 218.805977 -395.124287) (xy 218.828621 -395.07471) (xy 218.858089 -395.028859) (xy 218.893782 -394.987669)
			(xy 218.934974 -394.951978) (xy 218.980825 -394.922512) (xy 219.030404 -394.899871) (xy 219.0827 -394.884516)
			(xy 219.136648 -394.87676) (xy 219.1639 -394.876274) (xy 219.192818 -394.876764) (xy 219.249992 -394.885495)
			(xy 219.305193 -394.902757) (xy 219.357155 -394.928154) (xy 219.404688 -394.961103) (xy 219.446702 -395.000851)
			(xy 219.46489 -395.02334) (xy 219.472454 -395.0321) (xy 219.493211 -395.042283) (xy 219.504768 -395.042898)
			(xy 219.585032 -395.042898) (xy 219.596595 -395.042289) (xy 219.617366 -395.032122) (xy 219.62491 -395.02334)
			(xy 219.641663 -395.002557) (xy 219.680017 -394.965427) (xy 219.723171 -394.934005) (xy 219.770285 -394.908906)
			(xy 219.820437 -394.89062) (xy 219.872648 -394.879503) (xy 219.9259 -394.875773) (xy 219.979152 -394.879503)
			(xy 220.031363 -394.89062) (xy 220.081515 -394.908906) (xy 220.128629 -394.934005) (xy 220.171783 -394.965427)
			(xy 220.210137 -395.002557) (xy 220.22689 -395.02334) (xy 220.234454 -395.0321) (xy 220.255211 -395.042283)
			(xy 220.266768 -395.042898) (xy 220.347032 -395.042898) (xy 220.358595 -395.042289) (xy 220.379366 -395.032122)
			(xy 220.38691 -395.02334) (xy 220.403663 -395.002557) (xy 220.442017 -394.965427) (xy 220.485171 -394.934005)
			(xy 220.532285 -394.908906) (xy 220.582437 -394.89062) (xy 220.634648 -394.879503) (xy 220.6879 -394.875773)
			(xy 220.741152 -394.879503) (xy 220.793363 -394.89062) (xy 220.843515 -394.908906) (xy 220.890629 -394.934005)
			(xy 220.933783 -394.965427) (xy 220.972137 -395.002557) (xy 220.98889 -395.02334) (xy 220.996454 -395.0321)
			(xy 221.017211 -395.042283) (xy 221.028768 -395.042898) (xy 221.109032 -395.042898) (xy 221.120595 -395.042289)
			(xy 221.141366 -395.032122) (xy 221.14891 -395.02334) (xy 221.165663 -395.002557) (xy 221.204017 -394.965427)
			(xy 221.247171 -394.934005) (xy 221.294285 -394.908906) (xy 221.344437 -394.89062) (xy 221.396648 -394.879503)
			(xy 221.4499 -394.875773) (xy 221.503152 -394.879503) (xy 221.555363 -394.89062) (xy 221.605515 -394.908906)
			(xy 221.652629 -394.934005) (xy 221.695783 -394.965427) (xy 221.734137 -395.002557) (xy 221.75089 -395.02334)
			(xy 221.758454 -395.0321) (xy 221.779211 -395.042283) (xy 221.790768 -395.042898) (xy 221.871032 -395.042898)
			(xy 221.882595 -395.042289) (xy 221.903366 -395.032122) (xy 221.91091 -395.02334) (xy 221.927663 -395.002557)
			(xy 221.966017 -394.965427) (xy 222.009171 -394.934005) (xy 222.056285 -394.908906) (xy 222.106437 -394.89062)
			(xy 222.158648 -394.879503) (xy 222.2119 -394.875773) (xy 222.265152 -394.879503) (xy 222.317363 -394.89062)
			(xy 222.367515 -394.908906) (xy 222.414629 -394.934005) (xy 222.457783 -394.965427) (xy 222.496137 -395.002557)
			(xy 222.51289 -395.02334) (xy 222.520454 -395.0321) (xy 222.541211 -395.042283) (xy 222.552768 -395.042898)
			(xy 222.633032 -395.042898) (xy 222.644595 -395.042289) (xy 222.665366 -395.032122) (xy 222.67291 -395.02334)
			(xy 222.689663 -395.002557) (xy 222.728017 -394.965427) (xy 222.771171 -394.934005) (xy 222.818285 -394.908906)
			(xy 222.868437 -394.89062) (xy 222.920648 -394.879503) (xy 222.9739 -394.875773) (xy 223.027152 -394.879503)
			(xy 223.079363 -394.89062) (xy 223.129515 -394.908906) (xy 223.176629 -394.934005) (xy 223.219783 -394.965427)
			(xy 223.258137 -395.002557) (xy 223.27489 -395.02334) (xy 223.282454 -395.0321) (xy 223.303211 -395.042283)
			(xy 223.314768 -395.042898) (xy 223.395032 -395.042898) (xy 223.406595 -395.042289) (xy 223.427366 -395.032122)
			(xy 223.43491 -395.02334) (xy 223.453105 -395.00086) (xy 223.495123 -394.961123) (xy 223.542657 -394.928182)
			(xy 223.594617 -394.902793) (xy 223.649815 -394.885536) (xy 223.706984 -394.876808) (xy 223.7359 -394.876274)
			(xy 223.76315 -394.876778) (xy 223.817097 -394.884534) (xy 223.86939 -394.899888) (xy 223.918966 -394.922528)
			(xy 223.964815 -394.951992) (xy 224.006005 -394.987682) (xy 224.041697 -395.02887) (xy 224.071164 -395.074718)
			(xy 224.093806 -395.124293) (xy 224.109162 -395.176586) (xy 224.116921 -395.230532) (xy 224.117408 -395.257782)
			(xy 224.116912 -395.2867) (xy 224.108183 -395.343874) (xy 224.090923 -395.399075) (xy 224.065527 -395.451037)
			(xy 224.032578 -395.49857) (xy 223.992831 -395.540584) (xy 223.970342 -395.558772) (xy 223.961587 -395.56634)
			(xy 223.951402 -395.587095) (xy 223.950784 -395.59865) (xy 223.950784 -395.678914) (xy 223.951352 -395.690482)
			(xy 223.961549 -395.711252) (xy 223.970342 -395.718792) (xy 223.991107 -395.735567) (xy 224.028237 -395.773917)
			(xy 224.059659 -395.817069) (xy 224.084758 -395.86418) (xy 224.103045 -395.91433) (xy 224.114163 -395.96654)
			(xy 224.117894 -396.019789) (xy 224.114166 -396.073039) (xy 224.103051 -396.125249) (xy 224.084767 -396.175399)
			(xy 224.05967 -396.222512) (xy 224.028252 -396.265666) (xy 223.991124 -396.304019) (xy 223.970342 -396.320772)
			(xy 223.961587 -396.32834) (xy 223.951402 -396.349095) (xy 223.950784 -396.36065) (xy 223.950784 -396.440914)
			(xy 223.951352 -396.452482) (xy 223.961549 -396.473252) (xy 223.970342 -396.480792) (xy 223.991107 -396.497567)
			(xy 224.028237 -396.535917) (xy 224.059659 -396.579069) (xy 224.084758 -396.62618) (xy 224.103045 -396.67633)
			(xy 224.114163 -396.72854) (xy 224.117894 -396.781789) (xy 224.114166 -396.835039) (xy 224.103051 -396.887249)
			(xy 224.084767 -396.937399) (xy 224.05967 -396.984512) (xy 224.028252 -397.027666) (xy 223.991124 -397.066019)
			(xy 223.970342 -397.082772) (xy 223.961587 -397.09034) (xy 223.951402 -397.111095) (xy 223.950784 -397.12265)
			(xy 223.950784 -397.202914) (xy 223.951352 -397.214482) (xy 223.961549 -397.235252) (xy 223.970342 -397.242792)
			(xy 223.99283 -397.260977) (xy 224.032563 -397.302999) (xy 224.065501 -397.350536) (xy 224.090888 -397.402498)
			(xy 224.108143 -397.457696) (xy 224.116873 -397.514866) (xy 224.117408 -397.543782) (xy 224.116928 -397.571034)
			(xy 224.109173 -397.624985) (xy 224.09382 -397.677282) (xy 224.071179 -397.726862) (xy 224.041713 -397.772716)
			(xy 224.006021 -397.813908) (xy 223.96483 -397.849602) (xy 223.918978 -397.879071) (xy 223.869399 -397.901713)
			(xy 223.817102 -397.91707) (xy 223.763152 -397.924827) (xy 223.7359 -397.92529) (xy 223.706983 -397.924775)
			(xy 223.649811 -397.916046) (xy 223.594612 -397.898788) (xy 223.542651 -397.873395) (xy 223.495117 -397.840451)
			(xy 223.4531 -397.80071) (xy 223.43491 -397.778224) (xy 223.427352 -397.769458) (xy 223.40659 -397.75928)
			(xy 223.395032 -397.758666) (xy 223.314768 -397.758666) (xy 223.303202 -397.759252) (xy 223.282429 -397.769433)
			(xy 223.27489 -397.778224) (xy 223.26011 -397.796622) (xy 223.226741 -397.829993) (xy 223.208342 -397.844772)
			(xy 223.199587 -397.85234) (xy 223.189402 -397.873095) (xy 223.188784 -397.88465) (xy 223.188784 -397.964914)
			(xy 223.189352 -397.976482) (xy 223.199549 -397.997252) (xy 223.208342 -398.004792) (xy 223.229107 -398.021567)
			(xy 223.266237 -398.059917) (xy 223.297659 -398.103069) (xy 223.322758 -398.15018) (xy 223.341045 -398.20033)
			(xy 223.352163 -398.25254) (xy 223.355894 -398.305789) (xy 223.352166 -398.359039) (xy 223.341051 -398.411249)
			(xy 223.322767 -398.461399) (xy 223.29767 -398.508512) (xy 223.266252 -398.551666) (xy 223.229124 -398.590019)
			(xy 223.208342 -398.606772) (xy 223.199587 -398.61434) (xy 223.189402 -398.635095) (xy 223.188784 -398.64665)
			(xy 223.188784 -398.726914) (xy 223.189352 -398.738482) (xy 223.199549 -398.759252) (xy 223.208342 -398.766792)
			(xy 223.23083 -398.784977) (xy 223.270563 -398.826999) (xy 223.303501 -398.874536) (xy 223.328888 -398.926498)
			(xy 223.346143 -398.981696) (xy 223.354873 -399.038866) (xy 223.355408 -399.067782) (xy 223.354928 -399.095034)
			(xy 223.347173 -399.148985) (xy 223.33182 -399.201282) (xy 223.309179 -399.250862) (xy 223.279713 -399.296716)
			(xy 223.244021 -399.337908) (xy 223.20283 -399.373602) (xy 223.156978 -399.403071) (xy 223.107399 -399.425713)
			(xy 223.055102 -399.44107) (xy 223.001152 -399.448827) (xy 222.9739 -399.44929) (xy 222.944983 -399.448775)
			(xy 222.887811 -399.440046) (xy 222.832612 -399.422788) (xy 222.780651 -399.397395) (xy 222.733117 -399.364451)
			(xy 222.6911 -399.32471) (xy 222.67291 -399.302224) (xy 222.665352 -399.293458) (xy 222.64459 -399.28328)
			(xy 222.633032 -399.282666) (xy 222.552768 -399.282666) (xy 222.541202 -399.283252) (xy 222.520429 -399.293433)
			(xy 222.51289 -399.302224) (xy 222.496137 -399.323007) (xy 222.457783 -399.360137) (xy 222.414629 -399.391559)
			(xy 222.367515 -399.416658) (xy 222.317363 -399.434944) (xy 222.265152 -399.446061) (xy 222.2119 -399.449791)
			(xy 222.158648 -399.446061) (xy 222.106437 -399.434944) (xy 222.056285 -399.416658) (xy 222.009171 -399.391559)
			(xy 221.966017 -399.360137) (xy 221.927663 -399.323007) (xy 221.91091 -399.302224) (xy 221.903352 -399.293458)
			(xy 221.88259 -399.28328) (xy 221.871032 -399.282666) (xy 221.790768 -399.282666) (xy 221.779202 -399.283252)
			(xy 221.758429 -399.293433) (xy 221.75089 -399.302224) (xy 221.734137 -399.323007) (xy 221.695783 -399.360137)
			(xy 221.652629 -399.391559) (xy 221.605515 -399.416658) (xy 221.555363 -399.434944) (xy 221.503152 -399.446061)
			(xy 221.4499 -399.449791) (xy 221.396648 -399.446061) (xy 221.344437 -399.434944) (xy 221.294285 -399.416658)
			(xy 221.247171 -399.391559) (xy 221.204017 -399.360137) (xy 221.165663 -399.323007) (xy 221.14891 -399.302224)
			(xy 221.141352 -399.293458) (xy 221.12059 -399.28328) (xy 221.109032 -399.282666) (xy 221.028768 -399.282666)
			(xy 221.017202 -399.283252) (xy 220.996429 -399.293433) (xy 220.98889 -399.302224) (xy 220.972137 -399.323007)
			(xy 220.933783 -399.360137) (xy 220.890629 -399.391559) (xy 220.843515 -399.416658) (xy 220.793363 -399.434944)
			(xy 220.741152 -399.446061) (xy 220.6879 -399.449791) (xy 220.634648 -399.446061) (xy 220.582437 -399.434944)
			(xy 220.532285 -399.416658) (xy 220.485171 -399.391559) (xy 220.442017 -399.360137) (xy 220.403663 -399.323007)
			(xy 220.38691 -399.302224) (xy 220.379352 -399.293458) (xy 220.35859 -399.28328) (xy 220.347032 -399.282666)
			(xy 220.266768 -399.282666) (xy 220.255202 -399.283252) (xy 220.234429 -399.293433) (xy 220.22689 -399.302224)
			(xy 220.210137 -399.323007) (xy 220.171783 -399.360137) (xy 220.128629 -399.391559) (xy 220.081515 -399.416658)
			(xy 220.031363 -399.434944) (xy 219.979152 -399.446061) (xy 219.9259 -399.449791) (xy 219.872648 -399.446061)
			(xy 219.820437 -399.434944) (xy 219.770285 -399.416658) (xy 219.723171 -399.391559) (xy 219.680017 -399.360137)
			(xy 219.641663 -399.323007) (xy 219.62491 -399.302224) (xy 219.617352 -399.293458) (xy 219.59659 -399.28328)
			(xy 219.585032 -399.282666) (xy 219.504768 -399.282666) (xy 219.493202 -399.283252) (xy 219.472429 -399.293433)
			(xy 219.46489 -399.302224) (xy 219.446711 -399.324717) (xy 219.404688 -399.364451) (xy 219.35715 -399.397388)
			(xy 219.305187 -399.422774) (xy 219.249987 -399.440029) (xy 219.192817 -399.448756) (xy 219.1639 -399.44929)
			(xy 219.136646 -399.448845) (xy 219.082694 -399.441087) (xy 219.030395 -399.42573) (xy 218.980813 -399.403086)
			(xy 218.934959 -399.373617) (xy 218.893766 -399.337921) (xy 218.858072 -399.296726) (xy 218.828605 -399.250871)
			(xy 218.805963 -399.201289) (xy 218.790609 -399.148989) (xy 218.782854 -399.095036) (xy 218.782392 -399.067782)
			(xy 218.782934 -399.038866) (xy 218.791654 -398.981694) (xy 218.808904 -398.926494) (xy 218.834291 -398.874531)
			(xy 218.867233 -398.826997) (xy 218.906973 -398.784981) (xy 218.929458 -398.766792) (xy 218.938229 -398.759239)
			(xy 218.948405 -398.738473) (xy 218.949016 -398.726914) (xy 218.949016 -398.64665) (xy 218.948411 -398.635087)
			(xy 218.93824 -398.614316) (xy 218.929458 -398.606772) (xy 218.908657 -398.59004) (xy 218.871527 -398.551684)
			(xy 218.840105 -398.508527) (xy 218.815007 -398.461411) (xy 218.796721 -398.411256) (xy 218.785606 -398.359042)
			(xy 218.781878 -398.305789) (xy 218.143328 -398.305789) (xy 218.143328 -400.43862) (xy 218.142876 -400.458639)
			(xy 218.13507 -400.497907) (xy 218.119742 -400.534894) (xy 218.097485 -400.568174) (xy 218.083638 -400.582638)
			(xy 217.59037 -401.075652) (xy 217.583004 -401.098512) (xy 217.585036 -401.110704) (xy 217.587198 -401.125467)
			(xy 217.589486 -401.15522) (xy 217.589608 -401.17014) (xy 217.589122 -401.197391) (xy 217.581366 -401.251339)
			(xy 217.566011 -401.303634) (xy 217.543369 -401.353211) (xy 217.513903 -401.399061) (xy 217.478212 -401.440252)
			(xy 217.437021 -401.475943) (xy 217.391171 -401.505409) (xy 217.341594 -401.528051) (xy 217.289299 -401.543406)
			(xy 217.235351 -401.551162) (xy 217.180849 -401.551162) (xy 217.126901 -401.543406) (xy 217.074606 -401.528051)
			(xy 217.025029 -401.505409) (xy 216.979179 -401.475943) (xy 216.937988 -401.440252) (xy 216.902297 -401.399061)
			(xy 216.872831 -401.353211) (xy 216.850189 -401.303634) (xy 216.834834 -401.251339) (xy 216.827078 -401.197391)
			(xy 216.826592 -401.17014) (xy 216.827182 -401.140198) (xy 216.836551 -401.081051) (xy 216.855047 -401.024095)
			(xy 216.882218 -400.97073) (xy 216.917395 -400.922267) (xy 216.959714 -400.879897) (xy 216.983564 -400.861784)
			(xy 216.99286 -400.854127) (xy 217.003713 -400.832662) (xy 217.004392 -400.820636) (xy 217.004392 -400.06397)
			(xy 217.00394 -400.053944) (xy 216.996345 -400.03539) (xy 216.98966 -400.027902) (xy 216.981786 -400.020028)
			(xy 216.975288 -400.014108) (xy 216.959371 -400.006678) (xy 216.941882 -400.00504) (xy 216.933272 -400.00682)
			(xy 216.835482 -400.031966) (xy 216.816178 -400.050508) (xy 216.812368 -400.063462) (xy 216.804967 -400.087461)
			(xy 216.784721 -400.133423) (xy 216.758613 -400.176326) (xy 216.727095 -400.215428) (xy 216.690713 -400.25005)
			(xy 216.670636 -400.265138) (xy 216.661343 -400.272796) (xy 216.6505 -400.294262) (xy 216.649808 -400.306286)
			(xy 216.649808 -401.38731) (xy 216.650257 -401.397337) (xy 216.657846 -401.415897) (xy 216.66454 -401.423378)
			(xy 216.883742 -401.64258) (xy 216.891162 -401.649369) (xy 216.909759 -401.656987) (xy 216.91981 -401.657312)
		)
		(stroke
			(width 0)
			(type solid)
		)
		(fill yes)
		(layer "In4.Cu")
		(net "AGND_HSC")
	)
	(gr_poly
		(pts
			(xy 207.08239 -401.692872) (xy 207.092419 -401.692427) (xy 207.110982 -401.68484) (xy 207.118458 -401.67814)
			(xy 207.62214 -401.174458) (xy 207.628923 -401.167035) (xy 207.636531 -401.148439) (xy 207.636872 -401.13839)
			(xy 207.636872 -400.42338) (xy 207.637324 -400.403361) (xy 207.64513 -400.364093) (xy 207.660458 -400.327106)
			(xy 207.682715 -400.293826) (xy 207.696562 -400.279362) (xy 208.16316 -399.812764) (xy 208.177641 -399.798953)
			(xy 208.210931 -399.776756) (xy 208.247916 -399.761492) (xy 208.287171 -399.753747) (xy 208.307178 -399.753328)
			(xy 216.096596 -399.753328) (xy 216.108662 -399.75265) (xy 216.130134 -399.741636) (xy 216.137744 -399.732246)
			(xy 216.15285 -399.712186) (xy 216.187485 -399.675822) (xy 216.226587 -399.644312) (xy 216.269481 -399.618198)
			(xy 216.315429 -399.597933) (xy 216.33942 -399.590514) (xy 216.352374 -399.586704) (xy 216.370916 -399.5674)
			(xy 216.396062 -399.46961) (xy 216.397907 -399.461005) (xy 216.396282 -399.443494) (xy 216.388813 -399.427572)
			(xy 216.382854 -399.421096) (xy 215.444832 -398.483328) (xy 215.431018 -398.468849) (xy 215.408816 -398.43556)
			(xy 215.393548 -398.398574) (xy 215.385803 -398.359317) (xy 215.385396 -398.33931) (xy 215.385396 -393.862306)
			(xy 215.384974 -393.852235) (xy 215.37726 -393.83363) (xy 215.37041 -393.826238) (xy 215.093042 -393.54887)
			(xy 215.085644 -393.542025) (xy 215.067045 -393.534301) (xy 215.056974 -393.533884) (xy 207.681068 -393.533884)
			(xy 207.671 -393.534312) (xy 207.652402 -393.542033) (xy 207.645 -393.54887) (xy 207.45704 -393.73683)
			(xy 207.450273 -393.744259) (xy 207.4427 -393.762855) (xy 207.442308 -393.772898) (xy 207.442308 -398.305789)
			(xy 208.113878 -398.305789) (xy 208.117609 -398.252536) (xy 208.128728 -398.200322) (xy 208.147016 -398.150169)
			(xy 208.172117 -398.103054) (xy 208.203541 -398.059899) (xy 208.240674 -398.021545) (xy 208.261458 -398.004792)
			(xy 208.270229 -397.997239) (xy 208.280405 -397.976473) (xy 208.281016 -397.964914) (xy 208.281016 -397.88465)
			(xy 208.280411 -397.873087) (xy 208.27024 -397.852316) (xy 208.261458 -397.844772) (xy 208.240657 -397.82804)
			(xy 208.203527 -397.789684) (xy 208.172105 -397.746527) (xy 208.147007 -397.699411) (xy 208.128721 -397.649256)
			(xy 208.117606 -397.597042) (xy 208.113878 -397.543789) (xy 208.117609 -397.490536) (xy 208.128728 -397.438322)
			(xy 208.147016 -397.388169) (xy 208.172117 -397.341054) (xy 208.203541 -397.297899) (xy 208.240674 -397.259545)
			(xy 208.261458 -397.242792) (xy 208.270229 -397.235239) (xy 208.280405 -397.214473) (xy 208.281016 -397.202914)
			(xy 208.281016 -397.12265) (xy 208.280411 -397.111087) (xy 208.27024 -397.090316) (xy 208.261458 -397.082772)
			(xy 208.240657 -397.06604) (xy 208.203527 -397.027684) (xy 208.172105 -396.984527) (xy 208.147007 -396.937411)
			(xy 208.128721 -396.887256) (xy 208.117606 -396.835042) (xy 208.113878 -396.781789) (xy 208.117609 -396.728536)
			(xy 208.128728 -396.676322) (xy 208.147016 -396.626169) (xy 208.172117 -396.579054) (xy 208.203541 -396.535899)
			(xy 208.240674 -396.497545) (xy 208.261458 -396.480792) (xy 208.270229 -396.473239) (xy 208.280405 -396.452473)
			(xy 208.281016 -396.440914) (xy 208.281016 -396.36065) (xy 208.280411 -396.349087) (xy 208.27024 -396.328316)
			(xy 208.261458 -396.320772) (xy 208.240657 -396.30404) (xy 208.203527 -396.265684) (xy 208.172105 -396.222527)
			(xy 208.147007 -396.175411) (xy 208.128721 -396.125256) (xy 208.117606 -396.073042) (xy 208.113878 -396.019789)
			(xy 208.117609 -395.966536) (xy 208.128728 -395.914322) (xy 208.147016 -395.864169) (xy 208.172117 -395.817054)
			(xy 208.203541 -395.773899) (xy 208.240674 -395.735545) (xy 208.261458 -395.718792) (xy 208.270229 -395.711239)
			(xy 208.280405 -395.690473) (xy 208.281016 -395.678914) (xy 208.281016 -395.59865) (xy 208.280411 -395.587087)
			(xy 208.27024 -395.566316) (xy 208.261458 -395.558772) (xy 208.238952 -395.540607) (xy 208.19922 -395.498581)
			(xy 208.166285 -395.45104) (xy 208.140901 -395.399074) (xy 208.123649 -395.343872) (xy 208.114925 -395.286699)
			(xy 208.114392 -395.257782) (xy 208.114861 -395.23053) (xy 208.12262 -395.176582) (xy 208.137977 -395.124287)
			(xy 208.160621 -395.07471) (xy 208.190089 -395.028859) (xy 208.225782 -394.987669) (xy 208.266974 -394.951978)
			(xy 208.312825 -394.922512) (xy 208.362404 -394.899871) (xy 208.4147 -394.884516) (xy 208.468648 -394.87676)
			(xy 208.4959 -394.876274) (xy 208.524818 -394.876764) (xy 208.581992 -394.885495) (xy 208.637193 -394.902757)
			(xy 208.689155 -394.928154) (xy 208.736688 -394.961103) (xy 208.778702 -395.000851) (xy 208.79689 -395.02334)
			(xy 208.804454 -395.0321) (xy 208.825211 -395.042283) (xy 208.836768 -395.042898) (xy 208.917032 -395.042898)
			(xy 208.928595 -395.042289) (xy 208.949366 -395.032122) (xy 208.95691 -395.02334) (xy 208.973663 -395.002557)
			(xy 209.012017 -394.965427) (xy 209.055171 -394.934005) (xy 209.102285 -394.908906) (xy 209.152437 -394.89062)
			(xy 209.204648 -394.879503) (xy 209.2579 -394.875773) (xy 209.311152 -394.879503) (xy 209.363363 -394.89062)
			(xy 209.413515 -394.908906) (xy 209.460629 -394.934005) (xy 209.503783 -394.965427) (xy 209.542137 -395.002557)
			(xy 209.55889 -395.02334) (xy 209.566454 -395.0321) (xy 209.587211 -395.042283) (xy 209.598768 -395.042898)
			(xy 209.679032 -395.042898) (xy 209.690595 -395.042289) (xy 209.711366 -395.032122) (xy 209.71891 -395.02334)
			(xy 209.735663 -395.002557) (xy 209.774017 -394.965427) (xy 209.817171 -394.934005) (xy 209.864285 -394.908906)
			(xy 209.914437 -394.89062) (xy 209.966648 -394.879503) (xy 210.0199 -394.875773) (xy 210.073152 -394.879503)
			(xy 210.125363 -394.89062) (xy 210.175515 -394.908906) (xy 210.222629 -394.934005) (xy 210.265783 -394.965427)
			(xy 210.304137 -395.002557) (xy 210.32089 -395.02334) (xy 210.328454 -395.0321) (xy 210.349211 -395.042283)
			(xy 210.360768 -395.042898) (xy 210.441032 -395.042898) (xy 210.452595 -395.042289) (xy 210.473366 -395.032122)
			(xy 210.48091 -395.02334) (xy 210.497663 -395.002557) (xy 210.536017 -394.965427) (xy 210.579171 -394.934005)
			(xy 210.626285 -394.908906) (xy 210.676437 -394.89062) (xy 210.728648 -394.879503) (xy 210.7819 -394.875773)
			(xy 210.835152 -394.879503) (xy 210.887363 -394.89062) (xy 210.937515 -394.908906) (xy 210.984629 -394.934005)
			(xy 211.027783 -394.965427) (xy 211.066137 -395.002557) (xy 211.08289 -395.02334) (xy 211.090454 -395.0321)
			(xy 211.111211 -395.042283) (xy 211.122768 -395.042898) (xy 211.203032 -395.042898) (xy 211.214595 -395.042289)
			(xy 211.235366 -395.032122) (xy 211.24291 -395.02334) (xy 211.259663 -395.002557) (xy 211.298017 -394.965427)
			(xy 211.341171 -394.934005) (xy 211.388285 -394.908906) (xy 211.438437 -394.89062) (xy 211.490648 -394.879503)
			(xy 211.5439 -394.875773) (xy 211.597152 -394.879503) (xy 211.649363 -394.89062) (xy 211.699515 -394.908906)
			(xy 211.746629 -394.934005) (xy 211.789783 -394.965427) (xy 211.828137 -395.002557) (xy 211.84489 -395.02334)
			(xy 211.852454 -395.0321) (xy 211.873211 -395.042283) (xy 211.884768 -395.042898) (xy 211.965032 -395.042898)
			(xy 211.976595 -395.042289) (xy 211.997366 -395.032122) (xy 212.00491 -395.02334) (xy 212.021663 -395.002557)
			(xy 212.060017 -394.965427) (xy 212.103171 -394.934005) (xy 212.150285 -394.908906) (xy 212.200437 -394.89062)
			(xy 212.252648 -394.879503) (xy 212.3059 -394.875773) (xy 212.359152 -394.879503) (xy 212.411363 -394.89062)
			(xy 212.461515 -394.908906) (xy 212.508629 -394.934005) (xy 212.551783 -394.965427) (xy 212.590137 -395.002557)
			(xy 212.60689 -395.02334) (xy 212.614454 -395.0321) (xy 212.635211 -395.042283) (xy 212.646768 -395.042898)
			(xy 212.727032 -395.042898) (xy 212.738595 -395.042289) (xy 212.759366 -395.032122) (xy 212.76691 -395.02334)
			(xy 212.785105 -395.00086) (xy 212.827123 -394.961123) (xy 212.874657 -394.928182) (xy 212.926617 -394.902793)
			(xy 212.981815 -394.885536) (xy 213.038984 -394.876808) (xy 213.0679 -394.876274) (xy 213.09515 -394.876778)
			(xy 213.149097 -394.884534) (xy 213.20139 -394.899888) (xy 213.250966 -394.922528) (xy 213.296815 -394.951992)
			(xy 213.338005 -394.987682) (xy 213.373697 -395.02887) (xy 213.403164 -395.074718) (xy 213.425806 -395.124293)
			(xy 213.441162 -395.176586) (xy 213.448921 -395.230532) (xy 213.449408 -395.257782) (xy 213.448912 -395.2867)
			(xy 213.440183 -395.343874) (xy 213.422923 -395.399075) (xy 213.397527 -395.451037) (xy 213.364578 -395.49857)
			(xy 213.324831 -395.540584) (xy 213.302342 -395.558772) (xy 213.293587 -395.56634) (xy 213.283402 -395.587095)
			(xy 213.282784 -395.59865) (xy 213.282784 -395.678914) (xy 213.283352 -395.690482) (xy 213.293549 -395.711252)
			(xy 213.302342 -395.718792) (xy 213.323107 -395.735567) (xy 213.360237 -395.773917) (xy 213.391659 -395.817069)
			(xy 213.416758 -395.86418) (xy 213.435045 -395.91433) (xy 213.446163 -395.96654) (xy 213.449894 -396.019789)
			(xy 213.446166 -396.073039) (xy 213.435051 -396.125249) (xy 213.416767 -396.175399) (xy 213.39167 -396.222512)
			(xy 213.360252 -396.265666) (xy 213.323124 -396.304019) (xy 213.302342 -396.320772) (xy 213.293587 -396.32834)
			(xy 213.283402 -396.349095) (xy 213.282784 -396.36065) (xy 213.282784 -396.440914) (xy 213.283352 -396.452482)
			(xy 213.293549 -396.473252) (xy 213.302342 -396.480792) (xy 213.323107 -396.497567) (xy 213.360237 -396.535917)
			(xy 213.391659 -396.579069) (xy 213.416758 -396.62618) (xy 213.435045 -396.67633) (xy 213.446163 -396.72854)
			(xy 213.449894 -396.781789) (xy 213.446166 -396.835039) (xy 213.435051 -396.887249) (xy 213.416767 -396.937399)
			(xy 213.39167 -396.984512) (xy 213.360252 -397.027666) (xy 213.323124 -397.066019) (xy 213.302342 -397.082772)
			(xy 213.293587 -397.09034) (xy 213.283402 -397.111095) (xy 213.282784 -397.12265) (xy 213.282784 -397.202914)
			(xy 213.283352 -397.214482) (xy 213.293549 -397.235252) (xy 213.302342 -397.242792) (xy 213.32483 -397.260977)
			(xy 213.364563 -397.302999) (xy 213.397501 -397.350536) (xy 213.422888 -397.402498) (xy 213.440143 -397.457696)
			(xy 213.448873 -397.514866) (xy 213.449408 -397.543782) (xy 213.448928 -397.571034) (xy 213.441173 -397.624985)
			(xy 213.42582 -397.677282) (xy 213.403179 -397.726862) (xy 213.373713 -397.772716) (xy 213.338021 -397.813908)
			(xy 213.29683 -397.849602) (xy 213.250978 -397.879071) (xy 213.201399 -397.901713) (xy 213.149102 -397.91707)
			(xy 213.095152 -397.924827) (xy 213.0679 -397.92529) (xy 213.038983 -397.924775) (xy 212.981811 -397.916046)
			(xy 212.926612 -397.898788) (xy 212.874651 -397.873395) (xy 212.827117 -397.840451) (xy 212.7851 -397.80071)
			(xy 212.76691 -397.778224) (xy 212.759352 -397.769458) (xy 212.73859 -397.75928) (xy 212.727032 -397.758666)
			(xy 212.646768 -397.758666) (xy 212.635202 -397.759252) (xy 212.614429 -397.769433) (xy 212.60689 -397.778224)
			(xy 212.59211 -397.796622) (xy 212.558741 -397.829993) (xy 212.540342 -397.844772) (xy 212.531587 -397.85234)
			(xy 212.521402 -397.873095) (xy 212.520784 -397.88465) (xy 212.520784 -397.964914) (xy 212.521352 -397.976482)
			(xy 212.531549 -397.997252) (xy 212.540342 -398.004792) (xy 212.561107 -398.021567) (xy 212.598237 -398.059917)
			(xy 212.629659 -398.103069) (xy 212.654758 -398.15018) (xy 212.673045 -398.20033) (xy 212.684163 -398.25254)
			(xy 212.687894 -398.305789) (xy 212.684166 -398.359039) (xy 212.673051 -398.411249) (xy 212.654767 -398.461399)
			(xy 212.62967 -398.508512) (xy 212.598252 -398.551666) (xy 212.561124 -398.590019) (xy 212.540342 -398.606772)
			(xy 212.531587 -398.61434) (xy 212.521402 -398.635095) (xy 212.520784 -398.64665) (xy 212.520784 -398.726914)
			(xy 212.521352 -398.738482) (xy 212.531549 -398.759252) (xy 212.540342 -398.766792) (xy 212.56283 -398.784977)
			(xy 212.602563 -398.826999) (xy 212.635501 -398.874536) (xy 212.660888 -398.926498) (xy 212.678143 -398.981696)
			(xy 212.686873 -399.038866) (xy 212.687408 -399.067782) (xy 212.686928 -399.095034) (xy 212.679173 -399.148985)
			(xy 212.66382 -399.201282) (xy 212.641179 -399.250862) (xy 212.611713 -399.296716) (xy 212.576021 -399.337908)
			(xy 212.53483 -399.373602) (xy 212.488978 -399.403071) (xy 212.439399 -399.425713) (xy 212.387102 -399.44107)
			(xy 212.333152 -399.448827) (xy 212.3059 -399.44929) (xy 212.276983 -399.448775) (xy 212.219811 -399.440046)
			(xy 212.164612 -399.422788) (xy 212.112651 -399.397395) (xy 212.065117 -399.364451) (xy 212.0231 -399.32471)
			(xy 212.00491 -399.302224) (xy 211.997352 -399.293458) (xy 211.97659 -399.28328) (xy 211.965032 -399.282666)
			(xy 211.884768 -399.282666) (xy 211.873202 -399.283252) (xy 211.852429 -399.293433) (xy 211.84489 -399.302224)
			(xy 211.828137 -399.323007) (xy 211.789783 -399.360137) (xy 211.746629 -399.391559) (xy 211.699515 -399.416658)
			(xy 211.649363 -399.434944) (xy 211.597152 -399.446061) (xy 211.5439 -399.449791) (xy 211.490648 -399.446061)
			(xy 211.438437 -399.434944) (xy 211.388285 -399.416658) (xy 211.341171 -399.391559) (xy 211.298017 -399.360137)
			(xy 211.259663 -399.323007) (xy 211.24291 -399.302224) (xy 211.235352 -399.293458) (xy 211.21459 -399.28328)
			(xy 211.203032 -399.282666) (xy 211.122768 -399.282666) (xy 211.111202 -399.283252) (xy 211.090429 -399.293433)
			(xy 211.08289 -399.302224) (xy 211.066137 -399.323007) (xy 211.027783 -399.360137) (xy 210.984629 -399.391559)
			(xy 210.937515 -399.416658) (xy 210.887363 -399.434944) (xy 210.835152 -399.446061) (xy 210.7819 -399.449791)
			(xy 210.728648 -399.446061) (xy 210.676437 -399.434944) (xy 210.626285 -399.416658) (xy 210.579171 -399.391559)
			(xy 210.536017 -399.360137) (xy 210.497663 -399.323007) (xy 210.48091 -399.302224) (xy 210.473352 -399.293458)
			(xy 210.45259 -399.28328) (xy 210.441032 -399.282666) (xy 210.360768 -399.282666) (xy 210.349202 -399.283252)
			(xy 210.328429 -399.293433) (xy 210.32089 -399.302224) (xy 210.304137 -399.323007) (xy 210.265783 -399.360137)
			(xy 210.222629 -399.391559) (xy 210.175515 -399.416658) (xy 210.125363 -399.434944) (xy 210.073152 -399.446061)
			(xy 210.0199 -399.449791) (xy 209.966648 -399.446061) (xy 209.914437 -399.434944) (xy 209.864285 -399.416658)
			(xy 209.817171 -399.391559) (xy 209.774017 -399.360137) (xy 209.735663 -399.323007) (xy 209.71891 -399.302224)
			(xy 209.711352 -399.293458) (xy 209.69059 -399.28328) (xy 209.679032 -399.282666) (xy 209.598768 -399.282666)
			(xy 209.587202 -399.283252) (xy 209.566429 -399.293433) (xy 209.55889 -399.302224) (xy 209.542137 -399.323007)
			(xy 209.503783 -399.360137) (xy 209.460629 -399.391559) (xy 209.413515 -399.416658) (xy 209.363363 -399.434944)
			(xy 209.311152 -399.446061) (xy 209.2579 -399.449791) (xy 209.204648 -399.446061) (xy 209.152437 -399.434944)
			(xy 209.102285 -399.416658) (xy 209.055171 -399.391559) (xy 209.012017 -399.360137) (xy 208.973663 -399.323007)
			(xy 208.95691 -399.302224) (xy 208.949352 -399.293458) (xy 208.92859 -399.28328) (xy 208.917032 -399.282666)
			(xy 208.836768 -399.282666) (xy 208.825202 -399.283252) (xy 208.804429 -399.293433) (xy 208.79689 -399.302224)
			(xy 208.778711 -399.324717) (xy 208.736688 -399.364451) (xy 208.68915 -399.397388) (xy 208.637187 -399.422774)
			(xy 208.581987 -399.440029) (xy 208.524817 -399.448756) (xy 208.4959 -399.44929) (xy 208.468646 -399.448845)
			(xy 208.414694 -399.441087) (xy 208.362395 -399.42573) (xy 208.312813 -399.403086) (xy 208.266959 -399.373617)
			(xy 208.225766 -399.337921) (xy 208.190072 -399.296726) (xy 208.160605 -399.250871) (xy 208.137963 -399.201289)
			(xy 208.122609 -399.148989) (xy 208.114854 -399.095036) (xy 208.114392 -399.067782) (xy 208.114934 -399.038866)
			(xy 208.123654 -398.981694) (xy 208.140904 -398.926494) (xy 208.166291 -398.874531) (xy 208.199233 -398.826997)
			(xy 208.238973 -398.784981) (xy 208.261458 -398.766792) (xy 208.270229 -398.759239) (xy 208.280405 -398.738473)
			(xy 208.281016 -398.726914) (xy 208.281016 -398.64665) (xy 208.280411 -398.635087) (xy 208.27024 -398.614316)
			(xy 208.261458 -398.606772) (xy 208.240657 -398.59004) (xy 208.203527 -398.551684) (xy 208.172105 -398.508527)
			(xy 208.147007 -398.461411) (xy 208.128721 -398.411256) (xy 208.117606 -398.359042) (xy 208.113878 -398.305789)
			(xy 207.442308 -398.305789) (xy 207.442308 -400.47164) (xy 207.441854 -400.491659) (xy 207.434048 -400.530927)
			(xy 207.418722 -400.567915) (xy 207.396469 -400.601198) (xy 207.382618 -400.615658) (xy 206.92237 -401.075652)
			(xy 206.915004 -401.098512) (xy 206.917036 -401.110704) (xy 206.919198 -401.125467) (xy 206.921486 -401.15522)
			(xy 206.921608 -401.17014) (xy 206.921122 -401.197391) (xy 206.913366 -401.251339) (xy 206.898011 -401.303634)
			(xy 206.875369 -401.353211) (xy 206.845903 -401.399061) (xy 206.810212 -401.440252) (xy 206.769021 -401.475943)
			(xy 206.723171 -401.505409) (xy 206.673594 -401.528051) (xy 206.621299 -401.543406) (xy 206.567351 -401.551162)
			(xy 206.512849 -401.551162) (xy 206.458901 -401.543406) (xy 206.406606 -401.528051) (xy 206.357029 -401.505409)
			(xy 206.311179 -401.475943) (xy 206.269988 -401.440252) (xy 206.234297 -401.399061) (xy 206.204831 -401.353211)
			(xy 206.182189 -401.303634) (xy 206.166834 -401.251339) (xy 206.159078 -401.197391) (xy 206.158592 -401.17014)
			(xy 206.159182 -401.140198) (xy 206.168551 -401.081051) (xy 206.187047 -401.024095) (xy 206.214218 -400.97073)
			(xy 206.249395 -400.922267) (xy 206.291714 -400.879897) (xy 206.315564 -400.861784) (xy 206.32486 -400.854127)
			(xy 206.335713 -400.832662) (xy 206.336392 -400.820636) (xy 206.336392 -400.02333) (xy 206.335951 -400.013299)
			(xy 206.328371 -399.994729) (xy 206.32166 -399.987262) (xy 206.246222 -399.912078) (xy 206.238788 -399.905362)
			(xy 206.220288 -399.897726) (xy 206.200274 -399.897726) (xy 206.181774 -399.905362) (xy 206.17434 -399.912078)
			(xy 206.166974 -399.919444) (xy 206.159354 -399.938494) (xy 206.159608 -399.948908) (xy 206.159608 -399.956782)
			(xy 206.159016 -399.986723) (xy 206.149645 -400.045868) (xy 206.131146 -400.102822) (xy 206.103973 -400.156184)
			(xy 206.068795 -400.204645) (xy 206.026476 -400.247012) (xy 206.002636 -400.265138) (xy 205.993343 -400.272796)
			(xy 205.9825 -400.294262) (xy 205.981808 -400.306286) (xy 205.981808 -401.34667) (xy 205.982249 -401.356701)
			(xy 205.989829 -401.375271) (xy 205.99654 -401.382738) (xy 206.291942 -401.67814) (xy 206.299365 -401.684923)
			(xy 206.317961 -401.692531) (xy 206.32801 -401.692872)
		)
		(stroke
			(width 0)
			(type solid)
		)
		(fill yes)
		(layer "In4.Cu")
		(net "AGND_HSC")
	)
	(gr_poly
		(pts
			(xy 251.42571 -53.314092) (xy 251.435588 -53.313633) (xy 251.453887 -53.306191) (xy 251.46127 -53.299614)
			(xy 251.461524 -53.29936) (xy 251.76226 -52.998624) (xy 251.762768 -52.998116) (xy 251.769344 -52.990733)
			(xy 251.776781 -52.972434) (xy 251.777246 -52.962556) (xy 251.777246 -50.194972) (xy 251.776816 -50.184905)
			(xy 251.769089 -50.166313) (xy 251.76226 -50.158904) (xy 248.619772 -47.016416) (xy 248.612931 -47.009016)
			(xy 248.605216 -46.990417) (xy 248.604786 -46.980348) (xy 248.604786 -43.69435) (xy 248.605218 -43.684283)
			(xy 248.612943 -43.665691) (xy 248.619772 -43.658282) (xy 249.901456 -42.376598) (xy 249.908858 -42.369761)
			(xy 249.927456 -42.362047) (xy 249.937524 -42.361612) (xy 250.25223 -42.361612) (xy 250.279408 -42.340784)
			(xy 250.28398 -42.32402) (xy 250.295243 -42.284024) (xy 250.324231 -42.206147) (xy 250.360358 -42.131314)
			(xy 250.403307 -42.060178) (xy 250.452705 -41.993357) (xy 250.508121 -41.931437) (xy 250.569072 -41.874955)
			(xy 250.635026 -41.824406) (xy 250.705407 -41.78023) (xy 250.779603 -41.742811) (xy 250.856965 -41.712477)
			(xy 250.93682 -41.689492) (xy 251.018471 -41.674057) (xy 251.101205 -41.666305) (xy 251.184303 -41.666305)
			(xy 251.267037 -41.674057) (xy 251.348688 -41.689492) (xy 251.428543 -41.712477) (xy 251.505905 -41.742811)
			(xy 251.580101 -41.78023) (xy 251.650482 -41.824406) (xy 251.716436 -41.874955) (xy 251.777387 -41.931437)
			(xy 251.832803 -41.993357) (xy 251.882201 -42.060178) (xy 251.92515 -42.131314) (xy 251.961277 -42.206147)
			(xy 251.990265 -42.284024) (xy 252.001528 -42.32402) (xy 252.0061 -42.340784) (xy 252.033278 -42.361612)
			(xy 253.784862 -42.361612) (xy 253.797527 -42.360857) (xy 253.819774 -42.348727) (xy 253.82728 -42.338498)
			(xy 253.880874 -42.256202) (xy 253.882906 -42.230802) (xy 253.877826 -42.218864) (xy 253.859613 -42.176258)
			(xy 253.831106 -42.088089) (xy 253.811916 -41.997435) (xy 253.802251 -41.905277) (xy 253.801626 -41.858946)
			(xy 253.802084 -41.817842) (xy 253.809665 -41.735984) (xy 253.824768 -41.655176) (xy 253.847262 -41.576105)
			(xy 253.876957 -41.499448) (xy 253.913598 -41.425857) (xy 253.956874 -41.355962) (xy 254.006414 -41.290358)
			(xy 254.061797 -41.229605) (xy 254.122549 -41.174222) (xy 254.188152 -41.12468) (xy 254.258047 -41.081404)
			(xy 254.331637 -41.044762) (xy 254.408294 -41.015066) (xy 254.487364 -40.992571) (xy 254.568173 -40.977467)
			(xy 254.65003 -40.969885) (xy 254.691134 -40.969438) (xy 254.734931 -40.969956) (xy 254.8221 -40.978559)
			(xy 254.908 -40.995697) (xy 254.991797 -41.021204) (xy 255.072677 -41.054833) (xy 255.111504 -41.075102)
			(xy 255.12297 -41.08052) (xy 255.148298 -41.08052) (xy 255.159764 -41.075102) (xy 255.198608 -41.054868)
			(xy 255.279492 -41.021259) (xy 255.363285 -40.995755) (xy 255.449178 -40.978601) (xy 255.53634 -40.969965)
			(xy 255.580134 -40.969438) (xy 255.623931 -40.969956) (xy 255.7111 -40.978559) (xy 255.797 -40.995697)
			(xy 255.880797 -41.021204) (xy 255.961677 -41.054833) (xy 256.000504 -41.075102) (xy 256.01197 -41.08052)
			(xy 256.037298 -41.08052) (xy 256.048764 -41.075102) (xy 256.084416 -41.05645) (xy 256.158443 -41.024903)
			(xy 256.196592 -41.01211) (xy 256.212594 -41.00703) (xy 256.231898 -40.980614) (xy 256.231898 -39.807896)
			(xy 256.231474 -39.797826) (xy 256.223758 -39.779223) (xy 256.216912 -39.771828) (xy 255.734058 -39.288974)
			(xy 255.726661 -39.282126) (xy 255.708062 -39.274395) (xy 255.69799 -39.273988) (xy 254.88392 -39.273988)
			(xy 254.874137 -39.274442) (xy 254.855992 -39.281768) (xy 254.848614 -39.288212) (xy 254.790702 -39.344346)
			(xy 254.782574 -39.36238) (xy 254.78232 -39.372286) (xy 254.780419 -39.414843) (xy 254.769489 -39.499332)
			(xy 254.750535 -39.58239) (xy 254.737616 -39.622984) (xy 254.734314 -39.63289) (xy 254.736092 -39.652956)
			(xy 254.779272 -39.736268) (xy 254.794766 -39.749222) (xy 254.804926 -39.75227) (xy 254.83074 -39.760541)
			(xy 254.879907 -39.78336) (xy 254.92535 -39.812909) (xy 254.966153 -39.848592) (xy 255.001496 -39.88969)
			(xy 255.030666 -39.935377) (xy 255.053076 -39.984732) (xy 255.068275 -40.036762) (xy 255.075958 -40.09042)
			(xy 255.076452 -40.117522) (xy 255.075965 -40.144773) (xy 255.068206 -40.198721) (xy 255.052849 -40.251016)
			(xy 255.030208 -40.300593) (xy 255.000741 -40.346444) (xy 254.965051 -40.387635) (xy 254.923861 -40.423328)
			(xy 254.878012 -40.452797) (xy 254.828436 -40.475442) (xy 254.776143 -40.490801) (xy 254.722195 -40.498563)
			(xy 254.694944 -40.49903) (xy 254.66603 -40.498492) (xy 254.608865 -40.489756) (xy 254.553673 -40.472494)
			(xy 254.501719 -40.4471) (xy 254.454191 -40.414157) (xy 254.41218 -40.374418) (xy 254.393954 -40.351964)
			(xy 254.387672 -40.344577) (xy 254.370957 -40.334779) (xy 254.361442 -40.332914) (xy 254.353822 -40.332406)
			(xy 254.274066 -40.332406) (xy 254.266446 -40.332914) (xy 254.256925 -40.334774) (xy 254.240191 -40.344553)
			(xy 254.233934 -40.351964) (xy 254.215744 -40.374449) (xy 254.173728 -40.41419) (xy 254.126194 -40.447133)
			(xy 254.074232 -40.472522) (xy 254.019032 -40.489775) (xy 253.961861 -40.498498) (xy 253.932944 -40.49903)
			(xy 253.903619 -40.498495) (xy 253.845659 -40.489519) (xy 253.789757 -40.471772) (xy 253.737233 -40.445673)
			(xy 253.71298 -40.42918) (xy 253.703836 -40.42283) (xy 253.6825 -40.418766) (xy 253.586488 -40.44188)
			(xy 253.56947 -40.455342) (xy 253.56439 -40.464994) (xy 253.543515 -40.503793) (xy 253.495196 -40.577472)
			(xy 253.439828 -40.646012) (xy 253.377953 -40.70874) (xy 253.310178 -40.765043) (xy 253.237169 -40.814368)
			(xy 253.159639 -40.856231) (xy 253.07835 -40.890222) (xy 252.994097 -40.916008) (xy 252.907708 -40.933336)
			(xy 252.820029 -40.942037) (xy 252.775974 -40.942514) (xy 252.733356 -40.942012) (xy 252.64851 -40.933855)
			(xy 252.564833 -40.917618) (xy 252.483094 -40.89345) (xy 252.404042 -40.861574) (xy 252.328402 -40.822281)
			(xy 252.256868 -40.775931) (xy 252.190097 -40.722951) (xy 252.1287 -40.663826) (xy 252.073242 -40.599098)
			(xy 252.02423 -40.529361) (xy 251.982115 -40.455255) (xy 251.947282 -40.37746) (xy 251.933202 -40.337232)
			(xy 251.929714 -40.328191) (xy 251.917175 -40.313436) (xy 251.908818 -40.30853) (xy 251.881894 -40.294306)
			(xy 251.873171 -40.290148) (xy 251.853974 -40.288072) (xy 251.844556 -40.290242) (xy 251.805819 -40.300519)
			(xy 251.726967 -40.31488) (xy 251.647141 -40.322075) (xy 251.607066 -40.3225) (xy 251.581866 -40.322352)
			(xy 251.531544 -40.319555) (xy 251.506482 -40.316912) (xy 251.497134 -40.316192) (xy 251.478995 -40.320884)
			(xy 251.471176 -40.326056) (xy 251.446792 -40.343582) (xy 251.439356 -40.349308) (xy 251.429033 -40.364966)
			(xy 251.426726 -40.374062) (xy 251.417072 -40.41608) (xy 251.39069 -40.498164) (xy 251.356491 -40.577311)
			(xy 251.314794 -40.652777) (xy 251.26599 -40.723855) (xy 251.210539 -40.789877) (xy 251.14896 -40.850224)
			(xy 251.081831 -40.90433) (xy 251.009782 -40.951688) (xy 250.933488 -40.991851) (xy 250.853667 -41.024445)
			(xy 250.771067 -41.049163) (xy 250.686462 -41.065772) (xy 250.600648 -41.074118) (xy 250.557538 -41.074594)
			(xy 250.516434 -41.074136) (xy 250.434576 -41.066554) (xy 250.353767 -41.051451) (xy 250.274697 -41.028956)
			(xy 250.198039 -40.999261) (xy 250.124449 -40.96262) (xy 250.054553 -40.919344) (xy 249.988948 -40.869804)
			(xy 249.928195 -40.814422) (xy 249.872811 -40.75367) (xy 249.823269 -40.688067) (xy 249.779992 -40.618172)
			(xy 249.743348 -40.544583) (xy 249.713652 -40.467926) (xy 249.691155 -40.388856) (xy 249.67605 -40.308048)
			(xy 249.668466 -40.22619) (xy 249.66803 -40.185086) (xy 249.668526 -40.142576) (xy 249.67664 -40.057944)
			(xy 249.692793 -39.974473) (xy 249.716836 -39.892924) (xy 249.748552 -39.814041) (xy 249.787649 -39.738544)
			(xy 249.833773 -39.667122) (xy 249.8865 -39.600428) (xy 249.945351 -39.539069) (xy 250.009789 -39.483605)
			(xy 250.044204 -39.458646) (xy 250.058174 -39.44874) (xy 250.068588 -39.417752) (xy 250.034044 -39.309294)
			(xy 250.03023 -39.299292) (xy 250.015967 -39.283365) (xy 249.996471 -39.274588) (xy 249.985784 -39.273988)
			(xy 248.209562 -39.273988) (xy 248.202983 -39.274204) (xy 248.190258 -39.277558) (xy 248.184416 -39.280592)
			(xy 248.158508 -39.295324) (xy 248.149618 -39.303706) (xy 248.146316 -39.30904) (xy 248.128761 -39.335197)
			(xy 248.086508 -39.381915) (xy 248.062242 -39.402004) (xy 248.059702 -39.404036) (xy 248.059448 -39.40429)
			(xy 248.052056 -39.41057) (xy 248.042243 -39.427281) (xy 248.040398 -39.436802) (xy 248.03989 -39.444422)
			(xy 248.03989 -39.524178) (xy 248.040398 -39.531798) (xy 248.042268 -39.541311) (xy 248.052067 -39.558022)
			(xy 248.059448 -39.56431) (xy 248.081937 -39.582498) (xy 248.121686 -39.624511) (xy 248.154637 -39.672044)
			(xy 248.180035 -39.724006) (xy 248.197297 -39.779207) (xy 248.206028 -39.836381) (xy 248.206514 -39.8653)
			(xy 248.206028 -39.892551) (xy 248.198272 -39.946499) (xy 248.182917 -39.998795) (xy 248.160276 -40.048372)
			(xy 248.130809 -40.094223) (xy 248.095118 -40.135414) (xy 248.053928 -40.171106) (xy 248.008077 -40.200573)
			(xy 247.9585 -40.223215) (xy 247.906205 -40.23857) (xy 247.852257 -40.246328) (xy 247.825006 -40.246808)
			(xy 247.798299 -40.24636) (xy 247.745408 -40.238909) (xy 247.694073 -40.224151) (xy 247.6453 -40.202374)
			(xy 247.600042 -40.174006) (xy 247.559185 -40.139601) (xy 247.523528 -40.099832) (xy 247.493768 -40.055477)
			(xy 247.470488 -40.007403) (xy 247.454143 -39.956552) (xy 247.445052 -39.903917) (xy 247.443752 -39.877238)
			(xy 247.443244 -39.861998) (xy 247.425972 -39.83736) (xy 247.325134 -39.797228) (xy 247.315734 -39.793985)
			(xy 247.29587 -39.794181) (xy 247.277571 -39.80191) (xy 247.27027 -39.808658) (xy 247.124474 -39.9542)
			(xy 245.749572 -41.329102) (xy 245.740428 -41.338246) (xy 245.740174 -41.3385) (xy 245.344696 -41.733978)
			(xy 245.322164 -41.756027) (xy 245.273744 -41.796405) (xy 245.221865 -41.832229) (xy 245.194582 -41.848024)
			(xy 245.184422 -41.853866) (xy 245.17096 -41.872916) (xy 245.155212 -41.97477) (xy 245.16207 -41.997122)
			(xy 245.169944 -42.005758) (xy 245.197995 -42.036594) (xy 245.248851 -42.102649) (xy 245.293301 -42.173175)
			(xy 245.330956 -42.247551) (xy 245.361484 -42.325125) (xy 245.384618 -42.405216) (xy 245.400154 -42.487121)
			(xy 245.407956 -42.57012) (xy 245.40845 -42.611802) (xy 245.408039 -42.650091) (xy 245.40143 -42.726385)
			(xy 245.388279 -42.801826) (xy 245.368684 -42.875856) (xy 245.356126 -42.91203) (xy 245.353483 -42.920468)
			(xy 245.353484 -42.938136) (xy 245.356126 -42.946574) (xy 245.368669 -42.982752) (xy 245.388243 -43.056784)
			(xy 245.401388 -43.132224) (xy 245.408006 -43.208514) (xy 245.40845 -43.246802) (xy 245.407946 -43.28915)
			(xy 245.399895 -43.373464) (xy 245.383866 -43.45663) (xy 245.360005 -43.537897) (xy 245.328526 -43.616527)
			(xy 245.289715 -43.691808) (xy 245.243925 -43.76306) (xy 245.191569 -43.829636) (xy 245.133121 -43.890934)
			(xy 245.069111 -43.946399) (xy 245.000119 -43.995528) (xy 244.926769 -44.037877) (xy 244.849726 -44.073061)
			(xy 244.769687 -44.100763) (xy 244.687378 -44.120731) (xy 244.603543 -44.132784) (xy 244.518942 -44.136815)
			(xy 244.434341 -44.132784) (xy 244.350506 -44.120731) (xy 244.268197 -44.100763) (xy 244.188158 -44.073061)
			(xy 244.111115 -44.037877) (xy 244.037765 -43.995528) (xy 243.968773 -43.946399) (xy 243.904763 -43.890934)
			(xy 243.846315 -43.829636) (xy 243.793959 -43.76306) (xy 243.748169 -43.691808) (xy 243.709358 -43.616527)
			(xy 243.677879 -43.537897) (xy 243.654018 -43.45663) (xy 243.637989 -43.373464) (xy 243.629938 -43.28915)
			(xy 243.629434 -43.246802) (xy 243.629845 -43.208512) (xy 243.636453 -43.132219) (xy 243.649603 -43.056777)
			(xy 243.669198 -42.982747) (xy 243.681758 -42.946574) (xy 243.684401 -42.938136) (xy 243.684402 -42.920468)
			(xy 243.681758 -42.91203) (xy 243.669215 -42.875852) (xy 243.649641 -42.80182) (xy 243.636496 -42.72638)
			(xy 243.629877 -42.65009) (xy 243.629434 -42.611802) (xy 243.629964 -42.567433) (xy 243.638748 -42.479132)
			(xy 243.64696 -42.435526) (xy 243.649246 -42.424096) (xy 243.643912 -42.402252) (xy 243.586762 -42.332402)
			(xy 243.579138 -42.324041) (xy 243.558694 -42.314417) (xy 243.547392 -42.31386) (xy 243.385594 -42.31386)
			(xy 242.306856 -42.31386) (xy 242.297723 -42.314877) (xy 242.281046 -42.32256) (xy 242.274344 -42.328846)
			(xy 241.889534 -42.713656) (xy 241.882693 -42.721056) (xy 241.874973 -42.739654) (xy 241.874548 -42.749724)
			(xy 241.874548 -45.726153) (xy 244.028673 -45.726153) (xy 244.028673 -45.671647) (xy 244.036431 -45.617697)
			(xy 244.051787 -45.5654) (xy 244.07443 -45.515821) (xy 244.103899 -45.469969) (xy 244.139593 -45.428777)
			(xy 244.180786 -45.393085) (xy 244.22664 -45.363619) (xy 244.276221 -45.340979) (xy 244.328519 -45.325626)
			(xy 244.382469 -45.317872) (xy 244.409722 -45.31741) (xy 244.41912 -45.31741) (xy 244.432582 -45.317918)
			(xy 244.45595 -45.305218) (xy 244.51691 -45.208444) (xy 244.51818 -45.182028) (xy 244.512084 -45.169836)
			(xy 244.499055 -45.142926) (xy 244.480598 -45.086061) (xy 244.471261 -45.027009) (xy 244.470682 -44.997116)
			(xy 244.471168 -44.969865) (xy 244.478924 -44.915917) (xy 244.494279 -44.863622) (xy 244.516921 -44.814045)
			(xy 244.546387 -44.768195) (xy 244.582078 -44.727004) (xy 244.623269 -44.691313) (xy 244.669119 -44.661847)
			(xy 244.718696 -44.639205) (xy 244.770991 -44.62385) (xy 244.824939 -44.616094) (xy 244.879441 -44.616094)
			(xy 244.933389 -44.62385) (xy 244.985684 -44.639205) (xy 245.035261 -44.661847) (xy 245.081111 -44.691313)
			(xy 245.122302 -44.727004) (xy 245.157993 -44.768195) (xy 245.187459 -44.814045) (xy 245.210101 -44.863622)
			(xy 245.225456 -44.915917) (xy 245.233212 -44.969865) (xy 245.233698 -44.997116) (xy 245.233189 -45.025048)
			(xy 245.225048 -45.080314) (xy 245.208941 -45.133805) (xy 245.185214 -45.184379) (xy 245.170198 -45.207936)
			(xy 245.164102 -45.21708) (xy 245.160546 -45.23867) (xy 245.186708 -45.33392) (xy 245.200678 -45.350684)
			(xy 245.210838 -45.35551) (xy 245.234703 -45.367543) (xy 245.279101 -45.397298) (xy 245.31891 -45.43296)
			(xy 245.353352 -45.47383) (xy 245.38175 -45.519108) (xy 245.40355 -45.567907) (xy 245.418323 -45.619271)
			(xy 245.425782 -45.672195) (xy 245.42623 -45.698918) (xy 245.425739 -45.726169) (xy 245.417981 -45.780115)
			(xy 245.402624 -45.832408) (xy 245.379983 -45.881984) (xy 245.350517 -45.927833) (xy 245.314826 -45.969023)
			(xy 245.273637 -46.004714) (xy 245.227788 -46.034181) (xy 245.178212 -46.056823) (xy 245.125919 -46.07218)
			(xy 245.071973 -46.079939) (xy 245.044722 -46.080426) (xy 245.017351 -46.079965) (xy 244.963171 -46.072149)
			(xy 244.910667 -46.056659) (xy 244.860921 -46.033816) (xy 244.814955 -46.004089) (xy 244.794024 -45.986446)
			(xy 244.786912 -45.98035) (xy 244.769894 -45.974) (xy 244.68455 -45.974) (xy 244.667532 -45.98035)
			(xy 244.66042 -45.986446) (xy 244.639484 -46.004081) (xy 244.593513 -46.033795) (xy 244.543767 -46.056633)
			(xy 244.491267 -46.072125) (xy 244.437091 -46.079953) (xy 244.409722 -46.080426) (xy 244.382469 -46.079928)
			(xy 244.328519 -46.072174) (xy 244.276221 -46.056821) (xy 244.22664 -46.034181) (xy 244.180786 -46.004715)
			(xy 244.139593 -45.969023) (xy 244.103899 -45.927831) (xy 244.07443 -45.881979) (xy 244.051787 -45.8324)
			(xy 244.036431 -45.780103) (xy 244.028673 -45.726153) (xy 241.874548 -45.726153) (xy 241.874548 -50.418238)
			(xy 241.874979 -50.428304) (xy 241.882709 -50.446894) (xy 241.889534 -50.454306) (xy 243.643658 -52.20843)
			(xy 243.651293 -52.215439) (xy 243.670494 -52.223186) (xy 243.691194 -52.222714) (xy 243.700808 -52.218844)
			(xy 243.8019 -52.172616) (xy 243.817902 -52.145184) (xy 243.816886 -52.129182) (xy 243.81587 -52.10175)
			(xy 243.816329 -52.074494) (xy 243.82408 -52.020537) (xy 243.839432 -51.968231) (xy 243.862071 -51.918644)
			(xy 243.891538 -51.872783) (xy 243.927231 -51.831582) (xy 243.968425 -51.795881) (xy 244.01428 -51.766406)
			(xy 244.063864 -51.743757) (xy 244.116166 -51.728396) (xy 244.170122 -51.720635) (xy 244.197378 -51.720242)
			(xy 244.223758 -51.720686) (xy 244.276017 -51.727946) (xy 244.326778 -51.742332) (xy 244.375076 -51.763569)
			(xy 244.41999 -51.791253) (xy 244.460664 -51.824857) (xy 244.496326 -51.863741) (xy 244.526294 -51.907164)
			(xy 244.5385 -51.930554) (xy 244.54485 -51.943762) (xy 244.569234 -51.958748) (xy 244.689122 -51.958748)
			(xy 244.713506 -51.943762) (xy 244.719856 -51.930554) (xy 244.732101 -51.907187) (xy 244.762062 -51.863764)
			(xy 244.797716 -51.824881) (xy 244.838386 -51.791278) (xy 244.883295 -51.763596) (xy 244.931588 -51.742362)
			(xy 244.982346 -51.727981) (xy 245.0346 -51.720727) (xy 245.060978 -51.720242) (xy 245.088228 -51.720704)
			(xy 245.142175 -51.728457) (xy 245.194468 -51.743809) (xy 245.244045 -51.766448) (xy 245.289894 -51.795911)
			(xy 245.331084 -51.8316) (xy 245.366776 -51.872788) (xy 245.396242 -51.918636) (xy 245.418883 -51.968211)
			(xy 245.434238 -52.020504) (xy 245.441995 -52.07445) (xy 245.441995 -52.12895) (xy 245.434238 -52.182896)
			(xy 245.418883 -52.235189) (xy 245.396242 -52.284764) (xy 245.366776 -52.330612) (xy 245.331084 -52.3718)
			(xy 245.289894 -52.407489) (xy 245.244045 -52.436952) (xy 245.194468 -52.459591) (xy 245.142175 -52.474943)
			(xy 245.088228 -52.482696) (xy 245.060978 -52.483258) (xy 245.034599 -52.482811) (xy 244.982345 -52.475546)
			(xy 244.931588 -52.461156) (xy 244.883295 -52.439915) (xy 244.838386 -52.412229) (xy 244.797716 -52.378624)
			(xy 244.762059 -52.33974) (xy 244.732095 -52.296318) (xy 244.719856 -52.272946) (xy 244.713506 -52.259738)
			(xy 244.689122 -52.244752) (xy 244.569234 -52.244752) (xy 244.54485 -52.259738) (xy 244.5385 -52.272946)
			(xy 244.526255 -52.296316) (xy 244.496297 -52.339743) (xy 244.460644 -52.378631) (xy 244.419975 -52.41224)
			(xy 244.375066 -52.439928) (xy 244.326772 -52.461169) (xy 244.276014 -52.475557) (xy 244.223757 -52.482819)
			(xy 244.197378 -52.483258) (xy 244.169946 -52.482242) (xy 244.153944 -52.481226) (xy 244.126512 -52.497228)
			(xy 244.080284 -52.59832) (xy 244.076437 -52.607938) (xy 244.075978 -52.628628) (xy 244.083708 -52.647825)
			(xy 244.090698 -52.65547) (xy 244.734334 -53.299106) (xy 244.734842 -53.299614) (xy 244.742221 -53.306202)
			(xy 244.76052 -53.313663) (xy 244.770402 -53.314092)
		)
		(stroke
			(width 0)
			(type solid)
		)
		(fill yes)
		(layer "In4.Cu")
		(net "P12V_E1S_0")
	)
	(gr_poly
		(pts
			(xy 199.67829 -387.192012) (xy 199.688361 -387.191591) (xy 199.70697 -387.183881) (xy 199.714358 -387.177026)
			(xy 203.30287 -383.588514) (xy 203.309706 -383.581112) (xy 203.317414 -383.562514) (xy 203.317856 -383.552446)
			(xy 203.317856 -375.653046) (xy 203.318291 -375.642981) (xy 203.326025 -375.624397) (xy 203.332842 -375.616978)
			(xy 205.330552 -373.619268) (xy 205.33795 -373.612422) (xy 205.356549 -373.604696) (xy 205.36662 -373.604282)
			(xy 225.436938 -373.604282) (xy 225.447006 -373.604711) (xy 225.465602 -373.612434) (xy 225.473006 -373.619268)
			(xy 229.499668 -377.64593) (xy 229.506513 -377.653329) (xy 229.514242 -377.671927) (xy 229.514654 -377.681998)
			(xy 229.514654 -377.692666) (xy 229.515091 -377.70273) (xy 229.522828 -377.721312) (xy 229.52964 -377.728734)
			(xy 235.313474 -383.512568) (xy 235.315252 -383.512568) (xy 235.510324 -383.70764) (xy 235.515404 -383.70764)
			(xy 235.597446 -383.789682) (xy 235.604846 -383.796523) (xy 235.623444 -383.804244) (xy 235.633514 -383.804668)
			(xy 274.148804 -383.804668) (xy 274.158873 -383.804243) (xy 274.177474 -383.796524) (xy 274.184872 -383.789682)
			(xy 274.70608 -383.268474) (xy 274.712925 -383.261075) (xy 274.720653 -383.242477) (xy 274.721066 -383.232406)
			(xy 274.721066 -382.297178) (xy 274.71751 -382.284478) (xy 274.71497 -382.279906) (xy 274.710919 -382.273497)
			(xy 274.706402 -382.259033) (xy 274.70608 -382.251458) (xy 274.70608 -381.9271) (xy 274.705953 -381.922553)
			(xy 274.704288 -381.913611) (xy 274.702778 -381.90932) (xy 274.700238 -381.902462) (xy 274.685252 -381.885698)
			(xy 274.663916 -381.861822) (xy 274.663408 -381.860044) (xy 274.662646 -381.85725) (xy 274.656042 -381.848614)
			(xy 274.630992 -381.815266) (xy 274.586529 -381.744696) (xy 274.548864 -381.670274) (xy 274.51833 -381.592654)
			(xy 274.495193 -381.512516) (xy 274.479658 -381.430566) (xy 274.47186 -381.347521) (xy 274.471384 -381.305816)
			(xy 274.471384 -381.3048) (xy 274.472108 -381.254965) (xy 274.483314 -381.155926) (xy 274.493736 -381.107188)
			(xy 274.495514 -381.099822) (xy 274.49653 -381.094996) (xy 274.494244 -381.084836) (xy 274.49285 -381.079483)
			(xy 274.488108 -381.069492) (xy 274.484846 -381.065024) (xy 274.482306 -381.061722) (xy 274.482052 -381.061722)
			(xy 274.43811 -381.005588) (xy 274.434808 -381.00127) (xy 274.427195 -380.992629) (xy 274.406436 -380.982707)
			(xy 274.39493 -380.98222) (xy 273.990562 -380.98222) (xy 273.985466 -380.982336) (xy 273.975483 -380.98439)
			(xy 273.97075 -380.986284) (xy 273.967481 -380.987732) (xy 273.961362 -380.991431) (xy 273.958558 -380.99365)
			(xy 273.958304 -380.99365) (xy 273.957288 -380.994666) (xy 273.954748 -380.997206) (xy 273.852386 -381.099314)
			(xy 273.852132 -381.099568) (xy 273.849425 -381.102418) (xy 273.844828 -381.108795) (xy 273.842988 -381.112268)
			(xy 273.840408 -381.117696) (xy 273.837591 -381.129375) (xy 273.8374 -381.135382) (xy 273.8374 -381.826262)
			(xy 273.836965 -381.836327) (xy 273.829235 -381.854915) (xy 273.822414 -381.86233) (xy 273.518376 -382.166368)
			(xy 273.510978 -382.173214) (xy 273.492379 -382.180945) (xy 273.482308 -382.181354) (xy 272.208752 -382.181354)
			(xy 272.202148 -382.183132) (xy 272.158281 -382.194253) (xy 272.06858 -382.206224) (xy 272.023332 -382.207008)
			(xy 269.359888 -382.207008) (xy 269.314639 -382.206251) (xy 269.224936 -382.194268) (xy 269.181072 -382.183132)
			(xy 269.174468 -382.181354) (xy 269.066264 -382.181354) (xy 269.056198 -382.180923) (xy 269.037607 -382.173194)
			(xy 269.030196 -382.166368) (xy 268.834616 -381.970788) (xy 268.832584 -381.968756) (xy 268.801928 -381.940683)
			(xy 268.745415 -381.879716) (xy 268.694838 -381.813742) (xy 268.650638 -381.743336) (xy 268.6132 -381.669113)
			(xy 268.582852 -381.59172) (xy 268.559858 -381.511833) (xy 268.544419 -381.430149) (xy 268.53667 -381.347381)
			(xy 268.536166 -381.305816) (xy 268.536973 -381.253175) (xy 268.549454 -381.148635) (xy 268.561058 -381.097282)
			(xy 268.561566 -381.094742) (xy 268.55928 -381.084836) (xy 268.557877 -381.079604) (xy 268.553128 -381.06987)
			(xy 268.549882 -381.065532) (xy 268.547088 -381.061722) (xy 268.503146 -381.005588) (xy 268.499844 -381.00127)
			(xy 268.492233 -380.992623) (xy 268.471474 -380.982686) (xy 268.459966 -380.98222) (xy 268.055598 -380.98222)
			(xy 268.050501 -380.982333) (xy 268.040515 -380.98438) (xy 268.035786 -380.986284) (xy 268.032515 -380.98773)
			(xy 268.026393 -380.991425) (xy 268.023594 -380.99365) (xy 268.02334 -380.99365) (xy 268.022324 -380.994666)
			(xy 268.019784 -380.997206) (xy 267.917422 -381.099314) (xy 267.917168 -381.099568) (xy 267.914459 -381.102417)
			(xy 267.90986 -381.108792) (xy 267.908024 -381.112268) (xy 267.905442 -381.117695) (xy 267.902623 -381.129375)
			(xy 267.902436 -381.135382) (xy 267.902436 -381.826262) (xy 267.902 -381.836326) (xy 267.894262 -381.854908)
			(xy 267.88745 -381.86233) (xy 267.586206 -382.163574) (xy 267.578809 -382.170424) (xy 267.560211 -382.178165)
			(xy 267.550138 -382.17856) (xy 266.202922 -382.17856) (xy 266.198096 -382.179576) (xy 266.15671 -382.186971)
			(xy 266.073003 -382.194861) (xy 266.030964 -382.195324) (xy 265.996468 -382.19499) (xy 265.927684 -382.189652)
			(xy 265.89355 -382.184656) (xy 265.889486 -382.184148) (xy 265.537442 -382.184148) (xy 265.533378 -382.184656)
			(xy 265.499246 -382.189663) (xy 265.43046 -382.195) (xy 265.395964 -382.195324) (xy 265.361468 -382.19499)
			(xy 265.292684 -382.189652) (xy 265.25855 -382.184656) (xy 265.254486 -382.184148) (xy 264.902442 -382.184148)
			(xy 264.898378 -382.184656) (xy 264.864246 -382.189663) (xy 264.79546 -382.195) (xy 264.760964 -382.195324)
			(xy 264.726468 -382.19499) (xy 264.657684 -382.189652) (xy 264.62355 -382.184656) (xy 264.619486 -382.184148)
			(xy 264.267442 -382.184148) (xy 264.263378 -382.184656) (xy 264.229246 -382.189663) (xy 264.16046 -382.195)
			(xy 264.125964 -382.195324) (xy 264.091468 -382.19499) (xy 264.022684 -382.189652) (xy 263.98855 -382.184656)
			(xy 263.984486 -382.184148) (xy 263.632442 -382.184148) (xy 263.628378 -382.184656) (xy 263.594246 -382.189663)
			(xy 263.52546 -382.195) (xy 263.490964 -382.195324) (xy 263.448925 -382.194861) (xy 263.365217 -382.186978)
			(xy 263.323832 -382.179576) (xy 263.319006 -382.17856) (xy 263.128506 -382.17856) (xy 263.118436 -382.178137)
			(xy 263.099834 -382.170419) (xy 263.092438 -382.163574) (xy 262.895334 -381.96647) (xy 262.893302 -381.964692)
			(xy 262.87857 -381.950976) (xy 262.865884 -381.938829) (xy 262.841366 -381.913676) (xy 262.829548 -381.900684)
			(xy 262.829294 -381.90043) (xy 262.810402 -381.879084) (xy 262.77507 -381.834345) (xy 262.758682 -381.811022)
			(xy 262.752332 -381.801624) (xy 262.728352 -381.76493) (xy 262.686915 -381.687678) (xy 262.653275 -381.606725)
			(xy 262.627757 -381.522858) (xy 262.610609 -381.436888) (xy 262.601998 -381.349648) (xy 262.601456 -381.305816)
			(xy 262.601456 -381.3048) (xy 262.602181 -381.254965) (xy 262.613387 -381.155927) (xy 262.623808 -381.107188)
			(xy 262.625586 -381.099822) (xy 262.626602 -381.094996) (xy 262.624316 -381.084836) (xy 262.622921 -381.079483)
			(xy 262.618177 -381.069494) (xy 262.614918 -381.065024) (xy 262.612378 -381.061722) (xy 262.612124 -381.061722)
			(xy 262.568182 -381.005588) (xy 262.56488 -381.00127) (xy 262.557265 -380.992634) (xy 262.536506 -380.982723)
			(xy 262.525002 -380.98222) (xy 262.120634 -380.98222) (xy 262.115536 -380.982329) (xy 262.105548 -380.98437)
			(xy 262.100822 -380.986284) (xy 262.097554 -380.987734) (xy 262.091437 -380.991435) (xy 262.08863 -380.99365)
			(xy 262.088376 -380.99365) (xy 262.08736 -380.994666) (xy 262.08482 -380.997206) (xy 261.982458 -381.099314)
			(xy 261.982204 -381.099568) (xy 261.979498 -381.102419) (xy 261.974904 -381.108797) (xy 261.97306 -381.112268)
			(xy 261.970477 -381.117695) (xy 261.967656 -381.129375) (xy 261.967472 -381.135382) (xy 261.967472 -381.826262)
			(xy 261.967037 -381.836327) (xy 261.959304 -381.854912) (xy 261.952486 -381.86233) (xy 261.67334 -382.141476)
			(xy 261.665939 -382.148315) (xy 261.647341 -382.156032) (xy 261.637272 -382.156462) (xy 260.430772 -382.156462)
			(xy 260.424618 -382.156627) (xy 260.412667 -382.159573) (xy 260.40715 -382.162304) (xy 260.394239 -382.16895)
			(xy 260.367942 -382.181274) (xy 260.354572 -382.186942) (xy 260.323129 -382.199639) (xy 260.258285 -382.219492)
			(xy 260.191799 -382.232854) (xy 260.124319 -382.239592) (xy 260.090412 -382.240028) (xy 257.517392 -382.240028)
			(xy 257.476252 -382.239374) (xy 257.394571 -382.229439) (xy 257.314665 -382.209811) (xy 257.237678 -382.180769)
			(xy 257.200908 -382.162304) (xy 257.195574 -382.15951) (xy 257.183636 -382.156462) (xy 257.171444 -382.156462)
			(xy 257.161379 -382.156028) (xy 257.142793 -382.148295) (xy 257.135376 -382.141476) (xy 256.96037 -381.96647)
			(xy 256.958338 -381.964692) (xy 256.942188 -381.949868) (xy 256.911187 -381.918865) (xy 256.896362 -381.902716)
			(xy 256.894584 -381.900684) (xy 256.876804 -381.882904) (xy 256.875788 -381.879348) (xy 256.871724 -381.874268)
			(xy 256.859598 -381.859468) (xy 256.836477 -381.828977) (xy 256.825496 -381.813308) (xy 256.82321 -381.810006)
			(xy 256.822702 -381.809498) (xy 256.821178 -381.807212) (xy 256.796626 -381.77022) (xy 256.754162 -381.692245)
			(xy 256.719673 -381.610429) (xy 256.693501 -381.525585) (xy 256.675906 -381.438557) (xy 256.667064 -381.35021)
			(xy 256.666492 -381.305816) (xy 256.666492 -381.3048) (xy 256.667216 -381.254965) (xy 256.678422 -381.155926)
			(xy 256.688844 -381.107188) (xy 256.690622 -381.099822) (xy 256.691638 -381.094996) (xy 256.689352 -381.084836)
			(xy 256.687955 -381.079484) (xy 256.683206 -381.069498) (xy 256.679954 -381.065024) (xy 256.677414 -381.061722)
			(xy 256.67716 -381.061722) (xy 256.633218 -381.005588) (xy 256.629916 -381.00127) (xy 256.622303 -380.992628)
			(xy 256.601544 -380.982702) (xy 256.590038 -380.98222) (xy 256.18567 -380.98222) (xy 256.180574 -380.982336)
			(xy 256.17059 -380.984388) (xy 256.165858 -380.986284) (xy 256.162588 -380.987732) (xy 256.156469 -380.99143)
			(xy 256.153666 -380.99365) (xy 256.153412 -380.99365) (xy 256.152396 -380.994666) (xy 256.149856 -380.997206)
			(xy 256.047494 -381.099314) (xy 256.04724 -381.099568) (xy 256.044532 -381.102418) (xy 256.039935 -381.108794)
			(xy 256.038096 -381.112268) (xy 256.035516 -381.117695) (xy 256.032698 -381.129375) (xy 256.032508 -381.135382)
			(xy 256.032508 -381.826262) (xy 256.032074 -381.836327) (xy 256.024345 -381.854916) (xy 256.017522 -381.86233)
			(xy 255.693672 -382.18618) (xy 255.686273 -382.193024) (xy 255.667675 -382.200752) (xy 255.657604 -382.201166)
			(xy 251.281184 -382.201166) (xy 251.271116 -382.200739) (xy 251.252519 -382.193017) (xy 251.245116 -382.18618)
			(xy 251.026422 -381.967486) (xy 251.02439 -381.965708) (xy 251.007888 -381.950602) (xy 250.976249 -381.918965)
			(xy 250.961144 -381.902462) (xy 250.960382 -381.901446) (xy 250.95962 -381.900684) (xy 250.953524 -381.893826)
			(xy 250.936415 -381.874088) (xy 250.904266 -381.832912) (xy 250.889262 -381.81153) (xy 250.8885 -381.810514)
			(xy 250.887738 -381.809498) (xy 250.862945 -381.772415) (xy 250.820073 -381.694183) (xy 250.785243 -381.612055)
			(xy 250.758806 -381.526853) (xy 250.741026 -381.439434) (xy 250.732083 -381.350674) (xy 250.731528 -381.30607)
			(xy 250.731528 -381.29845) (xy 250.731908 -381.272983) (xy 250.735212 -381.222152) (xy 250.738132 -381.19685)
			(xy 250.741181 -381.17343) (xy 250.74944 -381.126924) (xy 250.754642 -381.103886) (xy 250.754896 -381.103632)
			(xy 250.755658 -381.099822) (xy 250.759976 -381.082042) (xy 250.761754 -381.075438) (xy 250.761754 -381.06223)
			(xy 250.759976 -381.056134) (xy 250.758054 -381.049878) (xy 250.751499 -381.038555) (xy 250.747022 -381.033782)
			(xy 250.710192 -380.996952) (xy 250.707341 -380.994246) (xy 250.700963 -380.989652) (xy 250.697492 -380.987808)
			(xy 250.692066 -380.985221) (xy 250.680386 -380.982389) (xy 250.674378 -380.98222) (xy 250.250706 -380.98222)
			(xy 250.245609 -380.982332) (xy 250.235622 -380.984378) (xy 250.230894 -380.986284) (xy 250.227623 -380.98773)
			(xy 250.221501 -380.991424) (xy 250.218702 -380.99365) (xy 250.218448 -380.99365) (xy 250.217432 -380.994666)
			(xy 250.214892 -380.997206) (xy 250.11253 -381.099314) (xy 250.112276 -381.099568) (xy 250.109567 -381.102417)
			(xy 250.104967 -381.108792) (xy 250.103132 -381.112268) (xy 250.10055 -381.117695) (xy 250.09773 -381.129375)
			(xy 250.097544 -381.135382) (xy 250.097544 -381.826262) (xy 250.097108 -381.836326) (xy 250.089372 -381.854909)
			(xy 250.082558 -381.86233) (xy 249.72645 -382.218438) (xy 249.719052 -382.225283) (xy 249.700453 -382.233009)
			(xy 249.690382 -382.233424) (xy 245.536466 -382.233424) (xy 245.526398 -382.232995) (xy 245.5078 -382.225275)
			(xy 245.500398 -382.218438) (xy 245.4529 -382.17094) (xy 245.442994 -382.163066) (xy 245.43766 -382.160018)
			(xy 245.43131 -382.157986) (xy 245.41988 -382.15443) (xy 245.419372 -382.15443) (xy 245.406926 -382.150366)
			(xy 245.406418 -382.150366) (xy 245.365942 -382.136412) (xy 245.287633 -382.101791) (xy 245.213011 -382.059808)
			(xy 245.142767 -382.010852) (xy 245.07755 -381.955375) (xy 245.017963 -381.893891) (xy 244.964557 -381.826967)
			(xy 244.917826 -381.755223) (xy 244.878203 -381.679322) (xy 244.846053 -381.599966) (xy 244.821674 -381.51789)
			(xy 244.805291 -381.433851) (xy 244.797056 -381.348626) (xy 244.796564 -381.305816) (xy 244.796564 -381.3048)
			(xy 244.797289 -381.254965) (xy 244.808495 -381.155927) (xy 244.818916 -381.107188) (xy 244.820694 -381.099822)
			(xy 244.82171 -381.094996) (xy 244.819424 -381.084836) (xy 244.818029 -381.079483) (xy 244.813285 -381.069493)
			(xy 244.810026 -381.065024) (xy 244.807486 -381.061722) (xy 244.807232 -381.061722) (xy 244.76329 -381.005588)
			(xy 244.759988 -381.00127) (xy 244.752373 -380.992632) (xy 244.731614 -380.982718) (xy 244.72011 -380.98222)
			(xy 244.315742 -380.98222) (xy 244.310644 -380.982328) (xy 244.300655 -380.984367) (xy 244.29593 -380.986284)
			(xy 244.292661 -380.987733) (xy 244.286544 -380.991434) (xy 244.283738 -380.99365) (xy 244.283484 -380.99365)
			(xy 244.282468 -380.994666) (xy 244.279928 -380.997206) (xy 244.177566 -381.099314) (xy 244.177312 -381.099568)
			(xy 244.174606 -381.102419) (xy 244.170011 -381.108796) (xy 244.168168 -381.112268) (xy 244.165589 -381.117696)
			(xy 244.162773 -381.129375) (xy 244.16258 -381.135382) (xy 244.16258 -382.233678) (xy 244.162164 -382.243701)
			(xy 244.154497 -382.262222) (xy 244.140323 -382.276396) (xy 244.121803 -382.284063) (xy 244.11178 -382.284478)
			(xy 237.630208 -382.284478) (xy 237.611666 -382.276858) (xy 237.609888 -382.27508) (xy 237.24997 -382.27508)
			(xy 237.239903 -382.274651) (xy 237.221308 -382.266927) (xy 237.213902 -382.260094) (xy 237.173262 -382.219454)
			(xy 237.165864 -382.212608) (xy 237.147265 -382.204879) (xy 237.137194 -382.204468) (xy 236.85373 -382.204468)
			(xy 236.843666 -382.204031) (xy 236.825083 -382.196296) (xy 236.817662 -382.189482) (xy 236.647482 -382.019302)
			(xy 236.642148 -382.01473) (xy 236.610118 -381.98982) (xy 236.550227 -381.935065) (xy 236.495558 -381.875095)
			(xy 236.470698 -381.843026) (xy 236.469174 -381.84074) (xy 236.083602 -381.455168) (xy 236.07676 -381.447768)
			(xy 236.069037 -381.42917) (xy 236.068616 -381.4191) (xy 236.068616 -381.13589) (xy 236.068192 -381.12582)
			(xy 236.060476 -381.107217) (xy 236.05363 -381.099822) (xy 227.236274 -372.282466) (xy 227.228877 -372.275617)
			(xy 227.210278 -372.267881) (xy 227.200206 -372.26748) (xy 221.752922 -372.26748) (xy 221.741073 -372.268094)
			(xy 221.719871 -372.278681) (xy 221.712282 -372.2878) (xy 221.663514 -372.35257) (xy 221.656931 -372.362286)
			(xy 221.652554 -372.385317) (xy 221.655132 -372.396766) (xy 221.655132 -372.39702) (xy 221.661983 -372.422639)
			(xy 221.669375 -372.475153) (xy 221.669864 -372.501668) (xy 221.669378 -372.528919) (xy 221.661622 -372.582867)
			(xy 221.646267 -372.635162) (xy 221.623625 -372.684739) (xy 221.594159 -372.730589) (xy 221.558468 -372.77178)
			(xy 221.517277 -372.807471) (xy 221.471427 -372.836937) (xy 221.42185 -372.859579) (xy 221.369555 -372.874934)
			(xy 221.315607 -372.88269) (xy 221.261105 -372.88269) (xy 221.207157 -372.874934) (xy 221.154862 -372.859579)
			(xy 221.105285 -372.836937) (xy 221.059435 -372.807471) (xy 221.018244 -372.77178) (xy 220.982553 -372.730589)
			(xy 220.953087 -372.684739) (xy 220.930445 -372.635162) (xy 220.91509 -372.582867) (xy 220.907334 -372.528919)
			(xy 220.906848 -372.501668) (xy 220.907318 -372.475151) (xy 220.914708 -372.422635) (xy 220.92158 -372.39702)
			(xy 220.92158 -372.396766) (xy 220.924175 -372.385317) (xy 220.919793 -372.362284) (xy 220.913198 -372.35257)
			(xy 220.86443 -372.2878) (xy 220.856825 -372.278699) (xy 220.835634 -372.268112) (xy 220.82379 -372.26748)
			(xy 203.271882 -372.26748) (xy 203.261813 -372.267906) (xy 203.243211 -372.275623) (xy 203.235814 -372.282466)
			(xy 201.082402 -374.435878) (xy 201.075568 -374.443281) (xy 201.067862 -374.461879) (xy 201.067416 -374.471946)
			(xy 201.067416 -377.816872) (xy 202.044552 -377.816872) (xy 202.048623 -377.76125) (xy 202.060749 -377.706813)
			(xy 202.080672 -377.654722) (xy 202.107968 -377.606087) (xy 202.142054 -377.561944) (xy 202.182203 -377.523235)
			(xy 202.227561 -377.490784) (xy 202.277161 -377.465283) (xy 202.329945 -377.447276) (xy 202.384788 -377.437146)
			(xy 202.440522 -377.435109) (xy 202.495959 -377.441209) (xy 202.549916 -377.455315) (xy 202.601245 -377.477127)
			(xy 202.648851 -377.506181) (xy 202.691719 -377.541856) (xy 202.728936 -377.583393) (xy 202.759709 -377.629906)
			(xy 202.783381 -377.680403) (xy 202.799449 -377.73381) (xy 202.807569 -377.788986) (xy 202.808078 -377.816872)
			(xy 202.807569 -377.844758) (xy 202.799449 -377.899934) (xy 202.783381 -377.953341) (xy 202.759709 -378.003838)
			(xy 202.728936 -378.050351) (xy 202.691719 -378.091888) (xy 202.648851 -378.127563) (xy 202.601245 -378.156617)
			(xy 202.549916 -378.178429) (xy 202.495959 -378.192535) (xy 202.440522 -378.198635) (xy 202.384788 -378.196598)
			(xy 202.329945 -378.186468) (xy 202.277161 -378.168461) (xy 202.227561 -378.14296) (xy 202.182203 -378.110509)
			(xy 202.142054 -378.0718) (xy 202.107968 -378.027657) (xy 202.080672 -377.979022) (xy 202.060749 -377.926931)
			(xy 202.048623 -377.872494) (xy 202.044552 -377.816872) (xy 201.067416 -377.816872) (xy 201.067416 -383.208784)
			(xy 201.066978 -383.218848) (xy 201.059244 -383.237432) (xy 201.05243 -383.244852) (xy 198.497698 -385.799584)
			(xy 198.4903 -385.806432) (xy 198.471702 -385.814168) (xy 198.46163 -385.81457) (xy 196.097144 -385.81457)
			(xy 196.087078 -385.815003) (xy 196.068485 -385.822728) (xy 196.061076 -385.829556) (xy 195.957444 -385.933188)
			(xy 195.950591 -385.940584) (xy 195.942845 -385.959182) (xy 195.942458 -385.969256) (xy 195.942458 -386.895848)
			(xy 195.946268 -386.904738) (xy 195.948064 -386.909425) (xy 195.949976 -386.919277) (xy 195.950078 -386.924296)
			(xy 195.950078 -386.982462) (xy 195.950512 -386.992528) (xy 195.95824 -387.011118) (xy 195.965064 -387.01853)
			(xy 196.12356 -387.177026) (xy 196.130958 -387.183871) (xy 196.149557 -387.191596) (xy 196.159628 -387.192012)
		)
		(stroke
			(width 0)
			(type solid)
		)
		(fill yes)
		(layer "In4.Cu")
		(net "P12V_HSC_GATE2")
	)
	(gr_poly
		(pts
			(arc
				(start 194.446144 -441.481972)
				(mid 194.482065 -441.467093)
				(end 194.496944 -441.431172)
			)
			(arc
				(start 194.496944 -441.17006)
				(mid 194.792217 -440.457207)
				(end 195.50507 -440.161934)
			)
			(arc
				(start 276.314916 -440.161934)
				(mid 277.027769 -440.457207)
				(end 277.323042 -441.17006)
			)
			(arc
				(start 277.323042 -441.431172)
				(mid 277.337921 -441.467093)
				(end 277.373842 -441.481972)
			)
			(arc
				(start 463.300064 -441.481972)
				(mid 464.355064 -441.044976)
				(end 464.79206 -439.989976)
			)
			(arc
				(start 464.79206 -409.528264)
				(mid 464.983018 -408.568632)
				(end 465.526628 -407.75509)
			)
			(arc
				(start 467.355174 -405.926544)
				(mid 467.678507 -405.442687)
				(end 467.792054 -404.871936)
			)
			(arc
				(start 467.792054 -363.649514)
				(mid 467.554484 -364.078202)
				(end 467.284816 -364.48746)
			)
			(arc
				(start 467.284816 -404.871936)
				(mid 467.209909 -405.248606)
				(end 466.996526 -405.567896)
			)
			(arc
				(start 465.16798 -407.396442)
				(mid 464.51433 -408.374514)
				(end 464.284568 -409.528264)
			)
			(arc
				(start 464.284568 -439.989976)
				(mid 463.996213 -440.686125)
				(end 463.300064 -440.97448)
			)
			(xy 410.91104 -440.97448)
			(arc
				(start 410.90342 -440.976766)
				(mid 410.82774 -440.99441)
				(end 410.750258 -441.000388)
			)
			(arc
				(start 410.74975 -441.000388)
				(mid 410.672265 -440.994435)
				(end 410.596588 -440.976766)
			)
			(xy 410.588968 -440.97448) (xy 406.911048 -440.97448)
			(arc
				(start 406.903428 -440.976766)
				(mid 406.827748 -440.99441)
				(end 406.750266 -441.000388)
			)
			(arc
				(start 406.749758 -441.000388)
				(mid 406.672273 -440.994435)
				(end 406.596596 -440.976766)
			)
			(xy 406.588976 -440.97448) (xy 402.911056 -440.97448)
			(arc
				(start 402.903436 -440.976766)
				(mid 402.827756 -440.99441)
				(end 402.750274 -441.000388)
			)
			(arc
				(start 402.749766 -441.000388)
				(mid 402.672281 -440.994435)
				(end 402.596604 -440.976766)
			)
			(xy 402.588984 -440.97448) (xy 398.911064 -440.97448)
			(arc
				(start 398.903444 -440.976766)
				(mid 398.827764 -440.99441)
				(end 398.750282 -441.000388)
			)
			(arc
				(start 398.749774 -441.000388)
				(mid 398.672289 -440.994435)
				(end 398.596612 -440.976766)
			)
			(xy 398.588992 -440.97448) (xy 393.91082 -440.97448)
			(arc
				(start 393.9032 -440.976766)
				(mid 393.82752 -440.99441)
				(end 393.750038 -441.000388)
			)
			(arc
				(start 393.74953 -441.000388)
				(mid 393.672045 -440.994435)
				(end 393.596368 -440.976766)
			)
			(xy 393.588748 -440.97448) (xy 389.910828 -440.97448)
			(arc
				(start 389.903208 -440.976766)
				(mid 389.827528 -440.99441)
				(end 389.750046 -441.000388)
			)
			(arc
				(start 389.749538 -441.000388)
				(mid 389.672053 -440.994435)
				(end 389.596376 -440.976766)
			)
			(xy 389.588756 -440.97448) (xy 385.910836 -440.97448)
			(arc
				(start 385.903216 -440.976766)
				(mid 385.827536 -440.99441)
				(end 385.750054 -441.000388)
			)
			(arc
				(start 385.749546 -441.000388)
				(mid 385.672061 -440.994435)
				(end 385.596384 -440.976766)
			)
			(xy 385.588764 -440.97448) (xy 381.910844 -440.97448)
			(arc
				(start 381.903224 -440.976766)
				(mid 381.827544 -440.99441)
				(end 381.750062 -441.000388)
			)
			(arc
				(start 381.749554 -441.000388)
				(mid 381.672069 -440.994435)
				(end 381.596392 -440.976766)
			)
			(xy 381.588772 -440.97448) (xy 343.810844 -440.97448)
			(arc
				(start 343.803224 -440.976766)
				(mid 343.727544 -440.99441)
				(end 343.650062 -441.000388)
			)
			(arc
				(start 343.649554 -441.000388)
				(mid 343.572069 -440.994435)
				(end 343.496392 -440.976766)
			)
			(xy 343.488772 -440.97448) (xy 339.810852 -440.97448)
			(arc
				(start 339.803232 -440.976766)
				(mid 339.727552 -440.99441)
				(end 339.65007 -441.000388)
			)
			(arc
				(start 339.649562 -441.000388)
				(mid 339.572077 -440.994435)
				(end 339.4964 -440.976766)
			)
			(xy 339.48878 -440.97448) (xy 335.81086 -440.97448)
			(arc
				(start 335.80324 -440.976766)
				(mid 335.72756 -440.99441)
				(end 335.650078 -441.000388)
			)
			(arc
				(start 335.64957 -441.000388)
				(mid 335.572085 -440.994435)
				(end 335.496408 -440.976766)
			)
			(xy 335.488788 -440.97448) (xy 331.810868 -440.97448)
			(arc
				(start 331.803248 -440.976766)
				(mid 331.727568 -440.99441)
				(end 331.650086 -441.000388)
			)
			(arc
				(start 331.649578 -441.000388)
				(mid 331.572093 -440.994435)
				(end 331.496416 -440.976766)
			)
			(xy 331.488796 -440.97448) (xy 326.810878 -440.97448)
			(arc
				(start 326.803258 -440.976766)
				(mid 326.727578 -440.99441)
				(end 326.650096 -441.000388)
			)
			(arc
				(start 326.649588 -441.000388)
				(mid 326.572103 -440.994435)
				(end 326.496426 -440.976766)
			)
			(xy 326.488806 -440.97448) (xy 322.810886 -440.97448)
			(arc
				(start 322.803266 -440.976766)
				(mid 322.727586 -440.99441)
				(end 322.650104 -441.000388)
			)
			(arc
				(start 322.649596 -441.000388)
				(mid 322.572111 -440.994435)
				(end 322.496434 -440.976766)
			)
			(xy 322.488814 -440.97448) (xy 318.810894 -440.97448)
			(arc
				(start 318.803274 -440.976766)
				(mid 318.727594 -440.99441)
				(end 318.650112 -441.000388)
			)
			(arc
				(start 318.649604 -441.000388)
				(mid 318.572119 -440.994435)
				(end 318.496442 -440.976766)
			)
			(xy 318.488822 -440.97448) (xy 314.810902 -440.97448)
			(arc
				(start 314.803282 -440.976766)
				(mid 314.727602 -440.99441)
				(end 314.65012 -441.000388)
			)
			(arc
				(start 314.649612 -441.000388)
				(mid 314.572127 -440.994435)
				(end 314.49645 -440.976766)
			)
			(xy 314.48883 -440.97448)
			(arc
				(start 277.817834 -440.97448)
				(mid 277.314992 -440.031472)
				(end 276.314916 -439.654696)
			)
			(arc
				(start 195.50507 -439.654696)
				(mid 194.504998 -440.031475)
				(end 194.002152 -440.97448)
			)
			(xy 154.911044 -440.97448)
			(arc
				(start 154.903424 -440.976766)
				(mid 154.827744 -440.99441)
				(end 154.750262 -441.000388)
			)
			(arc
				(start 154.749754 -441.000388)
				(mid 154.672269 -440.994435)
				(end 154.596592 -440.976766)
			)
			(xy 154.588972 -440.97448) (xy 150.911052 -440.97448)
			(arc
				(start 150.903432 -440.976766)
				(mid 150.827752 -440.99441)
				(end 150.75027 -441.000388)
			)
			(arc
				(start 150.749762 -441.000388)
				(mid 150.672277 -440.994435)
				(end 150.5966 -440.976766)
			)
			(xy 150.58898 -440.97448) (xy 146.91106 -440.97448)
			(arc
				(start 146.90344 -440.976766)
				(mid 146.82776 -440.99441)
				(end 146.750278 -441.000388)
			)
			(arc
				(start 146.74977 -441.000388)
				(mid 146.672285 -440.994435)
				(end 146.596608 -440.976766)
			)
			(xy 146.588988 -440.97448) (xy 142.911068 -440.97448)
			(arc
				(start 142.903448 -440.976766)
				(mid 142.827768 -440.99441)
				(end 142.750286 -441.000388)
			)
			(arc
				(start 142.749778 -441.000388)
				(mid 142.672293 -440.994435)
				(end 142.596616 -440.976766)
			)
			(xy 142.588996 -440.97448) (xy 137.910824 -440.97448)
			(arc
				(start 137.903204 -440.976766)
				(mid 137.827524 -440.99441)
				(end 137.750042 -441.000388)
			)
			(arc
				(start 137.749534 -441.000388)
				(mid 137.672049 -440.994435)
				(end 137.596372 -440.976766)
			)
			(xy 137.588752 -440.97448) (xy 133.910832 -440.97448)
			(arc
				(start 133.903212 -440.976766)
				(mid 133.827532 -440.99441)
				(end 133.75005 -441.000388)
			)
			(arc
				(start 133.749542 -441.000388)
				(mid 133.672057 -440.994435)
				(end 133.59638 -440.976766)
			)
			(xy 133.58876 -440.97448) (xy 129.91084 -440.97448)
			(arc
				(start 129.90322 -440.976766)
				(mid 129.82754 -440.99441)
				(end 129.750058 -441.000388)
			)
			(arc
				(start 129.74955 -441.000388)
				(mid 129.672065 -440.994435)
				(end 129.596388 -440.976766)
			)
			(xy 129.588768 -440.97448) (xy 125.910848 -440.97448)
			(arc
				(start 125.903228 -440.976766)
				(mid 125.827548 -440.99441)
				(end 125.750066 -441.000388)
			)
			(arc
				(start 125.749558 -441.000388)
				(mid 125.672073 -440.994435)
				(end 125.596396 -440.976766)
			)
			(xy 125.588776 -440.97448) (xy 87.811102 -440.97448)
			(arc
				(start 87.803482 -440.976766)
				(mid 87.727802 -440.99441)
				(end 87.65032 -441.000388)
			)
			(arc
				(start 87.649812 -441.000388)
				(mid 87.572327 -440.994435)
				(end 87.49665 -440.976766)
			)
			(xy 87.48903 -440.97448) (xy 83.81111 -440.97448)
			(arc
				(start 83.80349 -440.976766)
				(mid 83.72781 -440.99441)
				(end 83.650328 -441.000388)
			)
			(arc
				(start 83.64982 -441.000388)
				(mid 83.572335 -440.994435)
				(end 83.496658 -440.976766)
			)
			(xy 83.489038 -440.97448) (xy 79.811118 -440.97448)
			(arc
				(start 79.803498 -440.976766)
				(mid 79.727818 -440.99441)
				(end 79.650336 -441.000388)
			)
			(arc
				(start 79.649828 -441.000388)
				(mid 79.572343 -440.994435)
				(end 79.496666 -440.976766)
			)
			(xy 79.489046 -440.97448) (xy 75.811126 -440.97448)
			(arc
				(start 75.803506 -440.976766)
				(mid 75.727826 -440.99441)
				(end 75.650344 -441.000388)
			)
			(arc
				(start 75.649836 -441.000388)
				(mid 75.572351 -440.994435)
				(end 75.496674 -440.976766)
			)
			(xy 75.489054 -440.97448) (xy 73.907142 -440.97448) (xy 73.38568 -440.97448) (xy 73.11517 -441.24499)
			(xy 68.368418 -441.24499) (xy 68.097908 -440.97448) (xy 67.441064 -440.97448) (xy 67.153028 -441.262516)
			(xy 63.13043 -441.262516) (xy 62.842394 -440.97448) (xy 62.810898 -440.97448)
			(arc
				(start 62.803278 -440.976766)
				(mid 62.727598 -440.99441)
				(end 62.650116 -441.000388)
			)
			(arc
				(start 62.649608 -441.000388)
				(mid 62.572123 -440.994435)
				(end 62.496446 -440.976766)
			)
			(xy 62.488826 -440.97448) (xy 58.810906 -440.97448)
			(arc
				(start 58.803286 -440.976766)
				(mid 58.727606 -440.99441)
				(end 58.650124 -441.000388)
			)
			(arc
				(start 58.649616 -441.000388)
				(mid 58.572131 -440.994435)
				(end 58.496454 -440.976766)
			)
			(xy 58.488834 -440.97448)
			(arc
				(start 8.50011 -440.97448)
				(mid 7.803871 -440.686141)
				(end 7.515352 -439.989976)
			)
			(arc
				(start 7.515352 -409.528518)
				(mid 7.285694 -408.374511)
				(end 6.63194 -407.396188)
			)
			(arc
				(start 3.303778 -404.068026)
				(mid 3.090447 -403.748703)
				(end 3.015488 -403.372066)
			)
			(arc
				(start 3.015488 -354.005896)
				(mid 3.011587 -353.986373)
				(end 3.000502 -353.969828)
			)
			(arc
				(start 2.800096 -353.769168)
				(mid 2.789034 -353.752751)
				(end 2.78511 -353.733354)
			)
			(arc
				(start 2.78511 -330.863194)
				(mid 2.78906 -330.843807)
				(end 2.800096 -330.82738)
			)
			(arc
				(start 3.000502 -330.62672)
				(mid 3.011613 -330.610186)
				(end 3.015488 -330.590652)
			)
			(arc
				(start 3.015488 -81.32826)
				(mid 2.785816 -80.174473)
				(end 2.132076 -79.196438)
			)
			(arc
				(start 1.303528 -78.36789)
				(mid 1.090411 -78.048655)
				(end 1.015492 -77.672184)
			)
			(arc
				(start 1.015492 -13.780008)
				(mid 1.303847 -13.083859)
				(end 1.999996 -12.795504)
			)
			(arc
				(start 11.102086 -12.795504)
				(mid 13.234194 -11.912198)
				(end 14.11732 -9.780016)
			)
			(arc
				(start 14.11732 -3.98907)
				(mid 14.115908 -3.977177)
				(end 14.111732 -3.965956)
			)
			(xy 14.098778 -3.94081) (xy 14.091412 -3.932174)
			(arc
				(start 14.086332 -3.928618)
				(mid 13.924474 -3.77767)
				(end 13.80236 -3.593084)
			)
			(xy 13.794232 -3.577082) (xy 13.762482 -3.56235)
			(arc
				(start 13.649198 -3.589274)
				(mid 13.62338 -3.604404)
				(end 13.61059 -3.631438)
			)
			(xy 13.610082 -3.638804)
			(arc
				(start 13.610082 -9.780016)
				(mid 12.875507 -11.553437)
				(end 11.102086 -12.288012)
			)
			(arc
				(start 1.999996 -12.288012)
				(mid 0.944996 -12.725008)
				(end 0.508 -13.780008)
			)
			(arc
				(start 0.508 -77.67193)
				(mid 0.621601 -78.242658)
				(end 0.94488 -78.726538)
			)
			(arc
				(start 1.773428 -79.555086)
				(mid 2.317047 -80.368624)
				(end 2.507996 -81.32826)
			)
			(arc
				(start 2.507996 -403.371812)
				(mid 2.621533 -403.942691)
				(end 2.944876 -404.426674)
			)
			(arc
				(start 6.273292 -407.75509)
				(mid 6.817042 -408.568731)
				(end 7.008114 -409.528518)
			)
			(arc
				(start 7.008114 -439.989976)
				(mid 7.44511 -441.044976)
				(end 8.50011 -441.481972)
			)
		)
		(stroke
			(width 0)
			(type solid)
		)
		(fill yes)
		(layer "In4.Cu")
		(net "GND")
	)
	(gr_poly
		(pts
			(xy 247.781064 -364.34776) (xy 247.791087 -364.347346) (xy 247.809609 -364.339681) (xy 247.823783 -364.325506)
			(xy 247.831447 -364.306983) (xy 247.831864 -364.29696) (xy 247.831864 -352.946462) (xy 247.832291 -352.914649)
			(xy 247.839413 -352.851423) (xy 247.853573 -352.789393) (xy 247.874595 -352.72934) (xy 247.902212 -352.67202)
			(xy 247.936077 -352.618155) (xy 247.975764 -352.568424) (xy 247.99798 -352.54565) (xy 251.861574 -348.682056)
			(xy 251.868417 -348.674656) (xy 251.876139 -348.656058) (xy 251.87656 -348.645988) (xy 251.87656 -336.238342)
			(xy 251.876125 -336.228277) (xy 251.868391 -336.209692) (xy 251.861574 -336.202274) (xy 248.048526 -332.389226)
			(xy 248.041352 -332.382621) (xy 248.023456 -332.374916) (xy 248.013728 -332.37424) (xy 247.933464 -332.372462)
			(xy 247.915176 -332.37932) (xy 247.90781 -332.386178) (xy 247.886583 -332.404935) (xy 247.839628 -332.436618)
			(xy 247.788507 -332.461013) (xy 247.734342 -332.477586) (xy 247.678322 -332.485972) (xy 247.65 -332.486508)
			(xy 247.622749 -332.486022) (xy 247.568801 -332.478266) (xy 247.516506 -332.462911) (xy 247.466929 -332.440269)
			(xy 247.421079 -332.410803) (xy 247.379888 -332.375112) (xy 247.344197 -332.333921) (xy 247.314731 -332.288071)
			(xy 247.292089 -332.238494) (xy 247.276734 -332.186199) (xy 247.268978 -332.132251) (xy 247.268978 -332.077749)
			(xy 247.276734 -332.023801) (xy 247.292089 -331.971506) (xy 247.314731 -331.921929) (xy 247.344197 -331.876079)
			(xy 247.379888 -331.834888) (xy 247.421079 -331.799197) (xy 247.466929 -331.769731) (xy 247.516506 -331.747089)
			(xy 247.568801 -331.731734) (xy 247.622749 -331.723978) (xy 247.65 -331.723492) (xy 247.675393 -331.723891)
			(xy 247.725729 -331.730647) (xy 247.75033 -331.736954) (xy 247.76176 -331.740002) (xy 247.785128 -331.73543)
			(xy 247.858534 -331.679296) (xy 247.86751 -331.671699) (xy 247.877945 -331.650654) (xy 247.8786 -331.63891)
			(xy 247.8786 -323.624702) (xy 247.878177 -323.614632) (xy 247.870463 -323.596027) (xy 247.863614 -323.588634)
			(xy 244.467126 -320.192146) (xy 244.459726 -320.185306) (xy 244.441127 -320.177591) (xy 244.431058 -320.17716)
			(xy 238.684562 -320.17716) (xy 238.674496 -320.177592) (xy 238.655907 -320.185322) (xy 238.648494 -320.192146)
			(xy 238.470186 -320.370454) (xy 238.463339 -320.377851) (xy 238.455611 -320.396451) (xy 238.4552 -320.406522)
			(xy 238.4552 -321.652138) (xy 238.45563 -321.662205) (xy 238.463354 -321.680799) (xy 238.470186 -321.688206)
			(xy 238.59998 -321.818) (xy 242.187982 -321.818) (xy 242.192053 -321.762378) (xy 242.204179 -321.707941)
			(xy 242.224102 -321.65585) (xy 242.251398 -321.607215) (xy 242.285484 -321.563072) (xy 242.325633 -321.524363)
			(xy 242.370991 -321.491912) (xy 242.420591 -321.466411) (xy 242.473375 -321.448404) (xy 242.528218 -321.438274)
			(xy 242.583952 -321.436237) (xy 242.639389 -321.442337) (xy 242.693346 -321.456443) (xy 242.744675 -321.478255)
			(xy 242.792281 -321.507309) (xy 242.835149 -321.542984) (xy 242.872366 -321.584521) (xy 242.903139 -321.631034)
			(xy 242.926811 -321.681531) (xy 242.942879 -321.734938) (xy 242.950999 -321.790114) (xy 242.951508 -321.818)
			(xy 242.950999 -321.845886) (xy 242.942879 -321.901062) (xy 242.926811 -321.954469) (xy 242.903139 -322.004966)
			(xy 242.872366 -322.051479) (xy 242.835149 -322.093016) (xy 242.792281 -322.128691) (xy 242.744675 -322.157745)
			(xy 242.693346 -322.179557) (xy 242.639389 -322.193663) (xy 242.583952 -322.199763) (xy 242.528218 -322.197726)
			(xy 242.473375 -322.187596) (xy 242.420591 -322.169589) (xy 242.370991 -322.144088) (xy 242.325633 -322.111637)
			(xy 242.285484 -322.072928) (xy 242.251398 -322.028785) (xy 242.224102 -321.98015) (xy 242.204179 -321.928059)
			(xy 242.192053 -321.873622) (xy 242.187982 -321.818) (xy 238.59998 -321.818) (xy 238.691674 -321.909694)
			(xy 238.699076 -321.916529) (xy 238.717675 -321.924238) (xy 238.727742 -321.92468) (xy 241.078258 -321.92468)
			(xy 241.088324 -321.925113) (xy 241.106915 -321.93284) (xy 241.114326 -321.939666) (xy 242.019074 -322.844414)
			(xy 242.026037 -322.850851) (xy 242.043377 -322.858489) (xy 242.062307 -322.859301) (xy 242.071398 -322.856606)
			(xy 242.171474 -322.822316) (xy 242.189762 -322.799964) (xy 242.19154 -322.785486) (xy 242.195524 -322.758226)
			(xy 242.210318 -322.705159) (xy 242.232592 -322.654773) (xy 242.261882 -322.608114) (xy 242.29758 -322.566154)
			(xy 242.338943 -322.529766) (xy 242.38511 -322.499707) (xy 242.435121 -322.476601) (xy 242.487935 -322.46093)
			(xy 242.542455 -322.45302) (xy 242.57 -322.452492) (xy 242.597251 -322.452978) (xy 242.651199 -322.460734)
			(xy 242.703494 -322.476089) (xy 242.753071 -322.498731) (xy 242.798921 -322.528197) (xy 242.840112 -322.563888)
			(xy 242.875803 -322.605079) (xy 242.905269 -322.650929) (xy 242.927911 -322.700506) (xy 242.943266 -322.752801)
			(xy 242.951022 -322.806749) (xy 242.951022 -322.861251) (xy 242.943266 -322.915199) (xy 242.927911 -322.967494)
			(xy 242.905269 -323.017071) (xy 242.875803 -323.062921) (xy 242.840112 -323.104112) (xy 242.798921 -323.139803)
			(xy 242.753071 -323.169269) (xy 242.703494 -323.191911) (xy 242.651199 -323.207266) (xy 242.597251 -323.215022)
			(xy 242.57 -323.215508) (xy 242.557901 -323.215424) (xy 242.533753 -323.213901) (xy 242.52174 -323.21246)
			(xy 242.510818 -323.21119) (xy 242.490244 -323.21754) (xy 242.424712 -323.275198) (xy 242.416912 -323.282733)
			(xy 242.407959 -323.302466) (xy 242.40744 -323.313298) (xy 242.40744 -323.370702) (xy 242.40793 -323.381546)
			(xy 242.416866 -323.401304) (xy 242.424712 -323.408802) (xy 242.490244 -323.46646) (xy 242.510818 -323.47281)
			(xy 242.52174 -323.47154) (xy 242.533754 -323.470115) (xy 242.557902 -323.46859) (xy 242.57 -323.468492)
			(xy 242.597251 -323.468978) (xy 242.651199 -323.476734) (xy 242.703494 -323.492089) (xy 242.753071 -323.514731)
			(xy 242.798921 -323.544197) (xy 242.840112 -323.579888) (xy 242.875803 -323.621079) (xy 242.905269 -323.666929)
			(xy 242.927911 -323.716506) (xy 242.943266 -323.768801) (xy 242.951022 -323.822749) (xy 242.951022 -323.85)
			(xy 244.220492 -323.85) (xy 244.221001 -323.819154) (xy 244.228477 -323.757915) (xy 244.243305 -323.698031)
			(xy 244.265269 -323.64038) (xy 244.294045 -323.58581) (xy 244.329212 -323.535121) (xy 244.370252 -323.48906)
			(xy 244.416563 -323.448301) (xy 244.467465 -323.413443) (xy 244.52221 -323.385) (xy 244.579993 -323.363387)
			(xy 244.609874 -323.355716) (xy 244.623336 -323.352414) (xy 244.642894 -323.333618) (xy 244.675406 -323.222874)
			(xy 244.668802 -323.196204) (xy 244.659404 -323.186552) (xy 244.637288 -323.162772) (xy 244.598598 -323.110615)
			(xy 244.566862 -323.053956) (xy 244.542597 -322.993719) (xy 244.526198 -322.930883) (xy 244.517931 -322.86647)
			(xy 244.517418 -322.834) (xy 244.517845 -322.8035) (xy 244.525153 -322.742938) (xy 244.539653 -322.683685)
			(xy 244.561136 -322.626592) (xy 244.589294 -322.572479) (xy 244.623722 -322.522122) (xy 244.663927 -322.476244)
			(xy 244.686328 -322.45554) (xy 244.69598 -322.44665) (xy 244.704616 -322.422266) (xy 244.686074 -322.311776)
			(xy 244.670072 -322.291456) (xy 244.65788 -322.286376) (xy 244.627613 -322.273007) (xy 244.570536 -322.239533)
			(xy 244.518281 -322.198941) (xy 244.471732 -322.151915) (xy 244.431675 -322.099249) (xy 244.398786 -322.041833)
			(xy 244.37362 -321.980637) (xy 244.356603 -321.916694) (xy 244.348023 -321.851084) (xy 244.347492 -321.818)
			(xy 244.347994 -321.786039) (xy 244.356005 -321.722621) (xy 244.371902 -321.660707) (xy 244.395434 -321.601274)
			(xy 244.426228 -321.545259) (xy 244.463801 -321.493544) (xy 244.507558 -321.446947) (xy 244.556811 -321.406202)
			(xy 244.610782 -321.371951) (xy 244.668621 -321.344734) (xy 244.729414 -321.324981) (xy 244.792204 -321.313003)
			(xy 244.856 -321.30899) (xy 244.919796 -321.313003) (xy 244.982586 -321.324981) (xy 245.043379 -321.344734)
			(xy 245.101218 -321.371951) (xy 245.155189 -321.406202) (xy 245.204442 -321.446947) (xy 245.248199 -321.493544)
			(xy 245.285772 -321.545259) (xy 245.316566 -321.601274) (xy 245.340098 -321.660707) (xy 245.355995 -321.722621)
			(xy 245.364006 -321.786039) (xy 245.364508 -321.818) (xy 245.364072 -321.8485) (xy 245.356765 -321.909061)
			(xy 245.342266 -321.968313) (xy 245.320784 -322.025406) (xy 245.292627 -322.07952) (xy 245.258201 -322.129877)
			(xy 245.217998 -322.175755) (xy 245.195598 -322.19646) (xy 245.185946 -322.20535) (xy 245.17731 -322.229734)
			(xy 245.195852 -322.340224) (xy 245.211854 -322.360544) (xy 245.224046 -322.365624) (xy 245.254319 -322.37898)
			(xy 245.311395 -322.412456) (xy 245.363649 -322.453051) (xy 245.410197 -322.500079) (xy 245.450253 -322.552747)
			(xy 245.483141 -322.610164) (xy 245.508306 -322.671361) (xy 245.525323 -322.735305) (xy 245.533904 -322.800915)
			(xy 245.534434 -322.834) (xy 245.533905 -322.864846) (xy 245.52643 -322.926082) (xy 245.511603 -322.985965)
			(xy 245.48964 -323.043615) (xy 245.460865 -323.098184) (xy 245.425701 -323.148872) (xy 245.384663 -323.194934)
			(xy 245.338354 -323.235694) (xy 245.287455 -323.270552) (xy 245.232713 -323.298997) (xy 245.174932 -323.320611)
			(xy 245.145052 -323.328284) (xy 245.13159 -323.331586) (xy 245.112032 -323.350382) (xy 245.07952 -323.461126)
			(xy 245.086124 -323.487796) (xy 245.095522 -323.497448) (xy 245.117643 -323.521224) (xy 245.156332 -323.573383)
			(xy 245.188066 -323.630042) (xy 245.21233 -323.69028) (xy 245.228728 -323.753117) (xy 245.236995 -323.817529)
			(xy 245.237508 -323.85) (xy 245.237054 -323.880464) (xy 245.229752 -323.940953) (xy 245.215289 -324.00014)
			(xy 245.204996 -324.028816) (xy 245.199916 -324.042532) (xy 245.205504 -324.07098) (xy 245.287546 -324.15861)
			(xy 245.315486 -324.16623) (xy 245.329456 -324.161912) (xy 245.365249 -324.151807) (xy 245.438828 -324.140969)
			(xy 245.476014 -324.140322) (xy 245.507554 -324.140782) (xy 245.570148 -324.148586) (xy 245.631297 -324.164073)
			(xy 245.69006 -324.187004) (xy 245.745536 -324.217027) (xy 245.796873 -324.253682) (xy 245.843281 -324.296405)
			(xy 245.884048 -324.34454) (xy 245.918549 -324.397348) (xy 245.946253 -324.454018) (xy 245.966734 -324.51368)
			(xy 245.979679 -324.575416) (xy 245.984888 -324.63828) (xy 245.982281 -324.701305) (xy 245.971899 -324.763524)
			(xy 245.953901 -324.823981) (xy 245.928562 -324.881748) (xy 245.896274 -324.935937) (xy 245.85753 -324.985715)
			(xy 245.812927 -325.03032) (xy 245.76315 -325.069065) (xy 245.708962 -325.101355) (xy 245.651196 -325.126695)
			(xy 245.59074 -325.144695) (xy 245.528521 -325.15508) (xy 245.465496 -325.157688) (xy 245.402632 -325.152481)
			(xy 245.340895 -325.139538) (xy 245.281233 -325.119059) (xy 245.224562 -325.091357) (xy 245.171753 -325.056858)
			(xy 245.123617 -325.016092) (xy 245.080892 -324.969685) (xy 245.044236 -324.91835) (xy 245.014211 -324.862875)
			(xy 244.991278 -324.804112) (xy 244.975789 -324.742964) (xy 244.967983 -324.68037) (xy 244.967506 -324.64883)
			(xy 244.967968 -324.618366) (xy 244.975266 -324.557877) (xy 244.989727 -324.49869) (xy 245.000018 -324.470014)
			(xy 245.005098 -324.456298) (xy 244.99951 -324.42785) (xy 244.917468 -324.34022) (xy 244.889528 -324.3326)
			(xy 244.875558 -324.336918) (xy 244.839765 -324.347021) (xy 244.766186 -324.35786) (xy 244.729 -324.358508)
			(xy 244.698269 -324.358044) (xy 244.637255 -324.350635) (xy 244.577579 -324.335927) (xy 244.520111 -324.314132)
			(xy 244.465689 -324.285569) (xy 244.415107 -324.250655) (xy 244.369102 -324.209898) (xy 244.328345 -324.163893)
			(xy 244.293431 -324.113311) (xy 244.264868 -324.058889) (xy 244.243073 -324.001421) (xy 244.228365 -323.941745)
			(xy 244.220956 -323.880731) (xy 244.220492 -323.85) (xy 242.951022 -323.85) (xy 242.951022 -323.877251)
			(xy 242.943266 -323.931199) (xy 242.927911 -323.983494) (xy 242.905269 -324.033071) (xy 242.875803 -324.078921)
			(xy 242.840112 -324.120112) (xy 242.798921 -324.155803) (xy 242.753071 -324.185269) (xy 242.703494 -324.207911)
			(xy 242.651199 -324.223266) (xy 242.597251 -324.231022) (xy 242.57 -324.231508) (xy 242.557901 -324.231424)
			(xy 242.533753 -324.229901) (xy 242.52174 -324.22846) (xy 242.510818 -324.22719) (xy 242.490244 -324.23354)
			(xy 242.424712 -324.291198) (xy 242.416912 -324.298733) (xy 242.407959 -324.318466) (xy 242.40744 -324.329298)
			(xy 242.40744 -324.386702) (xy 242.40793 -324.397546) (xy 242.416866 -324.417304) (xy 242.424712 -324.424802)
			(xy 242.490244 -324.48246) (xy 242.510818 -324.48881) (xy 242.52174 -324.48754) (xy 242.533754 -324.486115)
			(xy 242.557902 -324.48459) (xy 242.57 -324.484492) (xy 242.597251 -324.484978) (xy 242.651199 -324.492734)
			(xy 242.703494 -324.508089) (xy 242.753071 -324.530731) (xy 242.798921 -324.560197) (xy 242.840112 -324.595888)
			(xy 242.875803 -324.637079) (xy 242.905269 -324.682929) (xy 242.927911 -324.732506) (xy 242.943266 -324.784801)
			(xy 242.951022 -324.838749) (xy 242.951022 -324.893251) (xy 242.943266 -324.947199) (xy 242.927911 -324.999494)
			(xy 242.905269 -325.049071) (xy 242.875803 -325.094921) (xy 242.840112 -325.136112) (xy 242.798921 -325.171803)
			(xy 242.753071 -325.201269) (xy 242.703494 -325.223911) (xy 242.651199 -325.239266) (xy 242.597251 -325.247022)
			(xy 242.57 -325.247508) (xy 242.54507 -325.247102) (xy 242.495636 -325.240605) (xy 242.471448 -325.234554)
			(xy 242.464844 -325.232776) (xy 242.45824 -325.232776) (xy 242.448212 -325.233188) (xy 242.429677 -325.24085)
			(xy 242.415486 -325.255023) (xy 242.407801 -325.273548) (xy 242.40744 -325.283576) (xy 242.40744 -325.333868)
			(xy 242.407855 -325.343891) (xy 242.41552 -325.362412) (xy 242.429695 -325.376584) (xy 242.448217 -325.384247)
			(xy 242.45824 -325.384668) (xy 242.46332 -325.384668) (xy 242.4684 -325.383652) (xy 242.493528 -325.378879)
			(xy 242.544425 -325.373793) (xy 242.57 -325.373492) (xy 242.600731 -325.373956) (xy 242.661745 -325.381365)
			(xy 242.721421 -325.396073) (xy 242.778889 -325.417868) (xy 242.833311 -325.446431) (xy 242.883893 -325.481345)
			(xy 242.929898 -325.522102) (xy 242.970655 -325.568107) (xy 243.005569 -325.618689) (xy 243.034132 -325.673111)
			(xy 243.055927 -325.730579) (xy 243.070635 -325.790255) (xy 243.078044 -325.851269) (xy 243.078508 -325.882)
			(xy 243.078024 -325.913275) (xy 243.070343 -325.975351) (xy 243.055108 -326.036017) (xy 243.03255 -326.094358)
			(xy 243.00301 -326.149492) (xy 242.966932 -326.200589) (xy 242.924861 -326.246876) (xy 242.877433 -326.287656)
			(xy 242.851686 -326.305418) (xy 242.841528 -326.31288) (xy 242.829506 -326.334999) (xy 242.828826 -326.347582)
			(xy 242.828826 -326.432418) (xy 242.82954 -326.444999) (xy 242.841526 -326.46713) (xy 242.851686 -326.474582)
			(xy 242.877468 -326.492301) (xy 242.924917 -326.533072) (xy 242.967005 -326.579358) (xy 243.003096 -326.630458)
			(xy 243.032642 -326.685601) (xy 243.055199 -326.743953) (xy 243.070425 -326.804631) (xy 243.078089 -326.86672)
			(xy 243.078508 -326.898) (xy 243.078044 -326.928731) (xy 243.070635 -326.989745) (xy 243.055927 -327.049421)
			(xy 243.034132 -327.106889) (xy 243.005569 -327.161311) (xy 242.978159 -327.201022) (xy 245.640858 -327.201022)
			(xy 245.644929 -327.1454) (xy 245.657055 -327.090963) (xy 245.676978 -327.038872) (xy 245.704274 -326.990237)
			(xy 245.73836 -326.946094) (xy 245.778509 -326.907385) (xy 245.823867 -326.874934) (xy 245.873467 -326.849433)
			(xy 245.926251 -326.831426) (xy 245.981094 -326.821296) (xy 246.036828 -326.819259) (xy 246.092265 -326.825359)
			(xy 246.146222 -326.839465) (xy 246.197551 -326.861277) (xy 246.245157 -326.890331) (xy 246.288025 -326.926006)
			(xy 246.325242 -326.967543) (xy 246.356015 -327.014056) (xy 246.379687 -327.064553) (xy 246.395755 -327.11796)
			(xy 246.403875 -327.173136) (xy 246.404384 -327.201022) (xy 246.403875 -327.228908) (xy 246.395755 -327.284084)
			(xy 246.379687 -327.337491) (xy 246.356015 -327.387988) (xy 246.325242 -327.434501) (xy 246.288025 -327.476038)
			(xy 246.245157 -327.511713) (xy 246.197551 -327.540767) (xy 246.146222 -327.562579) (xy 246.092265 -327.576685)
			(xy 246.036828 -327.582785) (xy 245.981094 -327.580748) (xy 245.926251 -327.570618) (xy 245.873467 -327.552611)
			(xy 245.823867 -327.52711) (xy 245.778509 -327.494659) (xy 245.73836 -327.45595) (xy 245.704274 -327.411807)
			(xy 245.676978 -327.363172) (xy 245.657055 -327.311081) (xy 245.644929 -327.256644) (xy 245.640858 -327.201022)
			(xy 242.978159 -327.201022) (xy 242.970655 -327.211893) (xy 242.929898 -327.257898) (xy 242.883893 -327.298655)
			(xy 242.833311 -327.333569) (xy 242.778889 -327.362132) (xy 242.721421 -327.383927) (xy 242.661745 -327.398635)
			(xy 242.600731 -327.406044) (xy 242.57 -327.406508) (xy 242.557278 -327.40643) (xy 242.531866 -327.40516)
			(xy 242.5192 -327.403968) (xy 242.508278 -327.402952) (xy 242.488212 -327.409556) (xy 242.424204 -327.467468)
			(xy 242.416694 -327.475013) (xy 242.408029 -327.494432) (xy 242.40744 -327.50506) (xy 242.40744 -330.227251)
			(xy 244.982978 -330.227251) (xy 244.982978 -330.172749) (xy 244.990734 -330.118801) (xy 245.006089 -330.066506)
			(xy 245.028731 -330.016929) (xy 245.058197 -329.971079) (xy 245.093888 -329.929888) (xy 245.135079 -329.894197)
			(xy 245.180929 -329.864731) (xy 245.230506 -329.842089) (xy 245.282801 -329.826734) (xy 245.336749 -329.818978)
			(xy 245.364 -329.818492) (xy 245.39137 -329.81896) (xy 245.445549 -329.826778) (xy 245.498052 -329.842266)
			(xy 245.547799 -329.865108) (xy 245.593766 -329.894831) (xy 245.614698 -329.912472) (xy 245.62181 -329.918568)
			(xy 245.638828 -329.924918) (xy 245.724172 -329.924918) (xy 245.74119 -329.918568) (xy 245.748302 -329.912472)
			(xy 245.769235 -329.894831) (xy 245.815203 -329.865107) (xy 245.864949 -329.842261) (xy 245.917451 -329.826765)
			(xy 245.971629 -329.818936) (xy 246.026371 -329.818936) (xy 246.080549 -329.826765) (xy 246.133051 -329.842261)
			(xy 246.182797 -329.865107) (xy 246.228765 -329.894831) (xy 246.249698 -329.912472) (xy 246.25681 -329.918568)
			(xy 246.273828 -329.924918) (xy 246.359172 -329.924918) (xy 246.37619 -329.918568) (xy 246.383302 -329.912472)
			(xy 246.404219 -329.894814) (xy 246.450196 -329.865106) (xy 246.499948 -329.842274) (xy 246.552452 -329.826787)
			(xy 246.60663 -329.818964) (xy 246.634 -329.818492) (xy 246.661251 -329.818978) (xy 246.715199 -329.826734)
			(xy 246.767494 -329.842089) (xy 246.817071 -329.864731) (xy 246.862921 -329.894197) (xy 246.904112 -329.929888)
			(xy 246.939803 -329.971079) (xy 246.969269 -330.016929) (xy 246.991911 -330.066506) (xy 247.007266 -330.118801)
			(xy 247.015022 -330.172749) (xy 247.015022 -330.227251) (xy 247.007266 -330.281199) (xy 246.991911 -330.333494)
			(xy 246.969269 -330.383071) (xy 246.939803 -330.428921) (xy 246.904112 -330.470112) (xy 246.862921 -330.505803)
			(xy 246.817071 -330.535269) (xy 246.767494 -330.557911) (xy 246.715199 -330.573266) (xy 246.661251 -330.581022)
			(xy 246.634 -330.581508) (xy 246.60663 -330.58104) (xy 246.552451 -330.573222) (xy 246.499948 -330.557734)
			(xy 246.450201 -330.534892) (xy 246.404234 -330.505169) (xy 246.383302 -330.487528) (xy 246.37619 -330.481432)
			(xy 246.359172 -330.475082) (xy 246.273828 -330.475082) (xy 246.25681 -330.481432) (xy 246.249698 -330.487528)
			(xy 246.228765 -330.505169) (xy 246.182797 -330.534893) (xy 246.133051 -330.557739) (xy 246.080549 -330.573235)
			(xy 246.026371 -330.581064) (xy 245.971629 -330.581064) (xy 245.917451 -330.573235) (xy 245.864949 -330.557739)
			(xy 245.815203 -330.534893) (xy 245.769235 -330.505169) (xy 245.748302 -330.487528) (xy 245.74119 -330.481432)
			(xy 245.724172 -330.475082) (xy 245.638828 -330.475082) (xy 245.62181 -330.481432) (xy 245.614698 -330.487528)
			(xy 245.593781 -330.505186) (xy 245.547804 -330.534894) (xy 245.498052 -330.557726) (xy 245.445548 -330.573213)
			(xy 245.39137 -330.581036) (xy 245.364 -330.581508) (xy 245.336749 -330.581022) (xy 245.282801 -330.573266)
			(xy 245.230506 -330.557911) (xy 245.180929 -330.535269) (xy 245.135079 -330.505803) (xy 245.093888 -330.470112)
			(xy 245.058197 -330.428921) (xy 245.028731 -330.383071) (xy 245.006089 -330.333494) (xy 244.990734 -330.281199)
			(xy 244.982978 -330.227251) (xy 242.40744 -330.227251) (xy 242.40744 -333.421439) (xy 246.483626 -333.421439)
			(xy 246.483626 -333.357517) (xy 246.491637 -333.294099) (xy 246.507534 -333.232185) (xy 246.531066 -333.172752)
			(xy 246.56186 -333.116737) (xy 246.599433 -333.065022) (xy 246.64319 -333.018425) (xy 246.692443 -332.97768)
			(xy 246.746414 -332.943429) (xy 246.804253 -332.916212) (xy 246.865046 -332.896459) (xy 246.927836 -332.884481)
			(xy 246.991632 -332.880468) (xy 247.055428 -332.884481) (xy 247.118218 -332.896459) (xy 247.179011 -332.916212)
			(xy 247.23685 -332.943429) (xy 247.290821 -332.97768) (xy 247.340074 -333.018425) (xy 247.383831 -333.065022)
			(xy 247.421404 -333.116737) (xy 247.452198 -333.172752) (xy 247.47573 -333.232185) (xy 247.491627 -333.294099)
			(xy 247.499638 -333.357517) (xy 247.50014 -333.389478) (xy 247.499638 -333.421439) (xy 247.491627 -333.484857)
			(xy 247.47573 -333.546771) (xy 247.452198 -333.606204) (xy 247.421404 -333.662219) (xy 247.383831 -333.713934)
			(xy 247.340074 -333.760531) (xy 247.290821 -333.801276) (xy 247.23685 -333.835527) (xy 247.179011 -333.862744)
			(xy 247.118218 -333.882497) (xy 247.055428 -333.894475) (xy 246.991632 -333.898489) (xy 246.927836 -333.894475)
			(xy 246.865046 -333.882497) (xy 246.804253 -333.862744) (xy 246.746414 -333.835527) (xy 246.692443 -333.801276)
			(xy 246.64319 -333.760531) (xy 246.599433 -333.713934) (xy 246.56186 -333.662219) (xy 246.531066 -333.606204)
			(xy 246.507534 -333.546771) (xy 246.491637 -333.484857) (xy 246.483626 -333.421439) (xy 242.40744 -333.421439)
			(xy 242.40744 -340.421214) (xy 245.362982 -340.421214) (xy 245.367053 -340.365592) (xy 245.379179 -340.311155)
			(xy 245.399102 -340.259064) (xy 245.426398 -340.210429) (xy 245.460484 -340.166286) (xy 245.500633 -340.127577)
			(xy 245.545991 -340.095126) (xy 245.595591 -340.069625) (xy 245.648375 -340.051618) (xy 245.703218 -340.041488)
			(xy 245.758952 -340.039451) (xy 245.814389 -340.045551) (xy 245.868346 -340.059657) (xy 245.919675 -340.081469)
			(xy 245.967281 -340.110523) (xy 246.010149 -340.146198) (xy 246.047366 -340.187735) (xy 246.078139 -340.234248)
			(xy 246.101811 -340.284745) (xy 246.117879 -340.338152) (xy 246.125999 -340.393328) (xy 246.126508 -340.421214)
			(xy 246.125999 -340.4491) (xy 246.117879 -340.504276) (xy 246.101811 -340.557683) (xy 246.078139 -340.60818)
			(xy 246.047366 -340.654693) (xy 246.010149 -340.69623) (xy 245.967281 -340.731905) (xy 245.919675 -340.760959)
			(xy 245.868346 -340.782771) (xy 245.814389 -340.796877) (xy 245.758952 -340.802977) (xy 245.703218 -340.80094)
			(xy 245.648375 -340.79081) (xy 245.595591 -340.772803) (xy 245.545991 -340.747302) (xy 245.500633 -340.714851)
			(xy 245.460484 -340.676142) (xy 245.426398 -340.631999) (xy 245.399102 -340.583364) (xy 245.379179 -340.531273)
			(xy 245.367053 -340.476836) (xy 245.362982 -340.421214) (xy 242.40744 -340.421214) (xy 242.40744 -343.229438)
			(xy 242.407871 -343.239504) (xy 242.4156 -343.258095) (xy 242.422426 -343.265506) (xy 246.530114 -347.373194)
			(xy 246.536971 -347.380588) (xy 246.544721 -347.399187) (xy 246.5451 -347.409262) (xy 246.5451 -348.926658)
			(xy 246.545534 -348.936723) (xy 246.553263 -348.955313) (xy 246.560086 -348.962726) (xy 246.726202 -349.128842)
			(xy 246.748369 -349.151653) (xy 246.788012 -349.201395) (xy 246.821838 -349.255263) (xy 246.849419 -349.31258)
			(xy 246.87041 -349.372624) (xy 246.884547 -349.43464) (xy 246.891651 -349.49785) (xy 246.892064 -349.529654)
			(xy 246.892064 -364.259876) (xy 246.892596 -364.269866) (xy 246.900299 -364.288308) (xy 246.90705 -364.29569)
			(xy 246.944134 -364.332774) (xy 246.951533 -364.339618) (xy 246.970131 -364.347344) (xy 246.980202 -364.34776)
		)
		(stroke
			(width 0)
			(type solid)
		)
		(fill yes)
		(layer "In4.Cu")
		(net "P5V_AUX")
	)
	(gr_poly
		(pts
			(xy 165.595046 -352.413316) (xy 165.605113 -352.412885) (xy 165.623707 -352.405161) (xy 165.631114 -352.39833)
			(xy 166.6113 -351.418144) (xy 166.618138 -351.410742) (xy 166.625852 -351.392144) (xy 166.626286 -351.382076)
			(xy 166.626286 -347.56344) (xy 166.625862 -347.553724) (xy 166.618647 -347.535681) (xy 166.605237 -347.521618)
			(xy 166.596568 -347.517212) (xy 166.498524 -347.472508) (xy 166.469568 -347.476826) (xy 166.457884 -347.486732)
			(xy 166.42868 -347.511532) (xy 166.366136 -347.555792) (xy 166.299464 -347.593549) (xy 166.26459 -347.609414)
			(xy 166.25443 -347.613732) (xy 166.240206 -347.629734) (xy 166.209726 -347.722698) (xy 166.212012 -347.74378)
			(xy 166.2176 -347.753432) (xy 166.229852 -347.775331) (xy 166.249139 -347.821657) (xy 166.262188 -347.870111)
			(xy 166.268772 -347.919858) (xy 166.269162 -347.944948) (xy 166.268632 -347.973508) (xy 166.260127 -348.029992)
			(xy 166.243298 -348.084578) (xy 166.218523 -348.136046) (xy 166.186353 -348.183246) (xy 166.167308 -348.204536)
			(xy 166.16045 -348.211902) (xy 166.153592 -348.229936) (xy 166.155116 -348.320614) (xy 166.162736 -348.338394)
			(xy 166.169848 -348.345506) (xy 166.190584 -348.367112) (xy 166.225746 -348.415586) (xy 166.252905 -348.468956)
			(xy 166.271395 -348.525913) (xy 166.280763 -348.585059) (xy 166.281354 -348.615) (xy 166.280869 -348.642893)
			(xy 166.272744 -348.698083) (xy 166.256667 -348.751502) (xy 166.232981 -348.80201) (xy 166.202191 -348.848529)
			(xy 166.164954 -348.890067) (xy 166.122064 -348.925739) (xy 166.098474 -348.940628) (xy 166.089076 -348.94647)
			(xy 166.076884 -348.964504) (xy 166.059612 -349.061024) (xy 166.064946 -349.082106) (xy 166.071804 -349.090742)
			(xy 166.087462 -349.111063) (xy 166.113759 -349.155111) (xy 166.133909 -349.202289) (xy 166.147547 -349.251744)
			(xy 166.154425 -349.302582) (xy 166.154862 -349.328232) (xy 166.154247 -349.359054) (xy 166.144297 -349.41989)
			(xy 166.124709 -349.47834) (xy 166.095991 -349.532887) (xy 166.0779 -349.557848) (xy 166.07155 -349.56623)
			(xy 166.066724 -349.58655) (xy 166.082726 -349.680276) (xy 166.094156 -349.697802) (xy 166.102792 -349.703644)
			(xy 166.124892 -349.718876) (xy 166.164994 -349.75455) (xy 166.199702 -349.795492) (xy 166.228331 -349.840893)
			(xy 166.250316 -349.889857) (xy 166.265223 -349.941419) (xy 166.272758 -349.994561) (xy 166.273226 -350.021398)
			(xy 166.27274 -350.048649) (xy 166.264984 -350.102597) (xy 166.249629 -350.154892) (xy 166.226987 -350.204469)
			(xy 166.197521 -350.250319) (xy 166.16183 -350.29151) (xy 166.120639 -350.327201) (xy 166.074789 -350.356667)
			(xy 166.025212 -350.379309) (xy 165.972917 -350.394664) (xy 165.918969 -350.40242) (xy 165.864467 -350.40242)
			(xy 165.810519 -350.394664) (xy 165.758224 -350.379309) (xy 165.708647 -350.356667) (xy 165.662797 -350.327201)
			(xy 165.621606 -350.29151) (xy 165.585915 -350.250319) (xy 165.556449 -350.204469) (xy 165.533807 -350.154892)
			(xy 165.518452 -350.102597) (xy 165.510696 -350.048649) (xy 165.51021 -350.021398) (xy 165.510823 -349.990576)
			(xy 165.52077 -349.929738) (xy 165.540358 -349.871288) (xy 165.569077 -349.816741) (xy 165.587172 -349.791782)
			(xy 165.593522 -349.7834) (xy 165.598348 -349.76308) (xy 165.582346 -349.669354) (xy 165.570916 -349.651828)
			(xy 165.56228 -349.645986) (xy 165.54018 -349.630754) (xy 165.500077 -349.595079) (xy 165.465369 -349.554137)
			(xy 165.436739 -349.508737) (xy 165.414752 -349.459773) (xy 165.399842 -349.408211) (xy 165.392304 -349.355069)
			(xy 165.391846 -349.328232) (xy 165.392336 -349.300342) (xy 165.400469 -349.245157) (xy 165.416553 -349.191745)
			(xy 165.440244 -349.141245) (xy 165.471038 -349.094734) (xy 165.508276 -349.053204) (xy 165.551166 -349.017539)
			(xy 165.574726 -349.002604) (xy 165.584124 -348.996762) (xy 165.596316 -348.978728) (xy 165.613588 -348.882208)
			(xy 165.608254 -348.861126) (xy 165.601396 -348.85249) (xy 165.585737 -348.832169) (xy 165.559435 -348.788122)
			(xy 165.539282 -348.740944) (xy 165.52564 -348.691489) (xy 165.518757 -348.640651) (xy 165.518338 -348.615)
			(xy 165.518872 -348.586441) (xy 165.527384 -348.529961) (xy 165.544218 -348.47538) (xy 165.568998 -348.423917)
			(xy 165.601172 -348.376723) (xy 165.620192 -348.355412) (xy 165.62705 -348.348046) (xy 165.633908 -348.330012)
			(xy 165.632384 -348.239334) (xy 165.624764 -348.221554) (xy 165.617652 -348.214442) (xy 165.596919 -348.192835)
			(xy 165.561764 -348.14436) (xy 165.534612 -348.090989) (xy 165.51613 -348.034032) (xy 165.50677 -347.974888)
			(xy 165.506146 -347.944948) (xy 165.506555 -347.919728) (xy 165.513205 -347.869727) (xy 165.526381 -347.821038)
			(xy 165.545855 -347.774508) (xy 165.571287 -347.730948) (xy 165.58641 -347.71076) (xy 165.593268 -347.702124)
			(xy 165.598348 -347.681296) (xy 165.580822 -347.58503) (xy 165.568884 -347.567504) (xy 165.559232 -347.561662)
			(xy 165.526276 -347.540905) (xy 165.464348 -347.493664) (xy 165.407558 -347.440356) (xy 165.356499 -347.381536)
			(xy 165.311702 -347.317817) (xy 165.273634 -347.249864) (xy 165.242692 -347.178383) (xy 165.219199 -347.104121)
			(xy 165.203398 -347.027851) (xy 165.195456 -346.950367) (xy 165.194996 -346.911422) (xy 165.195504 -346.88653)
			(xy 165.195464 -346.877924) (xy 165.190336 -346.861507) (xy 165.180073 -346.847705) (xy 165.173152 -346.842588)
			(xy 165.142639 -346.82136) (xy 165.085465 -346.773853) (xy 165.033188 -346.721005) (xy 164.986303 -346.663319)
			(xy 164.945258 -346.601343) (xy 164.91044 -346.535665) (xy 164.882181 -346.46691) (xy 164.86075 -346.395731)
			(xy 164.846351 -346.322803) (xy 164.839119 -346.24882) (xy 164.838634 -346.211652) (xy 164.839123 -346.173007)
			(xy 164.846943 -346.096113) (xy 164.862501 -346.020405) (xy 164.885639 -345.946659) (xy 164.916119 -345.875632)
			(xy 164.953628 -345.808054) (xy 164.997782 -345.744616) (xy 165.048127 -345.685972) (xy 165.104146 -345.632721)
			(xy 165.165265 -345.585411) (xy 165.230858 -345.544527) (xy 165.300249 -345.510489) (xy 165.372729 -345.483646)
			(xy 165.447552 -345.464273) (xy 165.523951 -345.452569) (xy 165.601142 -345.448654) (xy 165.678333 -345.452569)
			(xy 165.754732 -345.464273) (xy 165.829555 -345.483646) (xy 165.902035 -345.510489) (xy 165.971426 -345.544527)
			(xy 166.037019 -345.585411) (xy 166.098138 -345.632721) (xy 166.154157 -345.685972) (xy 166.204502 -345.744616)
			(xy 166.248656 -345.808054) (xy 166.286165 -345.875632) (xy 166.316645 -345.946659) (xy 166.339783 -346.020405)
			(xy 166.355341 -346.096113) (xy 166.363161 -346.173007) (xy 166.36365 -346.211652) (xy 166.363142 -346.236544)
			(xy 166.363177 -346.245153) (xy 166.368295 -346.261581) (xy 166.37855 -346.275398) (xy 166.385494 -346.280486)
			(xy 166.40431 -346.293432) (xy 166.44053 -346.321264) (xy 166.457884 -346.336112) (xy 166.469568 -346.346018)
			(xy 166.498524 -346.350336) (xy 166.596568 -346.305632) (xy 166.60523 -346.301211) (xy 166.618647 -346.287156)
			(xy 166.625875 -346.269119) (xy 166.626286 -346.259404) (xy 166.626286 -345.30157) (xy 166.625857 -345.291503)
			(xy 166.618133 -345.272907) (xy 166.6113 -345.265502) (xy 165.033452 -343.687654) (xy 165.026053 -343.680809)
			(xy 165.007455 -343.673084) (xy 164.997384 -343.672668) (xy 161.71037 -343.672668) (xy 161.699354 -343.673213)
			(xy 161.679344 -343.682436) (xy 161.671762 -343.690448) (xy 161.614104 -343.757758) (xy 161.608262 -343.779094)
			(xy 161.61004 -343.790016) (xy 161.612211 -343.804842) (xy 161.614496 -343.834722) (xy 161.614612 -343.849706)
			(xy 161.614126 -343.876957) (xy 161.606369 -343.930904) (xy 161.591013 -343.983199) (xy 161.568372 -344.032775)
			(xy 161.538905 -344.078625) (xy 161.503214 -344.119815) (xy 161.462024 -344.155506) (xy 161.416174 -344.184973)
			(xy 161.366597 -344.207614) (xy 161.314302 -344.222969) (xy 161.260355 -344.230726) (xy 161.233104 -344.231214)
			(xy 161.206484 -344.230752) (xy 161.15376 -344.223352) (xy 161.102578 -344.208695) (xy 161.053929 -344.187065)
			(xy 161.008759 -344.158884) (xy 160.967945 -344.124697) (xy 160.93228 -344.085168) (xy 160.902455 -344.041066)
			(xy 160.879051 -343.993246) (xy 160.870392 -343.96807) (xy 160.866328 -343.95537) (xy 160.847024 -343.93759)
			(xy 160.749742 -343.914476) (xy 160.741237 -343.91277) (xy 160.723994 -343.914564) (xy 160.708357 -343.922045)
			(xy 160.70199 -343.927938) (xy 160.151318 -344.47861) (xy 160.144506 -344.485978) (xy 160.136789 -344.504484)
			(xy 160.136753 -344.524535) (xy 160.140142 -344.533982) (xy 160.146238 -344.54846) (xy 160.171384 -344.565224)
			(xy 160.626552 -344.565224) (xy 160.651548 -344.565861) (xy 160.700572 -344.57566) (xy 160.746744 -344.594833)
			(xy 160.788289 -344.622643) (xy 160.806384 -344.6399) (xy 160.85566 -344.689176) (xy 160.874202 -344.696796)
			(xy 160.884616 -344.696796) (xy 160.911891 -344.697226) (xy 160.965894 -344.704927) (xy 161.01825 -344.720241)
			(xy 161.067891 -344.742856) (xy 161.113805 -344.772311) (xy 161.155055 -344.808005) (xy 161.190801 -344.849211)
			(xy 161.220313 -344.895087) (xy 161.242991 -344.944699) (xy 161.258371 -344.997036) (xy 161.26614 -345.051029)
			(xy 161.266632 -345.078304) (xy 161.266146 -345.105556) (xy 161.258389 -345.159504) (xy 161.243034 -345.2118)
			(xy 161.220393 -345.261378) (xy 161.190927 -345.30723) (xy 161.155236 -345.348421) (xy 161.114046 -345.384115)
			(xy 161.068196 -345.413583) (xy 161.018619 -345.436227) (xy 160.966324 -345.451585) (xy 160.912376 -345.459345)
			(xy 160.885124 -345.459812) (xy 160.857209 -345.459327) (xy 160.801975 -345.451191) (xy 160.748518 -345.435091)
			(xy 160.697978 -345.411369) (xy 160.651437 -345.380533) (xy 160.609888 -345.343242) (xy 160.574219 -345.300292)
			(xy 160.545193 -345.252601) (xy 160.523429 -345.201188) (xy 160.509392 -345.147152) (xy 160.505902 -345.119452)
			(xy 160.503616 -345.099894) (xy 160.474914 -345.07424) (xy 159.57677 -345.07424) (xy 159.566806 -345.074721)
			(xy 159.548376 -345.082304) (xy 159.540956 -345.088972) (xy 159.220154 -345.409774) (xy 159.213313 -345.417174)
			(xy 159.205597 -345.435773) (xy 159.205168 -345.445842) (xy 159.205168 -347.003878) (xy 160.322512 -347.003878)
			(xy 160.326583 -346.948256) (xy 160.338709 -346.893819) (xy 160.358632 -346.841728) (xy 160.385928 -346.793093)
			(xy 160.420014 -346.74895) (xy 160.460163 -346.710241) (xy 160.505521 -346.67779) (xy 160.555121 -346.652289)
			(xy 160.607905 -346.634282) (xy 160.662748 -346.624152) (xy 160.718482 -346.622115) (xy 160.773919 -346.628215)
			(xy 160.827876 -346.642321) (xy 160.879205 -346.664133) (xy 160.926811 -346.693187) (xy 160.969679 -346.728862)
			(xy 161.006896 -346.770399) (xy 161.037669 -346.816912) (xy 161.061341 -346.867409) (xy 161.077409 -346.920816)
			(xy 161.085529 -346.975992) (xy 161.086038 -347.003878) (xy 161.846512 -347.003878) (xy 161.850583 -346.948256)
			(xy 161.862709 -346.893819) (xy 161.882632 -346.841728) (xy 161.909928 -346.793093) (xy 161.944014 -346.74895)
			(xy 161.984163 -346.710241) (xy 162.029521 -346.67779) (xy 162.079121 -346.652289) (xy 162.131905 -346.634282)
			(xy 162.186748 -346.624152) (xy 162.242482 -346.622115) (xy 162.297919 -346.628215) (xy 162.351876 -346.642321)
			(xy 162.403205 -346.664133) (xy 162.450811 -346.693187) (xy 162.493679 -346.728862) (xy 162.530896 -346.770399)
			(xy 162.561669 -346.816912) (xy 162.585341 -346.867409) (xy 162.601409 -346.920816) (xy 162.609529 -346.975992)
			(xy 162.610038 -347.003878) (xy 163.395912 -347.003878) (xy 163.399983 -346.948256) (xy 163.412109 -346.893819)
			(xy 163.432032 -346.841728) (xy 163.459328 -346.793093) (xy 163.493414 -346.74895) (xy 163.533563 -346.710241)
			(xy 163.578921 -346.67779) (xy 163.628521 -346.652289) (xy 163.681305 -346.634282) (xy 163.736148 -346.624152)
			(xy 163.791882 -346.622115) (xy 163.847319 -346.628215) (xy 163.901276 -346.642321) (xy 163.952605 -346.664133)
			(xy 164.000211 -346.693187) (xy 164.043079 -346.728862) (xy 164.080296 -346.770399) (xy 164.111069 -346.816912)
			(xy 164.134741 -346.867409) (xy 164.150809 -346.920816) (xy 164.158929 -346.975992) (xy 164.159438 -347.003878)
			(xy 164.158929 -347.031764) (xy 164.150809 -347.08694) (xy 164.134741 -347.140347) (xy 164.111069 -347.190844)
			(xy 164.080296 -347.237357) (xy 164.043079 -347.278894) (xy 164.000211 -347.314569) (xy 163.952605 -347.343623)
			(xy 163.901276 -347.365435) (xy 163.847319 -347.379541) (xy 163.791882 -347.385641) (xy 163.736148 -347.383604)
			(xy 163.681305 -347.373474) (xy 163.628521 -347.355467) (xy 163.578921 -347.329966) (xy 163.533563 -347.297515)
			(xy 163.493414 -347.258806) (xy 163.459328 -347.214663) (xy 163.432032 -347.166028) (xy 163.412109 -347.113937)
			(xy 163.399983 -347.0595) (xy 163.395912 -347.003878) (xy 162.610038 -347.003878) (xy 162.609529 -347.031764)
			(xy 162.601409 -347.08694) (xy 162.585341 -347.140347) (xy 162.561669 -347.190844) (xy 162.530896 -347.237357)
			(xy 162.493679 -347.278894) (xy 162.450811 -347.314569) (xy 162.403205 -347.343623) (xy 162.351876 -347.365435)
			(xy 162.297919 -347.379541) (xy 162.242482 -347.385641) (xy 162.186748 -347.383604) (xy 162.131905 -347.373474)
			(xy 162.079121 -347.355467) (xy 162.029521 -347.329966) (xy 161.984163 -347.297515) (xy 161.944014 -347.258806)
			(xy 161.909928 -347.214663) (xy 161.882632 -347.166028) (xy 161.862709 -347.113937) (xy 161.850583 -347.0595)
			(xy 161.846512 -347.003878) (xy 161.086038 -347.003878) (xy 161.085529 -347.031764) (xy 161.077409 -347.08694)
			(xy 161.061341 -347.140347) (xy 161.037669 -347.190844) (xy 161.006896 -347.237357) (xy 160.969679 -347.278894)
			(xy 160.926811 -347.314569) (xy 160.879205 -347.343623) (xy 160.827876 -347.365435) (xy 160.773919 -347.379541)
			(xy 160.718482 -347.385641) (xy 160.662748 -347.383604) (xy 160.607905 -347.373474) (xy 160.555121 -347.355467)
			(xy 160.505521 -347.329966) (xy 160.460163 -347.297515) (xy 160.420014 -347.258806) (xy 160.385928 -347.214663)
			(xy 160.358632 -347.166028) (xy 160.338709 -347.113937) (xy 160.326583 -347.0595) (xy 160.322512 -347.003878)
			(xy 159.205168 -347.003878) (xy 159.205168 -348.215712) (xy 159.205709 -348.226071) (xy 159.213964 -348.245081)
			(xy 159.22117 -348.252542) (xy 159.249083 -348.279543) (xy 159.29986 -348.338308) (xy 159.344403 -348.401929)
			(xy 159.38225 -348.469748) (xy 159.413009 -348.541061) (xy 159.416861 -348.553278) (xy 160.322512 -348.553278)
			(xy 160.326583 -348.497656) (xy 160.338709 -348.443219) (xy 160.358632 -348.391128) (xy 160.385928 -348.342493)
			(xy 160.420014 -348.29835) (xy 160.460163 -348.259641) (xy 160.505521 -348.22719) (xy 160.555121 -348.201689)
			(xy 160.607905 -348.183682) (xy 160.662748 -348.173552) (xy 160.718482 -348.171515) (xy 160.773919 -348.177615)
			(xy 160.827876 -348.191721) (xy 160.879205 -348.213533) (xy 160.926811 -348.242587) (xy 160.969679 -348.278262)
			(xy 161.006896 -348.319799) (xy 161.037669 -348.366312) (xy 161.061341 -348.416809) (xy 161.077409 -348.470216)
			(xy 161.085529 -348.525392) (xy 161.086038 -348.553278) (xy 161.085529 -348.581164) (xy 161.077409 -348.63634)
			(xy 161.061341 -348.689747) (xy 161.053873 -348.705678) (xy 163.040312 -348.705678) (xy 163.044383 -348.650056)
			(xy 163.056509 -348.595619) (xy 163.076432 -348.543528) (xy 163.103728 -348.494893) (xy 163.137814 -348.45075)
			(xy 163.177963 -348.412041) (xy 163.223321 -348.37959) (xy 163.272921 -348.354089) (xy 163.325705 -348.336082)
			(xy 163.380548 -348.325952) (xy 163.436282 -348.323915) (xy 163.491719 -348.330015) (xy 163.545676 -348.344121)
			(xy 163.597005 -348.365933) (xy 163.644611 -348.394987) (xy 163.687479 -348.430662) (xy 163.724696 -348.472199)
			(xy 163.755469 -348.518712) (xy 163.779141 -348.569209) (xy 163.795209 -348.622616) (xy 163.803329 -348.677792)
			(xy 163.803838 -348.705678) (xy 163.803329 -348.733564) (xy 163.795209 -348.78874) (xy 163.779141 -348.842147)
			(xy 163.755469 -348.892644) (xy 163.724696 -348.939157) (xy 163.687479 -348.980694) (xy 163.644611 -349.016369)
			(xy 163.597005 -349.045423) (xy 163.545676 -349.067235) (xy 163.491719 -349.081341) (xy 163.436282 -349.087441)
			(xy 163.380548 -349.085404) (xy 163.325705 -349.075274) (xy 163.272921 -349.057267) (xy 163.223321 -349.031766)
			(xy 163.177963 -348.999315) (xy 163.137814 -348.960606) (xy 163.103728 -348.916463) (xy 163.076432 -348.867828)
			(xy 163.056509 -348.815737) (xy 163.044383 -348.7613) (xy 163.040312 -348.705678) (xy 161.053873 -348.705678)
			(xy 161.037669 -348.740244) (xy 161.006896 -348.786757) (xy 160.969679 -348.828294) (xy 160.926811 -348.863969)
			(xy 160.879205 -348.893023) (xy 160.827876 -348.914835) (xy 160.773919 -348.928941) (xy 160.718482 -348.935041)
			(xy 160.662748 -348.933004) (xy 160.607905 -348.922874) (xy 160.555121 -348.904867) (xy 160.505521 -348.879366)
			(xy 160.460163 -348.846915) (xy 160.420014 -348.808206) (xy 160.385928 -348.764063) (xy 160.358632 -348.715428)
			(xy 160.338709 -348.663337) (xy 160.326583 -348.6089) (xy 160.322512 -348.553278) (xy 159.416861 -348.553278)
			(xy 159.436362 -348.615131) (xy 159.452067 -348.691191) (xy 159.459961 -348.768453) (xy 159.459962 -348.846117)
			(xy 159.452071 -348.923379) (xy 159.436369 -348.99944) (xy 159.41302 -349.073511) (xy 159.382263 -349.144825)
			(xy 159.344419 -349.212645) (xy 159.299879 -349.276268) (xy 159.249103 -349.335035) (xy 159.22117 -349.362014)
			(xy 159.213296 -349.36938) (xy 159.205168 -349.388176) (xy 159.205168 -349.471234) (xy 159.215074 -349.491808)
			(xy 159.223964 -349.499174) (xy 159.254653 -349.524703) (xy 159.311096 -349.581157) (xy 159.361331 -349.643202)
			(xy 159.404805 -349.710157) (xy 159.441043 -349.781289) (xy 159.469649 -349.855819) (xy 159.490308 -349.932931)
			(xy 159.502795 -350.01178) (xy 159.506227 -350.077278) (xy 160.322512 -350.077278) (xy 160.326583 -350.021656)
			(xy 160.338709 -349.967219) (xy 160.358632 -349.915128) (xy 160.385928 -349.866493) (xy 160.420014 -349.82235)
			(xy 160.460163 -349.783641) (xy 160.505521 -349.75119) (xy 160.555121 -349.725689) (xy 160.607905 -349.707682)
			(xy 160.662748 -349.697552) (xy 160.718482 -349.695515) (xy 160.773919 -349.701615) (xy 160.827876 -349.715721)
			(xy 160.879205 -349.737533) (xy 160.926811 -349.766587) (xy 160.969679 -349.802262) (xy 161.006896 -349.843799)
			(xy 161.037669 -349.890312) (xy 161.061341 -349.940809) (xy 161.077409 -349.994216) (xy 161.085529 -350.049392)
			(xy 161.086038 -350.077278) (xy 161.846512 -350.077278) (xy 161.850583 -350.021656) (xy 161.862709 -349.967219)
			(xy 161.882632 -349.915128) (xy 161.909928 -349.866493) (xy 161.944014 -349.82235) (xy 161.984163 -349.783641)
			(xy 162.029521 -349.75119) (xy 162.079121 -349.725689) (xy 162.131905 -349.707682) (xy 162.186748 -349.697552)
			(xy 162.242482 -349.695515) (xy 162.297919 -349.701615) (xy 162.351876 -349.715721) (xy 162.403205 -349.737533)
			(xy 162.450811 -349.766587) (xy 162.493679 -349.802262) (xy 162.530896 -349.843799) (xy 162.561669 -349.890312)
			(xy 162.585341 -349.940809) (xy 162.601409 -349.994216) (xy 162.609529 -350.049392) (xy 162.610038 -350.077278)
			(xy 163.395912 -350.077278) (xy 163.399983 -350.021656) (xy 163.412109 -349.967219) (xy 163.432032 -349.915128)
			(xy 163.459328 -349.866493) (xy 163.493414 -349.82235) (xy 163.533563 -349.783641) (xy 163.578921 -349.75119)
			(xy 163.628521 -349.725689) (xy 163.681305 -349.707682) (xy 163.736148 -349.697552) (xy 163.791882 -349.695515)
			(xy 163.847319 -349.701615) (xy 163.901276 -349.715721) (xy 163.952605 -349.737533) (xy 164.000211 -349.766587)
			(xy 164.043079 -349.802262) (xy 164.080296 -349.843799) (xy 164.111069 -349.890312) (xy 164.134741 -349.940809)
			(xy 164.150809 -349.994216) (xy 164.158929 -350.049392) (xy 164.159438 -350.077278) (xy 164.158929 -350.105164)
			(xy 164.150809 -350.16034) (xy 164.134741 -350.213747) (xy 164.111069 -350.264244) (xy 164.080296 -350.310757)
			(xy 164.043079 -350.352294) (xy 164.000211 -350.387969) (xy 163.952605 -350.417023) (xy 163.901276 -350.438835)
			(xy 163.847319 -350.452941) (xy 163.791882 -350.459041) (xy 163.736148 -350.457004) (xy 163.681305 -350.446874)
			(xy 163.628521 -350.428867) (xy 163.578921 -350.403366) (xy 163.533563 -350.370915) (xy 163.493414 -350.332206)
			(xy 163.459328 -350.288063) (xy 163.432032 -350.239428) (xy 163.412109 -350.187337) (xy 163.399983 -350.1329)
			(xy 163.395912 -350.077278) (xy 162.610038 -350.077278) (xy 162.609529 -350.105164) (xy 162.601409 -350.16034)
			(xy 162.585341 -350.213747) (xy 162.561669 -350.264244) (xy 162.530896 -350.310757) (xy 162.493679 -350.352294)
			(xy 162.450811 -350.387969) (xy 162.403205 -350.417023) (xy 162.351876 -350.438835) (xy 162.297919 -350.452941)
			(xy 162.242482 -350.459041) (xy 162.186748 -350.457004) (xy 162.131905 -350.446874) (xy 162.079121 -350.428867)
			(xy 162.029521 -350.403366) (xy 161.984163 -350.370915) (xy 161.944014 -350.332206) (xy 161.909928 -350.288063)
			(xy 161.882632 -350.239428) (xy 161.862709 -350.187337) (xy 161.850583 -350.1329) (xy 161.846512 -350.077278)
			(xy 161.086038 -350.077278) (xy 161.085529 -350.105164) (xy 161.077409 -350.16034) (xy 161.061341 -350.213747)
			(xy 161.037669 -350.264244) (xy 161.006896 -350.310757) (xy 160.969679 -350.352294) (xy 160.926811 -350.387969)
			(xy 160.879205 -350.417023) (xy 160.827876 -350.438835) (xy 160.773919 -350.452941) (xy 160.718482 -350.459041)
			(xy 160.662748 -350.457004) (xy 160.607905 -350.446874) (xy 160.555121 -350.428867) (xy 160.505521 -350.403366)
			(xy 160.460163 -350.370915) (xy 160.420014 -350.332206) (xy 160.385928 -350.288063) (xy 160.358632 -350.239428)
			(xy 160.338709 -350.187337) (xy 160.326583 -350.1329) (xy 160.322512 -350.077278) (xy 159.506227 -350.077278)
			(xy 159.506972 -350.091501) (xy 159.502794 -350.171223) (xy 159.490307 -350.250071) (xy 159.469648 -350.327183)
			(xy 159.441042 -350.401713) (xy 159.404804 -350.472845) (xy 159.361329 -350.5398) (xy 159.311095 -350.601844)
			(xy 159.254651 -350.658299) (xy 159.223964 -350.68383) (xy 159.215074 -350.691196) (xy 159.205168 -350.71177)
			(xy 159.205168 -350.737678) (xy 159.216852 -350.759776) (xy 159.22752 -350.766888) (xy 159.259086 -350.788867)
			(xy 159.318082 -350.838227) (xy 159.371797 -350.893287) (xy 159.419684 -350.953485) (xy 159.44088 -350.985582)
			(xy 159.446976 -350.99498) (xy 159.464756 -351.006664) (xy 159.561022 -351.022158) (xy 159.581596 -351.01657)
			(xy 159.590232 -351.009712) (xy 159.619312 -350.986787) (xy 159.681158 -350.946057) (xy 159.74666 -350.911511)
			(xy 159.815202 -350.883474) (xy 159.886137 -350.862211) (xy 159.958799 -350.847921) (xy 160.032503 -350.840738)
			(xy 160.06953 -350.840294) (xy 160.108825 -350.84077) (xy 160.187001 -350.848829) (xy 160.263933 -350.86489)
			(xy 160.338803 -350.888782) (xy 160.410818 -350.920252) (xy 160.479212 -350.958965) (xy 160.543259 -351.00451)
			(xy 160.60228 -351.056404) (xy 160.629346 -351.084896) (xy 160.636204 -351.092516) (xy 160.654238 -351.100898)
			(xy 160.74644 -351.104454) (xy 160.764982 -351.09785) (xy 160.772602 -351.090738) (xy 160.802786 -351.063727)
			(xy 160.867904 -351.015546) (xy 160.93776 -350.974537) (xy 161.011568 -350.941159) (xy 161.088497 -350.91579)
			(xy 161.167681 -350.898714) (xy 161.248228 -350.890124) (xy 161.28873 -350.88957) (xy 161.327556 -350.890068)
			(xy 161.404802 -350.897987) (xy 161.480846 -350.91371) (xy 161.554899 -350.937075) (xy 161.626196 -350.967839)
			(xy 161.660332 -350.986344) (xy 161.671803 -350.991916) (xy 161.697271 -350.992201) (xy 161.708846 -350.986852)
			(xy 161.741857 -350.96987) (xy 161.81053 -350.941665) (xy 161.881621 -350.92027) (xy 161.954455 -350.905888)
			(xy 162.028342 -350.898657) (xy 162.065462 -350.898206) (xy 162.105398 -350.898709) (xy 162.184833 -350.907054)
			(xy 162.26296 -350.923657) (xy 162.338923 -350.948336) (xy 162.411891 -350.980821) (xy 162.481063 -351.020755)
			(xy 162.545681 -351.067701) (xy 162.605039 -351.121144) (xy 162.658484 -351.1805) (xy 162.705432 -351.245117)
			(xy 162.745368 -351.314288) (xy 162.777855 -351.387254) (xy 162.802537 -351.463217) (xy 162.819142 -351.541344)
			(xy 162.82749 -351.620778) (xy 162.82797 -351.660714) (xy 162.82745 -351.701392) (xy 162.818798 -351.782285)
			(xy 162.801584 -351.861798) (xy 162.776004 -351.939027) (xy 162.742347 -352.013093) (xy 162.700997 -352.083156)
			(xy 162.652423 -352.148418) (xy 162.597177 -352.208139) (xy 162.566858 -352.235262) (xy 162.55492 -352.245676)
			(xy 162.547046 -352.27641) (xy 162.586162 -352.380296) (xy 162.59022 -352.389779) (xy 162.604434 -352.404701)
			(xy 162.623358 -352.412862) (xy 162.63366 -352.413316)
		)
		(stroke
			(width 0)
			(type solid)
		)
		(fill yes)
		(layer "In4.Cu")
		(net "PVDD11_S3_P1_VCCS")
	)
	(gr_poly
		(pts
			(xy 376.422666 -150.759668) (xy 376.43249 -150.759142) (xy 376.450619 -150.751551) (xy 376.464484 -150.737621)
			(xy 376.471989 -150.719457) (xy 376.47245 -150.70963) (xy 376.47245 -149.791674) (xy 376.473002 -149.761692)
			(xy 376.482375 -149.702464) (xy 376.500902 -149.645433) (xy 376.528127 -149.592004) (xy 376.563377 -149.543495)
			(xy 376.58421 -149.521926) (xy 377.35129 -148.754846) (xy 377.358656 -148.739352) (xy 377.359418 -148.730462)
			(xy 377.362949 -148.699432) (xy 377.376627 -148.638496) (xy 377.39766 -148.579692) (xy 377.425732 -148.523904)
			(xy 377.460421 -148.471972) (xy 377.501205 -148.424675) (xy 377.547471 -148.382726) (xy 377.598523 -148.346754)
			(xy 377.653595 -148.317301) (xy 377.711857 -148.29481) (xy 377.772433 -148.279619) (xy 377.834414 -148.271956)
			(xy 377.86564 -148.271484) (xy 377.89637 -148.27195) (xy 377.95738 -148.279363) (xy 378.017053 -148.294075)
			(xy 378.074517 -148.315872) (xy 378.128935 -148.344436) (xy 378.179513 -148.379351) (xy 378.225515 -148.420108)
			(xy 378.266269 -148.466112) (xy 378.30118 -148.516693) (xy 378.329741 -148.571112) (xy 378.351535 -148.628578)
			(xy 378.366243 -148.688251) (xy 378.373652 -148.749262) (xy 378.374148 -148.779992) (xy 378.373679 -148.811222)
			(xy 378.366042 -148.873214) (xy 378.350871 -148.933804) (xy 378.328393 -148.992079) (xy 378.298947 -149.047163)
			(xy 378.262977 -149.098226) (xy 378.221023 -149.144499) (xy 378.173718 -149.185286) (xy 378.121774 -149.219972)
			(xy 378.065973 -149.248035) (xy 378.007155 -149.269053) (xy 377.946206 -149.282708) (xy 377.91517 -149.286214)
			(xy 377.90628 -149.286976) (xy 377.890786 -149.294342) (xy 377.873507 -149.311614) (xy 380.247904 -149.311614)
			(xy 380.251975 -149.255992) (xy 380.264101 -149.201555) (xy 380.284024 -149.149464) (xy 380.31132 -149.100829)
			(xy 380.345406 -149.056686) (xy 380.385555 -149.017977) (xy 380.430913 -148.985526) (xy 380.480513 -148.960025)
			(xy 380.533297 -148.942018) (xy 380.58814 -148.931888) (xy 380.643874 -148.929851) (xy 380.699311 -148.935951)
			(xy 380.753268 -148.950057) (xy 380.804597 -148.971869) (xy 380.852203 -149.000923) (xy 380.895071 -149.036598)
			(xy 380.932288 -149.078135) (xy 380.963061 -149.124648) (xy 380.986733 -149.175145) (xy 381.002801 -149.228552)
			(xy 381.010921 -149.283728) (xy 381.01143 -149.311614) (xy 381.010921 -149.3395) (xy 381.002801 -149.394676)
			(xy 380.986733 -149.448083) (xy 380.963061 -149.49858) (xy 380.932288 -149.545093) (xy 380.895071 -149.58663)
			(xy 380.852203 -149.622305) (xy 380.804597 -149.651359) (xy 380.753268 -149.673171) (xy 380.699311 -149.687277)
			(xy 380.643874 -149.693377) (xy 380.58814 -149.69134) (xy 380.533297 -149.68121) (xy 380.480513 -149.663203)
			(xy 380.430913 -149.637702) (xy 380.385555 -149.605251) (xy 380.345406 -149.566542) (xy 380.31132 -149.522399)
			(xy 380.284024 -149.473764) (xy 380.264101 -149.421673) (xy 380.251975 -149.367236) (xy 380.247904 -149.311614)
			(xy 377.873507 -149.311614) (xy 377.249944 -149.93493) (xy 377.243256 -149.942245) (xy 377.235779 -149.960584)
			(xy 377.235466 -149.97049) (xy 377.235466 -150.33244) (xy 377.23596 -150.342445) (xy 377.243626 -150.360929)
			(xy 377.257776 -150.375078) (xy 377.276261 -150.382741) (xy 377.286266 -150.38324) (xy 381.13589 -150.38324)
			(xy 381.14596 -150.383663) (xy 381.164563 -150.391379) (xy 381.171958 -150.398226) (xy 381.518414 -150.744682)
			(xy 381.525813 -150.751528) (xy 381.544411 -150.75926) (xy 381.554482 -150.759668) (xy 383.114804 -150.759668)
			(xy 383.124798 -150.75917) (xy 383.14327 -150.751531) (xy 383.157449 -150.737441) (xy 383.161794 -150.728426)
			(xy 383.16789 -150.713948) (xy 383.161794 -150.683976) (xy 380.648464 -148.170646) (xy 380.641066 -148.1638)
			(xy 380.622467 -148.156072) (xy 380.612396 -148.15566) (xy 379.521974 -148.15566) (xy 379.511907 -148.156089)
			(xy 379.493315 -148.163817) (xy 379.485906 -148.170646) (xy 379.400308 -148.256498) (xy 379.392942 -148.271992)
			(xy 379.39218 -148.280882) (xy 379.388647 -148.31191) (xy 379.374965 -148.372842) (xy 379.353928 -148.431641)
			(xy 379.325854 -148.487424) (xy 379.291164 -148.539352) (xy 379.25038 -148.586644) (xy 379.204114 -148.628589)
			(xy 379.153063 -148.664557) (xy 379.097993 -148.694007) (xy 379.039734 -148.716495) (xy 378.97916 -148.731685)
			(xy 378.917182 -148.739347) (xy 378.885958 -148.73986) (xy 378.855229 -148.739412) (xy 378.794218 -148.731999)
			(xy 378.734547 -148.717286) (xy 378.677083 -148.695487) (xy 378.622667 -148.666921) (xy 378.57209 -148.632004)
			(xy 378.526091 -148.591245) (xy 378.48534 -148.545239) (xy 378.450432 -148.494656) (xy 378.421876 -148.440234)
			(xy 378.400088 -148.382767) (xy 378.385385 -148.323093) (xy 378.377983 -148.262081) (xy 378.37745 -148.231352)
			(xy 378.37745 -148.231098) (xy 378.37802 -148.197764) (xy 378.386767 -148.131672) (xy 378.404059 -148.067285)
			(xy 378.416312 -148.03628) (xy 378.41809 -148.031962) (xy 378.420376 -148.02104) (xy 378.421529 -148.014295)
			(xy 378.42064 -148.000646) (xy 378.418598 -147.994116) (xy 378.412502 -147.976336) (xy 378.410876 -147.971993)
			(xy 378.40627 -147.963944) (xy 378.403358 -147.960334) (xy 378.386594 -147.940268) (xy 378.37872 -147.935696)
			(xy 378.350047 -147.918622) (xy 378.297023 -147.878103) (xy 378.249754 -147.830996) (xy 378.209052 -147.778112)
			(xy 378.175617 -147.720358) (xy 378.150023 -147.658727) (xy 378.132709 -147.594279) (xy 378.123974 -147.528119)
			(xy 378.12345 -147.494752) (xy 378.123916 -147.464022) (xy 378.131329 -147.40301) (xy 378.146042 -147.343337)
			(xy 378.167839 -147.285872) (xy 378.196403 -147.231453) (xy 378.231318 -147.180873) (xy 378.272074 -147.13487)
			(xy 378.318078 -147.094114) (xy 378.368658 -147.0592) (xy 378.423078 -147.030637) (xy 378.480543 -147.00884)
			(xy 378.540216 -146.994128) (xy 378.601228 -146.986716) (xy 378.631958 -146.986244) (xy 378.664089 -146.986733)
			(xy 378.72784 -146.994825) (xy 378.790064 -147.010886) (xy 378.849767 -147.034659) (xy 378.905999 -147.065766)
			(xy 378.957864 -147.10371) (xy 379.004534 -147.147887) (xy 379.045265 -147.197593) (xy 379.079408 -147.252035)
			(xy 379.106419 -147.310345) (xy 379.11659 -147.340828) (xy 379.119384 -147.350226) (xy 379.132084 -147.365466)
			(xy 379.21057 -147.40763) (xy 379.229874 -147.409662) (xy 379.239526 -147.407122) (xy 379.264902 -147.400373)
			(xy 379.316904 -147.393101) (xy 379.343158 -147.392644) (xy 380.791212 -147.392644) (xy 380.821192 -147.393203)
			(xy 380.880413 -147.402588) (xy 380.937435 -147.421124) (xy 380.990855 -147.448356) (xy 381.039354 -147.483611)
			(xy 381.06096 -147.504404) (xy 383.90576 -150.349458) (xy 383.91316 -150.3563) (xy 383.931758 -150.364019)
			(xy 383.941828 -150.364444) (xy 384.123692 -150.364444) (xy 384.13352 -150.363971) (xy 384.151689 -150.356475)
			(xy 384.165624 -150.342614) (xy 384.173217 -150.324485) (xy 384.17373 -150.31466) (xy 384.17373 -146.868388)
			(xy 384.173305 -146.858318) (xy 384.165591 -146.839714) (xy 384.158744 -146.83232) (xy 383.894076 -146.567398)
			(xy 383.886676 -146.560556) (xy 383.868078 -146.55283) (xy 383.858008 -146.552412) (xy 383.82448 -146.552412)
			(xy 383.808224 -146.558254) (xy 383.801112 -146.563842) (xy 383.773714 -146.585626) (xy 383.714069 -146.62226)
			(xy 383.649963 -146.650365) (xy 383.582607 -146.669411) (xy 383.513276 -146.679038) (xy 383.478278 -146.679666)
			(xy 383.446321 -146.679163) (xy 383.38291 -146.67115) (xy 383.321003 -146.655252) (xy 383.261577 -146.631722)
			(xy 383.205569 -146.600929) (xy 383.153862 -146.563359) (xy 383.107271 -146.519605) (xy 383.066531 -146.470357)
			(xy 383.032284 -146.416391) (xy 383.005071 -146.358559) (xy 382.985321 -146.297772) (xy 382.973345 -146.234989)
			(xy 382.969331 -146.1712) (xy 382.973345 -146.107411) (xy 382.985321 -146.044628) (xy 383.005071 -145.983841)
			(xy 383.032284 -145.926009) (xy 383.066531 -145.872043) (xy 383.107271 -145.822795) (xy 383.153862 -145.779041)
			(xy 383.205569 -145.741471) (xy 383.261577 -145.710678) (xy 383.321003 -145.687148) (xy 383.38291 -145.67125)
			(xy 383.446321 -145.663237) (xy 383.478278 -145.66265) (xy 383.512488 -145.663206) (xy 383.58029 -145.67238)
			(xy 383.646249 -145.690566) (xy 383.709172 -145.717434) (xy 383.767923 -145.7525) (xy 383.795016 -145.773394)
			(xy 383.80162 -145.778474) (xy 383.824734 -145.786856) (xy 383.828913 -145.788266) (xy 383.837597 -145.789801)
			(xy 383.842006 -145.789904) (xy 384.037078 -145.789904) (xy 384.06578 -145.79092) (xy 384.076194 -145.791682)
			(xy 384.096006 -145.784824) (xy 384.157728 -145.727928) (xy 384.164921 -145.720535) (xy 384.173173 -145.701653)
			(xy 384.17373 -145.691352) (xy 384.17373 -145.459704) (xy 384.173369 -145.449793) (xy 384.165869 -145.431451)
			(xy 384.151898 -145.417397) (xy 384.1336 -145.409788) (xy 384.123692 -145.409412) (xy 382.064006 -145.409412)
			(xy 382.059595 -145.409496) (xy 382.050905 -145.411022) (xy 382.046734 -145.41246) (xy 382.02362 -145.420842)
			(xy 382.017016 -145.425922) (xy 381.989914 -145.446806) (xy 381.931169 -145.481883) (xy 381.868249 -145.50876)
			(xy 381.802291 -145.526952) (xy 381.734488 -145.53613) (xy 381.700278 -145.536666) (xy 381.668321 -145.536163)
			(xy 381.60491 -145.52815) (xy 381.543003 -145.512252) (xy 381.483577 -145.488722) (xy 381.427569 -145.457929)
			(xy 381.375862 -145.420359) (xy 381.329271 -145.376605) (xy 381.288531 -145.327357) (xy 381.254284 -145.273391)
			(xy 381.227071 -145.215559) (xy 381.207321 -145.154772) (xy 381.195345 -145.091989) (xy 381.191331 -145.0282)
			(xy 381.195345 -144.964411) (xy 381.207321 -144.901628) (xy 381.227071 -144.840841) (xy 381.254284 -144.783009)
			(xy 381.288531 -144.729043) (xy 381.329271 -144.679795) (xy 381.375862 -144.636041) (xy 381.427569 -144.598471)
			(xy 381.483577 -144.567678) (xy 381.543003 -144.544148) (xy 381.60491 -144.52825) (xy 381.668321 -144.520237)
			(xy 381.700278 -144.51965) (xy 381.734488 -144.520206) (xy 381.80229 -144.52938) (xy 381.868249 -144.547566)
			(xy 381.931172 -144.574434) (xy 381.989923 -144.6095) (xy 382.017016 -144.630394) (xy 382.02362 -144.635474)
			(xy 382.046734 -144.643856) (xy 382.050913 -144.645266) (xy 382.059597 -144.646801) (xy 382.064006 -144.646904)
			(xy 384.123692 -144.646904) (xy 384.133593 -144.646485) (xy 384.151878 -144.638883) (xy 384.16584 -144.624842)
			(xy 384.17334 -144.606515) (xy 384.17373 -144.596612) (xy 384.17373 -138.58113) (xy 384.173226 -138.571079)
			(xy 384.165508 -138.552515) (xy 384.158744 -138.545062) (xy 383.754122 -138.14044) (xy 383.746721 -138.133601)
			(xy 383.728122 -138.125889) (xy 383.718054 -138.125454) (xy 381.238252 -138.125454) (xy 381.228412 -138.125985)
			(xy 381.210241 -138.133561) (xy 381.202946 -138.140186) (xy 381.097028 -138.246104) (xy 381.089916 -138.27125)
			(xy 381.092964 -138.284204) (xy 381.099355 -138.312991) (xy 381.106227 -138.371559) (xy 381.10668 -138.401044)
			(xy 381.10668 -138.401552) (xy 381.106112 -138.435484) (xy 381.097071 -138.502742) (xy 381.079157 -138.568198)
			(xy 381.052689 -138.630687) (xy 381.018137 -138.689096) (xy 380.976118 -138.742386) (xy 380.927379 -138.789608)
			(xy 380.900432 -138.810238) (xy 380.895606 -138.813794) (xy 380.88824 -138.82243) (xy 380.87554 -138.847068)
			(xy 380.872936 -138.852555) (xy 380.870115 -138.864365) (xy 380.869952 -138.870436) (xy 380.869952 -139.714986)
			(xy 382.423668 -139.714986) (xy 382.427739 -139.659364) (xy 382.439865 -139.604927) (xy 382.459788 -139.552836)
			(xy 382.487084 -139.504201) (xy 382.52117 -139.460058) (xy 382.561319 -139.421349) (xy 382.606677 -139.388898)
			(xy 382.656277 -139.363397) (xy 382.709061 -139.34539) (xy 382.763904 -139.33526) (xy 382.819638 -139.333223)
			(xy 382.875075 -139.339323) (xy 382.929032 -139.353429) (xy 382.980361 -139.375241) (xy 383.027967 -139.404295)
			(xy 383.070835 -139.43997) (xy 383.108052 -139.481507) (xy 383.138825 -139.52802) (xy 383.162497 -139.578517)
			(xy 383.178565 -139.631924) (xy 383.186685 -139.6871) (xy 383.187194 -139.714986) (xy 383.186685 -139.742872)
			(xy 383.178565 -139.798048) (xy 383.162497 -139.851455) (xy 383.138825 -139.901952) (xy 383.108052 -139.948465)
			(xy 383.070835 -139.990002) (xy 383.027967 -140.025677) (xy 382.980361 -140.054731) (xy 382.929032 -140.076543)
			(xy 382.875075 -140.090649) (xy 382.819638 -140.096749) (xy 382.763904 -140.094712) (xy 382.709061 -140.084582)
			(xy 382.656277 -140.066575) (xy 382.606677 -140.041074) (xy 382.561319 -140.008623) (xy 382.52117 -139.969914)
			(xy 382.487084 -139.925771) (xy 382.459788 -139.877136) (xy 382.439865 -139.825045) (xy 382.427739 -139.770608)
			(xy 382.423668 -139.714986) (xy 380.869952 -139.714986) (xy 380.869952 -140.810488) (xy 382.559558 -140.810488)
			(xy 382.563629 -140.754866) (xy 382.575755 -140.700429) (xy 382.595678 -140.648338) (xy 382.622974 -140.599703)
			(xy 382.65706 -140.55556) (xy 382.697209 -140.516851) (xy 382.742567 -140.4844) (xy 382.792167 -140.458899)
			(xy 382.844951 -140.440892) (xy 382.899794 -140.430762) (xy 382.955528 -140.428725) (xy 383.010965 -140.434825)
			(xy 383.064922 -140.448931) (xy 383.116251 -140.470743) (xy 383.163857 -140.499797) (xy 383.206725 -140.535472)
			(xy 383.243942 -140.577009) (xy 383.274715 -140.623522) (xy 383.298387 -140.674019) (xy 383.314455 -140.727426)
			(xy 383.322575 -140.782602) (xy 383.323084 -140.810488) (xy 383.322575 -140.838374) (xy 383.314455 -140.89355)
			(xy 383.298387 -140.946957) (xy 383.274715 -140.997454) (xy 383.243942 -141.043967) (xy 383.206725 -141.085504)
			(xy 383.163857 -141.121179) (xy 383.116251 -141.150233) (xy 383.064922 -141.172045) (xy 383.010965 -141.186151)
			(xy 382.955528 -141.192251) (xy 382.899794 -141.190214) (xy 382.844951 -141.180084) (xy 382.792167 -141.162077)
			(xy 382.742567 -141.136576) (xy 382.697209 -141.104125) (xy 382.65706 -141.065416) (xy 382.622974 -141.021273)
			(xy 382.595678 -140.972638) (xy 382.575755 -140.920547) (xy 382.563629 -140.86611) (xy 382.559558 -140.810488)
			(xy 380.869952 -140.810488) (xy 380.869952 -143.346678) (xy 382.134364 -143.346678) (xy 382.13483 -143.307591)
			(xy 382.142831 -143.229827) (xy 382.158748 -143.15329) (xy 382.182413 -143.078783) (xy 382.213578 -143.007089)
			(xy 382.251915 -142.93896) (xy 382.274064 -142.90675) (xy 382.279266 -142.898713) (xy 382.283812 -142.880131)
			(xy 382.281202 -142.86118) (xy 382.276858 -142.852648) (xy 382.26525 -142.831191) (xy 382.24701 -142.785943)
			(xy 382.234685 -142.73874) (xy 382.228474 -142.690351) (xy 382.22809 -142.665958) (xy 382.228539 -142.638706)
			(xy 382.236301 -142.584757) (xy 382.251661 -142.532462) (xy 382.274307 -142.482884) (xy 382.303778 -142.437034)
			(xy 382.339473 -142.395845) (xy 382.380666 -142.360154) (xy 382.426519 -142.330688) (xy 382.476099 -142.308047)
			(xy 382.528396 -142.292692) (xy 382.582346 -142.284936) (xy 382.609598 -142.28445) (xy 382.626108 -142.284704)
			(xy 382.637792 -142.285212) (xy 382.659128 -142.276068) (xy 382.726438 -142.19682) (xy 382.73228 -142.174214)
			(xy 382.72974 -142.16253) (xy 382.726046 -142.143376) (xy 382.7221 -142.104565) (xy 382.721866 -142.08506)
			(xy 382.722421 -142.057812) (xy 382.730182 -142.003871) (xy 382.745541 -141.951584) (xy 382.768185 -141.902015)
			(xy 382.797652 -141.856172) (xy 382.833344 -141.81499) (xy 382.874533 -141.779307) (xy 382.920381 -141.749848)
			(xy 382.969955 -141.727215) (xy 383.022245 -141.711866) (xy 383.076187 -141.704116) (xy 383.130683 -141.704121)
			(xy 383.184624 -141.711881) (xy 383.236912 -141.727239) (xy 383.286481 -141.749882) (xy 383.332324 -141.779349)
			(xy 383.373506 -141.81504) (xy 383.40919 -141.856229) (xy 383.438649 -141.902077) (xy 383.461284 -141.95165)
			(xy 383.476633 -142.00394) (xy 383.484384 -142.057882) (xy 383.48438 -142.112379) (xy 383.47662 -142.16632)
			(xy 383.461262 -142.218607) (xy 383.43862 -142.268177) (xy 383.409153 -142.31402) (xy 383.373463 -142.355203)
			(xy 383.332275 -142.390887) (xy 383.286427 -142.420347) (xy 383.236854 -142.442982) (xy 383.184564 -142.458332)
			(xy 383.130622 -142.466084) (xy 383.103374 -142.466568) (xy 383.089865 -142.466457) (xy 383.062916 -142.464549)
			(xy 383.049526 -142.462758) (xy 383.041042 -142.461867) (xy 383.024311 -142.465154) (xy 383.00959 -142.473758)
			(xy 383.003806 -142.48003) (xy 382.983486 -142.503906) (xy 382.978173 -142.510613) (xy 382.971977 -142.526554)
			(xy 382.971368 -142.543645) (xy 382.97358 -142.551912) (xy 382.975358 -142.557754) (xy 382.978492 -142.566832)
			(xy 382.990298 -142.581956) (xy 383.006837 -142.591682) (xy 383.016252 -142.593568) (xy 383.054197 -142.600121)
			(xy 383.128651 -142.619779) (xy 383.200744 -142.646841) (xy 383.269742 -142.681034) (xy 383.334942 -142.722006)
			(xy 383.39568 -142.769343) (xy 383.451338 -142.822561) (xy 383.501347 -142.881117) (xy 383.545199 -142.944417)
			(xy 383.582447 -143.011814) (xy 383.612712 -143.082623) (xy 383.635685 -143.156122) (xy 383.651132 -143.231562)
			(xy 383.658897 -143.308175) (xy 383.65938 -143.346678) (xy 383.658891 -143.385323) (xy 383.651071 -143.462217)
			(xy 383.635513 -143.537925) (xy 383.612375 -143.611671) (xy 383.581895 -143.682698) (xy 383.544386 -143.750276)
			(xy 383.500232 -143.813714) (xy 383.449887 -143.872358) (xy 383.393868 -143.925609) (xy 383.332749 -143.972919)
			(xy 383.267156 -144.013803) (xy 383.197765 -144.047841) (xy 383.125285 -144.074684) (xy 383.050462 -144.094057)
			(xy 382.974063 -144.105761) (xy 382.896872 -144.109676) (xy 382.819681 -144.105761) (xy 382.743282 -144.094057)
			(xy 382.668459 -144.074684) (xy 382.595979 -144.047841) (xy 382.526588 -144.013803) (xy 382.460995 -143.972919)
			(xy 382.399876 -143.925609) (xy 382.343857 -143.872358) (xy 382.293512 -143.813714) (xy 382.249358 -143.750276)
			(xy 382.211849 -143.682698) (xy 382.181369 -143.611671) (xy 382.158231 -143.537925) (xy 382.142673 -143.462217)
			(xy 382.134853 -143.385323) (xy 382.134364 -143.346678) (xy 380.869952 -143.346678) (xy 380.869952 -144.846802)
			(xy 380.869411 -144.856638) (xy 380.861822 -144.874796) (xy 380.85522 -144.882108) (xy 380.459488 -145.27784)
			(xy 380.452248 -145.28455) (xy 380.434044 -145.292139) (xy 380.424182 -145.292572) (xy 374.6119 -145.292572)
			(xy 374.602064 -145.293113) (xy 374.583908 -145.300704) (xy 374.576594 -145.307304) (xy 374.29694 -145.586958)
			(xy 374.290224 -145.594195) (xy 374.282617 -145.6124) (xy 374.282208 -145.622264) (xy 374.282208 -146.456908)
			(xy 378.786388 -146.456908) (xy 378.790459 -146.401286) (xy 378.802585 -146.346849) (xy 378.822508 -146.294758)
			(xy 378.849804 -146.246123) (xy 378.88389 -146.20198) (xy 378.924039 -146.163271) (xy 378.969397 -146.13082)
			(xy 379.018997 -146.105319) (xy 379.071781 -146.087312) (xy 379.126624 -146.077182) (xy 379.182358 -146.075145)
			(xy 379.237795 -146.081245) (xy 379.291752 -146.095351) (xy 379.343081 -146.117163) (xy 379.390687 -146.146217)
			(xy 379.433555 -146.181892) (xy 379.470772 -146.223429) (xy 379.501545 -146.269942) (xy 379.525217 -146.320439)
			(xy 379.541285 -146.373846) (xy 379.549405 -146.429022) (xy 379.549914 -146.456908) (xy 379.549405 -146.484794)
			(xy 379.541285 -146.53997) (xy 379.525217 -146.593377) (xy 379.501545 -146.643874) (xy 379.470772 -146.690387)
			(xy 379.438275 -146.726656) (xy 381.080516 -146.726656) (xy 381.084587 -146.671034) (xy 381.096713 -146.616597)
			(xy 381.116636 -146.564506) (xy 381.143932 -146.515871) (xy 381.178018 -146.471728) (xy 381.218167 -146.433019)
			(xy 381.263525 -146.400568) (xy 381.313125 -146.375067) (xy 381.365909 -146.35706) (xy 381.420752 -146.34693)
			(xy 381.476486 -146.344893) (xy 381.531923 -146.350993) (xy 381.58588 -146.365099) (xy 381.637209 -146.386911)
			(xy 381.684815 -146.415965) (xy 381.727683 -146.45164) (xy 381.7649 -146.493177) (xy 381.795673 -146.53969)
			(xy 381.819345 -146.590187) (xy 381.835413 -146.643594) (xy 381.843533 -146.69877) (xy 381.844042 -146.726656)
			(xy 381.843533 -146.754542) (xy 381.835413 -146.809718) (xy 381.819345 -146.863125) (xy 381.795673 -146.913622)
			(xy 381.7649 -146.960135) (xy 381.727683 -147.001672) (xy 381.684815 -147.037347) (xy 381.637209 -147.066401)
			(xy 381.58588 -147.088213) (xy 381.531923 -147.102319) (xy 381.476486 -147.108419) (xy 381.420752 -147.106382)
			(xy 381.365909 -147.096252) (xy 381.313125 -147.078245) (xy 381.263525 -147.052744) (xy 381.218167 -147.020293)
			(xy 381.178018 -146.981584) (xy 381.143932 -146.937441) (xy 381.116636 -146.888806) (xy 381.096713 -146.836715)
			(xy 381.084587 -146.782278) (xy 381.080516 -146.726656) (xy 379.438275 -146.726656) (xy 379.433555 -146.731924)
			(xy 379.390687 -146.767599) (xy 379.343081 -146.796653) (xy 379.291752 -146.818465) (xy 379.237795 -146.832571)
			(xy 379.182358 -146.838671) (xy 379.126624 -146.836634) (xy 379.071781 -146.826504) (xy 379.018997 -146.808497)
			(xy 378.969397 -146.782996) (xy 378.924039 -146.750545) (xy 378.88389 -146.711836) (xy 378.849804 -146.667693)
			(xy 378.822508 -146.619058) (xy 378.802585 -146.566967) (xy 378.790459 -146.51253) (xy 378.786388 -146.456908)
			(xy 374.282208 -146.456908) (xy 374.282208 -147.734528) (xy 374.282637 -147.744596) (xy 374.290359 -147.763192)
			(xy 374.297194 -147.770596) (xy 374.396254 -147.869656) (xy 374.40362 -147.876496) (xy 374.422153 -147.884238)
			(xy 374.442237 -147.884238) (xy 374.46077 -147.876496) (xy 374.468136 -147.869656) (xy 375.099326 -147.23872)
			(xy 375.117423 -147.221468) (xy 375.158971 -147.193668) (xy 375.205142 -147.174503) (xy 375.254163 -147.164709)
			(xy 375.279158 -147.164044) (xy 376.718068 -147.164044) (xy 376.728031 -147.163559) (xy 376.746459 -147.155975)
			(xy 376.753882 -147.149312) (xy 376.775492 -147.128423) (xy 376.824065 -147.093028) (xy 376.877586 -147.065684)
			(xy 376.934731 -147.047067) (xy 376.994088 -147.037637) (xy 377.024138 -147.037044) (xy 377.051391 -147.037532)
			(xy 377.105341 -147.045294) (xy 377.157638 -147.060655) (xy 377.207217 -147.083301) (xy 377.253068 -147.112772)
			(xy 377.294259 -147.148468) (xy 377.329951 -147.189662) (xy 377.359417 -147.235517) (xy 377.382059 -147.285098)
			(xy 377.397414 -147.337396) (xy 377.40517 -147.391347) (xy 377.40517 -147.445853) (xy 377.397414 -147.499804)
			(xy 377.382059 -147.552102) (xy 377.359417 -147.601683) (xy 377.329951 -147.647538) (xy 377.294259 -147.688732)
			(xy 377.253068 -147.724428) (xy 377.207217 -147.753899) (xy 377.157638 -147.776545) (xy 377.105341 -147.791906)
			(xy 377.051391 -147.799668) (xy 377.024138 -147.80006) (xy 376.994085 -147.799499) (xy 376.934722 -147.790077)
			(xy 376.877572 -147.771458) (xy 376.82405 -147.744106) (xy 376.775481 -147.708696) (xy 376.753882 -147.687792)
			(xy 376.746471 -147.681111) (xy 376.728035 -147.673537) (xy 376.718068 -147.67306) (xy 375.40565 -147.67306)
			(xy 375.395619 -147.673499) (xy 375.377048 -147.681079) (xy 375.369582 -147.687792) (xy 374.685554 -148.372068)
			(xy 375.095514 -148.372068) (xy 375.099585 -148.316446) (xy 375.111711 -148.262009) (xy 375.131634 -148.209918)
			(xy 375.15893 -148.161283) (xy 375.193016 -148.11714) (xy 375.233165 -148.078431) (xy 375.278523 -148.04598)
			(xy 375.328123 -148.020479) (xy 375.380907 -148.002472) (xy 375.43575 -147.992342) (xy 375.491484 -147.990305)
			(xy 375.546921 -147.996405) (xy 375.600878 -148.010511) (xy 375.652207 -148.032323) (xy 375.699813 -148.061377)
			(xy 375.742681 -148.097052) (xy 375.779898 -148.138589) (xy 375.810671 -148.185102) (xy 375.834343 -148.235599)
			(xy 375.850411 -148.289006) (xy 375.858531 -148.344182) (xy 375.85904 -148.372068) (xy 375.858531 -148.399954)
			(xy 375.850411 -148.45513) (xy 375.834343 -148.508537) (xy 375.810671 -148.559034) (xy 375.779898 -148.605547)
			(xy 375.742681 -148.647084) (xy 375.699813 -148.682759) (xy 375.653696 -148.710904) (xy 376.020074 -148.710904)
			(xy 376.024145 -148.655282) (xy 376.036271 -148.600845) (xy 376.056194 -148.548754) (xy 376.08349 -148.500119)
			(xy 376.117576 -148.455976) (xy 376.157725 -148.417267) (xy 376.203083 -148.384816) (xy 376.252683 -148.359315)
			(xy 376.305467 -148.341308) (xy 376.36031 -148.331178) (xy 376.416044 -148.329141) (xy 376.471481 -148.335241)
			(xy 376.525438 -148.349347) (xy 376.576767 -148.371159) (xy 376.624373 -148.400213) (xy 376.667241 -148.435888)
			(xy 376.704458 -148.477425) (xy 376.735231 -148.523938) (xy 376.758903 -148.574435) (xy 376.774971 -148.627842)
			(xy 376.783091 -148.683018) (xy 376.7836 -148.710904) (xy 376.783091 -148.73879) (xy 376.774971 -148.793966)
			(xy 376.758903 -148.847373) (xy 376.735231 -148.89787) (xy 376.704458 -148.944383) (xy 376.667241 -148.98592)
			(xy 376.624373 -149.021595) (xy 376.576767 -149.050649) (xy 376.525438 -149.072461) (xy 376.471481 -149.086567)
			(xy 376.416044 -149.092667) (xy 376.36031 -149.09063) (xy 376.305467 -149.0805) (xy 376.252683 -149.062493)
			(xy 376.203083 -149.036992) (xy 376.157725 -149.004541) (xy 376.117576 -148.965832) (xy 376.08349 -148.921689)
			(xy 376.056194 -148.873054) (xy 376.036271 -148.820963) (xy 376.024145 -148.766526) (xy 376.020074 -148.710904)
			(xy 375.653696 -148.710904) (xy 375.652207 -148.711813) (xy 375.600878 -148.733625) (xy 375.546921 -148.747731)
			(xy 375.491484 -148.753831) (xy 375.43575 -148.751794) (xy 375.380907 -148.741664) (xy 375.328123 -148.723657)
			(xy 375.278523 -148.698156) (xy 375.233165 -148.665705) (xy 375.193016 -148.626996) (xy 375.15893 -148.582853)
			(xy 375.131634 -148.534218) (xy 375.111711 -148.482127) (xy 375.099585 -148.42769) (xy 375.095514 -148.372068)
			(xy 374.685554 -148.372068) (xy 374.66905 -148.388578) (xy 374.662246 -148.395925) (xy 374.654534 -148.414388)
			(xy 374.654064 -148.424392) (xy 374.654064 -148.563076) (xy 374.653925 -148.567966) (xy 374.652001 -148.577556)
			(xy 374.650254 -148.582126) (xy 374.643396 -148.599398) (xy 374.641642 -148.603965) (xy 374.639724 -148.613558)
			(xy 374.639586 -148.618448) (xy 374.639586 -149.379432) (xy 375.095514 -149.379432) (xy 375.099585 -149.32381)
			(xy 375.111711 -149.269373) (xy 375.131634 -149.217282) (xy 375.15893 -149.168647) (xy 375.193016 -149.124504)
			(xy 375.233165 -149.085795) (xy 375.278523 -149.053344) (xy 375.328123 -149.027843) (xy 375.380907 -149.009836)
			(xy 375.43575 -148.999706) (xy 375.491484 -148.997669) (xy 375.546921 -149.003769) (xy 375.600878 -149.017875)
			(xy 375.652207 -149.039687) (xy 375.699813 -149.068741) (xy 375.742681 -149.104416) (xy 375.779898 -149.145953)
			(xy 375.810671 -149.192466) (xy 375.834343 -149.242963) (xy 375.850411 -149.29637) (xy 375.858531 -149.351546)
			(xy 375.85904 -149.379432) (xy 375.858531 -149.407318) (xy 375.850411 -149.462494) (xy 375.834343 -149.515901)
			(xy 375.810671 -149.566398) (xy 375.779898 -149.612911) (xy 375.742681 -149.654448) (xy 375.699813 -149.690123)
			(xy 375.652207 -149.719177) (xy 375.600878 -149.740989) (xy 375.546921 -149.755095) (xy 375.491484 -149.761195)
			(xy 375.43575 -149.759158) (xy 375.380907 -149.749028) (xy 375.328123 -149.731021) (xy 375.278523 -149.70552)
			(xy 375.233165 -149.673069) (xy 375.193016 -149.63436) (xy 375.15893 -149.590217) (xy 375.131634 -149.541582)
			(xy 375.111711 -149.489491) (xy 375.099585 -149.435054) (xy 375.095514 -149.379432) (xy 374.639586 -149.379432)
			(xy 374.639586 -150.70963) (xy 374.640066 -150.71945) (xy 374.64757 -150.737602) (xy 374.66143 -150.751518)
			(xy 374.679552 -150.759094) (xy 374.68937 -150.759668)
		)
		(stroke
			(width 0)
			(type solid)
		)
		(fill yes)
		(layer "In4.Cu")
		(net "PVDDCR_CPU0_P0_VCCS")
	)
	(gr_poly
		(pts
			(xy 93.363542 -153.15692) (xy 93.373366 -153.156397) (xy 93.391495 -153.148809) (xy 93.405355 -153.134876)
			(xy 93.412849 -153.116709) (xy 93.413326 -153.106882) (xy 93.413326 -152.789636) (xy 93.40215 -152.75814)
			(xy 93.38035 -152.730721) (xy 93.343693 -152.67103) (xy 93.315577 -152.606872) (xy 93.296534 -152.539462)
			(xy 93.286925 -152.470076) (xy 93.286326 -152.435052) (xy 93.286828 -152.403091) (xy 93.294839 -152.339673)
			(xy 93.310736 -152.277759) (xy 93.334268 -152.218326) (xy 93.365062 -152.162311) (xy 93.402635 -152.110596)
			(xy 93.446392 -152.063999) (xy 93.495645 -152.023254) (xy 93.549616 -151.989003) (xy 93.607455 -151.961786)
			(xy 93.668248 -151.942033) (xy 93.731038 -151.930055) (xy 93.794834 -151.926042) (xy 93.85863 -151.930055)
			(xy 93.92142 -151.942033) (xy 93.982213 -151.961786) (xy 94.040052 -151.989003) (xy 94.094023 -152.023254)
			(xy 94.143276 -152.063999) (xy 94.187033 -152.110596) (xy 94.224606 -152.162311) (xy 94.2554 -152.218326)
			(xy 94.278932 -152.277759) (xy 94.294829 -152.339673) (xy 94.30284 -152.403091) (xy 94.303342 -152.435052)
			(xy 94.302753 -152.470075) (xy 94.293133 -152.539458) (xy 94.27408 -152.606864) (xy 94.245957 -152.671017)
			(xy 94.209295 -152.730703) (xy 94.187518 -152.75814) (xy 94.176342 -152.789636) (xy 94.176342 -153.106882)
			(xy 94.176813 -153.116712) (xy 94.184307 -153.134887) (xy 94.198167 -153.148829) (xy 94.216299 -153.156429)
			(xy 94.226126 -153.15692) (xy 94.706694 -153.15692) (xy 94.716591 -153.156542) (xy 94.734897 -153.149023)
			(xy 94.748918 -153.135056) (xy 94.756505 -153.116777) (xy 94.756986 -153.106882) (xy 94.756986 -151.227282)
			(xy 94.73692 -151.200612) (xy 94.720918 -151.19604) (xy 94.689627 -151.186392) (xy 94.629632 -151.160153)
			(xy 94.573501 -151.126431) (xy 94.522163 -151.085783) (xy 94.476467 -151.038881) (xy 94.437169 -150.986502)
			(xy 94.404919 -150.929513) (xy 94.380252 -150.868855) (xy 94.363574 -150.805532) (xy 94.355162 -150.740593)
			(xy 94.35465 -150.707852) (xy 94.355116 -150.677122) (xy 94.362529 -150.61611) (xy 94.377242 -150.556437)
			(xy 94.399039 -150.498972) (xy 94.427603 -150.444553) (xy 94.462518 -150.393973) (xy 94.503274 -150.34797)
			(xy 94.549278 -150.307214) (xy 94.599858 -150.2723) (xy 94.654278 -150.243737) (xy 94.711743 -150.22194)
			(xy 94.771416 -150.207228) (xy 94.832428 -150.199816) (xy 94.863158 -150.199344) (xy 94.894397 -150.199823)
			(xy 94.956403 -150.207481) (xy 95.017004 -150.222674) (xy 95.07529 -150.245174) (xy 95.130381 -150.274642)
			(xy 95.181449 -150.310635) (xy 95.227725 -150.35261) (xy 95.268513 -150.399936) (xy 95.303198 -150.4519)
			(xy 95.331259 -150.507721) (xy 95.352274 -150.566559) (xy 95.365925 -150.627526) (xy 95.36938 -150.658576)
			(xy 95.370142 -150.667212) (xy 95.377508 -150.682706) (xy 95.407988 -150.713186) (xy 95.428723 -150.734763)
			(xy 95.463884 -150.78318) (xy 95.491043 -150.836499) (xy 95.509533 -150.893408) (xy 95.518899 -150.952507)
			(xy 95.519494 -150.982426) (xy 95.519494 -153.106882) (xy 95.519911 -153.116784) (xy 95.527511 -153.135073)
			(xy 95.541553 -153.149039) (xy 95.559881 -153.156541) (xy 95.569786 -153.15692) (xy 95.725488 -153.15692)
			(xy 95.734029 -153.156581) (xy 95.750135 -153.150891) (xy 95.763423 -153.140158) (xy 95.76816 -153.133044)
			(xy 95.819722 -153.049224) (xy 95.820738 -153.023316) (xy 95.814896 -153.011632) (xy 95.801897 -152.984756)
			(xy 95.783476 -152.927971) (xy 95.774099 -152.869014) (xy 95.773494 -152.839166) (xy 95.773494 -150.97887)
			(xy 95.762572 -150.947628) (xy 95.741374 -150.920402) (xy 95.705745 -150.861312) (xy 95.678434 -150.797947)
			(xy 95.659942 -150.731471) (xy 95.650611 -150.663104) (xy 95.65005 -150.628604) (xy 95.65005 -150.62835)
			(xy 95.650599 -150.594232) (xy 95.659727 -150.52661) (xy 95.677827 -150.460819) (xy 95.69069 -150.429214)
			(xy 95.694754 -150.409656) (xy 95.694649 -150.405511) (xy 95.693249 -150.39734) (xy 95.69196 -150.3934)
			(xy 95.682054 -150.364698) (xy 95.65894 -150.337266) (xy 95.632758 -150.322318) (xy 95.583777 -150.287163)
			(xy 95.539297 -150.246463) (xy 95.499942 -150.200788) (xy 95.466265 -150.15078) (xy 95.438738 -150.09714)
			(xy 95.417747 -150.040621) (xy 95.403587 -149.982017) (xy 95.396457 -149.922149) (xy 95.39605 -149.892004)
			(xy 95.396552 -149.860043) (xy 95.404563 -149.796625) (xy 95.42046 -149.734711) (xy 95.443992 -149.675278)
			(xy 95.474786 -149.619263) (xy 95.512359 -149.567548) (xy 95.556116 -149.520951) (xy 95.605369 -149.480206)
			(xy 95.65934 -149.445955) (xy 95.717179 -149.418738) (xy 95.777972 -149.398985) (xy 95.840762 -149.387007)
			(xy 95.904558 -149.382994) (xy 95.968354 -149.387007) (xy 96.031144 -149.398985) (xy 96.091937 -149.418738)
			(xy 96.149776 -149.445955) (xy 96.203747 -149.480206) (xy 96.253 -149.520951) (xy 96.296757 -149.567548)
			(xy 96.33433 -149.619263) (xy 96.365124 -149.675278) (xy 96.388656 -149.734711) (xy 96.404553 -149.796625)
			(xy 96.412564 -149.860043) (xy 96.413066 -149.892004) (xy 96.413066 -149.892258) (xy 96.412516 -149.926376)
			(xy 96.403386 -149.993997) (xy 96.385283 -150.059787) (xy 96.372426 -150.091394) (xy 96.368362 -150.110952)
			(xy 96.368467 -150.115097) (xy 96.369866 -150.123268) (xy 96.371156 -150.127208) (xy 96.381062 -150.15591)
			(xy 96.404176 -150.183342) (xy 96.430357 -150.198291) (xy 96.479336 -150.233447) (xy 96.523814 -150.274148)
			(xy 96.563167 -150.319823) (xy 96.596842 -150.369831) (xy 96.624368 -150.42347) (xy 96.645357 -150.479989)
			(xy 96.659515 -150.538592) (xy 96.666644 -150.598459) (xy 96.667066 -150.628604) (xy 96.667066 -150.628858)
			(xy 96.66666 -150.658432) (xy 96.659807 -150.717183) (xy 96.646177 -150.774739) (xy 96.625954 -150.830323)
			(xy 96.599413 -150.883182) (xy 96.566911 -150.932601) (xy 96.548194 -150.955502) (xy 96.53651 -150.987506)
			(xy 96.53651 -151.708866) (xy 97.520504 -151.708866) (xy 97.524575 -151.653244) (xy 97.536701 -151.598807)
			(xy 97.556624 -151.546716) (xy 97.58392 -151.498081) (xy 97.618006 -151.453938) (xy 97.658155 -151.415229)
			(xy 97.703513 -151.382778) (xy 97.753113 -151.357277) (xy 97.805897 -151.33927) (xy 97.86074 -151.32914)
			(xy 97.916474 -151.327103) (xy 97.971911 -151.333203) (xy 98.025868 -151.347309) (xy 98.077197 -151.369121)
			(xy 98.124803 -151.398175) (xy 98.167671 -151.43385) (xy 98.204888 -151.475387) (xy 98.235661 -151.5219)
			(xy 98.259333 -151.572397) (xy 98.275401 -151.625804) (xy 98.283521 -151.68098) (xy 98.28403 -151.708866)
			(xy 98.283521 -151.736752) (xy 98.275401 -151.791928) (xy 98.259333 -151.845335) (xy 98.235661 -151.895832)
			(xy 98.204888 -151.942345) (xy 98.167671 -151.983882) (xy 98.124803 -152.019557) (xy 98.077197 -152.048611)
			(xy 98.025868 -152.070423) (xy 97.971911 -152.084529) (xy 97.916474 -152.090629) (xy 97.86074 -152.088592)
			(xy 97.805897 -152.078462) (xy 97.753113 -152.060455) (xy 97.703513 -152.034954) (xy 97.658155 -152.002503)
			(xy 97.618006 -151.963794) (xy 97.58392 -151.919651) (xy 97.556624 -151.871016) (xy 97.536701 -151.818925)
			(xy 97.524575 -151.764488) (xy 97.520504 -151.708866) (xy 96.53651 -151.708866) (xy 96.53651 -152.66035)
			(xy 96.536952 -152.67023) (xy 96.544409 -152.688525) (xy 96.550988 -152.69591) (xy 96.99752 -153.142188)
			(xy 97.004757 -153.148902) (xy 97.022963 -153.156497) (xy 97.032826 -153.15692) (xy 99.256342 -153.15692)
			(xy 99.266193 -153.156432) (xy 99.28439 -153.148879) (xy 99.298313 -153.134939) (xy 99.305844 -153.116733)
			(xy 99.30638 -153.106882) (xy 99.30638 -153.105612) (xy 99.306126 -153.095452) (xy 99.306126 -151.989536)
			(xy 99.29495 -151.95804) (xy 99.27315 -151.930621) (xy 99.236493 -151.87093) (xy 99.208377 -151.806772)
			(xy 99.189334 -151.739362) (xy 99.179725 -151.669976) (xy 99.179126 -151.634952) (xy 99.179628 -151.602991)
			(xy 99.187639 -151.539573) (xy 99.203536 -151.477659) (xy 99.227068 -151.418226) (xy 99.257862 -151.362211)
			(xy 99.295435 -151.310496) (xy 99.339192 -151.263899) (xy 99.388445 -151.223154) (xy 99.442416 -151.188903)
			(xy 99.500255 -151.161686) (xy 99.561048 -151.141933) (xy 99.623838 -151.129955) (xy 99.687634 -151.125942)
			(xy 99.75143 -151.129955) (xy 99.81422 -151.141933) (xy 99.875013 -151.161686) (xy 99.932852 -151.188903)
			(xy 99.986823 -151.223154) (xy 100.036076 -151.263899) (xy 100.079833 -151.310496) (xy 100.117406 -151.362211)
			(xy 100.1482 -151.418226) (xy 100.171732 -151.477659) (xy 100.187629 -151.539573) (xy 100.19564 -151.602991)
			(xy 100.196142 -151.634952) (xy 100.195553 -151.669975) (xy 100.185933 -151.739358) (xy 100.16688 -151.806764)
			(xy 100.138757 -151.870917) (xy 100.102095 -151.930603) (xy 100.080318 -151.95804) (xy 100.069142 -151.989536)
			(xy 100.069142 -152.916636) (xy 100.06958 -152.926518) (xy 100.077026 -152.944824) (xy 100.08362 -152.952196)
			(xy 100.273866 -153.142188) (xy 100.2811 -153.148911) (xy 100.299306 -153.156525) (xy 100.309172 -153.15692)
			(xy 101.07803 -153.15692) (xy 101.087871 -153.156392) (xy 101.106045 -153.148817) (xy 101.113336 -153.142188)
			(xy 101.431598 -152.823926) (xy 101.438318 -152.816691) (xy 101.445929 -152.798486) (xy 101.44633 -152.78862)
			(xy 101.44633 -152.239218) (xy 101.445793 -152.229381) (xy 101.438206 -152.21122) (xy 101.431598 -152.203912)
			(xy 99.294188 -150.066502) (xy 99.278694 -150.059136) (xy 99.270058 -150.058374) (xy 99.239007 -150.05488)
			(xy 99.178021 -150.041264) (xy 99.119163 -150.020277) (xy 99.063321 -149.992236) (xy 99.011336 -149.957562)
			(xy 98.963993 -149.916779) (xy 98.922004 -149.870502) (xy 98.886003 -149.819428) (xy 98.856532 -149.764327)
			(xy 98.834036 -149.706029) (xy 98.818853 -149.645414) (xy 98.811214 -149.583396) (xy 98.810826 -149.552152)
			(xy 98.811293 -149.521424) (xy 98.818706 -149.460416) (xy 98.833419 -149.400746) (xy 98.855217 -149.343285)
			(xy 98.883782 -149.28887) (xy 98.918698 -149.238295) (xy 98.959455 -149.192297) (xy 99.005459 -149.151547)
			(xy 99.05604 -149.11664) (xy 99.11046 -149.088084) (xy 99.167924 -149.066295) (xy 99.227596 -149.051592)
			(xy 99.288606 -149.044188) (xy 99.319334 -149.043644) (xy 99.350573 -149.044122) (xy 99.412582 -149.051777)
			(xy 99.473186 -149.066968) (xy 99.531474 -149.089467) (xy 99.586567 -149.118934) (xy 99.637638 -149.154926)
			(xy 99.683917 -149.196901) (xy 99.724707 -149.244227) (xy 99.759394 -149.296193) (xy 99.787457 -149.352015)
			(xy 99.808472 -149.410854) (xy 99.822124 -149.471823) (xy 99.825556 -149.502876) (xy 99.826318 -149.511512)
			(xy 99.833684 -149.527006) (xy 101.360986 -151.054562) (xy 101.368245 -151.061306) (xy 101.386512 -151.068939)
			(xy 101.406309 -151.068935) (xy 101.415596 -151.065484) (xy 101.429566 -151.059642) (xy 101.44633 -151.03475)
			(xy 101.44633 -150.359618) (xy 101.445793 -150.349781) (xy 101.438206 -150.33162) (xy 101.431598 -150.324312)
			(xy 99.96805 -148.86051) (xy 99.960732 -148.853829) (xy 99.942394 -148.846364) (xy 99.93249 -148.846032)
			(xy 98.678746 -148.846032) (xy 98.64725 -148.857208) (xy 98.619832 -148.87901) (xy 98.560142 -148.915671)
			(xy 98.495984 -148.943791) (xy 98.428574 -148.962837) (xy 98.359187 -148.972449) (xy 98.324162 -148.973032)
			(xy 98.292201 -148.972528) (xy 98.228784 -148.964512) (xy 98.166871 -148.948611) (xy 98.107439 -148.925077)
			(xy 98.051425 -148.894279) (xy 97.999713 -148.856704) (xy 97.953117 -148.812945) (xy 97.912373 -148.763691)
			(xy 97.878124 -148.709719) (xy 97.850908 -148.65188) (xy 97.831156 -148.591086) (xy 97.819179 -148.528296)
			(xy 97.815165 -148.4645) (xy 97.819179 -148.400704) (xy 97.831156 -148.337914) (xy 97.850908 -148.27712)
			(xy 97.878124 -148.219281) (xy 97.912373 -148.165309) (xy 97.953117 -148.116055) (xy 97.999713 -148.072296)
			(xy 98.051425 -148.034721) (xy 98.107439 -148.003923) (xy 98.166871 -147.980389) (xy 98.228784 -147.964488)
			(xy 98.292201 -147.956472) (xy 98.324162 -147.956016) (xy 98.359188 -147.956598) (xy 98.428577 -147.966207)
			(xy 98.49599 -147.985249) (xy 98.560153 -148.013362) (xy 98.61985 -148.050015) (xy 98.64725 -148.07184)
			(xy 98.678746 -148.083016) (xy 100.111306 -148.083016) (xy 100.141286 -148.083574) (xy 100.200508 -148.092958)
			(xy 100.257532 -148.111493) (xy 100.310953 -148.138722) (xy 100.359456 -148.173976) (xy 100.381054 -148.194776)
			(xy 101.360986 -149.174962) (xy 101.368245 -149.181706) (xy 101.386512 -149.189339) (xy 101.406309 -149.189335)
			(xy 101.415596 -149.185884) (xy 101.429566 -149.180042) (xy 101.44633 -149.15515) (xy 101.44633 -140.977874)
			(xy 101.445803 -140.968032) (xy 101.43823 -140.949857) (xy 101.431598 -140.942568) (xy 101.026468 -140.537438)
			(xy 101.019226 -140.530734) (xy 101.001022 -140.523155) (xy 100.991162 -140.522706) (xy 98.510852 -140.522706)
			(xy 98.501013 -140.523238) (xy 98.482847 -140.53082) (xy 98.475546 -140.537438) (xy 98.310954 -140.70203)
			(xy 98.304212 -140.709324) (xy 98.296628 -140.727664) (xy 98.296222 -140.73759) (xy 98.303588 -140.763752)
			(xy 98.321515 -140.793949) (xy 98.3498 -140.858226) (xy 98.368968 -140.925785) (xy 98.378655 -140.995339)
			(xy 98.37928 -141.030452) (xy 98.378837 -141.060871) (xy 98.371579 -141.121275) (xy 98.357161 -141.180381)
			(xy 98.335789 -141.237342) (xy 98.307769 -141.291344) (xy 98.273502 -141.341614) (xy 98.233478 -141.387434)
			(xy 98.188269 -141.428147) (xy 98.163634 -141.445996) (xy 98.142806 -141.486382) (xy 98.142552 -141.490192)
			(xy 98.142552 -142.103602) (xy 99.864926 -142.103602) (xy 99.865428 -142.071641) (xy 99.873439 -142.008223)
			(xy 99.889336 -141.946309) (xy 99.912868 -141.886876) (xy 99.943662 -141.830861) (xy 99.981235 -141.779146)
			(xy 100.024992 -141.732549) (xy 100.074245 -141.691804) (xy 100.128216 -141.657553) (xy 100.186055 -141.630336)
			(xy 100.246848 -141.610583) (xy 100.309638 -141.598605) (xy 100.373434 -141.594592) (xy 100.43723 -141.598605)
			(xy 100.50002 -141.610583) (xy 100.560813 -141.630336) (xy 100.618652 -141.657553) (xy 100.672623 -141.691804)
			(xy 100.721876 -141.732549) (xy 100.765633 -141.779146) (xy 100.803206 -141.830861) (xy 100.834 -141.886876)
			(xy 100.857532 -141.946309) (xy 100.873429 -142.008223) (xy 100.88144 -142.071641) (xy 100.881942 -142.103602)
			(xy 100.88151 -142.13345) (xy 100.874533 -142.192735) (xy 100.860665 -142.250797) (xy 100.840095 -142.306836)
			(xy 100.813107 -142.360082) (xy 100.780072 -142.409802) (xy 100.741443 -142.455314) (xy 100.71989 -142.475966)
			(xy 100.710746 -142.484348) (xy 100.702618 -142.5067) (xy 100.71608 -142.611856) (xy 100.729796 -142.631668)
			(xy 100.740464 -142.637256) (xy 100.767115 -142.652028) (xy 100.816968 -142.687071) (xy 100.862276 -142.727819)
			(xy 100.902392 -142.773689) (xy 100.936739 -142.824023) (xy 100.964827 -142.8781) (xy 100.986252 -142.935146)
			(xy 101.000708 -142.994343) (xy 101.007987 -143.054844) (xy 101.008434 -143.085312) (xy 101.007932 -143.117273)
			(xy 100.999921 -143.180691) (xy 100.984024 -143.242605) (xy 100.960492 -143.302038) (xy 100.929698 -143.358053)
			(xy 100.892125 -143.409768) (xy 100.848368 -143.456365) (xy 100.799115 -143.49711) (xy 100.745144 -143.531361)
			(xy 100.687305 -143.558578) (xy 100.626512 -143.578331) (xy 100.563722 -143.590309) (xy 100.499926 -143.594323)
			(xy 100.43613 -143.590309) (xy 100.37334 -143.578331) (xy 100.312547 -143.558578) (xy 100.254708 -143.531361)
			(xy 100.200737 -143.49711) (xy 100.151484 -143.456365) (xy 100.107727 -143.409768) (xy 100.070154 -143.358053)
			(xy 100.03936 -143.302038) (xy 100.015828 -143.242605) (xy 99.999931 -143.180691) (xy 99.99192 -143.117273)
			(xy 99.991418 -143.085312) (xy 99.991872 -143.055465) (xy 99.998847 -142.996181) (xy 100.012712 -142.93812)
			(xy 100.033279 -142.882082) (xy 100.060263 -142.828836) (xy 100.093294 -142.779114) (xy 100.131919 -142.733601)
			(xy 100.15347 -142.712948) (xy 100.162614 -142.704566) (xy 100.170742 -142.682214) (xy 100.15728 -142.577058)
			(xy 100.143564 -142.557246) (xy 100.132896 -142.551658) (xy 100.106265 -142.536851) (xy 100.05641 -142.501815)
			(xy 100.011099 -142.461072) (xy 99.970981 -142.415208) (xy 99.936631 -142.364878) (xy 99.908541 -142.310804)
			(xy 99.887113 -142.253762) (xy 99.872655 -142.194567) (xy 99.865374 -142.134069) (xy 99.864926 -142.103602)
			(xy 98.142552 -142.103602) (xy 98.142552 -145.094706) (xy 99.435666 -145.094706) (xy 99.436168 -145.063679)
			(xy 99.443719 -145.002087) (xy 99.458709 -144.941871) (xy 99.480915 -144.883927) (xy 99.510007 -144.829115)
			(xy 99.545554 -144.778252) (xy 99.587025 -144.732092) (xy 99.633806 -144.691322) (xy 99.685201 -144.656547)
			(xy 99.740445 -144.628286) (xy 99.769422 -144.617186) (xy 99.757924 -144.58466) (xy 99.745527 -144.516802)
			(xy 99.744784 -144.482312) (xy 99.745038 -144.472152) (xy 99.741239 -144.452946) (xy 99.737172 -144.414004)
			(xy 99.73691 -144.394428) (xy 99.73745 -144.367161) (xy 99.745208 -144.31318) (xy 99.760568 -144.260854)
			(xy 99.783219 -144.211245) (xy 99.812699 -144.165366) (xy 99.848409 -144.124148) (xy 99.889621 -144.088433)
			(xy 99.935496 -144.058946) (xy 99.985101 -144.036287) (xy 100.037426 -144.020919) (xy 100.091405 -144.013154)
			(xy 100.118672 -144.012666) (xy 100.132053 -144.012797) (xy 100.158748 -144.014703) (xy 100.172012 -144.016476)
			(xy 100.204306 -144.002989) (xy 100.271659 -143.983983) (xy 100.340982 -143.974388) (xy 100.375974 -143.973804)
			(xy 100.406706 -143.974262) (xy 100.467722 -143.981668) (xy 100.527401 -143.996375) (xy 100.584871 -144.018168)
			(xy 100.639296 -144.046731) (xy 100.689881 -144.081645) (xy 100.735888 -144.122402) (xy 100.776646 -144.168408)
			(xy 100.811562 -144.218992) (xy 100.840126 -144.273416) (xy 100.861921 -144.330886) (xy 100.876629 -144.390564)
			(xy 100.884037 -144.45158) (xy 100.884482 -144.482312) (xy 100.883908 -144.515737) (xy 100.875167 -144.582012)
			(xy 100.85781 -144.646569) (xy 100.832138 -144.708292) (xy 100.798594 -144.766117) (xy 100.757757 -144.819043)
			(xy 100.710333 -144.866157) (xy 100.65714 -144.906646) (xy 100.599097 -144.93981) (xy 100.537206 -144.965076)
			(xy 100.505006 -144.974056) (xy 100.496625 -144.976684) (xy 100.482199 -144.986678) (xy 100.476812 -144.993614)
			(xy 100.476812 -144.993868) (xy 100.515328 -144.999802) (xy 100.590981 -145.018523) (xy 100.66433 -145.044863)
			(xy 100.73461 -145.078548) (xy 100.801086 -145.119226) (xy 100.863067 -145.166472) (xy 100.919906 -145.219794)
			(xy 100.971009 -145.278636) (xy 101.015843 -145.342384) (xy 101.053941 -145.410372) (xy 101.084905 -145.481892)
			(xy 101.108412 -145.556197) (xy 101.124218 -145.632513) (xy 101.132156 -145.710042) (xy 101.13264 -145.74901)
			(xy 101.13215 -145.787668) (xy 101.124328 -145.864588) (xy 101.108765 -145.940321) (xy 101.085619 -146.014091)
			(xy 101.055129 -146.085142) (xy 101.017607 -146.152743) (xy 100.973439 -146.216201) (xy 100.923078 -146.274865)
			(xy 100.867039 -146.328134) (xy 100.8059 -146.375459) (xy 100.740286 -146.416357) (xy 100.670871 -146.450406)
			(xy 100.598368 -146.477259) (xy 100.523519 -146.496638) (xy 100.447095 -146.508346) (xy 100.369878 -146.512262)
			(xy 100.292661 -146.508346) (xy 100.216237 -146.496638) (xy 100.141388 -146.477259) (xy 100.068885 -146.450406)
			(xy 99.99947 -146.416357) (xy 99.933856 -146.375459) (xy 99.872717 -146.328134) (xy 99.816678 -146.274865)
			(xy 99.766317 -146.216201) (xy 99.722149 -146.152743) (xy 99.684627 -146.085142) (xy 99.654137 -146.014091)
			(xy 99.630991 -145.940321) (xy 99.615428 -145.864588) (xy 99.607606 -145.787668) (xy 99.607116 -145.74901)
			(xy 99.607116 -145.748756) (xy 99.607665 -145.707736) (xy 99.616485 -145.626173) (xy 99.633998 -145.546024)
			(xy 99.646486 -145.506948) (xy 99.622386 -145.488985) (xy 99.57814 -145.448301) (xy 99.538999 -145.402683)
			(xy 99.50551 -145.352769) (xy 99.478141 -145.299254) (xy 99.457272 -145.242885) (xy 99.443195 -145.184448)
			(xy 99.436107 -145.12476) (xy 99.435666 -145.094706) (xy 98.142552 -145.094706) (xy 98.142552 -147.244054)
			(xy 98.14202 -147.253894) (xy 98.134443 -147.272064) (xy 98.12782 -147.27936) (xy 97.732088 -147.675092)
			(xy 97.724851 -147.681807) (xy 97.706646 -147.689405) (xy 97.696782 -147.689824) (xy 91.8845 -147.689824)
			(xy 91.874666 -147.690366) (xy 91.856514 -147.697963) (xy 91.849194 -147.704556) (xy 91.56954 -147.98421)
			(xy 91.562832 -147.99145) (xy 91.555245 -148.009655) (xy 91.554808 -148.019516) (xy 91.554808 -149.38756)
			(xy 91.555334 -149.397379) (xy 91.562927 -149.415497) (xy 91.57686 -149.429345) (xy 91.595023 -149.436826)
			(xy 91.604846 -149.437344) (xy 93.013276 -149.437344) (xy 93.023155 -149.436898) (xy 93.041449 -149.429441)
			(xy 93.048836 -149.422866) (xy 93.160342 -149.311106) (xy 93.167708 -149.295612) (xy 93.16847 -149.286976)
			(xy 93.171969 -149.255929) (xy 93.185593 -149.194953) (xy 93.206586 -149.136106) (xy 93.234633 -149.080275)
			(xy 93.269309 -149.028302) (xy 93.310093 -148.98097) (xy 93.35637 -148.938992) (xy 93.407442 -148.903002)
			(xy 93.46254 -148.873541) (xy 93.520832 -148.851054) (xy 93.581441 -148.835879) (xy 93.643452 -148.828247)
			(xy 93.674692 -148.827744) (xy 93.705424 -148.828207) (xy 93.766441 -148.835615) (xy 93.82612 -148.850322)
			(xy 93.883592 -148.872116) (xy 93.910279 -148.886121) (xy 95.933 -148.886121) (xy 95.933 -148.822199)
			(xy 95.941011 -148.758781) (xy 95.956908 -148.696867) (xy 95.98044 -148.637434) (xy 96.011234 -148.581419)
			(xy 96.048807 -148.529704) (xy 96.092564 -148.483107) (xy 96.141817 -148.442362) (xy 96.195788 -148.408111)
			(xy 96.253627 -148.380894) (xy 96.31442 -148.361141) (xy 96.37721 -148.349163) (xy 96.441006 -148.34515)
			(xy 96.504802 -148.349163) (xy 96.567592 -148.361141) (xy 96.628385 -148.380894) (xy 96.686224 -148.408111)
			(xy 96.740195 -148.442362) (xy 96.789448 -148.483107) (xy 96.833205 -148.529704) (xy 96.870778 -148.581419)
			(xy 96.901572 -148.637434) (xy 96.925104 -148.696867) (xy 96.941001 -148.758781) (xy 96.949012 -148.822199)
			(xy 96.949514 -148.85416) (xy 96.949012 -148.886121) (xy 96.941001 -148.949539) (xy 96.925104 -149.011453)
			(xy 96.901572 -149.070886) (xy 96.870778 -149.126901) (xy 96.833205 -149.178616) (xy 96.789448 -149.225213)
			(xy 96.740195 -149.265958) (xy 96.686224 -149.300209) (xy 96.628385 -149.327426) (xy 96.567592 -149.347179)
			(xy 96.504802 -149.359157) (xy 96.441006 -149.363171) (xy 96.37721 -149.359157) (xy 96.31442 -149.347179)
			(xy 96.253627 -149.327426) (xy 96.195788 -149.300209) (xy 96.141817 -149.265958) (xy 96.092564 -149.225213)
			(xy 96.048807 -149.178616) (xy 96.011234 -149.126901) (xy 95.98044 -149.070886) (xy 95.956908 -149.011453)
			(xy 95.941011 -148.949539) (xy 95.933 -148.886121) (xy 93.910279 -148.886121) (xy 93.938017 -148.900678)
			(xy 93.988603 -148.935592) (xy 94.034612 -148.976348) (xy 94.075374 -149.022353) (xy 94.110293 -149.072935)
			(xy 94.138861 -149.127357) (xy 94.160661 -149.184826) (xy 94.175375 -149.244504) (xy 94.18279 -149.30552)
			(xy 94.1832 -149.336252) (xy 94.182721 -149.36749) (xy 94.175064 -149.429494) (xy 94.15987 -149.490094)
			(xy 94.13737 -149.548377) (xy 94.107901 -149.603466) (xy 94.071908 -149.654531) (xy 94.029932 -149.700804)
			(xy 93.982605 -149.741588) (xy 93.930639 -149.776269) (xy 93.874817 -149.804325) (xy 93.81598 -149.825333)
			(xy 93.755013 -149.838978) (xy 93.723968 -149.842474) (xy 93.715332 -149.843236) (xy 93.699838 -149.850602)
			(xy 93.46184 -150.0886) (xy 93.440225 -150.109379) (xy 93.39172 -150.144618) (xy 93.338301 -150.171838)
			(xy 93.281283 -150.19037) (xy 93.222069 -150.199759) (xy 93.192092 -150.20036) (xy 93.13799 -150.20036)
			(xy 93.127706 -150.200803) (xy 93.108808 -150.208906) (xy 93.09472 -150.223883) (xy 93.090746 -150.23338)
			(xy 93.053662 -150.336758) (xy 93.062044 -150.367238) (xy 93.074236 -150.377398) (xy 93.098544 -150.398167)
			(xy 93.142305 -150.444783) (xy 93.17988 -150.496513) (xy 93.210679 -150.552544) (xy 93.234216 -150.611991)
			(xy 93.25012 -150.673919) (xy 93.25814 -150.737351) (xy 93.25864 -150.76932) (xy 93.258184 -150.800312)
			(xy 93.250659 -150.861839) (xy 93.235712 -150.921994) (xy 93.213565 -150.979887) (xy 93.184545 -151.034658)
			(xy 93.149083 -151.085497) (xy 93.107704 -151.131648) (xy 93.061023 -151.172427) (xy 93.035628 -151.190198)
			(xy 93.01353 -151.2316) (xy 93.01353 -151.314404) (xy 93.035628 -151.355806) (xy 93.061005 -151.373597)
			(xy 93.107667 -151.414388) (xy 93.149031 -151.460543) (xy 93.184482 -151.511381) (xy 93.213498 -151.566147)
			(xy 93.235647 -151.624032) (xy 93.250603 -151.684178) (xy 93.258144 -151.745695) (xy 93.25864 -151.776684)
			(xy 93.258138 -151.808645) (xy 93.250127 -151.872063) (xy 93.23423 -151.933977) (xy 93.210698 -151.99341)
			(xy 93.179904 -152.049425) (xy 93.142331 -152.10114) (xy 93.098574 -152.147737) (xy 93.049321 -152.188482)
			(xy 92.99535 -152.222733) (xy 92.937511 -152.24995) (xy 92.876718 -152.269703) (xy 92.813928 -152.281681)
			(xy 92.750132 -152.285695) (xy 92.686336 -152.281681) (xy 92.623546 -152.269703) (xy 92.562753 -152.24995)
			(xy 92.504914 -152.222733) (xy 92.450943 -152.188482) (xy 92.40169 -152.147737) (xy 92.357933 -152.10114)
			(xy 92.32036 -152.049425) (xy 92.289566 -151.99341) (xy 92.266034 -151.933977) (xy 92.250137 -151.872063)
			(xy 92.242126 -151.808645) (xy 92.241624 -151.776684) (xy 92.24208 -151.745691) (xy 92.249604 -151.684164)
			(xy 92.264549 -151.624007) (xy 92.286696 -151.566113) (xy 92.315714 -151.51134) (xy 92.351175 -151.460499)
			(xy 92.392551 -151.414345) (xy 92.439231 -151.373563) (xy 92.464636 -151.355806) (xy 92.486734 -151.314404)
			(xy 92.486734 -151.2316) (xy 92.464636 -151.190198) (xy 92.439256 -151.172409) (xy 92.392588 -151.131621)
			(xy 92.351219 -151.085467) (xy 92.315763 -151.03463) (xy 92.286743 -150.979864) (xy 92.26459 -150.921978)
			(xy 92.249631 -150.86183) (xy 92.242089 -150.80031) (xy 92.241624 -150.76932) (xy 92.242104 -150.73735)
			(xy 92.250116 -150.673914) (xy 92.266017 -150.611982) (xy 92.289555 -150.552532) (xy 92.320359 -150.496501)
			(xy 92.357944 -150.444774) (xy 92.401716 -150.398165) (xy 92.426028 -150.377398) (xy 92.43822 -150.367238)
			(xy 92.446602 -150.336758) (xy 92.409518 -150.23338) (xy 92.405546 -150.22389) (xy 92.391435 -150.208947)
			(xy 92.372551 -150.200835) (xy 92.362274 -150.20036) (xy 91.604846 -150.20036) (xy 91.595014 -150.200827)
			(xy 91.576832 -150.208316) (xy 91.562886 -150.222178) (xy 91.555287 -150.240314) (xy 91.554808 -150.250144)
			(xy 91.554808 -152.731978) (xy 91.555285 -152.742203) (xy 91.563417 -152.760964) (xy 91.570556 -152.7683)
			(xy 91.630754 -152.82545) (xy 91.650058 -152.832562) (xy 91.660218 -152.8318) (xy 91.701874 -152.830784)
			(xy 91.741242 -152.831276) (xy 91.819559 -152.839387) (xy 91.896623 -152.855525) (xy 91.971614 -152.879519)
			(xy 92.043734 -152.911114) (xy 92.112213 -152.949971) (xy 92.176324 -152.995679) (xy 92.235383 -153.04775)
			(xy 92.288761 -153.10563) (xy 92.312744 -153.136854) (xy 92.352622 -153.15692)
		)
		(stroke
			(width 0)
			(type solid)
		)
		(fill yes)
		(layer "In4.Cu")
		(net "PVDDCR_CPU0_P1_VCCS")
	)
	(gr_poly
		(pts
			(xy 442.519308 -27.117294) (xy 442.527087 -27.121318) (xy 442.544327 -27.124336) (xy 442.561567 -27.121318)
			(xy 442.569346 -27.117294) (xy 442.608315 -27.09593) (xy 442.689772 -27.060385) (xy 442.774448 -27.03339)
			(xy 442.861447 -27.015229) (xy 442.949851 -27.006094) (xy 442.994288 -27.005534) (xy 443.038751 -27.00609)
			(xy 443.127208 -27.015199) (xy 443.21426 -27.033352) (xy 443.298986 -27.060358) (xy 443.380486 -27.09593)
			(xy 443.419484 -27.117294) (xy 443.427236 -27.121253) (xy 443.444376 -27.124213) (xy 443.461516 -27.121253)
			(xy 443.469268 -27.117294) (xy 443.508263 -27.095926) (xy 443.589772 -27.060378) (xy 443.674499 -27.033381)
			(xy 443.761548 -27.015223) (xy 443.850002 -27.006093) (xy 443.894464 -27.005534) (xy 443.933755 -27.005967)
			(xy 444.012014 -27.013077) (xy 444.089305 -27.027257) (xy 444.16499 -27.048393) (xy 444.238446 -27.076309)
			(xy 444.27394 -27.093164) (xy 444.288672 -27.10053) (xy 444.320422 -27.095196) (xy 445.436752 -25.978866)
			(xy 445.444632 -25.970223) (xy 445.452161 -25.948109) (xy 445.45123 -25.936448) (xy 445.439292 -25.844754)
			(xy 445.426338 -25.82545) (xy 445.415924 -25.819354) (xy 445.391626 -25.804578) (xy 445.347304 -25.768949)
			(xy 445.308774 -25.727126) (xy 445.276892 -25.680037) (xy 445.252368 -25.62873) (xy 445.235747 -25.574347)
			(xy 445.227399 -25.518096) (xy 445.226948 -25.489662) (xy 445.227436 -25.462411) (xy 445.235197 -25.408465)
			(xy 445.250555 -25.356173) (xy 445.273198 -25.306597) (xy 445.302664 -25.260749) (xy 445.338355 -25.219559)
			(xy 445.379544 -25.183868) (xy 445.425392 -25.154401) (xy 445.474967 -25.131757) (xy 445.52726 -25.116398)
			(xy 445.581205 -25.108637) (xy 445.608456 -25.108154) (xy 445.636447 -25.10865) (xy 445.691828 -25.116839)
			(xy 445.745418 -25.133032) (xy 445.796066 -25.156883) (xy 445.842685 -25.187878) (xy 445.884275 -25.225354)
			(xy 445.919942 -25.268504) (xy 445.94892 -25.316403) (xy 445.970589 -25.368023) (xy 445.984481 -25.422255)
			(xy 445.987932 -25.450038) (xy 445.989456 -25.464516) (xy 446.00749 -25.48763) (xy 446.107566 -25.523444)
			(xy 446.11675 -25.526264) (xy 446.135937 -25.525605) (xy 446.153558 -25.517985) (xy 446.160652 -25.511506)
			(xy 449.814696 -21.857462) (xy 449.815966 -21.855938) (xy 449.837124 -21.831928) (xy 449.882379 -21.78667)
			(xy 449.90639 -21.765514) (xy 449.907914 -21.764244) (xy 451.362318 -20.30984) (xy 451.369164 -20.302442)
			(xy 451.376889 -20.283843) (xy 451.377304 -20.273772) (xy 451.377304 -20.26793) (xy 452.895462 -20.26793)
			(xy 452.90645 -20.267398) (xy 452.926414 -20.258216) (xy 452.940701 -20.24152) (xy 452.94423 -20.2311)
			(xy 452.975726 -20.120356) (xy 452.963788 -20.089114) (xy 452.949056 -20.07997) (xy 452.914373 -20.057925)
			(xy 452.848799 -20.008381) (xy 452.788074 -19.953001) (xy 452.732715 -19.892256) (xy 452.683195 -19.826663)
			(xy 452.639936 -19.756783) (xy 452.603306 -19.683211) (xy 452.573618 -19.606574) (xy 452.551125 -19.527526)
			(xy 452.536019 -19.44674) (xy 452.528429 -19.364905) (xy 452.527924 -19.323812) (xy 452.528384 -19.282709)
			(xy 452.535968 -19.200854) (xy 452.551072 -19.120047) (xy 452.573569 -19.040979) (xy 452.603265 -18.964325)
			(xy 452.639907 -18.890737) (xy 452.683183 -18.820844) (xy 452.732724 -18.755243) (xy 452.788106 -18.694492)
			(xy 452.848858 -18.639111) (xy 452.914461 -18.589572) (xy 452.984354 -18.546298) (xy 453.057943 -18.509657)
			(xy 453.134598 -18.479962) (xy 453.213667 -18.457468) (xy 453.294473 -18.442365) (xy 453.376329 -18.434783)
			(xy 453.417432 -18.434304) (xy 453.442699 -18.434512) (xy 453.493148 -18.437436) (xy 453.51827 -18.440146)
			(xy 453.530096 -18.44089) (xy 453.552336 -18.432799) (xy 453.560942 -18.424652) (xy 453.588843 -18.39609)
			(xy 453.648971 -18.343546) (xy 453.713568 -18.296604) (xy 453.782113 -18.255644) (xy 453.854056 -18.220996)
			(xy 453.928816 -18.192939) (xy 454.00579 -18.171698) (xy 454.08436 -18.157445) (xy 454.16389 -18.150295)
			(xy 454.203816 -18.149824) (xy 454.247122 -18.150338) (xy 454.333325 -18.158747) (xy 454.418303 -18.175495)
			(xy 454.50125 -18.200423) (xy 454.581383 -18.233294) (xy 454.657941 -18.273797) (xy 454.7302 -18.32155)
			(xy 454.76414 -18.348452) (xy 454.77557 -18.35785) (xy 454.80478 -18.361152) (xy 454.900792 -18.315432)
			(xy 454.90926 -18.310984) (xy 454.922333 -18.297041) (xy 454.929364 -18.279268) (xy 454.929748 -18.269712)
			(xy 454.929748 -14.137894) (xy 454.922128 -14.119098) (xy 454.914762 -14.111986) (xy 454.759314 -13.956538)
			(xy 454.751913 -13.949701) (xy 454.733314 -13.941992) (xy 454.723246 -13.941552) (xy 453.10171 -13.941552)
			(xy 453.07377 -13.964666) (xy 453.070214 -13.982954) (xy 453.062122 -14.023189) (xy 453.0395 -14.102087)
			(xy 453.009706 -14.178565) (xy 452.972993 -14.251973) (xy 452.929674 -14.321687) (xy 452.880116 -14.387114)
			(xy 452.824742 -14.447697) (xy 452.764023 -14.502921) (xy 452.698474 -14.552317) (xy 452.628653 -14.595464)
			(xy 452.555154 -14.631995) (xy 452.478603 -14.6616) (xy 452.39965 -14.684027) (xy 452.318966 -14.699085)
			(xy 452.237238 -14.706646) (xy 452.1962 -14.707108) (xy 452.155213 -14.706643) (xy 452.073585 -14.699108)
			(xy 451.992997 -14.684093) (xy 451.914133 -14.661724) (xy 451.837662 -14.632193) (xy 451.764234 -14.595749)
			(xy 451.694471 -14.552703) (xy 451.628966 -14.503418) (xy 451.568274 -14.448315) (xy 451.512912 -14.387859)
			(xy 451.463348 -14.322565) (xy 451.420003 -14.252987) (xy 451.383246 -14.179715) (xy 451.367906 -14.141704)
			(xy 451.364707 -14.134204) (xy 451.354344 -14.121628) (xy 451.347586 -14.117066) (xy 451.326164 -14.103223)
			(xy 451.286878 -14.070696) (xy 451.252288 -14.033213) (xy 451.223013 -13.991447) (xy 451.210934 -13.968984)
			(xy 451.20433 -13.956284) (xy 451.1802 -13.941552) (xy 450.277484 -13.941552) (xy 450.249798 -13.963904)
			(xy 450.245988 -13.98143) (xy 450.236326 -14.023439) (xy 450.209931 -14.105505) (xy 450.175721 -14.184632)
			(xy 450.134015 -14.260078) (xy 450.085205 -14.331134) (xy 450.02975 -14.397136) (xy 449.968169 -14.457462)
			(xy 449.90104 -14.511547) (xy 449.828994 -14.558883) (xy 449.752705 -14.599027) (xy 449.672891 -14.631602)
			(xy 449.590299 -14.656302) (xy 449.505705 -14.672895) (xy 449.419903 -14.681226) (xy 449.3768 -14.681708)
			(xy 449.332888 -14.681174) (xy 449.245491 -14.672516) (xy 449.159371 -14.655293) (xy 449.075366 -14.629673)
			(xy 448.994292 -14.595906) (xy 448.916938 -14.554318) (xy 448.844055 -14.505316) (xy 448.809872 -14.477746)
			(xy 448.802736 -14.472372) (xy 448.785909 -14.466416) (xy 448.76806 -14.466562) (xy 448.75958 -14.469364)
			(xy 448.7186 -14.484381) (xy 448.634374 -14.507284) (xy 448.591432 -14.515084) (xy 448.58226 -14.517053)
			(xy 448.566103 -14.526557) (xy 448.559936 -14.533626) (xy 448.54114 -14.557502) (xy 448.535826 -14.564815)
			(xy 448.530229 -14.581991) (xy 448.530218 -14.59103) (xy 448.530472 -14.607032) (xy 448.529986 -14.634283)
			(xy 448.52223 -14.688231) (xy 448.506875 -14.740526) (xy 448.484233 -14.790103) (xy 448.454767 -14.835953)
			(xy 448.419076 -14.877144) (xy 448.377885 -14.912835) (xy 448.332035 -14.942301) (xy 448.282458 -14.964943)
			(xy 448.230163 -14.980298) (xy 448.176215 -14.988054) (xy 448.121713 -14.988054) (xy 448.067765 -14.980298)
			(xy 448.01547 -14.964943) (xy 447.965893 -14.942301) (xy 447.920043 -14.912835) (xy 447.878852 -14.877144)
			(xy 447.843161 -14.835953) (xy 447.813695 -14.790103) (xy 447.791053 -14.740526) (xy 447.775698 -14.688231)
			(xy 447.767942 -14.634283) (xy 447.767456 -14.607032) (xy 447.768023 -14.576842) (xy 447.777532 -14.517216)
			(xy 447.796332 -14.459838) (xy 447.823953 -14.406146) (xy 447.84137 -14.38148) (xy 447.846407 -14.37394)
			(xy 447.851353 -14.356506) (xy 447.851022 -14.347444) (xy 447.848482 -14.317218) (xy 447.847402 -14.307878)
			(xy 447.839308 -14.290921) (xy 447.832734 -14.284198) (xy 447.798686 -14.251142) (xy 447.73708 -14.178954)
			(xy 447.683507 -14.100619) (xy 447.638575 -14.017028) (xy 447.620136 -13.973302) (xy 447.615926 -13.964093)
			(xy 447.601683 -13.949725) (xy 447.583008 -13.941943) (xy 447.572892 -13.941552) (xy 442.463428 -13.941552)
			(xy 442.452913 -13.942072) (xy 442.433625 -13.950458) (xy 442.42609 -13.957808) (xy 442.368178 -14.0208)
			(xy 442.36132 -14.040612) (xy 442.362336 -14.05128) (xy 442.363666 -14.06922) (xy 442.365063 -14.105172)
			(xy 442.36513 -14.123162) (xy 442.364646 -14.16412) (xy 442.357086 -14.245688) (xy 442.342062 -14.326215)
			(xy 442.319701 -14.405021) (xy 442.290194 -14.481439) (xy 442.253789 -14.554822) (xy 442.210795 -14.62455)
			(xy 442.186568 -14.657578) (xy 442.186392 -14.657832) (xy 446.573146 -14.657832) (xy 446.577217 -14.60221)
			(xy 446.589343 -14.547773) (xy 446.609266 -14.495682) (xy 446.636562 -14.447047) (xy 446.670648 -14.402904)
			(xy 446.710797 -14.364195) (xy 446.756155 -14.331744) (xy 446.805755 -14.306243) (xy 446.858539 -14.288236)
			(xy 446.913382 -14.278106) (xy 446.969116 -14.276069) (xy 447.024553 -14.282169) (xy 447.07851 -14.296275)
			(xy 447.129839 -14.318087) (xy 447.177445 -14.347141) (xy 447.220313 -14.382816) (xy 447.25753 -14.424353)
			(xy 447.288303 -14.470866) (xy 447.311975 -14.521363) (xy 447.328043 -14.57477) (xy 447.336163 -14.629946)
			(xy 447.336672 -14.657832) (xy 447.336163 -14.685718) (xy 447.328043 -14.740894) (xy 447.311975 -14.794301)
			(xy 447.288303 -14.844798) (xy 447.25753 -14.891311) (xy 447.220313 -14.932848) (xy 447.177445 -14.968523)
			(xy 447.129839 -14.997577) (xy 447.07851 -15.019389) (xy 447.024553 -15.033495) (xy 446.969116 -15.039595)
			(xy 446.913382 -15.037558) (xy 446.858539 -15.027428) (xy 446.805755 -15.009421) (xy 446.756155 -14.98392)
			(xy 446.710797 -14.951469) (xy 446.670648 -14.91276) (xy 446.636562 -14.868617) (xy 446.609266 -14.819982)
			(xy 446.589343 -14.767891) (xy 446.577217 -14.713454) (xy 446.573146 -14.657832) (xy 442.186392 -14.657832)
			(xy 442.181863 -14.664373) (xy 442.176667 -14.680052) (xy 442.176408 -14.688312) (xy 442.176408 -18.449798)
			(xy 445.622934 -18.449798) (xy 445.623464 -18.407497) (xy 445.631504 -18.323278) (xy 445.647501 -18.240202)
			(xy 445.67131 -18.159019) (xy 445.702718 -18.080463) (xy 445.74144 -18.005243) (xy 445.787127 -17.934037)
			(xy 445.839365 -17.867489) (xy 445.897685 -17.8062) (xy 445.961558 -17.750723) (xy 446.030408 -17.701559)
			(xy 446.103615 -17.659151) (xy 446.141856 -17.641062) (xy 446.150289 -17.636862) (xy 446.163463 -17.623409)
			(xy 446.16751 -17.6149) (xy 446.179448 -17.586706) (xy 446.182664 -17.578162) (xy 446.183442 -17.559935)
			(xy 446.180972 -17.551146) (xy 446.172351 -17.522576) (xy 446.163032 -17.463634) (xy 446.16243 -17.433798)
			(xy 446.162916 -17.406547) (xy 446.170672 -17.352599) (xy 446.186027 -17.300304) (xy 446.208669 -17.250727)
			(xy 446.238135 -17.204877) (xy 446.273826 -17.163686) (xy 446.315017 -17.127995) (xy 446.360867 -17.098529)
			(xy 446.410444 -17.075887) (xy 446.462739 -17.060532) (xy 446.516687 -17.052776) (xy 446.571189 -17.052776)
			(xy 446.625137 -17.060532) (xy 446.677432 -17.075887) (xy 446.727009 -17.098529) (xy 446.772859 -17.127995)
			(xy 446.81405 -17.163686) (xy 446.849741 -17.204877) (xy 446.879207 -17.250727) (xy 446.901849 -17.300304)
			(xy 446.917204 -17.352599) (xy 446.92496 -17.406547) (xy 446.925446 -17.433798) (xy 446.925094 -17.457641)
			(xy 446.919171 -17.504959) (xy 446.907403 -17.55117) (xy 446.89903 -17.573498) (xy 446.896011 -17.582106)
			(xy 446.89562 -17.600329) (xy 446.898268 -17.609058) (xy 446.908428 -17.63776) (xy 446.911978 -17.646502)
			(xy 446.92422 -17.660835) (xy 446.932304 -17.6657) (xy 446.970503 -17.686808) (xy 447.043045 -17.735339)
			(xy 447.110485 -17.790741) (xy 447.172173 -17.852483) (xy 447.227518 -17.91997) (xy 447.275986 -17.992554)
			(xy 447.317111 -18.069536) (xy 447.350499 -18.150176) (xy 447.375827 -18.233699) (xy 447.392852 -18.319301)
			(xy 447.401411 -18.406159) (xy 447.40195 -18.449798) (xy 447.401446 -18.492146) (xy 447.393395 -18.57646)
			(xy 447.377366 -18.659626) (xy 447.353505 -18.740893) (xy 447.322026 -18.819523) (xy 447.283215 -18.894804)
			(xy 447.237425 -18.966056) (xy 447.185069 -19.032632) (xy 447.126621 -19.09393) (xy 447.062611 -19.149395)
			(xy 446.993619 -19.198524) (xy 446.920269 -19.240873) (xy 446.843226 -19.276057) (xy 446.763187 -19.303759)
			(xy 446.680878 -19.323727) (xy 446.597043 -19.33578) (xy 446.512442 -19.339811) (xy 446.427841 -19.33578)
			(xy 446.344006 -19.323727) (xy 446.261697 -19.303759) (xy 446.181658 -19.276057) (xy 446.104615 -19.240873)
			(xy 446.031265 -19.198524) (xy 445.962273 -19.149395) (xy 445.898263 -19.09393) (xy 445.839815 -19.032632)
			(xy 445.787459 -18.966056) (xy 445.741669 -18.894804) (xy 445.702858 -18.819523) (xy 445.671379 -18.740893)
			(xy 445.647518 -18.659626) (xy 445.631489 -18.57646) (xy 445.623438 -18.492146) (xy 445.622934 -18.449798)
			(xy 442.176408 -18.449798) (xy 442.176408 -20.254722) (xy 446.285618 -20.254722) (xy 446.289689 -20.1991)
			(xy 446.301815 -20.144663) (xy 446.321738 -20.092572) (xy 446.349034 -20.043937) (xy 446.38312 -19.999794)
			(xy 446.423269 -19.961085) (xy 446.468627 -19.928634) (xy 446.518227 -19.903133) (xy 446.571011 -19.885126)
			(xy 446.625854 -19.874996) (xy 446.681588 -19.872959) (xy 446.737025 -19.879059) (xy 446.790982 -19.893165)
			(xy 446.842311 -19.914977) (xy 446.889917 -19.944031) (xy 446.932785 -19.979706) (xy 446.970002 -20.021243)
			(xy 447.000775 -20.067756) (xy 447.024447 -20.118253) (xy 447.040515 -20.17166) (xy 447.048635 -20.226836)
			(xy 447.049144 -20.254722) (xy 447.048635 -20.282608) (xy 447.040515 -20.337784) (xy 447.024447 -20.391191)
			(xy 447.005072 -20.432522) (xy 447.937128 -20.432522) (xy 447.937613 -20.405439) (xy 447.945246 -20.351813)
			(xy 447.960391 -20.299807) (xy 447.982742 -20.250467) (xy 448.01185 -20.204787) (xy 448.047129 -20.163684)
			(xy 448.087869 -20.127988) (xy 448.13325 -20.098415) (xy 448.182359 -20.075562) (xy 448.208146 -20.06727)
			(xy 448.219068 -20.063968) (xy 448.235832 -20.048982) (xy 448.275202 -19.956272) (xy 448.27444 -19.93392)
			(xy 448.269106 -19.92376) (xy 448.250322 -19.886049) (xy 448.219172 -19.807764) (xy 448.195571 -19.726882)
			(xy 448.17973 -19.64413) (xy 448.171792 -19.56025) (xy 448.171316 -19.518122) (xy 448.171744 -19.476362)
			(xy 448.179588 -19.393211) (xy 448.195191 -19.311162) (xy 448.218416 -19.230936) (xy 448.249057 -19.15324)
			(xy 448.286846 -19.078758) (xy 448.331448 -19.008145) (xy 448.382473 -18.942023) (xy 448.43947 -18.880975)
			(xy 448.501938 -18.825537) (xy 448.569327 -18.776199) (xy 448.641044 -18.733393) (xy 448.716457 -18.697498)
			(xy 448.755516 -18.682716) (xy 448.763756 -18.679388) (xy 448.777379 -18.667992) (xy 448.78629 -18.652628)
			(xy 448.789419 -18.635144) (xy 448.788282 -18.626328) (xy 448.782214 -18.58884) (xy 448.775726 -18.513171)
			(xy 448.775328 -18.475198) (xy 448.77575 -18.434094) (xy 448.783336 -18.352236) (xy 448.798442 -18.271427)
			(xy 448.82094 -18.192357) (xy 448.850638 -18.1157) (xy 448.887283 -18.042111) (xy 448.930561 -17.972216)
			(xy 448.980104 -17.906614) (xy 449.035489 -17.845862) (xy 449.096243 -17.79048) (xy 449.161848 -17.74094)
			(xy 449.231744 -17.697664) (xy 449.305335 -17.661023) (xy 449.381993 -17.631328) (xy 449.461064 -17.608834)
			(xy 449.541874 -17.593731) (xy 449.623732 -17.586149) (xy 449.664836 -17.58569) (xy 449.706215 -17.586191)
			(xy 449.788614 -17.59389) (xy 449.869941 -17.609209) (xy 449.949494 -17.632015) (xy 450.026586 -17.662111)
			(xy 450.100548 -17.699237) (xy 450.170743 -17.743072) (xy 450.236563 -17.793237) (xy 450.29744 -17.849298)
			(xy 450.352846 -17.910772) (xy 450.402304 -17.977125) (xy 450.445385 -18.047785) (xy 450.481717 -18.122141)
			(xy 450.510986 -18.19955) (xy 450.532939 -18.279343) (xy 450.540628 -18.320004) (xy 450.543168 -18.334228)
			(xy 450.562218 -18.355564) (xy 450.676264 -18.390362) (xy 450.70395 -18.38325) (xy 450.713856 -18.372836)
			(xy 450.731887 -18.354686) (xy 450.771988 -18.322913) (xy 450.815976 -18.296786) (xy 450.863061 -18.276771)
			(xy 450.912398 -18.263229) (xy 450.963103 -18.256402) (xy 450.988684 -18.255996) (xy 451.015938 -18.25645)
			(xy 451.069891 -18.264205) (xy 451.122191 -18.27956) (xy 451.171774 -18.302202) (xy 451.21763 -18.33167)
			(xy 451.258825 -18.367364) (xy 451.29452 -18.408558) (xy 451.32399 -18.454412) (xy 451.346634 -18.503994)
			(xy 451.361991 -18.556293) (xy 451.369749 -18.610246) (xy 451.369749 -18.664754) (xy 451.361991 -18.718707)
			(xy 451.346634 -18.771006) (xy 451.32399 -18.820588) (xy 451.29452 -18.866442) (xy 451.258825 -18.907636)
			(xy 451.21763 -18.94333) (xy 451.171774 -18.972798) (xy 451.122191 -18.99544) (xy 451.069891 -19.010795)
			(xy 451.015938 -19.01855) (xy 450.988684 -19.019012) (xy 450.960115 -19.018478) (xy 450.903615 -19.009975)
			(xy 450.849017 -18.993132) (xy 450.797545 -18.968326) (xy 450.750354 -18.936115) (xy 450.708501 -18.897218)
			(xy 450.672924 -18.852509) (xy 450.65823 -18.828004) (xy 450.650864 -18.815558) (xy 450.625718 -18.801842)
			(xy 450.506592 -18.807938) (xy 450.483224 -18.824194) (xy 450.477382 -18.837402) (xy 450.458738 -18.877865)
			(xy 450.414508 -18.955209) (xy 450.362763 -19.027739) (xy 450.304022 -19.09473) (xy 450.238874 -19.155508)
			(xy 450.167972 -19.209465) (xy 450.092029 -19.256058) (xy 450.011806 -19.29482) (xy 449.970144 -19.310604)
			(xy 449.961952 -19.314034) (xy 449.948328 -19.325396) (xy 449.939404 -19.340727) (xy 449.936254 -19.358185)
			(xy 449.937378 -19.366992) (xy 449.943448 -19.404479) (xy 449.949935 -19.480149) (xy 449.950332 -19.518122)
			(xy 449.949794 -19.560947) (xy 449.941575 -19.646201) (xy 449.925195 -19.730269) (xy 449.900806 -19.812373)
			(xy 449.868636 -19.891751) (xy 449.828981 -19.967667) (xy 449.782209 -20.039418) (xy 449.728754 -20.106339)
			(xy 449.669111 -20.167809) (xy 449.603833 -20.223259) (xy 449.533526 -20.272174) (xy 449.496434 -20.293584)
			(xy 449.486741 -20.29966) (xy 449.473594 -20.318348) (xy 449.469859 -20.34089) (xy 449.472558 -20.352004)
			(xy 449.479572 -20.377919) (xy 449.48709 -20.431078) (xy 449.487544 -20.457922) (xy 449.487027 -20.486356)
			(xy 449.478608 -20.542596) (xy 449.47078 -20.569936) (xy 449.468401 -20.578822) (xy 449.469497 -20.597172)
			(xy 449.477019 -20.613945) (xy 449.483226 -20.620736) (xy 449.513551 -20.651948) (xy 449.568612 -20.719344)
			(xy 449.616825 -20.791797) (xy 449.657727 -20.868615) (xy 449.690927 -20.949061) (xy 449.716108 -21.032367)
			(xy 449.733028 -21.117735) (xy 449.741526 -21.204348) (xy 449.742052 -21.247862) (xy 449.741548 -21.29021)
			(xy 449.733497 -21.374524) (xy 449.717468 -21.45769) (xy 449.693607 -21.538957) (xy 449.662128 -21.617587)
			(xy 449.623317 -21.692868) (xy 449.577527 -21.76412) (xy 449.525171 -21.830696) (xy 449.466723 -21.891994)
			(xy 449.402713 -21.947459) (xy 449.333721 -21.996588) (xy 449.260371 -22.038937) (xy 449.183328 -22.074121)
			(xy 449.103289 -22.101823) (xy 449.02098 -22.121791) (xy 448.937145 -22.133844) (xy 448.852544 -22.137875)
			(xy 448.767943 -22.133844) (xy 448.684108 -22.121791) (xy 448.601799 -22.101823) (xy 448.52176 -22.074121)
			(xy 448.444717 -22.038937) (xy 448.371367 -21.996588) (xy 448.302375 -21.947459) (xy 448.238365 -21.891994)
			(xy 448.179917 -21.830696) (xy 448.127561 -21.76412) (xy 448.081771 -21.692868) (xy 448.04296 -21.617587)
			(xy 448.011481 -21.538957) (xy 447.98762 -21.45769) (xy 447.971591 -21.374524) (xy 447.96354 -21.29021)
			(xy 447.963036 -21.247862) (xy 447.963596 -21.201892) (xy 447.973081 -21.110442) (xy 447.991946 -21.020458)
			(xy 448.019989 -20.932899) (xy 448.056911 -20.848699) (xy 448.079114 -20.808442) (xy 448.083099 -20.800629)
			(xy 448.086084 -20.783358) (xy 448.084956 -20.77466) (xy 448.079876 -20.74545) (xy 448.078056 -20.7372)
			(xy 448.06989 -20.722424) (xy 448.063874 -20.716494) (xy 448.044309 -20.698314) (xy 448.009915 -20.657458)
			(xy 447.981555 -20.612204) (xy 447.959785 -20.563436) (xy 447.945029 -20.512109) (xy 447.937577 -20.459225)
			(xy 447.937128 -20.432522) (xy 447.005072 -20.432522) (xy 447.000775 -20.441688) (xy 446.970002 -20.488201)
			(xy 446.932785 -20.529738) (xy 446.889917 -20.565413) (xy 446.842311 -20.594467) (xy 446.790982 -20.616279)
			(xy 446.737025 -20.630385) (xy 446.681588 -20.636485) (xy 446.625854 -20.634448) (xy 446.571011 -20.624318)
			(xy 446.518227 -20.606311) (xy 446.468627 -20.58081) (xy 446.423269 -20.548359) (xy 446.38312 -20.50965)
			(xy 446.349034 -20.465507) (xy 446.321738 -20.416872) (xy 446.301815 -20.364781) (xy 446.289689 -20.310344)
			(xy 446.285618 -20.254722) (xy 442.176408 -20.254722) (xy 442.176408 -21.033994) (xy 442.175986 -21.044065)
			(xy 442.168274 -21.062672) (xy 442.161422 -21.070062) (xy 441.983622 -21.247862) (xy 446.286888 -21.247862)
			(xy 446.290959 -21.19224) (xy 446.303085 -21.137803) (xy 446.323008 -21.085712) (xy 446.350304 -21.037077)
			(xy 446.38439 -20.992934) (xy 446.424539 -20.954225) (xy 446.469897 -20.921774) (xy 446.519497 -20.896273)
			(xy 446.572281 -20.878266) (xy 446.627124 -20.868136) (xy 446.682858 -20.866099) (xy 446.738295 -20.872199)
			(xy 446.792252 -20.886305) (xy 446.843581 -20.908117) (xy 446.891187 -20.937171) (xy 446.934055 -20.972846)
			(xy 446.971272 -21.014383) (xy 447.002045 -21.060896) (xy 447.025717 -21.111393) (xy 447.041785 -21.1648)
			(xy 447.049905 -21.219976) (xy 447.050414 -21.247862) (xy 447.049905 -21.275748) (xy 447.041785 -21.330924)
			(xy 447.025717 -21.384331) (xy 447.002045 -21.434828) (xy 446.971272 -21.481341) (xy 446.934055 -21.522878)
			(xy 446.891187 -21.558553) (xy 446.843581 -21.587607) (xy 446.792252 -21.609419) (xy 446.738295 -21.623525)
			(xy 446.682858 -21.629625) (xy 446.627124 -21.627588) (xy 446.572281 -21.617458) (xy 446.519497 -21.599451)
			(xy 446.469897 -21.57395) (xy 446.424539 -21.541499) (xy 446.38439 -21.50279) (xy 446.350304 -21.458647)
			(xy 446.323008 -21.410012) (xy 446.303085 -21.357921) (xy 446.290959 -21.303484) (xy 446.286888 -21.247862)
			(xy 441.983622 -21.247862) (xy 441.879228 -21.352256) (xy 441.871828 -21.359096) (xy 441.853229 -21.366811)
			(xy 441.84316 -21.367242) (xy 440.85891 -21.367242) (xy 440.85347 -21.367381) (xy 440.842835 -21.369683)
			(xy 440.837828 -21.371814) (xy 440.837828 -22.136862) (xy 446.287398 -22.136862) (xy 446.287842 -22.10961)
			(xy 446.295604 -22.05566) (xy 446.310965 -22.003364) (xy 446.333611 -21.953786) (xy 446.363081 -21.907936)
			(xy 446.398777 -21.866746) (xy 446.439971 -21.831055) (xy 446.485825 -21.801589) (xy 446.535405 -21.778949)
			(xy 446.587703 -21.763595) (xy 446.641653 -21.755839) (xy 446.668906 -21.755354) (xy 446.6965 -21.755882)
			(xy 446.75111 -21.763847) (xy 446.804003 -21.779595) (xy 446.854077 -21.802798) (xy 446.900285 -21.832972)
			(xy 446.941665 -21.869488) (xy 446.977354 -21.911583) (xy 447.006607 -21.95838) (xy 447.018156 -21.983446)
			(xy 447.022313 -21.991779) (xy 447.035482 -22.004929) (xy 447.04381 -22.0091) (xy 447.07175 -22.0218)
			(xy 447.080736 -22.025401) (xy 447.100058 -22.02632) (xy 447.109342 -22.023578) (xy 447.144444 -22.011855)
			(xy 447.216166 -21.99359) (xy 447.289157 -21.981341) (xy 447.362912 -21.975191) (xy 447.399918 -21.97481)
			(xy 447.441842 -21.975294) (xy 447.525318 -21.983187) (xy 447.607681 -21.9989) (xy 447.688199 -22.022294)
			(xy 447.766159 -22.053162) (xy 447.840868 -22.09123) (xy 447.911662 -22.136159) (xy 447.977915 -22.187551)
			(xy 448.039037 -22.24495) (xy 448.094486 -22.307846) (xy 448.14377 -22.375681) (xy 448.186451 -22.447854)
			(xy 448.222151 -22.523722) (xy 448.250553 -22.602614) (xy 448.271404 -22.683828) (xy 448.284521 -22.766644)
			(xy 448.289785 -22.850327) (xy 448.287151 -22.934134) (xy 448.276641 -23.017321) (xy 448.25835 -23.099149)
			(xy 448.232439 -23.178894) (xy 448.199138 -23.255846) (xy 448.158744 -23.329322) (xy 448.111614 -23.398672)
			(xy 448.058167 -23.463278) (xy 447.998878 -23.522567) (xy 447.934272 -23.576014) (xy 447.864922 -23.623144)
			(xy 447.791446 -23.663538) (xy 447.714494 -23.696839) (xy 447.634749 -23.72275) (xy 447.552921 -23.741041)
			(xy 447.469734 -23.751551) (xy 447.385927 -23.754185) (xy 447.302244 -23.748921) (xy 447.219428 -23.735804)
			(xy 447.138214 -23.714953) (xy 447.059322 -23.686551) (xy 446.983454 -23.650851) (xy 446.911281 -23.60817)
			(xy 446.843446 -23.558886) (xy 446.78055 -23.503437) (xy 446.723151 -23.442315) (xy 446.671759 -23.376062)
			(xy 446.62683 -23.305268) (xy 446.588762 -23.230559) (xy 446.557894 -23.152599) (xy 446.5345 -23.072081)
			(xy 446.518787 -22.989718) (xy 446.510894 -22.906242) (xy 446.51041 -22.864318) (xy 446.511084 -22.815684)
			(xy 446.521725 -22.719) (xy 446.542849 -22.624054) (xy 446.557908 -22.577806) (xy 446.560613 -22.568504)
			(xy 446.559556 -22.549176) (xy 446.555876 -22.540214) (xy 446.542922 -22.512274) (xy 446.538643 -22.504008)
			(xy 446.525365 -22.490985) (xy 446.517014 -22.486874) (xy 446.491816 -22.475349) (xy 446.444717 -22.446166)
			(xy 446.402334 -22.410478) (xy 446.365558 -22.369035) (xy 446.335162 -22.32271) (xy 446.311786 -22.272476)
			(xy 446.29592 -22.219389) (xy 446.287898 -22.164565) (xy 446.287398 -22.136862) (xy 440.837828 -22.136862)
			(xy 440.837828 -23.5781) (xy 441.09303 -23.5781) (xy 441.09706 -23.493493) (xy 441.109115 -23.409651)
			(xy 441.129085 -23.327336) (xy 441.156789 -23.247291) (xy 441.191976 -23.170243) (xy 441.234328 -23.096888)
			(xy 441.283461 -23.027891) (xy 441.338931 -22.963876) (xy 441.400234 -22.905425) (xy 441.466816 -22.853065)
			(xy 441.538073 -22.807272) (xy 441.613361 -22.76846) (xy 441.691997 -22.73698) (xy 441.77327 -22.713117)
			(xy 441.856442 -22.697088) (xy 441.940762 -22.689038) (xy 441.983114 -22.68855) (xy 442.025557 -22.689042)
			(xy 442.110058 -22.69713) (xy 442.193403 -22.713231) (xy 442.274836 -22.737198) (xy 442.353615 -22.768813)
			(xy 442.391546 -22.787864) (xy 442.40271 -22.792845) (xy 442.427118 -22.792845) (xy 442.438282 -22.787864)
			(xy 442.476212 -22.768812) (xy 442.554991 -22.737195) (xy 442.636424 -22.713228) (xy 442.71977 -22.697128)
			(xy 442.804271 -22.689042) (xy 442.846714 -22.68855) (xy 442.88906 -22.689138) (xy 442.973369 -22.69719)
			(xy 443.05653 -22.713219) (xy 443.137791 -22.737081) (xy 443.216416 -22.768559) (xy 443.291693 -22.807368)
			(xy 443.36294 -22.853156) (xy 443.429513 -22.90551) (xy 443.490807 -22.963955) (xy 443.546268 -23.027961)
			(xy 443.595394 -23.09695) (xy 443.637739 -23.170296) (xy 443.672921 -23.247335) (xy 443.700621 -23.327369)
			(xy 443.720588 -23.409674) (xy 443.732641 -23.493504) (xy 443.736671 -23.5781) (xy 443.732641 -23.662696)
			(xy 443.720588 -23.746526) (xy 443.700621 -23.828831) (xy 443.672921 -23.908865) (xy 443.637739 -23.985904)
			(xy 443.595394 -24.05925) (xy 443.546268 -24.128239) (xy 443.490807 -24.192245) (xy 443.429513 -24.25069)
			(xy 443.36294 -24.303044) (xy 443.291693 -24.348832) (xy 443.216416 -24.387641) (xy 443.137791 -24.419119)
			(xy 443.05653 -24.442981) (xy 442.973369 -24.45901) (xy 442.88906 -24.467062) (xy 442.846714 -24.467566)
			(xy 442.804271 -24.467061) (xy 442.719771 -24.458976) (xy 442.636426 -24.442878) (xy 442.554993 -24.418914)
			(xy 442.476213 -24.387301) (xy 442.438282 -24.368252) (xy 442.427118 -24.363271) (xy 442.40271 -24.363271)
			(xy 442.391546 -24.368252) (xy 442.353611 -24.387295) (xy 442.274834 -24.418913) (xy 442.193402 -24.442882)
			(xy 442.110057 -24.458984) (xy 442.025557 -24.467073) (xy 441.983114 -24.467566) (xy 441.940762 -24.467162)
			(xy 441.856442 -24.459112) (xy 441.77327 -24.443083) (xy 441.691997 -24.41922) (xy 441.613361 -24.38774)
			(xy 441.538073 -24.348928) (xy 441.466816 -24.303135) (xy 441.400234 -24.250775) (xy 441.338931 -24.192324)
			(xy 441.283461 -24.128309) (xy 441.234328 -24.059312) (xy 441.191976 -23.985957) (xy 441.156789 -23.908909)
			(xy 441.129085 -23.828864) (xy 441.109115 -23.746549) (xy 441.09706 -23.662707) (xy 441.09303 -23.5781)
			(xy 440.837828 -23.5781) (xy 440.837828 -26.938224) (xy 440.838418 -26.949983) (xy 440.848873 -26.971046)
			(xy 440.857894 -26.97861) (xy 440.931554 -27.034744) (xy 440.954922 -27.039316) (xy 440.966352 -27.036268)
			(xy 441.003575 -27.026506) (xy 441.079313 -27.012845) (xy 441.155964 -27.005968) (xy 441.194444 -27.005534)
			(xy 441.238882 -27.006101) (xy 441.327288 -27.015223) (xy 441.41429 -27.033376) (xy 441.498968 -27.060368)
			(xy 441.580426 -27.095914) (xy 441.619386 -27.117294) (xy 441.627165 -27.121318) (xy 441.644405 -27.124336)
			(xy 441.661645 -27.121318) (xy 441.669424 -27.117294) (xy 441.704825 -27.097831) (xy 441.778569 -27.06483)
			(xy 441.855071 -27.038858) (xy 441.933665 -27.020143) (xy 442.013663 -27.008848) (xy 442.094366 -27.005072)
			(xy 442.175069 -27.008848) (xy 442.255067 -27.020143) (xy 442.333661 -27.038858) (xy 442.410163 -27.06483)
			(xy 442.483907 -27.097831)
		)
		(stroke
			(width 0)
			(type solid)
		)
		(fill yes)
		(layer "In4.Cu")
		(net "P12V_OCP_SFF")
	)
	(gr_poly
		(pts
			(xy 436.66537 -112.609884) (xy 436.675434 -112.609448) (xy 436.694019 -112.601714) (xy 436.701438 -112.594898)
			(xy 437.545988 -111.750348) (xy 437.552828 -111.742947) (xy 437.560545 -111.724349) (xy 437.560974 -111.71428)
			(xy 437.560974 -102.429056) (xy 437.560542 -102.41899) (xy 437.552814 -102.400399) (xy 437.545988 -102.392988)
			(xy 436.79872 -101.64572) (xy 436.791318 -101.638884) (xy 436.77272 -101.631176) (xy 436.762652 -101.630734)
			(xy 433.889912 -101.630734) (xy 433.879842 -101.630311) (xy 433.861241 -101.622593) (xy 433.853844 -101.615748)
			(xy 432.717956 -100.47986) (xy 432.71111 -100.472462) (xy 432.703381 -100.453863) (xy 432.70297 -100.443792)
			(xy 432.70297 -97.230946) (xy 432.702536 -97.220881) (xy 432.694805 -97.202293) (xy 432.687984 -97.194878)
			(xy 431.551842 -96.058736) (xy 431.544442 -96.051895) (xy 431.525843 -96.044176) (xy 431.515774 -96.04375)
			(xy 414.797748 -96.04375) (xy 414.787683 -96.044184) (xy 414.769097 -96.051917) (xy 414.76168 -96.058736)
			(xy 413.965644 -96.854772) (xy 413.958804 -96.862172) (xy 413.951089 -96.880771) (xy 413.950658 -96.89084)
			(xy 413.950658 -99.80295) (xy 414.058606 -99.80295) (xy 414.062679 -99.747291) (xy 414.074814 -99.692818)
			(xy 414.09475 -99.640692) (xy 414.122064 -99.592024) (xy 414.156172 -99.547852) (xy 414.196349 -99.509117)
			(xy 414.241737 -99.476645) (xy 414.291369 -99.451127) (xy 414.344189 -99.433108) (xy 414.399068 -99.422971)
			(xy 414.454839 -99.420933) (xy 414.510313 -99.427036) (xy 414.564306 -99.441152) (xy 414.615669 -99.462979)
			(xy 414.663307 -99.492052) (xy 414.706203 -99.527751) (xy 414.743445 -99.569315) (xy 414.774239 -99.615859)
			(xy 414.797927 -99.66639) (xy 414.814005 -99.719832) (xy 414.822131 -99.775046) (xy 414.82264 -99.80295)
			(xy 414.822131 -99.830854) (xy 414.814005 -99.886068) (xy 414.797927 -99.93951) (xy 414.774239 -99.990041)
			(xy 414.743445 -100.036585) (xy 414.706203 -100.078149) (xy 414.663307 -100.113848) (xy 414.615669 -100.142921)
			(xy 414.564306 -100.164748) (xy 414.510313 -100.178864) (xy 414.454839 -100.184967) (xy 414.399068 -100.182929)
			(xy 414.344189 -100.172792) (xy 414.291369 -100.154773) (xy 414.241737 -100.129255) (xy 414.196349 -100.096783)
			(xy 414.156172 -100.058048) (xy 414.122064 -100.013876) (xy 414.09475 -99.965208) (xy 414.074814 -99.913082)
			(xy 414.062679 -99.858609) (xy 414.058606 -99.80295) (xy 413.950658 -99.80295) (xy 413.950658 -102.63945)
			(xy 429.495968 -102.63945) (xy 429.495968 -102.58495) (xy 429.503724 -102.531003) (xy 429.519077 -102.47871)
			(xy 429.541717 -102.429134) (xy 429.57118 -102.383284) (xy 429.606869 -102.342093) (xy 429.648057 -102.306401)
			(xy 429.693904 -102.276933) (xy 429.743478 -102.254289) (xy 429.79577 -102.238931) (xy 429.849716 -102.23117)
			(xy 429.876966 -102.230682) (xy 429.903569 -102.231164) (xy 429.95626 -102.238541) (xy 430.007415 -102.25317)
			(xy 430.056039 -102.274767) (xy 430.10119 -102.302914) (xy 430.14199 -102.337062) (xy 430.177648 -102.376551)
			(xy 430.192942 -102.398322) (xy 430.200507 -102.408301) (xy 430.222601 -102.420025) (xy 430.235106 -102.420674)
			(xy 430.318926 -102.420674) (xy 430.331447 -102.420083) (xy 430.353565 -102.408348) (xy 430.36109 -102.398322)
			(xy 430.376374 -102.376544) (xy 430.412042 -102.337065) (xy 430.452848 -102.302923) (xy 430.498 -102.274779)
			(xy 430.546623 -102.253178) (xy 430.597775 -102.238539) (xy 430.650463 -102.231145) (xy 430.677066 -102.230682)
			(xy 430.704318 -102.231187) (xy 430.758266 -102.238939) (xy 430.810563 -102.25429) (xy 430.860142 -102.276928)
			(xy 430.905995 -102.306392) (xy 430.947188 -102.342081) (xy 430.982882 -102.38327) (xy 431.012351 -102.429119)
			(xy 431.034994 -102.478696) (xy 431.050352 -102.53099) (xy 431.05811 -102.584938) (xy 431.058574 -102.61219)
			(xy 431.058169 -102.636998) (xy 431.057848 -102.639451) (xy 431.370468 -102.639451) (xy 431.370468 -102.584949)
			(xy 431.378224 -102.531001) (xy 431.393579 -102.478706) (xy 431.41622 -102.429128) (xy 431.445685 -102.383277)
			(xy 431.481376 -102.342086) (xy 431.522566 -102.306394) (xy 431.568416 -102.276926) (xy 431.617993 -102.254284)
			(xy 431.670287 -102.238927) (xy 431.724235 -102.231169) (xy 431.751486 -102.230682) (xy 431.780451 -102.231233)
			(xy 431.837715 -102.240002) (xy 431.892995 -102.257325) (xy 431.945022 -102.282805) (xy 431.9926 -102.315856)
			(xy 432.034635 -102.355719) (xy 432.070163 -102.401477) (xy 432.084734 -102.426516) (xy 432.092088 -102.438728)
			(xy 432.112316 -102.458797) (xy 432.137304 -102.472494) (xy 432.165104 -102.47875) (xy 432.19355 -102.47708)
			(xy 432.220426 -102.467612) (xy 432.243639 -102.451085) (xy 432.252882 -102.440232) (xy 432.271098 -102.418176)
			(xy 432.313 -102.379236) (xy 432.360242 -102.346983) (xy 432.411768 -102.322139) (xy 432.466423 -102.30526)
			(xy 432.522985 -102.296724) (xy 432.551586 -102.296214) (xy 432.578841 -102.296632) (xy 432.632797 -102.304388)
			(xy 432.685099 -102.319743) (xy 432.734684 -102.342386) (xy 432.780542 -102.371856) (xy 432.821738 -102.407552)
			(xy 432.857436 -102.448747) (xy 432.886907 -102.494604) (xy 432.909552 -102.544188) (xy 432.924909 -102.59649)
			(xy 432.932667 -102.650445) (xy 432.932667 -102.704955) (xy 432.924909 -102.75891) (xy 432.909552 -102.811212)
			(xy 432.886907 -102.860796) (xy 432.857436 -102.906653) (xy 432.821738 -102.947848) (xy 432.780542 -102.983544)
			(xy 432.734684 -103.013014) (xy 432.685099 -103.035657) (xy 432.632797 -103.051012) (xy 432.578841 -103.058768)
			(xy 432.551586 -103.05923) (xy 432.522618 -103.058746) (xy 432.465349 -103.049971) (xy 432.410065 -103.032639)
			(xy 432.358036 -103.007149) (xy 432.310459 -102.974086) (xy 432.268427 -102.934212) (xy 432.232905 -102.888441)
			(xy 432.218338 -102.863396) (xy 432.211021 -102.851159) (xy 432.190786 -102.831086) (xy 432.16579 -102.817388)
			(xy 432.137982 -102.811133) (xy 432.109529 -102.812809) (xy 432.082648 -102.822285) (xy 432.059433 -102.838822)
			(xy 432.05019 -102.84968) (xy 432.031993 -102.871752) (xy 431.990086 -102.91069) (xy 431.94284 -102.942941)
			(xy 431.891311 -102.967782) (xy 431.836652 -102.984658) (xy 431.780088 -102.99319) (xy 431.751486 -102.993698)
			(xy 431.724235 -102.993231) (xy 431.670287 -102.985473) (xy 431.617993 -102.970116) (xy 431.568416 -102.947474)
			(xy 431.522566 -102.918006) (xy 431.481376 -102.882314) (xy 431.445685 -102.841123) (xy 431.41622 -102.795272)
			(xy 431.393579 -102.745694) (xy 431.378224 -102.693399) (xy 431.370468 -102.639451) (xy 431.057848 -102.639451)
			(xy 431.051732 -102.686194) (xy 431.038953 -102.734135) (xy 431.029872 -102.757224) (xy 431.0253 -102.7684)
			(xy 431.026824 -102.791514) (xy 431.03292 -102.801928) (xy 431.033428 -102.802944) (xy 431.081942 -102.883208)
			(xy 431.102262 -102.896162) (xy 431.114454 -102.897178) (xy 431.142478 -102.90029) (xy 431.197232 -102.913751)
			(xy 431.249408 -102.935124) (xy 431.29787 -102.963943) (xy 431.341562 -102.999582) (xy 431.379534 -103.041264)
			(xy 431.410956 -103.08808) (xy 431.435146 -103.139011) (xy 431.451576 -103.192948) (xy 431.459889 -103.248716)
			(xy 431.460402 -103.276908) (xy 431.45993 -103.30416) (xy 431.452172 -103.358108) (xy 431.436815 -103.410404)
			(xy 431.414173 -103.459981) (xy 431.384705 -103.505832) (xy 431.349012 -103.547022) (xy 431.307821 -103.582714)
			(xy 431.261969 -103.61218) (xy 431.21239 -103.63482) (xy 431.160095 -103.650175) (xy 431.106146 -103.657931)
			(xy 431.078894 -103.658416) (xy 431.051643 -103.657928) (xy 430.997696 -103.650171) (xy 430.945402 -103.634815)
			(xy 430.895825 -103.612174) (xy 430.849975 -103.582708) (xy 430.808785 -103.547017) (xy 430.773093 -103.505827)
			(xy 430.743627 -103.459977) (xy 430.720985 -103.4104) (xy 430.70563 -103.358106) (xy 430.697872 -103.304159)
			(xy 430.697386 -103.276908) (xy 430.697793 -103.2521) (xy 430.704229 -103.202905) (xy 430.717007 -103.154963)
			(xy 430.726088 -103.131874) (xy 430.73066 -103.120698) (xy 430.729136 -103.097584) (xy 430.72304 -103.08717)
			(xy 430.722532 -103.086154) (xy 430.674018 -103.00589) (xy 430.653698 -102.992936) (xy 430.641506 -102.99192)
			(xy 430.613609 -102.988818) (xy 430.559087 -102.975477) (xy 430.50711 -102.95429) (xy 430.458798 -102.925714)
			(xy 430.415195 -102.890368) (xy 430.377243 -102.849014) (xy 430.36109 -102.826058) (xy 430.353562 -102.816044)
			(xy 430.33144 -102.80434) (xy 430.318926 -102.803706) (xy 430.235106 -102.803706) (xy 430.222589 -102.804325)
			(xy 430.200471 -102.816041) (xy 430.192942 -102.826058) (xy 430.177632 -102.847817) (xy 430.141968 -102.887297)
			(xy 430.101167 -102.921441) (xy 430.05602 -102.949588) (xy 430.007401 -102.971192) (xy 429.956253 -102.985835)
			(xy 429.903567 -102.993232) (xy 429.876966 -102.993698) (xy 429.849716 -102.99323) (xy 429.79577 -102.985469)
			(xy 429.743478 -102.970111) (xy 429.693904 -102.947467) (xy 429.648057 -102.917999) (xy 429.606869 -102.882307)
			(xy 429.57118 -102.841116) (xy 429.541717 -102.795266) (xy 429.519077 -102.74569) (xy 429.503724 -102.693397)
			(xy 429.495968 -102.63945) (xy 413.950658 -102.63945) (xy 413.950658 -102.835456) (xy 413.951093 -102.84552)
			(xy 413.958828 -102.864105) (xy 413.965644 -102.871524) (xy 415.595308 -104.501188) (xy 418.034978 -104.501188)
			(xy 418.035432 -104.473818) (xy 418.043261 -104.419641) (xy 418.058756 -104.367139) (xy 418.081599 -104.317393)
			(xy 418.11132 -104.271424) (xy 418.128958 -104.25049) (xy 418.129212 -104.250236) (xy 418.129466 -104.249982)
			(xy 418.135074 -104.24291) (xy 418.141306 -104.225982) (xy 418.141658 -104.216962) (xy 418.141658 -104.150414)
			(xy 418.141303 -104.141397) (xy 418.135055 -104.124479) (xy 418.129466 -104.117394) (xy 418.129212 -104.11714)
			(xy 418.128958 -104.116886) (xy 418.111354 -104.095928) (xy 418.081665 -104.049949) (xy 418.058836 -104.000207)
			(xy 418.043333 -103.947717) (xy 418.035474 -103.893553) (xy 418.034978 -103.866188) (xy 418.03539 -103.838915)
			(xy 418.043155 -103.784924) (xy 418.058525 -103.732588) (xy 418.081187 -103.682972) (xy 418.11068 -103.637087)
			(xy 418.146402 -103.595866) (xy 418.187628 -103.560148) (xy 418.233518 -103.530662) (xy 418.283137 -103.508007)
			(xy 418.335475 -103.492644) (xy 418.389467 -103.484887) (xy 418.41674 -103.484426) (xy 418.442319 -103.484846)
			(xy 418.493016 -103.491693) (xy 418.542345 -103.505245) (xy 418.589425 -103.52526) (xy 418.633412 -103.55138)
			(xy 418.673518 -103.583137) (xy 418.691568 -103.601266) (xy 418.69868 -103.608632) (xy 418.717222 -103.61676)
			(xy 418.799518 -103.617776) (xy 418.809692 -103.617472) (xy 418.82856 -103.609887) (xy 418.836094 -103.603044)
			(xy 418.857657 -103.582363) (xy 418.906069 -103.547352) (xy 418.959348 -103.520319) (xy 419.016191 -103.501925)
			(xy 419.075207 -103.49262) (xy 419.10508 -103.492046) (xy 419.132351 -103.49252) (xy 419.186338 -103.50028)
			(xy 419.238671 -103.515644) (xy 419.288284 -103.5383) (xy 419.334169 -103.567786) (xy 419.375389 -103.603502)
			(xy 419.411107 -103.644722) (xy 419.440595 -103.690605) (xy 419.463252 -103.740218) (xy 419.478618 -103.79255)
			(xy 419.486379 -103.846537) (xy 419.486842 -103.873808) (xy 419.486405 -103.901179) (xy 419.478575 -103.955358)
			(xy 419.463077 -104.00786) (xy 419.44023 -104.057606) (xy 419.410504 -104.103574) (xy 419.392862 -104.124506)
			(xy 419.392608 -104.12476) (xy 419.392354 -104.125014) (xy 419.38675 -104.132088) (xy 419.380515 -104.149015)
			(xy 419.380162 -104.158034) (xy 419.380162 -104.224582) (xy 419.380536 -104.233597) (xy 419.386773 -104.250514)
			(xy 419.392354 -104.257602) (xy 419.392608 -104.257856) (xy 419.392862 -104.25811) (xy 419.410467 -104.279067)
			(xy 419.440155 -104.325046) (xy 419.462984 -104.374789) (xy 419.478486 -104.427279) (xy 419.486346 -104.481443)
			(xy 419.486842 -104.508808) (xy 419.486406 -104.53608) (xy 419.478642 -104.590069) (xy 419.463274 -104.642403)
			(xy 419.440614 -104.692018) (xy 419.411124 -104.737903) (xy 419.375403 -104.779123) (xy 419.33418 -104.81484)
			(xy 419.288293 -104.844327) (xy 419.238677 -104.866984) (xy 419.186342 -104.882348) (xy 419.132352 -104.890108)
			(xy 419.10508 -104.89057) (xy 419.079471 -104.890143) (xy 419.028716 -104.883282) (xy 418.979332 -104.869701)
			(xy 418.932206 -104.849642) (xy 418.888183 -104.823466) (xy 418.848053 -104.791641) (xy 418.829998 -104.773476)
			(xy 418.82265 -104.766502) (xy 418.804047 -104.75852) (xy 418.79393 -104.757982) (xy 418.711888 -104.756966)
			(xy 418.693346 -104.764586) (xy 418.68598 -104.771952) (xy 418.664348 -104.792592) (xy 418.61589 -104.827607)
			(xy 418.562569 -104.854646) (xy 418.505687 -104.873049) (xy 418.446632 -104.882368) (xy 418.41674 -104.88295)
			(xy 418.389469 -104.882461) (xy 418.335483 -104.874704) (xy 418.28315 -104.859342) (xy 418.233536 -104.836689)
			(xy 418.187652 -104.807204) (xy 418.146431 -104.771489) (xy 418.110713 -104.730271) (xy 418.081225 -104.684389)
			(xy 418.058567 -104.634776) (xy 418.043202 -104.582445) (xy 418.035441 -104.528459) (xy 418.034978 -104.501188)
			(xy 415.595308 -104.501188) (xy 416.921442 -105.827322) (xy 429.906682 -105.827322) (xy 429.910753 -105.7717)
			(xy 429.922879 -105.717263) (xy 429.942802 -105.665172) (xy 429.970098 -105.616537) (xy 430.004184 -105.572394)
			(xy 430.044333 -105.533685) (xy 430.089691 -105.501234) (xy 430.139291 -105.475733) (xy 430.192075 -105.457726)
			(xy 430.246918 -105.447596) (xy 430.302652 -105.445559) (xy 430.358089 -105.451659) (xy 430.412046 -105.465765)
			(xy 430.463375 -105.487577) (xy 430.510981 -105.516631) (xy 430.553849 -105.552306) (xy 430.591066 -105.593843)
			(xy 430.614291 -105.628948) (xy 433.069238 -105.628948) (xy 433.06973 -105.601545) (xy 433.077581 -105.547303)
			(xy 433.093114 -105.494744) (xy 433.11601 -105.444948) (xy 433.145797 -105.398943) (xy 433.163472 -105.377996)
			(xy 433.169568 -105.370884) (xy 433.175918 -105.353866) (xy 433.175918 -105.26903) (xy 433.169568 -105.252012)
			(xy 433.163472 -105.2449) (xy 433.145815 -105.22394) (xy 433.116046 -105.177928) (xy 433.093155 -105.128135)
			(xy 433.077612 -105.075583) (xy 433.069734 -105.021349) (xy 433.069238 -104.993948) (xy 433.069745 -104.965754)
			(xy 433.078059 -104.909981) (xy 433.094485 -104.856037) (xy 433.118665 -104.805096) (xy 433.150074 -104.758264)
			(xy 433.188028 -104.71656) (xy 433.231702 -104.680891) (xy 433.280147 -104.652032) (xy 433.332309 -104.630611)
			(xy 433.35956 -104.623362) (xy 433.370482 -104.620568) (xy 433.388008 -104.606344) (xy 433.43195 -104.516428)
			(xy 433.432458 -104.494076) (xy 433.427886 -104.483662) (xy 433.417298 -104.458996) (xy 433.402381 -104.407434)
			(xy 433.394831 -104.35429) (xy 433.394358 -104.327452) (xy 433.394844 -104.300183) (xy 433.402606 -104.246199)
			(xy 433.417971 -104.193869) (xy 433.440628 -104.144259) (xy 433.470114 -104.098378) (xy 433.505829 -104.057161)
			(xy 433.547046 -104.021446) (xy 433.592927 -103.99196) (xy 433.642537 -103.969303) (xy 433.694867 -103.953938)
			(xy 433.748851 -103.946176) (xy 433.803389 -103.946176) (xy 433.857373 -103.953938) (xy 433.909703 -103.969303)
			(xy 433.959313 -103.99196) (xy 434.005194 -104.021446) (xy 434.046411 -104.057161) (xy 434.082126 -104.098378)
			(xy 434.111612 -104.144259) (xy 434.134269 -104.193869) (xy 434.149634 -104.246199) (xy 434.157396 -104.300183)
			(xy 434.157882 -104.327452) (xy 434.157329 -104.355691) (xy 434.148965 -104.411547) (xy 434.132472 -104.465564)
			(xy 434.120798 -104.491282) (xy 434.120544 -104.492552) (xy 434.118225 -104.501539) (xy 434.119545 -104.520039)
			(xy 434.123084 -104.52862) (xy 434.160168 -104.60863) (xy 434.177186 -104.623108) (xy 434.188108 -104.626156)
			(xy 434.214567 -104.633967) (xy 434.265052 -104.656214) (xy 434.311807 -104.685498) (xy 434.353859 -104.721208)
			(xy 434.390332 -104.762601) (xy 434.420464 -104.808815) (xy 434.443629 -104.858885) (xy 434.459343 -104.911768)
			(xy 434.467279 -104.966363) (xy 434.467762 -104.993948) (xy 434.467268 -105.021351) (xy 434.459417 -105.075593)
			(xy 434.443884 -105.128152) (xy 434.420989 -105.177947) (xy 434.391203 -105.223953) (xy 434.373528 -105.2449)
			(xy 434.367432 -105.252012) (xy 434.361082 -105.26903) (xy 434.361082 -105.353866) (xy 434.367432 -105.370884)
			(xy 434.373528 -105.377996) (xy 434.391183 -105.398957) (xy 434.420952 -105.444969) (xy 434.443843 -105.494762)
			(xy 434.459387 -105.547314) (xy 434.467265 -105.601547) (xy 434.467762 -105.628948) (xy 434.46732 -105.656219)
			(xy 434.459552 -105.710204) (xy 434.444181 -105.762534) (xy 434.421519 -105.812144) (xy 434.392028 -105.858025)
			(xy 434.356308 -105.899242) (xy 434.315087 -105.934957) (xy 434.269202 -105.964442) (xy 434.219589 -105.987097)
			(xy 434.167257 -106.002462) (xy 434.113271 -106.010224) (xy 434.086 -106.01071) (xy 434.058595 -106.010259)
			(xy 434.004351 -106.0024) (xy 433.951791 -105.986858) (xy 433.901996 -105.963953) (xy 433.855993 -105.934156)
			(xy 433.835048 -105.916476) (xy 433.827936 -105.91038) (xy 433.810918 -105.90403) (xy 433.726082 -105.90403)
			(xy 433.709064 -105.91038) (xy 433.701952 -105.916476) (xy 433.681004 -105.934147) (xy 433.634989 -105.963916)
			(xy 433.585193 -105.986805) (xy 433.532638 -106.002345) (xy 433.478402 -106.010217) (xy 433.451 -106.01071)
			(xy 433.423733 -106.010176) (xy 433.369753 -106.002415) (xy 433.317428 -105.987052) (xy 433.267821 -105.9644)
			(xy 433.221942 -105.934918) (xy 433.180726 -105.899208) (xy 433.145011 -105.857996) (xy 433.115523 -105.812121)
			(xy 433.092864 -105.762517) (xy 433.077495 -105.710194) (xy 433.069728 -105.656215) (xy 433.069238 -105.628948)
			(xy 430.614291 -105.628948) (xy 430.621839 -105.640356) (xy 430.645511 -105.690853) (xy 430.661579 -105.74426)
			(xy 430.669699 -105.799436) (xy 430.670208 -105.827322) (xy 430.669699 -105.855208) (xy 430.661579 -105.910384)
			(xy 430.645511 -105.963791) (xy 430.621839 -106.014288) (xy 430.591066 -106.060801) (xy 430.553849 -106.102338)
			(xy 430.510981 -106.138013) (xy 430.463375 -106.167067) (xy 430.412046 -106.188879) (xy 430.358089 -106.202985)
			(xy 430.302652 -106.209085) (xy 430.246918 -106.207048) (xy 430.192075 -106.196918) (xy 430.139291 -106.178911)
			(xy 430.089691 -106.15341) (xy 430.044333 -106.120959) (xy 430.004184 -106.08225) (xy 429.970098 -106.038107)
			(xy 429.942802 -105.989472) (xy 429.922879 -105.937381) (xy 429.910753 -105.882944) (xy 429.906682 -105.827322)
			(xy 416.921442 -105.827322) (xy 418.24529 -107.15117) (xy 428.930814 -107.15117) (xy 428.934885 -107.095548)
			(xy 428.947011 -107.041111) (xy 428.966934 -106.98902) (xy 428.99423 -106.940385) (xy 429.028316 -106.896242)
			(xy 429.068465 -106.857533) (xy 429.113823 -106.825082) (xy 429.163423 -106.799581) (xy 429.216207 -106.781574)
			(xy 429.27105 -106.771444) (xy 429.326784 -106.769407) (xy 429.368344 -106.77398) (xy 433.34 -106.77398)
			(xy 433.344073 -106.718321) (xy 433.356208 -106.663848) (xy 433.376144 -106.611722) (xy 433.403458 -106.563054)
			(xy 433.437566 -106.518882) (xy 433.477743 -106.480147) (xy 433.523131 -106.447675) (xy 433.572763 -106.422157)
			(xy 433.625583 -106.404138) (xy 433.680462 -106.394001) (xy 433.736233 -106.391963) (xy 433.791707 -106.398066)
			(xy 433.8457 -106.412182) (xy 433.897063 -106.434009) (xy 433.944701 -106.463082) (xy 433.987597 -106.498781)
			(xy 434.024839 -106.540345) (xy 434.055633 -106.586889) (xy 434.079321 -106.63742) (xy 434.095399 -106.690862)
			(xy 434.103525 -106.746076) (xy 434.104034 -106.77398) (xy 434.103525 -106.801884) (xy 434.095399 -106.857098)
			(xy 434.079321 -106.91054) (xy 434.055633 -106.961071) (xy 434.024839 -107.007615) (xy 433.987597 -107.049179)
			(xy 433.944701 -107.084878) (xy 433.897063 -107.113951) (xy 433.8457 -107.135778) (xy 433.791707 -107.149894)
			(xy 433.736233 -107.155997) (xy 433.680462 -107.153959) (xy 433.625583 -107.143822) (xy 433.572763 -107.125803)
			(xy 433.523131 -107.100285) (xy 433.477743 -107.067813) (xy 433.437566 -107.029078) (xy 433.403458 -106.984906)
			(xy 433.376144 -106.936238) (xy 433.356208 -106.884112) (xy 433.344073 -106.829639) (xy 433.34 -106.77398)
			(xy 429.368344 -106.77398) (xy 429.382221 -106.775507) (xy 429.436178 -106.789613) (xy 429.487507 -106.811425)
			(xy 429.535113 -106.840479) (xy 429.577981 -106.876154) (xy 429.615198 -106.917691) (xy 429.645971 -106.964204)
			(xy 429.669643 -107.014701) (xy 429.685711 -107.068108) (xy 429.693831 -107.123284) (xy 429.69434 -107.15117)
			(xy 429.693831 -107.179056) (xy 429.685711 -107.234232) (xy 429.677688 -107.260898) (xy 430.263552 -107.260898)
			(xy 430.267623 -107.205276) (xy 430.279749 -107.150839) (xy 430.299672 -107.098748) (xy 430.326968 -107.050113)
			(xy 430.361054 -107.00597) (xy 430.401203 -106.967261) (xy 430.446561 -106.93481) (xy 430.496161 -106.909309)
			(xy 430.548945 -106.891302) (xy 430.603788 -106.881172) (xy 430.659522 -106.879135) (xy 430.714959 -106.885235)
			(xy 430.768916 -106.899341) (xy 430.820245 -106.921153) (xy 430.867851 -106.950207) (xy 430.910719 -106.985882)
			(xy 430.947936 -107.027419) (xy 430.978709 -107.073932) (xy 431.002381 -107.124429) (xy 431.018449 -107.177836)
			(xy 431.026569 -107.233012) (xy 431.027078 -107.260898) (xy 431.026569 -107.288784) (xy 431.018449 -107.34396)
			(xy 431.002381 -107.397367) (xy 430.978709 -107.447864) (xy 430.947936 -107.494377) (xy 430.910719 -107.535914)
			(xy 430.867851 -107.571589) (xy 430.820245 -107.600643) (xy 430.768916 -107.622455) (xy 430.714959 -107.636561)
			(xy 430.659522 -107.642661) (xy 430.603788 -107.640624) (xy 430.548945 -107.630494) (xy 430.496161 -107.612487)
			(xy 430.446561 -107.586986) (xy 430.401203 -107.554535) (xy 430.361054 -107.515826) (xy 430.326968 -107.471683)
			(xy 430.299672 -107.423048) (xy 430.279749 -107.370957) (xy 430.267623 -107.31652) (xy 430.263552 -107.260898)
			(xy 429.677688 -107.260898) (xy 429.669643 -107.287639) (xy 429.645971 -107.338136) (xy 429.615198 -107.384649)
			(xy 429.577981 -107.426186) (xy 429.535113 -107.461861) (xy 429.487507 -107.490915) (xy 429.436178 -107.512727)
			(xy 429.382221 -107.526833) (xy 429.326784 -107.532933) (xy 429.27105 -107.530896) (xy 429.216207 -107.520766)
			(xy 429.163423 -107.502759) (xy 429.113823 -107.477258) (xy 429.068465 -107.444807) (xy 429.028316 -107.406098)
			(xy 428.99423 -107.361955) (xy 428.966934 -107.31332) (xy 428.947011 -107.261229) (xy 428.934885 -107.206792)
			(xy 428.930814 -107.15117) (xy 418.24529 -107.15117) (xy 418.739828 -107.645708) (xy 431.703478 -107.645708)
			(xy 431.707549 -107.590086) (xy 431.719675 -107.535649) (xy 431.739598 -107.483558) (xy 431.766894 -107.434923)
			(xy 431.80098 -107.39078) (xy 431.841129 -107.352071) (xy 431.886487 -107.31962) (xy 431.936087 -107.294119)
			(xy 431.988871 -107.276112) (xy 432.043714 -107.265982) (xy 432.099448 -107.263945) (xy 432.154885 -107.270045)
			(xy 432.208842 -107.284151) (xy 432.260171 -107.305963) (xy 432.307777 -107.335017) (xy 432.350645 -107.370692)
			(xy 432.387862 -107.412229) (xy 432.418635 -107.458742) (xy 432.442307 -107.509239) (xy 432.458375 -107.562646)
			(xy 432.466495 -107.617822) (xy 432.467004 -107.645708) (xy 432.466495 -107.673594) (xy 432.458375 -107.72877)
			(xy 432.442307 -107.782177) (xy 432.418635 -107.832674) (xy 432.387862 -107.879187) (xy 432.350645 -107.920724)
			(xy 432.307777 -107.956399) (xy 432.260171 -107.985453) (xy 432.208842 -108.007265) (xy 432.154885 -108.021371)
			(xy 432.099448 -108.027471) (xy 432.043714 -108.025434) (xy 431.988871 -108.015304) (xy 431.936087 -107.997297)
			(xy 431.886487 -107.971796) (xy 431.841129 -107.939345) (xy 431.80098 -107.900636) (xy 431.766894 -107.856493)
			(xy 431.739598 -107.807858) (xy 431.719675 -107.755767) (xy 431.707549 -107.70133) (xy 431.703478 -107.645708)
			(xy 418.739828 -107.645708) (xy 420.75735 -109.66323) (xy 433.334158 -109.66323) (xy 433.338229 -109.607608)
			(xy 433.350355 -109.553171) (xy 433.370278 -109.50108) (xy 433.397574 -109.452445) (xy 433.43166 -109.408302)
			(xy 433.471809 -109.369593) (xy 433.517167 -109.337142) (xy 433.566767 -109.311641) (xy 433.619551 -109.293634)
			(xy 433.674394 -109.283504) (xy 433.730128 -109.281467) (xy 433.785565 -109.287567) (xy 433.839522 -109.301673)
			(xy 433.890851 -109.323485) (xy 433.938457 -109.352539) (xy 433.981325 -109.388214) (xy 434.018542 -109.429751)
			(xy 434.049315 -109.476264) (xy 434.072987 -109.526761) (xy 434.089055 -109.580168) (xy 434.097175 -109.635344)
			(xy 434.097684 -109.66323) (xy 434.097175 -109.691116) (xy 434.089055 -109.746292) (xy 434.072987 -109.799699)
			(xy 434.049315 -109.850196) (xy 434.018542 -109.896709) (xy 433.981325 -109.938246) (xy 433.938457 -109.973921)
			(xy 433.890851 -110.002975) (xy 433.839522 -110.024787) (xy 433.785565 -110.038893) (xy 433.730128 -110.044993)
			(xy 433.674394 -110.042956) (xy 433.619551 -110.032826) (xy 433.566767 -110.014819) (xy 433.517167 -109.989318)
			(xy 433.471809 -109.956867) (xy 433.43166 -109.918158) (xy 433.397574 -109.874015) (xy 433.370278 -109.82538)
			(xy 433.350355 -109.773289) (xy 433.338229 -109.718852) (xy 433.334158 -109.66323) (xy 420.75735 -109.66323)
			(xy 421.071802 -109.977682) (xy 421.074378 -109.980191) (xy 421.080114 -109.984526) (xy 421.083232 -109.986318)
			(xy 421.09009 -109.989874) (xy 421.115804 -109.995375) (xy 421.165522 -110.0125) (xy 421.212419 -110.036289)
			(xy 421.255606 -110.06629) (xy 421.294265 -110.101936) (xy 421.327666 -110.142551) (xy 421.355174 -110.187367)
			(xy 421.37627 -110.235534) (xy 421.387873 -110.27664) (xy 428.913542 -110.27664) (xy 428.917613 -110.221018)
			(xy 428.929739 -110.166581) (xy 428.949662 -110.11449) (xy 428.976958 -110.065855) (xy 429.011044 -110.021712)
			(xy 429.051193 -109.983003) (xy 429.096551 -109.950552) (xy 429.146151 -109.925051) (xy 429.198935 -109.907044)
			(xy 429.253778 -109.896914) (xy 429.309512 -109.894877) (xy 429.364949 -109.900977) (xy 429.418906 -109.915083)
			(xy 429.470235 -109.936895) (xy 429.517841 -109.965949) (xy 429.560709 -110.001624) (xy 429.597926 -110.043161)
			(xy 429.628699 -110.089674) (xy 429.652371 -110.140171) (xy 429.668439 -110.193578) (xy 429.676559 -110.248754)
			(xy 429.677068 -110.27664) (xy 429.676559 -110.304526) (xy 429.668439 -110.359702) (xy 429.652371 -110.413109)
			(xy 429.628699 -110.463606) (xy 429.597926 -110.510119) (xy 429.560709 -110.551656) (xy 429.517841 -110.587331)
			(xy 429.470235 -110.616385) (xy 429.418906 -110.638197) (xy 429.364949 -110.652303) (xy 429.309512 -110.658403)
			(xy 429.253778 -110.656366) (xy 429.198935 -110.646236) (xy 429.146151 -110.628229) (xy 429.096551 -110.602728)
			(xy 429.051193 -110.570277) (xy 429.011044 -110.531568) (xy 428.976958 -110.487425) (xy 428.949662 -110.43879)
			(xy 428.929739 -110.386699) (xy 428.917613 -110.332262) (xy 428.913542 -110.27664) (xy 421.387873 -110.27664)
			(xy 421.390555 -110.286142) (xy 421.397756 -110.338231) (xy 421.398192 -110.364524) (xy 421.397704 -110.391793)
			(xy 421.38994 -110.445776) (xy 421.374573 -110.498104) (xy 421.351915 -110.547713) (xy 421.322429 -110.593593)
			(xy 421.286715 -110.63481) (xy 421.245498 -110.670526) (xy 421.199618 -110.700013) (xy 421.15001 -110.72267)
			(xy 421.097682 -110.738038) (xy 421.043699 -110.745804) (xy 421.01643 -110.746286) (xy 420.987608 -110.745762)
			(xy 420.930618 -110.737098) (xy 420.87558 -110.719963) (xy 420.823744 -110.694747) (xy 420.776289 -110.662022)
			(xy 420.734295 -110.622534) (xy 420.698716 -110.577179) (xy 420.670362 -110.526991) (xy 420.649877 -110.473109)
			(xy 420.643304 -110.445042) (xy 420.64178 -110.43793) (xy 420.638224 -110.431326) (xy 420.636427 -110.428212)
			(xy 420.632094 -110.422474) (xy 420.629588 -110.419896) (xy 420.59733 -110.387638) (xy 420.59072 -110.381569)
			(xy 420.574416 -110.374099) (xy 420.556535 -110.372718) (xy 420.539277 -110.377597) (xy 420.531798 -110.382558)
			(xy 420.513002 -110.39602) (xy 420.504112 -110.407704) (xy 420.501318 -110.414816) (xy 420.490685 -110.441739)
			(xy 420.462465 -110.492278) (xy 420.426932 -110.537972) (xy 420.384904 -110.577774) (xy 420.337345 -110.610768)
			(xy 420.285346 -110.636198) (xy 420.230103 -110.65348) (xy 420.172882 -110.662216) (xy 420.14394 -110.66272)
			(xy 420.115156 -110.6622) (xy 420.058239 -110.653564) (xy 420.003264 -110.636481) (xy 419.951477 -110.611338)
			(xy 419.904051 -110.578706) (xy 419.862061 -110.539324) (xy 419.826459 -110.494084) (xy 419.798053 -110.444012)
			(xy 419.777485 -110.390244) (xy 419.770814 -110.362238) (xy 419.770814 -110.361984) (xy 419.769042 -110.354772)
			(xy 419.761934 -110.341739) (xy 419.756844 -110.33633) (xy 419.508178 -110.087664) (xy 419.500746 -110.080969)
			(xy 419.48226 -110.073379) (xy 419.462278 -110.073431) (xy 419.443832 -110.081117) (xy 419.429725 -110.09527)
			(xy 419.422099 -110.11374) (xy 419.421564 -110.123732) (xy 419.421564 -110.19917) (xy 419.425628 -110.213394)
			(xy 419.429692 -110.21949) (xy 419.44412 -110.24274) (xy 419.466899 -110.292491) (xy 419.482349 -110.344983)
			(xy 419.490154 -110.399141) (xy 419.490652 -110.4265) (xy 419.490166 -110.453769) (xy 419.482404 -110.507753)
			(xy 419.467039 -110.560083) (xy 419.444382 -110.609693) (xy 419.414896 -110.655574) (xy 419.379181 -110.696791)
			(xy 419.337964 -110.732506) (xy 419.292083 -110.761992) (xy 419.242473 -110.784649) (xy 419.190143 -110.800014)
			(xy 419.136159 -110.807776) (xy 419.081621 -110.807776) (xy 419.027637 -110.800014) (xy 418.975307 -110.784649)
			(xy 418.925697 -110.761992) (xy 418.879816 -110.732506) (xy 418.838599 -110.696791) (xy 418.802884 -110.655574)
			(xy 418.773398 -110.609693) (xy 418.750741 -110.560083) (xy 418.735376 -110.507753) (xy 418.727614 -110.453769)
			(xy 418.727128 -110.4265) (xy 418.727598 -110.39914) (xy 418.735408 -110.34498) (xy 418.750869 -110.29249)
			(xy 418.773664 -110.242744) (xy 418.788088 -110.21949) (xy 418.792152 -110.213394) (xy 418.796216 -110.19917)
			(xy 418.796216 -110.055152) (xy 418.795785 -110.045085) (xy 418.78806 -110.026492) (xy 418.78123 -110.019084)
			(xy 414.12414 -105.361994) (xy 414.113176 -105.351775) (xy 414.086762 -105.337642) (xy 414.057385 -105.33178)
			(xy 414.02757 -105.334692) (xy 413.999882 -105.346129) (xy 413.976702 -105.365106) (xy 413.960025 -105.389991)
			(xy 413.951284 -105.418645) (xy 413.950658 -105.433622) (xy 413.950658 -110.940088) (xy 429.500282 -110.940088)
			(xy 429.504353 -110.884466) (xy 429.516479 -110.830029) (xy 429.536402 -110.777938) (xy 429.563698 -110.729303)
			(xy 429.597784 -110.68516) (xy 429.637933 -110.646451) (xy 429.683291 -110.614) (xy 429.732891 -110.588499)
			(xy 429.785675 -110.570492) (xy 429.840518 -110.560362) (xy 429.896252 -110.558325) (xy 429.951689 -110.564425)
			(xy 430.005646 -110.578531) (xy 430.056975 -110.600343) (xy 430.104581 -110.629397) (xy 430.147449 -110.665072)
			(xy 430.184666 -110.706609) (xy 430.215439 -110.753122) (xy 430.239111 -110.803619) (xy 430.255179 -110.857026)
			(xy 430.263299 -110.912202) (xy 430.263808 -110.940088) (xy 430.263299 -110.967974) (xy 430.255179 -111.02315)
			(xy 430.239111 -111.076557) (xy 430.215439 -111.127054) (xy 430.184666 -111.173567) (xy 430.147449 -111.215104)
			(xy 430.104581 -111.250779) (xy 430.056975 -111.279833) (xy 430.005646 -111.301645) (xy 429.951689 -111.315751)
			(xy 429.896252 -111.321851) (xy 429.840518 -111.319814) (xy 429.785675 -111.309684) (xy 429.732891 -111.291677)
			(xy 429.683291 -111.266176) (xy 429.637933 -111.233725) (xy 429.597784 -111.195016) (xy 429.563698 -111.150873)
			(xy 429.536402 -111.102238) (xy 429.516479 -111.050147) (xy 429.504353 -110.99571) (xy 429.500282 -110.940088)
			(xy 413.950658 -110.940088) (xy 413.950658 -110.985808) (xy 413.951084 -110.995876) (xy 413.958807 -111.014473)
			(xy 413.965644 -111.021876) (xy 415.538666 -112.594898) (xy 415.546068 -112.601734) (xy 415.564666 -112.609445)
			(xy 415.574734 -112.609884)
		)
		(stroke
			(width 0)
			(type solid)
		)
		(fill yes)
		(layer "In4.Cu")
		(net "GND")
	)
	(gr_poly
		(pts
			(xy 131.615688 -81.31302) (xy 131.625699 -81.312535) (xy 131.644198 -81.304878) (xy 131.65836 -81.290725)
			(xy 131.666028 -81.27223) (xy 131.666488 -81.26222) (xy 131.666488 -80.032606) (xy 131.666001 -80.018289)
			(xy 131.658045 -79.990782) (xy 131.642757 -79.96657) (xy 131.621342 -79.947561) (xy 131.595488 -79.935252)
			(xy 131.567231 -79.930614) (xy 131.55295 -79.931768) (xy 131.526232 -79.934455) (xy 131.472549 -79.9332)
			(xy 131.419571 -79.924436) (xy 131.368344 -79.908334) (xy 131.319879 -79.885214) (xy 131.275131 -79.85553)
			(xy 131.254754 -79.838042) (xy 131.247642 -79.831946) (xy 131.239006 -79.828644) (xy 131.234658 -79.8271)
			(xy 131.225585 -79.825435) (xy 131.220972 -79.825342) (xy 131.153662 -79.825342) (xy 131.14905 -79.825445)
			(xy 131.139979 -79.827111) (xy 131.135628 -79.828644) (xy 131.126992 -79.831946) (xy 131.11988 -79.838042)
			(xy 131.098836 -79.856076) (xy 131.052517 -79.886502) (xy 131.00228 -79.909903) (xy 130.949186 -79.925785)
			(xy 130.894351 -79.933813) (xy 130.866642 -79.934308) (xy 130.839387 -79.933848) (xy 130.785432 -79.926095)
			(xy 130.733129 -79.910743) (xy 130.683543 -79.888103) (xy 130.637685 -79.858636) (xy 130.596487 -79.822942)
			(xy 130.560789 -79.781749) (xy 130.531317 -79.735893) (xy 130.508672 -79.686311) (xy 130.493314 -79.634009)
			(xy 130.485555 -79.580055) (xy 130.485555 -79.525545) (xy 130.493314 -79.471591) (xy 130.508672 -79.419289)
			(xy 130.531317 -79.369707) (xy 130.560789 -79.323851) (xy 130.596487 -79.282658) (xy 130.637685 -79.246964)
			(xy 130.683543 -79.217497) (xy 130.733129 -79.194857) (xy 130.785432 -79.179505) (xy 130.839387 -79.171752)
			(xy 130.866642 -79.171292) (xy 130.894353 -79.171785) (xy 130.949192 -79.179802) (xy 131.002292 -79.195676)
			(xy 131.052534 -79.219072) (xy 131.098859 -79.249497) (xy 131.11988 -79.267558) (xy 131.126992 -79.273654)
			(xy 131.135628 -79.276956) (xy 131.139976 -79.278498) (xy 131.14905 -79.280156) (xy 131.153662 -79.280258)
			(xy 131.220972 -79.280258) (xy 131.225585 -79.280161) (xy 131.234661 -79.278506) (xy 131.239006 -79.276956)
			(xy 131.247642 -79.273654) (xy 131.254754 -79.267558) (xy 131.276121 -79.249254) (xy 131.32322 -79.218479)
			(xy 131.37433 -79.194957) (xy 131.428341 -79.179201) (xy 131.48408 -79.17155) (xy 131.540339 -79.172172)
			(xy 131.595896 -79.181053) (xy 131.649545 -79.198) (xy 131.700122 -79.222645) (xy 131.723638 -79.238094)
			(xy 131.731425 -79.242951) (xy 131.749237 -79.247326) (xy 131.76745 -79.245172) (xy 131.783749 -79.236763)
			(xy 131.790186 -79.23022) (xy 131.809836 -79.208964) (xy 131.853375 -79.170817) (xy 131.901164 -79.13815)
			(xy 131.952518 -79.111435) (xy 132.006698 -79.091053) (xy 132.062928 -79.077298) (xy 132.120398 -79.070367)
			(xy 132.149342 -79.069946) (xy 132.180954 -79.070466) (xy 132.243637 -79.078723) (xy 132.304706 -79.095091)
			(xy 132.363117 -79.11929) (xy 132.417869 -79.150905) (xy 132.468026 -79.189397) (xy 132.512731 -79.234105)
			(xy 132.551218 -79.284266) (xy 132.582829 -79.339021) (xy 132.607022 -79.397433) (xy 132.623385 -79.458504)
			(xy 132.631637 -79.521188) (xy 132.632196 -79.5528) (xy 132.632196 -81.26222) (xy 132.632688 -81.272225)
			(xy 132.640351 -81.290711) (xy 132.654503 -81.304858) (xy 132.672991 -81.312516) (xy 132.682996 -81.31302)
			(xy 133.245352 -81.31302) (xy 133.255381 -81.312609) (xy 133.273918 -81.304948) (xy 133.28811 -81.290775)
			(xy 133.295795 -81.272249) (xy 133.296152 -81.26222) (xy 133.296152 -70.546214) (xy 133.288532 -70.527418)
			(xy 133.281166 -70.520306) (xy 132.613908 -69.853048) (xy 132.606796 -69.845682) (xy 132.588 -69.838062)
			(xy 114.682778 -69.838062) (xy 114.672711 -69.838491) (xy 114.654118 -69.846218) (xy 114.64671 -69.853048)
			(xy 113.884202 -70.615556) (xy 113.883948 -70.615556) (xy 113.848134 -70.65137) (xy 113.840768 -70.658482)
			(xy 113.833148 -70.677278) (xy 113.833148 -71.348667) (xy 115.066346 -71.348667) (xy 115.066346 -71.294133)
			(xy 115.074107 -71.240155) (xy 115.08947 -71.187831) (xy 115.112123 -71.138226) (xy 115.141604 -71.092349)
			(xy 115.177314 -71.051134) (xy 115.218526 -71.015421) (xy 115.264401 -70.985936) (xy 115.314005 -70.96328)
			(xy 115.366328 -70.947913) (xy 115.420306 -70.940148) (xy 115.447572 -70.93966) (xy 115.475962 -70.940192)
			(xy 115.532116 -70.948599) (xy 115.586405 -70.96523) (xy 115.637631 -70.98972) (xy 115.66144 -71.005192)
			(xy 115.668044 -71.009764) (xy 115.677188 -71.012304) (xy 115.683493 -71.013883) (xy 115.696481 -71.014146)
			(xy 115.702842 -71.012812) (xy 115.784884 -70.993254) (xy 115.801902 -70.9803) (xy 115.807236 -70.970902)
			(xy 115.821775 -70.945779) (xy 115.857336 -70.899902) (xy 115.899429 -70.859934) (xy 115.947085 -70.826796)
			(xy 115.999206 -70.80125) (xy 116.054593 -70.783885) (xy 116.111969 -70.775101) (xy 116.140992 -70.77456)
			(xy 116.168264 -70.775009) (xy 116.222252 -70.782771) (xy 116.274587 -70.798137) (xy 116.324201 -70.820795)
			(xy 116.370086 -70.850284) (xy 116.411307 -70.886003) (xy 116.447024 -70.927225) (xy 116.476511 -70.973111)
			(xy 116.499168 -71.022726) (xy 116.514532 -71.075061) (xy 116.522292 -71.12905) (xy 116.522754 -71.156322)
			(xy 116.522247 -71.183725) (xy 116.5144 -71.237966) (xy 116.49887 -71.290525) (xy 116.48056 -71.330352)
			(xy 130.866589 -71.330352) (xy 130.866589 -71.275848) (xy 130.874347 -71.221898) (xy 130.889704 -71.169601)
			(xy 130.912347 -71.120023) (xy 130.941816 -71.074172) (xy 130.977511 -71.032982) (xy 131.018705 -70.997291)
			(xy 131.06456 -70.967827) (xy 131.114141 -70.945189) (xy 131.166439 -70.929838) (xy 131.22039 -70.922086)
			(xy 131.247642 -70.921626) (xy 131.275352 -70.922112) (xy 131.330187 -70.930142) (xy 131.383282 -70.946025)
			(xy 131.433518 -70.969427) (xy 131.479837 -70.999856) (xy 131.50088 -71.017892) (xy 131.507992 -71.023988)
			(xy 131.516628 -71.02729) (xy 131.520978 -71.028824) (xy 131.53005 -71.030489) (xy 131.534662 -71.030592)
			(xy 131.601972 -71.030592) (xy 131.606585 -71.030497) (xy 131.615658 -71.028834) (xy 131.620006 -71.02729)
			(xy 131.628642 -71.023988) (xy 131.635754 -71.017892) (xy 131.656797 -70.999858) (xy 131.703117 -70.969432)
			(xy 131.753353 -70.946034) (xy 131.806448 -70.930156) (xy 131.861283 -70.922132) (xy 131.916701 -70.922132)
			(xy 131.971536 -70.930156) (xy 132.024631 -70.946034) (xy 132.074867 -70.969432) (xy 132.121187 -70.999858)
			(xy 132.14223 -71.017892) (xy 132.149342 -71.023988) (xy 132.157978 -71.02729) (xy 132.162324 -71.028837)
			(xy 132.171399 -71.030493) (xy 132.176012 -71.030592) (xy 132.243322 -71.030592) (xy 132.247934 -71.030483)
			(xy 132.257008 -71.028829) (xy 132.261356 -71.02729) (xy 132.269992 -71.023988) (xy 132.277104 -71.017892)
			(xy 132.298136 -70.999844) (xy 132.344457 -70.969416) (xy 132.394696 -70.946017) (xy 132.447794 -70.93014)
			(xy 132.502632 -70.92212) (xy 132.530342 -70.921626) (xy 132.557594 -70.922047) (xy 132.611542 -70.929809)
			(xy 132.663836 -70.945169) (xy 132.713412 -70.967814) (xy 132.759262 -70.997285) (xy 132.800451 -71.032979)
			(xy 132.836141 -71.074172) (xy 132.865606 -71.120024) (xy 132.888246 -71.169603) (xy 132.9036 -71.221899)
			(xy 132.911356 -71.275848) (xy 132.911356 -71.330352) (xy 132.9036 -71.384301) (xy 132.888246 -71.436597)
			(xy 132.865606 -71.486176) (xy 132.836141 -71.532028) (xy 132.800451 -71.573221) (xy 132.759262 -71.608915)
			(xy 132.713412 -71.638386) (xy 132.663836 -71.661031) (xy 132.611542 -71.676391) (xy 132.557594 -71.684153)
			(xy 132.530342 -71.684642) (xy 132.502633 -71.684148) (xy 132.447799 -71.676118) (xy 132.394704 -71.660236)
			(xy 132.344468 -71.636835) (xy 132.298148 -71.60641) (xy 132.277104 -71.588376) (xy 132.269992 -71.58228)
			(xy 132.261356 -71.578978) (xy 132.257007 -71.577438) (xy 132.247934 -71.575777) (xy 132.243322 -71.575676)
			(xy 132.176012 -71.575676) (xy 132.171399 -71.575763) (xy 132.162325 -71.577431) (xy 132.157978 -71.578978)
			(xy 132.149342 -71.58228) (xy 132.14223 -71.588376) (xy 132.121187 -71.60641) (xy 132.074867 -71.636836)
			(xy 132.024631 -71.660234) (xy 131.971536 -71.676112) (xy 131.916701 -71.684136) (xy 131.861283 -71.684136)
			(xy 131.806448 -71.676112) (xy 131.753353 -71.660234) (xy 131.703117 -71.636836) (xy 131.656797 -71.60641)
			(xy 131.635754 -71.588376) (xy 131.628642 -71.58228) (xy 131.620006 -71.578978) (xy 131.615662 -71.577425)
			(xy 131.606585 -71.575772) (xy 131.601972 -71.575676) (xy 131.534662 -71.575676) (xy 131.53005 -71.575776)
			(xy 131.520976 -71.577435) (xy 131.516628 -71.578978) (xy 131.507992 -71.58228) (xy 131.50088 -71.588376)
			(xy 131.479849 -71.606427) (xy 131.433529 -71.636855) (xy 131.383289 -71.660254) (xy 131.330191 -71.67613)
			(xy 131.275353 -71.684148) (xy 131.247642 -71.684642) (xy 131.22039 -71.684114) (xy 131.166439 -71.676362)
			(xy 131.114141 -71.661011) (xy 131.06456 -71.638373) (xy 131.018705 -71.608909) (xy 130.977511 -71.573218)
			(xy 130.941816 -71.532028) (xy 130.912347 -71.486177) (xy 130.889704 -71.436599) (xy 130.874347 -71.384302)
			(xy 130.866589 -71.330352) (xy 116.48056 -71.330352) (xy 116.475977 -71.340321) (xy 116.446194 -71.386327)
			(xy 116.42852 -71.407274) (xy 116.422424 -71.414386) (xy 116.416074 -71.431404) (xy 116.416074 -71.51624)
			(xy 116.422424 -71.533258) (xy 116.42852 -71.54037) (xy 116.446208 -71.561304) (xy 116.475973 -71.607324)
			(xy 116.498858 -71.657123) (xy 116.514394 -71.709681) (xy 116.522263 -71.763919) (xy 116.522754 -71.791322)
			(xy 116.522264 -71.817662) (xy 116.515019 -71.869841) (xy 116.500669 -71.920528) (xy 116.479486 -71.968762)
			(xy 116.451874 -72.013625) (xy 116.418357 -72.054266) (xy 116.37957 -72.089914) (xy 116.358162 -72.105266)
			(xy 116.350034 -72.111108) (xy 116.339366 -72.12711) (xy 116.325904 -72.193912) (xy 116.324479 -72.203129)
			(xy 116.327604 -72.2215) (xy 116.332 -72.229726) (xy 116.332254 -72.230234) (xy 116.332508 -72.230742)
			(xy 116.333524 -72.23252) (xy 116.346591 -72.254944) (xy 116.367248 -72.302555) (xy 116.381272 -72.352523)
			(xy 116.388406 -72.40393) (xy 116.388896 -72.429878) (xy 116.388896 -72.430386) (xy 116.388388 -72.446642)
			(xy 116.388388 -72.448674) (xy 116.387678 -72.475771) (xy 116.379542 -72.529362) (xy 116.368495 -72.566022)
			(xy 119.05945 -72.566022) (xy 119.063523 -72.510363) (xy 119.075658 -72.45589) (xy 119.095594 -72.403764)
			(xy 119.122908 -72.355096) (xy 119.157016 -72.310924) (xy 119.197193 -72.272189) (xy 119.242581 -72.239717)
			(xy 119.292213 -72.214199) (xy 119.345033 -72.19618) (xy 119.399912 -72.186043) (xy 119.455683 -72.184005)
			(xy 119.511157 -72.190108) (xy 119.56515 -72.204224) (xy 119.616513 -72.226051) (xy 119.664151 -72.255124)
			(xy 119.707047 -72.290823) (xy 119.744289 -72.332387) (xy 119.775083 -72.378931) (xy 119.798771 -72.429462)
			(xy 119.814849 -72.482904) (xy 119.822975 -72.538118) (xy 119.823484 -72.566022) (xy 119.822975 -72.593926)
			(xy 119.819605 -72.616822) (xy 122.50877 -72.616822) (xy 122.512843 -72.561163) (xy 122.524978 -72.50669)
			(xy 122.544914 -72.454564) (xy 122.572228 -72.405896) (xy 122.606336 -72.361724) (xy 122.646513 -72.322989)
			(xy 122.691901 -72.290517) (xy 122.741533 -72.264999) (xy 122.794353 -72.24698) (xy 122.849232 -72.236843)
			(xy 122.905003 -72.234805) (xy 122.960477 -72.240908) (xy 123.01447 -72.255024) (xy 123.065833 -72.276851)
			(xy 123.113471 -72.305924) (xy 123.156367 -72.341623) (xy 123.193609 -72.383187) (xy 123.224403 -72.429731)
			(xy 123.248091 -72.480262) (xy 123.264169 -72.533704) (xy 123.272295 -72.588918) (xy 123.272804 -72.616822)
			(xy 123.272295 -72.644726) (xy 123.264169 -72.69994) (xy 123.248091 -72.753382) (xy 123.224403 -72.803913)
			(xy 123.193609 -72.850457) (xy 123.156367 -72.892021) (xy 123.113471 -72.92772) (xy 123.065833 -72.956793)
			(xy 123.01447 -72.97862) (xy 122.960477 -72.992736) (xy 122.905003 -72.998839) (xy 122.849232 -72.996801)
			(xy 122.794353 -72.986664) (xy 122.741533 -72.968645) (xy 122.691901 -72.943127) (xy 122.646513 -72.910655)
			(xy 122.606336 -72.87192) (xy 122.572228 -72.827748) (xy 122.544914 -72.77908) (xy 122.524978 -72.726954)
			(xy 122.512843 -72.672481) (xy 122.50877 -72.616822) (xy 119.819605 -72.616822) (xy 119.814849 -72.64914)
			(xy 119.798771 -72.702582) (xy 119.775083 -72.753113) (xy 119.744289 -72.799657) (xy 119.707047 -72.841221)
			(xy 119.664151 -72.87692) (xy 119.616513 -72.905993) (xy 119.56515 -72.92782) (xy 119.511157 -72.941936)
			(xy 119.455683 -72.948039) (xy 119.399912 -72.946001) (xy 119.345033 -72.935864) (xy 119.292213 -72.917845)
			(xy 119.242581 -72.892327) (xy 119.197193 -72.859855) (xy 119.157016 -72.82112) (xy 119.122908 -72.776948)
			(xy 119.095594 -72.72828) (xy 119.075658 -72.676154) (xy 119.063523 -72.621681) (xy 119.05945 -72.566022)
			(xy 116.368495 -72.566022) (xy 116.363903 -72.581261) (xy 116.341076 -72.630425) (xy 116.31152 -72.675863)
			(xy 116.27583 -72.71666) (xy 116.234726 -72.751995) (xy 116.189034 -72.781157) (xy 116.139674 -72.803558)
			(xy 116.087641 -72.818747) (xy 116.033982 -72.826419) (xy 115.979778 -72.826419) (xy 115.926119 -72.818747)
			(xy 115.874086 -72.803558) (xy 115.824726 -72.781157) (xy 115.779034 -72.751995) (xy 115.73793 -72.71666)
			(xy 115.70224 -72.675863) (xy 115.672684 -72.630425) (xy 115.649857 -72.581261) (xy 115.634218 -72.529362)
			(xy 115.626082 -72.475771) (xy 115.625372 -72.448674) (xy 115.625372 -72.446642) (xy 115.624864 -72.430132)
			(xy 115.625298 -72.403476) (xy 115.632731 -72.350685) (xy 115.647429 -72.299439) (xy 115.669107 -72.250733)
			(xy 115.697344 -72.205513) (xy 115.731591 -72.164657) (xy 115.771186 -72.128957) (xy 115.793012 -72.113648)
			(xy 115.801394 -72.10806) (xy 115.812316 -72.09155) (xy 115.82654 -72.0217) (xy 115.822984 -72.00265)
			(xy 115.81765 -71.994268) (xy 115.803818 -71.971356) (xy 115.78197 -71.922501) (xy 115.767161 -71.871073)
			(xy 115.759682 -71.818081) (xy 115.75923 -71.791322) (xy 115.760246 -71.763128) (xy 115.761262 -71.749158)
			(xy 115.754912 -71.736204) (xy 115.751809 -71.730473) (xy 115.743186 -71.720705) (xy 115.737894 -71.7169)
			(xy 115.654328 -71.660512) (xy 115.62715 -71.65848) (xy 115.614958 -71.664576) (xy 115.588752 -71.676752)
			(xy 115.533587 -71.693948) (xy 115.476463 -71.70265) (xy 115.447572 -71.703184) (xy 115.420306 -71.702652)
			(xy 115.366328 -71.694887) (xy 115.314005 -71.67952) (xy 115.264401 -71.656864) (xy 115.218526 -71.627379)
			(xy 115.177314 -71.591666) (xy 115.141604 -71.550451) (xy 115.112123 -71.504574) (xy 115.08947 -71.454969)
			(xy 115.074107 -71.402645) (xy 115.066346 -71.348667) (xy 113.833148 -71.348667) (xy 113.833148 -73.442156)
			(xy 130.485545 -73.442156) (xy 130.485545 -73.387644) (xy 130.493303 -73.333688) (xy 130.508662 -73.281386)
			(xy 130.531308 -73.231801) (xy 130.560781 -73.185945) (xy 130.59648 -73.14475) (xy 130.637679 -73.109056)
			(xy 130.683538 -73.079588) (xy 130.733125 -73.056947) (xy 130.785429 -73.041594) (xy 130.839386 -73.033842)
			(xy 130.866642 -73.033382) (xy 130.894351 -73.033879) (xy 130.949186 -73.041908) (xy 131.00228 -73.057789)
			(xy 131.052516 -73.081189) (xy 131.098836 -73.111614) (xy 131.11988 -73.129648) (xy 131.126992 -73.135744)
			(xy 131.135628 -73.139046) (xy 131.139978 -73.140583) (xy 131.14905 -73.142246) (xy 131.153662 -73.142348)
			(xy 131.220972 -73.142348) (xy 131.225585 -73.142255) (xy 131.234659 -73.140591) (xy 131.239006 -73.139046)
			(xy 131.247642 -73.135744) (xy 131.254754 -73.129648) (xy 131.275797 -73.111614) (xy 131.322117 -73.081188)
			(xy 131.372353 -73.05779) (xy 131.425448 -73.041912) (xy 131.480283 -73.033888) (xy 131.535701 -73.033888)
			(xy 131.590536 -73.041912) (xy 131.643631 -73.05779) (xy 131.693867 -73.081188) (xy 131.740187 -73.111614)
			(xy 131.76123 -73.129648) (xy 131.768342 -73.135744) (xy 131.776978 -73.139046) (xy 131.781323 -73.140595)
			(xy 131.790399 -73.14225) (xy 131.795012 -73.142348) (xy 131.862322 -73.142348) (xy 131.866934 -73.142242)
			(xy 131.876008 -73.140586) (xy 131.880356 -73.139046) (xy 131.888992 -73.135744) (xy 131.896104 -73.129648)
			(xy 131.917147 -73.111614) (xy 131.963467 -73.081188) (xy 132.013703 -73.05779) (xy 132.066798 -73.041912)
			(xy 132.121633 -73.033888) (xy 132.177051 -73.033888) (xy 132.231886 -73.041912) (xy 132.284981 -73.05779)
			(xy 132.335217 -73.081188) (xy 132.381537 -73.111614) (xy 132.40258 -73.129648) (xy 132.409692 -73.135744)
			(xy 132.418328 -73.139046) (xy 132.422678 -73.140583) (xy 132.43175 -73.142246) (xy 132.436362 -73.142348)
			(xy 132.503672 -73.142348) (xy 132.508285 -73.142255) (xy 132.517359 -73.140591) (xy 132.521706 -73.139046)
			(xy 132.530342 -73.135744) (xy 132.537454 -73.129648) (xy 132.5585 -73.111616) (xy 132.604817 -73.081187)
			(xy 132.655053 -73.057786) (xy 132.708148 -73.041905) (xy 132.762983 -73.03388) (xy 132.790692 -73.033382)
			(xy 132.817945 -73.033865) (xy 132.871895 -73.041621) (xy 132.924192 -73.056976) (xy 132.973772 -73.079617)
			(xy 133.019625 -73.109084) (xy 133.060818 -73.144777) (xy 133.096511 -73.185969) (xy 133.125979 -73.231821)
			(xy 133.148622 -73.2814) (xy 133.163978 -73.333697) (xy 133.171735 -73.387647) (xy 133.171735 -73.442153)
			(xy 133.163978 -73.496103) (xy 133.148622 -73.5484) (xy 133.125979 -73.597979) (xy 133.096511 -73.643831)
			(xy 133.060818 -73.685023) (xy 133.019625 -73.720716) (xy 132.973772 -73.750183) (xy 132.924192 -73.772824)
			(xy 132.871895 -73.788179) (xy 132.817945 -73.795935) (xy 132.790692 -73.796398) (xy 132.762983 -73.795886)
			(xy 132.708149 -73.787862) (xy 132.655055 -73.771984) (xy 132.604818 -73.748588) (xy 132.558498 -73.718165)
			(xy 132.537454 -73.700132) (xy 132.530342 -73.694036) (xy 132.521706 -73.690734) (xy 132.517361 -73.689184)
			(xy 132.508285 -73.687529) (xy 132.503672 -73.687432) (xy 132.436362 -73.687432) (xy 132.43175 -73.687535)
			(xy 132.422676 -73.689193) (xy 132.418328 -73.690734) (xy 132.409692 -73.694036) (xy 132.40258 -73.700132)
			(xy 132.381537 -73.718166) (xy 132.335217 -73.748592) (xy 132.284981 -73.77199) (xy 132.231886 -73.787868)
			(xy 132.177051 -73.795892) (xy 132.121633 -73.795892) (xy 132.066798 -73.787868) (xy 132.013703 -73.77199)
			(xy 131.963467 -73.748592) (xy 131.917147 -73.718166) (xy 131.896104 -73.700132) (xy 131.888992 -73.694036)
			(xy 131.880356 -73.690734) (xy 131.876007 -73.689196) (xy 131.866934 -73.687534) (xy 131.862322 -73.687432)
			(xy 131.795012 -73.687432) (xy 131.790399 -73.687522) (xy 131.781325 -73.689188) (xy 131.776978 -73.690734)
			(xy 131.768342 -73.694036) (xy 131.76123 -73.700132) (xy 131.740187 -73.718166) (xy 131.693867 -73.748592)
			(xy 131.643631 -73.77199) (xy 131.590536 -73.787868) (xy 131.535701 -73.795892) (xy 131.480283 -73.795892)
			(xy 131.425448 -73.787868) (xy 131.372353 -73.77199) (xy 131.322117 -73.748592) (xy 131.275797 -73.718166)
			(xy 131.254754 -73.700132) (xy 131.247642 -73.694036) (xy 131.239006 -73.690734) (xy 131.234661 -73.689184)
			(xy 131.225585 -73.687529) (xy 131.220972 -73.687432) (xy 131.153662 -73.687432) (xy 131.14905 -73.687535)
			(xy 131.139976 -73.689193) (xy 131.135628 -73.690734) (xy 131.126992 -73.694036) (xy 131.11988 -73.700132)
			(xy 131.098857 -73.718192) (xy 131.052533 -73.748617) (xy 131.002292 -73.772013) (xy 130.949192 -73.787888)
			(xy 130.894353 -73.795905) (xy 130.866642 -73.796398) (xy 130.839386 -73.795958) (xy 130.785429 -73.788206)
			(xy 130.733125 -73.772853) (xy 130.683538 -73.750212) (xy 130.637679 -73.720744) (xy 130.59648 -73.68505)
			(xy 130.560781 -73.643855) (xy 130.531308 -73.597999) (xy 130.508662 -73.548414) (xy 130.493303 -73.496112)
			(xy 130.485545 -73.442156) (xy 113.833148 -73.442156) (xy 113.833148 -74.038968) (xy 120.21896 -74.038968)
			(xy 120.223033 -73.983309) (xy 120.235168 -73.928836) (xy 120.255104 -73.87671) (xy 120.282418 -73.828042)
			(xy 120.316526 -73.78387) (xy 120.356703 -73.745135) (xy 120.402091 -73.712663) (xy 120.451723 -73.687145)
			(xy 120.504543 -73.669126) (xy 120.559422 -73.658989) (xy 120.615193 -73.656951) (xy 120.670667 -73.663054)
			(xy 120.72466 -73.67717) (xy 120.776023 -73.698997) (xy 120.823661 -73.72807) (xy 120.866557 -73.763769)
			(xy 120.903799 -73.805333) (xy 120.934593 -73.851877) (xy 120.958281 -73.902408) (xy 120.974359 -73.95585)
			(xy 120.982485 -74.011064) (xy 120.982569 -74.01567) (xy 122.273524 -74.01567) (xy 122.273524 -73.96113)
			(xy 122.281286 -73.907144) (xy 122.296652 -73.854812) (xy 122.31931 -73.805201) (xy 122.348798 -73.759319)
			(xy 122.384516 -73.7181) (xy 122.425736 -73.682385) (xy 122.47162 -73.6529) (xy 122.521233 -73.630245)
			(xy 122.573565 -73.614881) (xy 122.627552 -73.607122) (xy 122.654822 -73.60666) (xy 122.684158 -73.607172)
			(xy 122.74214 -73.616146) (xy 122.798063 -73.633895) (xy 122.850608 -73.659999) (xy 122.898535 -73.693843)
			(xy 122.919998 -73.713848) (xy 122.930374 -73.723307) (xy 122.955131 -73.736541) (xy 122.982554 -73.742543)
			(xy 123.010575 -73.740862) (xy 123.037084 -73.731625) (xy 123.060081 -73.715527) (xy 123.077834 -73.693782)
			(xy 123.083828 -73.681082) (xy 123.095317 -73.655801) (xy 123.124497 -73.608556) (xy 123.160212 -73.566036)
			(xy 123.201709 -73.529137) (xy 123.248112 -73.498636) (xy 123.298443 -73.475178) (xy 123.35164 -73.459256)
			(xy 123.406583 -73.451206) (xy 123.434348 -73.450704) (xy 123.461613 -73.451262) (xy 123.515586 -73.459028)
			(xy 123.567905 -73.474396) (xy 123.617505 -73.497053) (xy 123.663376 -73.526538) (xy 123.704584 -73.56225)
			(xy 123.740291 -73.603463) (xy 123.76977 -73.649337) (xy 123.792421 -73.69894) (xy 123.807782 -73.751261)
			(xy 123.815542 -73.805235) (xy 123.815542 -73.859765) (xy 123.807782 -73.913739) (xy 123.792421 -73.96606)
			(xy 123.76977 -74.015663) (xy 123.740291 -74.061537) (xy 123.704584 -74.10275) (xy 123.663376 -74.138462)
			(xy 123.617505 -74.167947) (xy 123.567905 -74.190604) (xy 123.515586 -74.205972) (xy 123.461613 -74.213738)
			(xy 123.434348 -74.214228) (xy 123.405013 -74.213676) (xy 123.347033 -74.204712) (xy 123.291111 -74.186973)
			(xy 123.238565 -74.160878) (xy 123.190637 -74.127042) (xy 123.169172 -74.10704) (xy 123.158724 -74.097666)
			(xy 123.133987 -74.08443) (xy 123.106582 -74.07842) (xy 123.078576 -74.080088) (xy 123.052079 -74.08931)
			(xy 123.029089 -74.10539) (xy 123.011337 -74.127116) (xy 123.005342 -74.139806) (xy 122.99387 -74.165096)
			(xy 122.964689 -74.212341) (xy 122.928972 -74.254862) (xy 122.887473 -74.291762) (xy 122.841067 -74.322261)
			(xy 122.790733 -74.345718) (xy 122.737533 -74.361637) (xy 122.682588 -74.369684) (xy 122.654822 -74.370184)
			(xy 122.627552 -74.369678) (xy 122.573565 -74.361919) (xy 122.521233 -74.346555) (xy 122.47162 -74.3239)
			(xy 122.425736 -74.294415) (xy 122.384516 -74.2587) (xy 122.348798 -74.217481) (xy 122.31931 -74.171599)
			(xy 122.296652 -74.121988) (xy 122.281286 -74.069656) (xy 122.273524 -74.01567) (xy 120.982569 -74.01567)
			(xy 120.982994 -74.038968) (xy 120.982485 -74.066872) (xy 120.974359 -74.122086) (xy 120.958281 -74.175528)
			(xy 120.934593 -74.226059) (xy 120.903799 -74.272603) (xy 120.866557 -74.314167) (xy 120.823661 -74.349866)
			(xy 120.776023 -74.378939) (xy 120.72466 -74.400766) (xy 120.670667 -74.414882) (xy 120.615193 -74.420985)
			(xy 120.559422 -74.418947) (xy 120.504543 -74.40881) (xy 120.451723 -74.390791) (xy 120.402091 -74.365273)
			(xy 120.356703 -74.332801) (xy 120.316526 -74.294066) (xy 120.282418 -74.249894) (xy 120.255104 -74.201226)
			(xy 120.235168 -74.1491) (xy 120.223033 -74.094627) (xy 120.21896 -74.038968) (xy 113.833148 -74.038968)
			(xy 113.833148 -78.016862) (xy 121.734324 -78.016862) (xy 121.738395 -77.96124) (xy 121.750521 -77.906803)
			(xy 121.770444 -77.854712) (xy 121.79774 -77.806077) (xy 121.831826 -77.761934) (xy 121.871975 -77.723225)
			(xy 121.917333 -77.690774) (xy 121.966933 -77.665273) (xy 122.019717 -77.647266) (xy 122.07456 -77.637136)
			(xy 122.130294 -77.635099) (xy 122.174162 -77.639926) (xy 122.569984 -77.639926) (xy 122.574055 -77.584304)
			(xy 122.586181 -77.529867) (xy 122.606104 -77.477776) (xy 122.6334 -77.429141) (xy 122.667486 -77.384998)
			(xy 122.707635 -77.346289) (xy 122.752993 -77.313838) (xy 122.802593 -77.288337) (xy 122.855377 -77.27033)
			(xy 122.91022 -77.2602) (xy 122.965954 -77.258163) (xy 123.021391 -77.264263) (xy 123.075348 -77.278369)
			(xy 123.126677 -77.300181) (xy 123.174283 -77.329235) (xy 123.217151 -77.36491) (xy 123.254368 -77.406447)
			(xy 123.285141 -77.45296) (xy 123.308813 -77.503457) (xy 123.318018 -77.534053) (xy 130.485585 -77.534053)
			(xy 130.485585 -77.479547) (xy 130.493343 -77.425597) (xy 130.5087 -77.3733) (xy 130.531344 -77.323721)
			(xy 130.560813 -77.277869) (xy 130.596509 -77.236679) (xy 130.637703 -77.200988) (xy 130.683558 -77.171523)
			(xy 130.733139 -77.148885) (xy 130.785438 -77.133534) (xy 130.839389 -77.125782) (xy 130.866642 -77.125322)
			(xy 130.894352 -77.125809) (xy 130.949187 -77.133838) (xy 131.002282 -77.149722) (xy 131.052518 -77.173124)
			(xy 131.098837 -77.203553) (xy 131.11988 -77.221588) (xy 131.126992 -77.227684) (xy 131.135628 -77.230986)
			(xy 131.139978 -77.23252) (xy 131.14905 -77.234185) (xy 131.153662 -77.234288) (xy 131.220972 -77.234288)
			(xy 131.225585 -77.234193) (xy 131.234658 -77.23253) (xy 131.239006 -77.230986) (xy 131.247642 -77.227684)
			(xy 131.254754 -77.221588) (xy 131.275797 -77.203554) (xy 131.322117 -77.173128) (xy 131.372353 -77.14973)
			(xy 131.425448 -77.133852) (xy 131.480283 -77.125828) (xy 131.535701 -77.125828) (xy 131.590536 -77.133852)
			(xy 131.643631 -77.14973) (xy 131.693867 -77.173128) (xy 131.740187 -77.203554) (xy 131.76123 -77.221588)
			(xy 131.768342 -77.227684) (xy 131.776978 -77.230986) (xy 131.781324 -77.232533) (xy 131.790399 -77.234189)
			(xy 131.795012 -77.234288) (xy 131.862322 -77.234288) (xy 131.866934 -77.23418) (xy 131.876008 -77.232525)
			(xy 131.880356 -77.230986) (xy 131.888992 -77.227684) (xy 131.896104 -77.221588) (xy 131.917136 -77.203539)
			(xy 131.963457 -77.173111) (xy 132.013696 -77.149713) (xy 132.066794 -77.133836) (xy 132.121631 -77.125816)
			(xy 132.149342 -77.125322) (xy 132.176593 -77.125751) (xy 132.230541 -77.133513) (xy 132.282835 -77.148873)
			(xy 132.332411 -77.171518) (xy 132.378259 -77.200988) (xy 132.419448 -77.236682) (xy 132.455137 -77.277874)
			(xy 132.484602 -77.323726) (xy 132.507242 -77.373305) (xy 132.522596 -77.4256) (xy 132.530352 -77.479549)
			(xy 132.530352 -77.534051) (xy 132.522596 -77.588) (xy 132.507242 -77.640295) (xy 132.484602 -77.689874)
			(xy 132.455137 -77.735726) (xy 132.419448 -77.776918) (xy 132.378259 -77.812612) (xy 132.33241 -77.842082)
			(xy 132.282835 -77.864727) (xy 132.230541 -77.880087) (xy 132.176593 -77.887849) (xy 132.149342 -77.888338)
			(xy 132.121633 -77.887845) (xy 132.066798 -77.879815) (xy 132.013704 -77.863932) (xy 131.963468 -77.840532)
			(xy 131.917148 -77.810106) (xy 131.896104 -77.792072) (xy 131.888992 -77.785976) (xy 131.880356 -77.782674)
			(xy 131.876008 -77.781134) (xy 131.866934 -77.779473) (xy 131.862322 -77.779372) (xy 131.795012 -77.779372)
			(xy 131.790399 -77.779459) (xy 131.781325 -77.781127) (xy 131.776978 -77.782674) (xy 131.768342 -77.785976)
			(xy 131.76123 -77.792072) (xy 131.740187 -77.810106) (xy 131.693867 -77.840532) (xy 131.643631 -77.86393)
			(xy 131.590536 -77.879808) (xy 131.535701 -77.887832) (xy 131.480283 -77.887832) (xy 131.425448 -77.879808)
			(xy 131.372353 -77.86393) (xy 131.322117 -77.840532) (xy 131.275797 -77.810106) (xy 131.254754 -77.792072)
			(xy 131.247642 -77.785976) (xy 131.239006 -77.782674) (xy 131.234662 -77.781121) (xy 131.225585 -77.779468)
			(xy 131.220972 -77.779372) (xy 131.153662 -77.779372) (xy 131.14905 -77.779472) (xy 131.139976 -77.781132)
			(xy 131.135628 -77.782674) (xy 131.126992 -77.785976) (xy 131.11988 -77.792072) (xy 131.098849 -77.810122)
			(xy 131.052528 -77.840551) (xy 131.002289 -77.86395) (xy 130.949191 -77.879826) (xy 130.894353 -77.887844)
			(xy 130.866642 -77.888338) (xy 130.839389 -77.887818) (xy 130.785438 -77.880066) (xy 130.733139 -77.864715)
			(xy 130.683558 -77.842077) (xy 130.637703 -77.812612) (xy 130.596509 -77.776921) (xy 130.560813 -77.735731)
			(xy 130.531344 -77.689879) (xy 130.5087 -77.6403) (xy 130.493343 -77.588003) (xy 130.485585 -77.534053)
			(xy 123.318018 -77.534053) (xy 123.324881 -77.556864) (xy 123.333001 -77.61204) (xy 123.33351 -77.639926)
			(xy 123.333001 -77.667812) (xy 123.324881 -77.722988) (xy 123.308813 -77.776395) (xy 123.285141 -77.826892)
			(xy 123.254368 -77.873405) (xy 123.217151 -77.914942) (xy 123.174283 -77.950617) (xy 123.126677 -77.979671)
			(xy 123.075348 -78.001483) (xy 123.021391 -78.015589) (xy 122.965954 -78.021689) (xy 122.91022 -78.019652)
			(xy 122.855377 -78.009522) (xy 122.802593 -77.991515) (xy 122.752993 -77.966014) (xy 122.707635 -77.933563)
			(xy 122.667486 -77.894854) (xy 122.6334 -77.850711) (xy 122.606104 -77.802076) (xy 122.586181 -77.749985)
			(xy 122.574055 -77.695548) (xy 122.569984 -77.639926) (xy 122.174162 -77.639926) (xy 122.185731 -77.641199)
			(xy 122.239688 -77.655305) (xy 122.291017 -77.677117) (xy 122.338623 -77.706171) (xy 122.381491 -77.741846)
			(xy 122.418708 -77.783383) (xy 122.449481 -77.829896) (xy 122.473153 -77.880393) (xy 122.489221 -77.9338)
			(xy 122.497341 -77.988976) (xy 122.49785 -78.016862) (xy 122.497341 -78.044748) (xy 122.489221 -78.099924)
			(xy 122.473153 -78.153331) (xy 122.449481 -78.203828) (xy 122.418708 -78.250341) (xy 122.381491 -78.291878)
			(xy 122.338623 -78.327553) (xy 122.291017 -78.356607) (xy 122.239688 -78.378419) (xy 122.185731 -78.392525)
			(xy 122.130294 -78.398625) (xy 122.07456 -78.396588) (xy 122.019717 -78.386458) (xy 121.966933 -78.368451)
			(xy 121.917333 -78.34295) (xy 121.871975 -78.310499) (xy 121.831826 -78.27179) (xy 121.79774 -78.227647)
			(xy 121.770444 -78.179012) (xy 121.750521 -78.126921) (xy 121.738395 -78.072484) (xy 121.734324 -78.016862)
			(xy 113.833148 -78.016862) (xy 113.833148 -80.137508) (xy 121.321574 -80.137508) (xy 121.325645 -80.081886)
			(xy 121.337771 -80.027449) (xy 121.357694 -79.975358) (xy 121.38499 -79.926723) (xy 121.419076 -79.88258)
			(xy 121.459225 -79.843871) (xy 121.504583 -79.81142) (xy 121.554183 -79.785919) (xy 121.606967 -79.767912)
			(xy 121.66181 -79.757782) (xy 121.717544 -79.755745) (xy 121.772981 -79.761845) (xy 121.826938 -79.775951)
			(xy 121.878267 -79.797763) (xy 121.925873 -79.826817) (xy 121.968741 -79.862492) (xy 122.005958 -79.904029)
			(xy 122.036731 -79.950542) (xy 122.060403 -80.001039) (xy 122.076471 -80.054446) (xy 122.084591 -80.109622)
			(xy 122.0851 -80.137508) (xy 122.084591 -80.165394) (xy 122.076471 -80.22057) (xy 122.060403 -80.273977)
			(xy 122.036731 -80.324474) (xy 122.005958 -80.370987) (xy 121.968741 -80.412524) (xy 121.925873 -80.448199)
			(xy 121.878267 -80.477253) (xy 121.826938 -80.499065) (xy 121.772981 -80.513171) (xy 121.717544 -80.519271)
			(xy 121.66181 -80.517234) (xy 121.606967 -80.507104) (xy 121.554183 -80.489097) (xy 121.504583 -80.463596)
			(xy 121.459225 -80.431145) (xy 121.419076 -80.392436) (xy 121.38499 -80.348293) (xy 121.357694 -80.299658)
			(xy 121.337771 -80.247567) (xy 121.325645 -80.19313) (xy 121.321574 -80.137508) (xy 113.833148 -80.137508)
			(xy 113.833148 -81.241138) (xy 113.833579 -81.251204) (xy 113.841309 -81.269794) (xy 113.848134 -81.277206)
			(xy 113.868962 -81.298034) (xy 113.876361 -81.304878) (xy 113.89496 -81.3126) (xy 113.90503 -81.31302)
		)
		(stroke
			(width 0)
			(type solid)
		)
		(fill yes)
		(layer "In4.Cu")
		(net "GND")
	)
	(gr_poly
		(pts
			(xy 156.193998 -83.59902) (xy 156.204069 -83.598598) (xy 156.222676 -83.590886) (xy 156.230066 -83.584034)
			(xy 156.250894 -83.563206) (xy 156.257742 -83.555808) (xy 156.26548 -83.53721) (xy 156.26588 -83.527138)
			(xy 156.26588 -72.304656) (xy 156.265448 -72.29459) (xy 156.25772 -72.275999) (xy 156.250894 -72.268588)
			(xy 156.121354 -72.139048) (xy 156.114242 -72.131682) (xy 156.095446 -72.124062) (xy 136.780778 -72.124062)
			(xy 136.770711 -72.124491) (xy 136.752118 -72.132218) (xy 136.74471 -72.139048) (xy 135.982202 -72.901556)
			(xy 135.981948 -72.901556) (xy 135.946134 -72.93737) (xy 135.938768 -72.944482) (xy 135.931148 -72.963278)
			(xy 135.931148 -73.594722) (xy 137.237724 -73.594722) (xy 137.238176 -73.567468) (xy 137.245931 -73.513515)
			(xy 137.261286 -73.461215) (xy 137.283928 -73.411633) (xy 137.313397 -73.365778) (xy 137.349092 -73.324584)
			(xy 137.390286 -73.288891) (xy 137.436142 -73.259423) (xy 137.485725 -73.236782) (xy 137.538025 -73.221429)
			(xy 137.591978 -73.213675) (xy 137.619232 -73.213214) (xy 137.61974 -73.213214) (xy 137.650646 -73.213857)
			(xy 137.71164 -73.223883) (xy 137.770224 -73.243602) (xy 137.824867 -73.272499) (xy 137.849864 -73.290684)
			(xy 137.858754 -73.297288) (xy 137.880344 -73.302114) (xy 137.977118 -73.281032) (xy 137.994898 -73.267824)
			(xy 138.000232 -73.257918) (xy 138.014686 -73.232456) (xy 138.050123 -73.185852) (xy 138.092266 -73.14521)
			(xy 138.140124 -73.111485) (xy 138.192573 -73.08547) (xy 138.248382 -73.067774) (xy 138.306239 -73.058814)
			(xy 138.335512 -73.058274) (xy 138.362763 -73.058767) (xy 138.416709 -73.066524) (xy 138.469003 -73.08188)
			(xy 138.518579 -73.104521) (xy 138.564428 -73.133987) (xy 138.605618 -73.169678) (xy 138.641309 -73.210867)
			(xy 138.670776 -73.256716) (xy 138.693418 -73.306292) (xy 138.708774 -73.358585) (xy 138.716533 -73.412531)
			(xy 138.71702 -73.439782) (xy 138.716562 -73.467116) (xy 138.70875 -73.521223) (xy 138.693297 -73.573662)
			(xy 138.673732 -73.616352) (xy 152.964589 -73.616352) (xy 152.964589 -73.561848) (xy 152.972347 -73.507898)
			(xy 152.987704 -73.455601) (xy 153.010347 -73.406023) (xy 153.039816 -73.360172) (xy 153.075511 -73.318982)
			(xy 153.116705 -73.283291) (xy 153.16256 -73.253827) (xy 153.212141 -73.231189) (xy 153.264439 -73.215838)
			(xy 153.31839 -73.208086) (xy 153.345642 -73.207626) (xy 153.373352 -73.208112) (xy 153.428187 -73.216142)
			(xy 153.481282 -73.232025) (xy 153.531518 -73.255427) (xy 153.577837 -73.285856) (xy 153.59888 -73.303892)
			(xy 153.605992 -73.309988) (xy 153.614628 -73.31329) (xy 153.618978 -73.314824) (xy 153.62805 -73.316489)
			(xy 153.632662 -73.316592) (xy 153.699972 -73.316592) (xy 153.704585 -73.316497) (xy 153.713658 -73.314834)
			(xy 153.718006 -73.31329) (xy 153.726642 -73.309988) (xy 153.733754 -73.303892) (xy 153.754797 -73.285858)
			(xy 153.801117 -73.255432) (xy 153.851353 -73.232034) (xy 153.904448 -73.216156) (xy 153.959283 -73.208132)
			(xy 154.014701 -73.208132) (xy 154.069536 -73.216156) (xy 154.122631 -73.232034) (xy 154.172867 -73.255432)
			(xy 154.219187 -73.285858) (xy 154.24023 -73.303892) (xy 154.247342 -73.309988) (xy 154.255978 -73.31329)
			(xy 154.260324 -73.314837) (xy 154.269399 -73.316493) (xy 154.274012 -73.316592) (xy 154.341322 -73.316592)
			(xy 154.345934 -73.316483) (xy 154.355008 -73.314829) (xy 154.359356 -73.31329) (xy 154.367992 -73.309988)
			(xy 154.375104 -73.303892) (xy 154.396136 -73.285844) (xy 154.442457 -73.255416) (xy 154.492696 -73.232017)
			(xy 154.545794 -73.21614) (xy 154.600632 -73.20812) (xy 154.628342 -73.207626) (xy 154.655594 -73.208047)
			(xy 154.709542 -73.215809) (xy 154.761836 -73.231169) (xy 154.811412 -73.253814) (xy 154.857262 -73.283285)
			(xy 154.898451 -73.318979) (xy 154.934141 -73.360172) (xy 154.963606 -73.406024) (xy 154.986246 -73.455603)
			(xy 155.0016 -73.507899) (xy 155.009356 -73.561848) (xy 155.009356 -73.616352) (xy 155.0016 -73.670301)
			(xy 154.986246 -73.722597) (xy 154.963606 -73.772176) (xy 154.934141 -73.818028) (xy 154.898451 -73.859221)
			(xy 154.857262 -73.894915) (xy 154.811412 -73.924386) (xy 154.761836 -73.947031) (xy 154.709542 -73.962391)
			(xy 154.655594 -73.970153) (xy 154.628342 -73.970642) (xy 154.600633 -73.970148) (xy 154.545799 -73.962118)
			(xy 154.492704 -73.946236) (xy 154.442468 -73.922835) (xy 154.396148 -73.89241) (xy 154.375104 -73.874376)
			(xy 154.367992 -73.86828) (xy 154.359356 -73.864978) (xy 154.355007 -73.863438) (xy 154.345934 -73.861777)
			(xy 154.341322 -73.861676) (xy 154.274012 -73.861676) (xy 154.269399 -73.861763) (xy 154.260325 -73.863431)
			(xy 154.255978 -73.864978) (xy 154.247342 -73.86828) (xy 154.24023 -73.874376) (xy 154.219187 -73.89241)
			(xy 154.172867 -73.922836) (xy 154.122631 -73.946234) (xy 154.069536 -73.962112) (xy 154.014701 -73.970136)
			(xy 153.959283 -73.970136) (xy 153.904448 -73.962112) (xy 153.851353 -73.946234) (xy 153.801117 -73.922836)
			(xy 153.754797 -73.89241) (xy 153.733754 -73.874376) (xy 153.726642 -73.86828) (xy 153.718006 -73.864978)
			(xy 153.713662 -73.863425) (xy 153.704585 -73.861772) (xy 153.699972 -73.861676) (xy 153.632662 -73.861676)
			(xy 153.62805 -73.861776) (xy 153.618976 -73.863435) (xy 153.614628 -73.864978) (xy 153.605992 -73.86828)
			(xy 153.59888 -73.874376) (xy 153.577849 -73.892427) (xy 153.531529 -73.922855) (xy 153.481289 -73.946254)
			(xy 153.428191 -73.96213) (xy 153.373353 -73.970148) (xy 153.345642 -73.970642) (xy 153.31839 -73.970114)
			(xy 153.264439 -73.962362) (xy 153.212141 -73.947011) (xy 153.16256 -73.924373) (xy 153.116705 -73.894909)
			(xy 153.075511 -73.859218) (xy 153.039816 -73.818028) (xy 153.010347 -73.772177) (xy 152.987704 -73.722599)
			(xy 152.972347 -73.670302) (xy 152.964589 -73.616352) (xy 138.673732 -73.616352) (xy 138.67052 -73.62336)
			(xy 138.640884 -73.669299) (xy 138.623294 -73.690226) (xy 138.62304 -73.69048) (xy 138.622786 -73.690734)
			(xy 138.617219 -73.697834) (xy 138.610961 -73.714741) (xy 138.610594 -73.723754) (xy 138.610594 -73.79081)
			(xy 138.610948 -73.799827) (xy 138.617198 -73.816744) (xy 138.622786 -73.82383) (xy 138.62304 -73.824084)
			(xy 138.623294 -73.824338) (xy 138.64087 -73.845277) (xy 138.670511 -73.89121) (xy 138.693291 -73.940905)
			(xy 138.708742 -73.993342) (xy 138.716549 -74.047449) (xy 138.71702 -74.074782) (xy 138.716585 -74.101067)
			(xy 138.709381 -74.153142) (xy 138.695094 -74.203734) (xy 138.673994 -74.251885) (xy 138.646482 -74.296681)
			(xy 138.613077 -74.337274) (xy 138.574415 -74.372896) (xy 138.531227 -74.40287) (xy 138.507978 -74.415142)
			(xy 138.498834 -74.419714) (xy 138.48588 -74.4347) (xy 138.459972 -74.511916) (xy 138.457274 -74.521299)
			(xy 138.458457 -74.540769) (xy 138.462258 -74.549762) (xy 138.462512 -74.550524) (xy 138.462766 -74.550778)
			(xy 138.475042 -74.577044) (xy 138.492374 -74.632369) (xy 138.501112 -74.689683) (xy 138.501628 -74.718672)
			(xy 138.501142 -74.745923) (xy 138.493386 -74.799871) (xy 138.478073 -74.852022) (xy 141.15745 -74.852022)
			(xy 141.161523 -74.796363) (xy 141.173658 -74.74189) (xy 141.193594 -74.689764) (xy 141.220908 -74.641096)
			(xy 141.255016 -74.596924) (xy 141.295193 -74.558189) (xy 141.340581 -74.525717) (xy 141.390213 -74.500199)
			(xy 141.443033 -74.48218) (xy 141.497912 -74.472043) (xy 141.553683 -74.470005) (xy 141.609157 -74.476108)
			(xy 141.66315 -74.490224) (xy 141.714513 -74.512051) (xy 141.762151 -74.541124) (xy 141.805047 -74.576823)
			(xy 141.842289 -74.618387) (xy 141.873083 -74.664931) (xy 141.896771 -74.715462) (xy 141.912849 -74.768904)
			(xy 141.920975 -74.824118) (xy 141.921484 -74.852022) (xy 141.920975 -74.879926) (xy 141.917605 -74.902822)
			(xy 144.60677 -74.902822) (xy 144.610843 -74.847163) (xy 144.622978 -74.79269) (xy 144.642914 -74.740564)
			(xy 144.670228 -74.691896) (xy 144.704336 -74.647724) (xy 144.744513 -74.608989) (xy 144.789901 -74.576517)
			(xy 144.839533 -74.550999) (xy 144.892353 -74.53298) (xy 144.947232 -74.522843) (xy 145.003003 -74.520805)
			(xy 145.058477 -74.526908) (xy 145.11247 -74.541024) (xy 145.163833 -74.562851) (xy 145.211471 -74.591924)
			(xy 145.254367 -74.627623) (xy 145.291609 -74.669187) (xy 145.322403 -74.715731) (xy 145.346091 -74.766262)
			(xy 145.362169 -74.819704) (xy 145.370295 -74.874918) (xy 145.370804 -74.902822) (xy 145.370295 -74.930726)
			(xy 145.362169 -74.98594) (xy 145.346091 -75.039382) (xy 145.322403 -75.089913) (xy 145.291609 -75.136457)
			(xy 145.254367 -75.178021) (xy 145.211471 -75.21372) (xy 145.163833 -75.242793) (xy 145.11247 -75.26462)
			(xy 145.058477 -75.278736) (xy 145.003003 -75.284839) (xy 144.947232 -75.282801) (xy 144.892353 -75.272664)
			(xy 144.839533 -75.254645) (xy 144.789901 -75.229127) (xy 144.744513 -75.196655) (xy 144.704336 -75.15792)
			(xy 144.670228 -75.113748) (xy 144.642914 -75.06508) (xy 144.622978 -75.012954) (xy 144.610843 -74.958481)
			(xy 144.60677 -74.902822) (xy 141.917605 -74.902822) (xy 141.912849 -74.93514) (xy 141.896771 -74.988582)
			(xy 141.873083 -75.039113) (xy 141.842289 -75.085657) (xy 141.805047 -75.127221) (xy 141.762151 -75.16292)
			(xy 141.714513 -75.191993) (xy 141.66315 -75.21382) (xy 141.609157 -75.227936) (xy 141.553683 -75.234039)
			(xy 141.497912 -75.232001) (xy 141.443033 -75.221864) (xy 141.390213 -75.203845) (xy 141.340581 -75.178327)
			(xy 141.295193 -75.145855) (xy 141.255016 -75.10712) (xy 141.220908 -75.062948) (xy 141.193594 -75.01428)
			(xy 141.173658 -74.962154) (xy 141.161523 -74.907681) (xy 141.15745 -74.852022) (xy 138.478073 -74.852022)
			(xy 138.478031 -74.852166) (xy 138.455389 -74.901743) (xy 138.425923 -74.947593) (xy 138.390232 -74.988784)
			(xy 138.349041 -75.024475) (xy 138.303191 -75.053941) (xy 138.253614 -75.076583) (xy 138.201319 -75.091938)
			(xy 138.147371 -75.099694) (xy 138.092869 -75.099694) (xy 138.038921 -75.091938) (xy 137.986626 -75.076583)
			(xy 137.937049 -75.053941) (xy 137.891199 -75.024475) (xy 137.850008 -74.988784) (xy 137.814317 -74.947593)
			(xy 137.784851 -74.901743) (xy 137.762209 -74.852166) (xy 137.746854 -74.799871) (xy 137.739098 -74.745923)
			(xy 137.738612 -74.718672) (xy 137.739074 -74.692387) (xy 137.746271 -74.640313) (xy 137.760553 -74.589721)
			(xy 137.781648 -74.54157) (xy 137.809157 -74.496773) (xy 137.842558 -74.456179) (xy 137.881219 -74.420557)
			(xy 137.924406 -74.390584) (xy 137.947654 -74.378312) (xy 137.956798 -74.37374) (xy 137.969752 -74.358754)
			(xy 137.99566 -74.281538) (xy 137.998326 -74.272149) (xy 137.997163 -74.252685) (xy 137.993374 -74.243692)
			(xy 137.99312 -74.24293) (xy 137.992866 -74.242676) (xy 137.98061 -74.216401) (xy 137.963271 -74.16108)
			(xy 137.954524 -74.10377) (xy 137.954004 -74.074782) (xy 137.954004 -74.07402) (xy 137.954108 -74.062561)
			(xy 137.955504 -74.039686) (xy 137.956798 -74.0283) (xy 137.957475 -74.018943) (xy 137.952948 -74.000757)
			(xy 137.942222 -73.98539) (xy 137.9347 -73.979786) (xy 137.847324 -73.921366) (xy 137.818622 -73.920096)
			(xy 137.806176 -73.927208) (xy 137.784693 -73.93885) (xy 137.73939 -73.957162) (xy 137.692124 -73.969554)
			(xy 137.643664 -73.975822) (xy 137.619232 -73.97623) (xy 137.591981 -73.975715) (xy 137.538033 -73.967963)
			(xy 137.485737 -73.952612) (xy 137.436159 -73.929975) (xy 137.390307 -73.900512) (xy 137.349114 -73.864824)
			(xy 137.31342 -73.823637) (xy 137.283951 -73.777789) (xy 137.261307 -73.728213) (xy 137.245949 -73.67592)
			(xy 137.238189 -73.621973) (xy 137.237724 -73.594722) (xy 135.931148 -73.594722) (xy 135.931148 -76.324968)
			(xy 142.31696 -76.324968) (xy 142.321033 -76.269309) (xy 142.333168 -76.214836) (xy 142.353104 -76.16271)
			(xy 142.380418 -76.114042) (xy 142.414526 -76.06987) (xy 142.454703 -76.031135) (xy 142.500091 -75.998663)
			(xy 142.549723 -75.973145) (xy 142.602543 -75.955126) (xy 142.657422 -75.944989) (xy 142.713193 -75.942951)
			(xy 142.768667 -75.949054) (xy 142.82266 -75.96317) (xy 142.874023 -75.984997) (xy 142.921661 -76.01407)
			(xy 142.964557 -76.049769) (xy 143.001799 -76.091333) (xy 143.032593 -76.137877) (xy 143.056281 -76.188408)
			(xy 143.072359 -76.24185) (xy 143.080485 -76.297064) (xy 143.080569 -76.30167) (xy 144.371524 -76.30167)
			(xy 144.371524 -76.24713) (xy 144.379286 -76.193144) (xy 144.394652 -76.140812) (xy 144.41731 -76.091201)
			(xy 144.446798 -76.045319) (xy 144.482516 -76.0041) (xy 144.523736 -75.968385) (xy 144.56962 -75.9389)
			(xy 144.619233 -75.916245) (xy 144.671565 -75.900881) (xy 144.725552 -75.893122) (xy 144.752822 -75.89266)
			(xy 144.782801 -75.893196) (xy 144.842031 -75.902508) (xy 144.899073 -75.920975) (xy 144.92605 -75.934062)
			(xy 144.938048 -75.939701) (xy 144.963973 -75.945206) (xy 144.99044 -75.94384) (xy 145.015661 -75.935697)
			(xy 145.037929 -75.921327) (xy 145.05574 -75.901701) (xy 145.062194 -75.89012) (xy 145.074617 -75.867141)
			(xy 145.104715 -75.824448) (xy 145.140348 -75.786252) (xy 145.180853 -75.753268) (xy 145.225473 -75.726108)
			(xy 145.273377 -75.70528) (xy 145.323672 -75.691173) (xy 145.37542 -75.684048) (xy 145.401538 -75.683618)
			(xy 145.428804 -75.684147) (xy 145.482781 -75.691913) (xy 145.535103 -75.70728) (xy 145.580805 -75.728156)
			(xy 152.583545 -75.728156) (xy 152.583545 -75.673644) (xy 152.591303 -75.619688) (xy 152.606662 -75.567386)
			(xy 152.629308 -75.517801) (xy 152.658781 -75.471945) (xy 152.69448 -75.43075) (xy 152.735679 -75.395056)
			(xy 152.781538 -75.365588) (xy 152.831125 -75.342947) (xy 152.883429 -75.327594) (xy 152.937386 -75.319842)
			(xy 152.964642 -75.319382) (xy 152.992351 -75.319879) (xy 153.047186 -75.327908) (xy 153.10028 -75.343789)
			(xy 153.150516 -75.367189) (xy 153.196836 -75.397614) (xy 153.21788 -75.415648) (xy 153.224992 -75.421744)
			(xy 153.233628 -75.425046) (xy 153.237978 -75.426583) (xy 153.24705 -75.428246) (xy 153.251662 -75.428348)
			(xy 153.318972 -75.428348) (xy 153.323585 -75.428255) (xy 153.332659 -75.426591) (xy 153.337006 -75.425046)
			(xy 153.345642 -75.421744) (xy 153.352754 -75.415648) (xy 153.373797 -75.397614) (xy 153.420117 -75.367188)
			(xy 153.470353 -75.34379) (xy 153.523448 -75.327912) (xy 153.578283 -75.319888) (xy 153.633701 -75.319888)
			(xy 153.688536 -75.327912) (xy 153.741631 -75.34379) (xy 153.791867 -75.367188) (xy 153.838187 -75.397614)
			(xy 153.85923 -75.415648) (xy 153.866342 -75.421744) (xy 153.874978 -75.425046) (xy 153.879323 -75.426595)
			(xy 153.888399 -75.42825) (xy 153.893012 -75.428348) (xy 153.960322 -75.428348) (xy 153.964934 -75.428242)
			(xy 153.974008 -75.426586) (xy 153.978356 -75.425046) (xy 153.986992 -75.421744) (xy 153.994104 -75.415648)
			(xy 154.015147 -75.397614) (xy 154.061467 -75.367188) (xy 154.111703 -75.34379) (xy 154.164798 -75.327912)
			(xy 154.219633 -75.319888) (xy 154.275051 -75.319888) (xy 154.329886 -75.327912) (xy 154.382981 -75.34379)
			(xy 154.433217 -75.367188) (xy 154.479537 -75.397614) (xy 154.50058 -75.415648) (xy 154.507692 -75.421744)
			(xy 154.516328 -75.425046) (xy 154.520678 -75.426583) (xy 154.52975 -75.428246) (xy 154.534362 -75.428348)
			(xy 154.601672 -75.428348) (xy 154.606285 -75.428255) (xy 154.615359 -75.426591) (xy 154.619706 -75.425046)
			(xy 154.628342 -75.421744) (xy 154.635454 -75.415648) (xy 154.6565 -75.397616) (xy 154.702817 -75.367187)
			(xy 154.753053 -75.343786) (xy 154.806148 -75.327905) (xy 154.860983 -75.31988) (xy 154.888692 -75.319382)
			(xy 154.915945 -75.319865) (xy 154.969895 -75.327621) (xy 155.022192 -75.342976) (xy 155.071772 -75.365617)
			(xy 155.117625 -75.395084) (xy 155.158818 -75.430777) (xy 155.194511 -75.471969) (xy 155.223979 -75.517821)
			(xy 155.246622 -75.5674) (xy 155.261978 -75.619697) (xy 155.269735 -75.673647) (xy 155.269735 -75.728153)
			(xy 155.261978 -75.782103) (xy 155.246622 -75.8344) (xy 155.223979 -75.883979) (xy 155.194511 -75.929831)
			(xy 155.158818 -75.971023) (xy 155.117625 -76.006716) (xy 155.071772 -76.036183) (xy 155.022192 -76.058824)
			(xy 154.969895 -76.074179) (xy 154.915945 -76.081935) (xy 154.888692 -76.082398) (xy 154.860983 -76.081886)
			(xy 154.806149 -76.073862) (xy 154.753055 -76.057984) (xy 154.702818 -76.034588) (xy 154.656498 -76.004165)
			(xy 154.635454 -75.986132) (xy 154.628342 -75.980036) (xy 154.619706 -75.976734) (xy 154.615361 -75.975184)
			(xy 154.606285 -75.973529) (xy 154.601672 -75.973432) (xy 154.534362 -75.973432) (xy 154.52975 -75.973535)
			(xy 154.520676 -75.975193) (xy 154.516328 -75.976734) (xy 154.507692 -75.980036) (xy 154.50058 -75.986132)
			(xy 154.479537 -76.004166) (xy 154.433217 -76.034592) (xy 154.382981 -76.05799) (xy 154.329886 -76.073868)
			(xy 154.275051 -76.081892) (xy 154.219633 -76.081892) (xy 154.164798 -76.073868) (xy 154.111703 -76.05799)
			(xy 154.061467 -76.034592) (xy 154.015147 -76.004166) (xy 153.994104 -75.986132) (xy 153.986992 -75.980036)
			(xy 153.978356 -75.976734) (xy 153.974007 -75.975196) (xy 153.964934 -75.973534) (xy 153.960322 -75.973432)
			(xy 153.893012 -75.973432) (xy 153.888399 -75.973522) (xy 153.879325 -75.975188) (xy 153.874978 -75.976734)
			(xy 153.866342 -75.980036) (xy 153.85923 -75.986132) (xy 153.838187 -76.004166) (xy 153.791867 -76.034592)
			(xy 153.741631 -76.05799) (xy 153.688536 -76.073868) (xy 153.633701 -76.081892) (xy 153.578283 -76.081892)
			(xy 153.523448 -76.073868) (xy 153.470353 -76.05799) (xy 153.420117 -76.034592) (xy 153.373797 -76.004166)
			(xy 153.352754 -75.986132) (xy 153.345642 -75.980036) (xy 153.337006 -75.976734) (xy 153.332661 -75.975184)
			(xy 153.323585 -75.973529) (xy 153.318972 -75.973432) (xy 153.251662 -75.973432) (xy 153.24705 -75.973535)
			(xy 153.237976 -75.975193) (xy 153.233628 -75.976734) (xy 153.224992 -75.980036) (xy 153.21788 -75.986132)
			(xy 153.196857 -76.004192) (xy 153.150533 -76.034617) (xy 153.100292 -76.058013) (xy 153.047192 -76.073888)
			(xy 152.992353 -76.081905) (xy 152.964642 -76.082398) (xy 152.937386 -76.081958) (xy 152.883429 -76.074206)
			(xy 152.831125 -76.058853) (xy 152.781538 -76.036212) (xy 152.735679 -76.006744) (xy 152.69448 -75.97105)
			(xy 152.658781 -75.929855) (xy 152.629308 -75.883999) (xy 152.606662 -75.834414) (xy 152.591303 -75.782112)
			(xy 152.583545 -75.728156) (xy 145.580805 -75.728156) (xy 145.584706 -75.729938) (xy 145.63058 -75.759423)
			(xy 145.671791 -75.795136) (xy 145.7075 -75.836351) (xy 145.736981 -75.882228) (xy 145.759633 -75.931833)
			(xy 145.774995 -75.984156) (xy 145.782756 -76.038134) (xy 145.782756 -76.092666) (xy 145.774995 -76.146644)
			(xy 145.759633 -76.198967) (xy 145.736981 -76.248572) (xy 145.7075 -76.294449) (xy 145.671791 -76.335664)
			(xy 145.63058 -76.371377) (xy 145.584706 -76.400862) (xy 145.535103 -76.42352) (xy 145.482781 -76.438887)
			(xy 145.428804 -76.446653) (xy 145.401538 -76.447142) (xy 145.371558 -76.44662) (xy 145.312328 -76.437303)
			(xy 145.255287 -76.418829) (xy 145.22831 -76.40574) (xy 145.216283 -76.400168) (xy 145.19037 -76.394653)
			(xy 145.163911 -76.396006) (xy 145.138697 -76.404136) (xy 145.116431 -76.418493) (xy 145.098621 -76.438107)
			(xy 145.092166 -76.449682) (xy 145.079773 -76.472678) (xy 145.049671 -76.515372) (xy 145.014034 -76.553567)
			(xy 144.973525 -76.586551) (xy 144.9289 -76.613708) (xy 144.880992 -76.634533) (xy 144.830693 -76.648637)
			(xy 144.778941 -76.655756) (xy 144.752822 -76.656184) (xy 144.725552 -76.655678) (xy 144.671565 -76.647919)
			(xy 144.619233 -76.632555) (xy 144.56962 -76.6099) (xy 144.523736 -76.580415) (xy 144.482516 -76.5447)
			(xy 144.446798 -76.503481) (xy 144.41731 -76.457599) (xy 144.394652 -76.407988) (xy 144.379286 -76.355656)
			(xy 144.371524 -76.30167) (xy 143.080569 -76.30167) (xy 143.080994 -76.324968) (xy 143.080485 -76.352872)
			(xy 143.072359 -76.408086) (xy 143.056281 -76.461528) (xy 143.032593 -76.512059) (xy 143.001799 -76.558603)
			(xy 142.964557 -76.600167) (xy 142.921661 -76.635866) (xy 142.874023 -76.664939) (xy 142.82266 -76.686766)
			(xy 142.768667 -76.700882) (xy 142.713193 -76.706985) (xy 142.657422 -76.704947) (xy 142.602543 -76.69481)
			(xy 142.549723 -76.676791) (xy 142.500091 -76.651273) (xy 142.454703 -76.618801) (xy 142.414526 -76.580066)
			(xy 142.380418 -76.535894) (xy 142.353104 -76.487226) (xy 142.333168 -76.4351) (xy 142.321033 -76.380627)
			(xy 142.31696 -76.324968) (xy 135.931148 -76.324968) (xy 135.931148 -80.302862) (xy 143.832324 -80.302862)
			(xy 143.836395 -80.24724) (xy 143.848521 -80.192803) (xy 143.868444 -80.140712) (xy 143.89574 -80.092077)
			(xy 143.929826 -80.047934) (xy 143.969975 -80.009225) (xy 144.015333 -79.976774) (xy 144.064933 -79.951273)
			(xy 144.117717 -79.933266) (xy 144.17256 -79.923136) (xy 144.228294 -79.921099) (xy 144.272162 -79.925926)
			(xy 144.667984 -79.925926) (xy 144.672055 -79.870304) (xy 144.684181 -79.815867) (xy 144.704104 -79.763776)
			(xy 144.7314 -79.715141) (xy 144.765486 -79.670998) (xy 144.805635 -79.632289) (xy 144.850993 -79.599838)
			(xy 144.900593 -79.574337) (xy 144.953377 -79.55633) (xy 145.00822 -79.5462) (xy 145.063954 -79.544163)
			(xy 145.119391 -79.550263) (xy 145.173348 -79.564369) (xy 145.224677 -79.586181) (xy 145.272283 -79.615235)
			(xy 145.315151 -79.65091) (xy 145.352368 -79.692447) (xy 145.383141 -79.73896) (xy 145.406813 -79.789457)
			(xy 145.416018 -79.820053) (xy 152.583585 -79.820053) (xy 152.583585 -79.765547) (xy 152.591343 -79.711597)
			(xy 152.6067 -79.6593) (xy 152.629344 -79.609721) (xy 152.658813 -79.563869) (xy 152.694509 -79.522679)
			(xy 152.735703 -79.486988) (xy 152.781558 -79.457523) (xy 152.831139 -79.434885) (xy 152.883438 -79.419534)
			(xy 152.937389 -79.411782) (xy 152.964642 -79.411322) (xy 152.992352 -79.411809) (xy 153.047187 -79.419838)
			(xy 153.100282 -79.435722) (xy 153.150518 -79.459124) (xy 153.196837 -79.489553) (xy 153.21788 -79.507588)
			(xy 153.224992 -79.513684) (xy 153.233628 -79.516986) (xy 153.237978 -79.51852) (xy 153.24705 -79.520185)
			(xy 153.251662 -79.520288) (xy 153.318972 -79.520288) (xy 153.323585 -79.520193) (xy 153.332658 -79.51853)
			(xy 153.337006 -79.516986) (xy 153.345642 -79.513684) (xy 153.352754 -79.507588) (xy 153.373797 -79.489554)
			(xy 153.420117 -79.459128) (xy 153.470353 -79.43573) (xy 153.523448 -79.419852) (xy 153.578283 -79.411828)
			(xy 153.633701 -79.411828) (xy 153.688536 -79.419852) (xy 153.741631 -79.43573) (xy 153.791867 -79.459128)
			(xy 153.838187 -79.489554) (xy 153.85923 -79.507588) (xy 153.866342 -79.513684) (xy 153.874978 -79.516986)
			(xy 153.879324 -79.518533) (xy 153.888399 -79.520189) (xy 153.893012 -79.520288) (xy 153.960322 -79.520288)
			(xy 153.964934 -79.52018) (xy 153.974008 -79.518525) (xy 153.978356 -79.516986) (xy 153.986992 -79.513684)
			(xy 153.994104 -79.507588) (xy 154.015147 -79.489554) (xy 154.061467 -79.459128) (xy 154.111703 -79.43573)
			(xy 154.164798 -79.419852) (xy 154.219633 -79.411828) (xy 154.275051 -79.411828) (xy 154.329886 -79.419852)
			(xy 154.382981 -79.43573) (xy 154.433217 -79.459128) (xy 154.479537 -79.489554) (xy 154.50058 -79.507588)
			(xy 154.507692 -79.513684) (xy 154.516328 -79.516986) (xy 154.520678 -79.51852) (xy 154.52975 -79.520185)
			(xy 154.534362 -79.520288) (xy 154.601672 -79.520288) (xy 154.606285 -79.520193) (xy 154.615358 -79.51853)
			(xy 154.619706 -79.516986) (xy 154.628342 -79.513684) (xy 154.635454 -79.507588) (xy 154.656505 -79.489562)
			(xy 154.702821 -79.459131) (xy 154.753055 -79.435728) (xy 154.806149 -79.419846) (xy 154.860983 -79.41182)
			(xy 154.888692 -79.411322) (xy 154.915947 -79.411724) (xy 154.969903 -79.419481) (xy 155.022206 -79.434838)
			(xy 155.071792 -79.457481) (xy 155.117649 -79.486952) (xy 155.158846 -79.522648) (xy 155.194544 -79.563844)
			(xy 155.224015 -79.609701) (xy 155.24666 -79.659286) (xy 155.262017 -79.711589) (xy 155.269775 -79.765545)
			(xy 155.269775 -79.820055) (xy 155.262017 -79.874011) (xy 155.24666 -79.926314) (xy 155.224015 -79.975899)
			(xy 155.194544 -80.021756) (xy 155.158846 -80.062952) (xy 155.117649 -80.098648) (xy 155.071792 -80.128119)
			(xy 155.022206 -80.150762) (xy 154.969903 -80.166119) (xy 154.915947 -80.173876) (xy 154.888692 -80.174338)
			(xy 154.860984 -80.173816) (xy 154.806151 -80.165793) (xy 154.753057 -80.149917) (xy 154.70282 -80.126523)
			(xy 154.656499 -80.096103) (xy 154.635454 -80.078072) (xy 154.628342 -80.071976) (xy 154.619706 -80.068674)
			(xy 154.615362 -80.067121) (xy 154.606285 -80.065468) (xy 154.601672 -80.065372) (xy 154.534362 -80.065372)
			(xy 154.52975 -80.065472) (xy 154.520676 -80.067132) (xy 154.516328 -80.068674) (xy 154.507692 -80.071976)
			(xy 154.50058 -80.078072) (xy 154.479537 -80.096106) (xy 154.433217 -80.126532) (xy 154.382981 -80.14993)
			(xy 154.329886 -80.165808) (xy 154.275051 -80.173832) (xy 154.219633 -80.173832) (xy 154.164798 -80.165808)
			(xy 154.111703 -80.14993) (xy 154.061467 -80.126532) (xy 154.015147 -80.096106) (xy 153.994104 -80.078072)
			(xy 153.986992 -80.071976) (xy 153.978356 -80.068674) (xy 153.974008 -80.067134) (xy 153.964934 -80.065473)
			(xy 153.960322 -80.065372) (xy 153.893012 -80.065372) (xy 153.888399 -80.065459) (xy 153.879325 -80.067127)
			(xy 153.874978 -80.068674) (xy 153.866342 -80.071976) (xy 153.85923 -80.078072) (xy 153.838187 -80.096106)
			(xy 153.791867 -80.126532) (xy 153.741631 -80.14993) (xy 153.688536 -80.165808) (xy 153.633701 -80.173832)
			(xy 153.578283 -80.173832) (xy 153.523448 -80.165808) (xy 153.470353 -80.14993) (xy 153.420117 -80.126532)
			(xy 153.373797 -80.096106) (xy 153.352754 -80.078072) (xy 153.345642 -80.071976) (xy 153.337006 -80.068674)
			(xy 153.332662 -80.067121) (xy 153.323585 -80.065468) (xy 153.318972 -80.065372) (xy 153.251662 -80.065372)
			(xy 153.24705 -80.065472) (xy 153.237976 -80.067132) (xy 153.233628 -80.068674) (xy 153.224992 -80.071976)
			(xy 153.21788 -80.078072) (xy 153.196849 -80.096122) (xy 153.150528 -80.126551) (xy 153.100289 -80.14995)
			(xy 153.047191 -80.165826) (xy 152.992353 -80.173844) (xy 152.964642 -80.174338) (xy 152.937389 -80.173818)
			(xy 152.883438 -80.166066) (xy 152.831139 -80.150715) (xy 152.781558 -80.128077) (xy 152.735703 -80.098612)
			(xy 152.694509 -80.062921) (xy 152.658813 -80.021731) (xy 152.629344 -79.975879) (xy 152.6067 -79.9263)
			(xy 152.591343 -79.874003) (xy 152.583585 -79.820053) (xy 145.416018 -79.820053) (xy 145.422881 -79.842864)
			(xy 145.431001 -79.89804) (xy 145.43151 -79.925926) (xy 145.431001 -79.953812) (xy 145.422881 -80.008988)
			(xy 145.406813 -80.062395) (xy 145.383141 -80.112892) (xy 145.352368 -80.159405) (xy 145.315151 -80.200942)
			(xy 145.272283 -80.236617) (xy 145.224677 -80.265671) (xy 145.173348 -80.287483) (xy 145.119391 -80.301589)
			(xy 145.063954 -80.307689) (xy 145.00822 -80.305652) (xy 144.953377 -80.295522) (xy 144.900593 -80.277515)
			(xy 144.850993 -80.252014) (xy 144.805635 -80.219563) (xy 144.765486 -80.180854) (xy 144.7314 -80.136711)
			(xy 144.704104 -80.088076) (xy 144.684181 -80.035985) (xy 144.672055 -79.981548) (xy 144.667984 -79.925926)
			(xy 144.272162 -79.925926) (xy 144.283731 -79.927199) (xy 144.337688 -79.941305) (xy 144.389017 -79.963117)
			(xy 144.436623 -79.992171) (xy 144.479491 -80.027846) (xy 144.516708 -80.069383) (xy 144.547481 -80.115896)
			(xy 144.571153 -80.166393) (xy 144.587221 -80.2198) (xy 144.595341 -80.274976) (xy 144.59585 -80.302862)
			(xy 144.595341 -80.330748) (xy 144.587221 -80.385924) (xy 144.571153 -80.439331) (xy 144.547481 -80.489828)
			(xy 144.516708 -80.536341) (xy 144.479491 -80.577878) (xy 144.436623 -80.613553) (xy 144.389017 -80.642607)
			(xy 144.337688 -80.664419) (xy 144.283731 -80.678525) (xy 144.228294 -80.684625) (xy 144.17256 -80.682588)
			(xy 144.117717 -80.672458) (xy 144.064933 -80.654451) (xy 144.015333 -80.62895) (xy 143.969975 -80.596499)
			(xy 143.929826 -80.55779) (xy 143.89574 -80.513647) (xy 143.868444 -80.465012) (xy 143.848521 -80.412921)
			(xy 143.836395 -80.358484) (xy 143.832324 -80.302862) (xy 135.931148 -80.302862) (xy 135.931148 -81.866055)
			(xy 152.583555 -81.866055) (xy 152.583555 -81.811545) (xy 152.591314 -81.757591) (xy 152.606672 -81.705289)
			(xy 152.629317 -81.655707) (xy 152.658789 -81.609851) (xy 152.694487 -81.568658) (xy 152.735685 -81.532964)
			(xy 152.781543 -81.503497) (xy 152.831129 -81.480857) (xy 152.883432 -81.465505) (xy 152.937387 -81.457752)
			(xy 152.964642 -81.457292) (xy 152.992351 -81.457787) (xy 153.047186 -81.465815) (xy 153.10028 -81.481697)
			(xy 153.150517 -81.505098) (xy 153.196836 -81.535524) (xy 153.21788 -81.553558) (xy 153.224992 -81.559654)
			(xy 153.233628 -81.562956) (xy 153.237979 -81.564489) (xy 153.24705 -81.566155) (xy 153.251662 -81.566258)
			(xy 153.318972 -81.566258) (xy 153.323585 -81.566165) (xy 153.332658 -81.5645) (xy 153.337006 -81.562956)
			(xy 153.345642 -81.559654) (xy 153.352754 -81.553558) (xy 153.373797 -81.535524) (xy 153.420117 -81.505098)
			(xy 153.470353 -81.4817) (xy 153.523448 -81.465822) (xy 153.578283 -81.457798) (xy 153.633701 -81.457798)
			(xy 153.688536 -81.465822) (xy 153.741631 -81.4817) (xy 153.791867 -81.505098) (xy 153.838187 -81.535524)
			(xy 153.85923 -81.553558) (xy 153.866342 -81.559654) (xy 153.874978 -81.562956) (xy 153.879325 -81.564502)
			(xy 153.8884 -81.566159) (xy 153.893012 -81.566258) (xy 153.960322 -81.566258) (xy 153.964934 -81.566151)
			(xy 153.974008 -81.564496) (xy 153.978356 -81.562956) (xy 153.986992 -81.559654) (xy 153.994104 -81.553558)
			(xy 154.015147 -81.535524) (xy 154.061467 -81.505098) (xy 154.111703 -81.4817) (xy 154.164798 -81.465822)
			(xy 154.219633 -81.457798) (xy 154.275051 -81.457798) (xy 154.329886 -81.465822) (xy 154.382981 -81.4817)
			(xy 154.433217 -81.505098) (xy 154.479537 -81.535524) (xy 154.50058 -81.553558) (xy 154.507692 -81.559654)
			(xy 154.516328 -81.562956) (xy 154.520679 -81.564489) (xy 154.52975 -81.566155) (xy 154.534362 -81.566258)
			(xy 154.601672 -81.566258) (xy 154.606285 -81.566165) (xy 154.615358 -81.5645) (xy 154.619706 -81.562956)
			(xy 154.628342 -81.559654) (xy 154.635454 -81.553558) (xy 154.656501 -81.535528) (xy 154.702818 -81.505098)
			(xy 154.753054 -81.481697) (xy 154.806148 -81.465815) (xy 154.860983 -81.45779) (xy 154.888692 -81.457292)
			(xy 154.915945 -81.457755) (xy 154.969897 -81.465511) (xy 155.022196 -81.480866) (xy 155.071777 -81.503508)
			(xy 155.117631 -81.532976) (xy 155.158825 -81.56867) (xy 155.194519 -81.609863) (xy 155.223988 -81.655716)
			(xy 155.246631 -81.705297) (xy 155.261987 -81.757595) (xy 155.269745 -81.811547) (xy 155.269745 -81.866053)
			(xy 155.261987 -81.920005) (xy 155.246631 -81.972303) (xy 155.223988 -82.021884) (xy 155.194519 -82.067737)
			(xy 155.158825 -82.10893) (xy 155.117631 -82.144624) (xy 155.071777 -82.174092) (xy 155.022196 -82.196734)
			(xy 154.969897 -82.212089) (xy 154.915945 -82.219845) (xy 154.888692 -82.220308) (xy 154.860983 -82.219793)
			(xy 154.80615 -82.21177) (xy 154.753055 -82.195892) (xy 154.702819 -82.172496) (xy 154.656498 -82.142074)
			(xy 154.635454 -82.124042) (xy 154.628342 -82.117946) (xy 154.619706 -82.114644) (xy 154.615361 -82.113094)
			(xy 154.606285 -82.111439) (xy 154.601672 -82.111342) (xy 154.534362 -82.111342) (xy 154.52975 -82.111444)
			(xy 154.520676 -82.113102) (xy 154.516328 -82.114644) (xy 154.507692 -82.117946) (xy 154.50058 -82.124042)
			(xy 154.479537 -82.142076) (xy 154.433217 -82.172502) (xy 154.382981 -82.1959) (xy 154.329886 -82.211778)
			(xy 154.275051 -82.219802) (xy 154.219633 -82.219802) (xy 154.164798 -82.211778) (xy 154.111703 -82.1959)
			(xy 154.061467 -82.172502) (xy 154.015147 -82.142076) (xy 153.994104 -82.124042) (xy 153.986992 -82.117946)
			(xy 153.978356 -82.114644) (xy 153.974007 -82.113107) (xy 153.964934 -82.111444) (xy 153.960322 -82.111342)
			(xy 153.893012 -82.111342) (xy 153.888399 -82.111431) (xy 153.879325 -82.113098) (xy 153.874978 -82.114644)
			(xy 153.866342 -82.117946) (xy 153.85923 -82.124042) (xy 153.838187 -82.142076) (xy 153.791867 -82.172502)
			(xy 153.741631 -82.1959) (xy 153.688536 -82.211778) (xy 153.633701 -82.219802) (xy 153.578283 -82.219802)
			(xy 153.523448 -82.211778) (xy 153.470353 -82.1959) (xy 153.420117 -82.172502) (xy 153.373797 -82.142076)
			(xy 153.352754 -82.124042) (xy 153.345642 -82.117946) (xy 153.337006 -82.114644) (xy 153.332661 -82.113094)
			(xy 153.323585 -82.111439) (xy 153.318972 -82.111342) (xy 153.251662 -82.111342) (xy 153.24705 -82.111444)
			(xy 153.237976 -82.113102) (xy 153.233628 -82.114644) (xy 153.224992 -82.117946) (xy 153.21788 -82.124042)
			(xy 153.196859 -82.142103) (xy 153.150534 -82.172528) (xy 153.100292 -82.195924) (xy 153.047192 -82.211798)
			(xy 152.992353 -82.219815) (xy 152.964642 -82.220308) (xy 152.937387 -82.219848) (xy 152.883432 -82.212095)
			(xy 152.831129 -82.196743) (xy 152.781543 -82.174103) (xy 152.735685 -82.144636) (xy 152.694487 -82.108942)
			(xy 152.658789 -82.067749) (xy 152.629317 -82.021893) (xy 152.606672 -81.972311) (xy 152.591314 -81.920009)
			(xy 152.583555 -81.866055) (xy 135.931148 -81.866055) (xy 135.931148 -82.423508) (xy 143.419574 -82.423508)
			(xy 143.423645 -82.367886) (xy 143.435771 -82.313449) (xy 143.455694 -82.261358) (xy 143.48299 -82.212723)
			(xy 143.517076 -82.16858) (xy 143.557225 -82.129871) (xy 143.602583 -82.09742) (xy 143.652183 -82.071919)
			(xy 143.704967 -82.053912) (xy 143.75981 -82.043782) (xy 143.815544 -82.041745) (xy 143.870981 -82.047845)
			(xy 143.924938 -82.061951) (xy 143.976267 -82.083763) (xy 144.023873 -82.112817) (xy 144.066741 -82.148492)
			(xy 144.103958 -82.190029) (xy 144.134731 -82.236542) (xy 144.158403 -82.287039) (xy 144.174471 -82.340446)
			(xy 144.182591 -82.395622) (xy 144.1831 -82.423508) (xy 144.182591 -82.451394) (xy 144.174471 -82.50657)
			(xy 144.158403 -82.559977) (xy 144.134731 -82.610474) (xy 144.103958 -82.656987) (xy 144.066741 -82.698524)
			(xy 144.023873 -82.734199) (xy 143.976267 -82.763253) (xy 143.924938 -82.785065) (xy 143.870981 -82.799171)
			(xy 143.815544 -82.805271) (xy 143.75981 -82.803234) (xy 143.704967 -82.793104) (xy 143.652183 -82.775097)
			(xy 143.602583 -82.749596) (xy 143.557225 -82.717145) (xy 143.517076 -82.678436) (xy 143.48299 -82.634293)
			(xy 143.455694 -82.585658) (xy 143.435771 -82.533567) (xy 143.423645 -82.47913) (xy 143.419574 -82.423508)
			(xy 135.931148 -82.423508) (xy 135.931148 -83.527138) (xy 135.931579 -83.537204) (xy 135.939309 -83.555794)
			(xy 135.946134 -83.563206) (xy 135.966962 -83.584034) (xy 135.974361 -83.590878) (xy 135.99296 -83.5986)
			(xy 136.00303 -83.59902)
		)
		(stroke
			(width 0)
			(type solid)
		)
		(fill yes)
		(layer "In4.Cu")
		(net "GND")
	)
	(gr_poly
		(pts
			(xy 96.515936 -76.746608) (xy 96.525812 -76.746145) (xy 96.544106 -76.738698) (xy 96.551496 -76.73213)
			(xy 96.55175 -76.731876) (xy 99.558348 -73.725278) (xy 99.558856 -73.72477) (xy 99.565441 -73.71739)
			(xy 99.5729 -73.699091) (xy 99.573334 -73.68921) (xy 99.573334 -73.296272) (xy 99.56673 -73.289668)
			(xy 99.56673 -73.16851) (xy 99.566476 -73.160128) (xy 99.566476 -72.865234) (xy 99.566476 -72.62368)
			(xy 99.565964 -72.609486) (xy 99.558067 -72.582215) (xy 99.542973 -72.558168) (xy 99.521845 -72.539203)
			(xy 99.496315 -72.526781) (xy 99.468353 -72.521862) (xy 99.440117 -72.524826) (xy 99.426776 -72.5297)
			(xy 99.404049 -72.538449) (xy 99.356932 -72.550763) (xy 99.308632 -72.556982) (xy 99.284282 -72.557386)
			(xy 99.283774 -72.557386) (xy 99.256504 -72.556898) (xy 99.20252 -72.549133) (xy 99.15019 -72.533764)
			(xy 99.10058 -72.511105) (xy 99.0547 -72.481616) (xy 99.013483 -72.445899) (xy 98.977768 -72.404679)
			(xy 98.948283 -72.358797) (xy 98.925627 -72.309185) (xy 98.910262 -72.256855) (xy 98.9025 -72.20287)
			(xy 98.9025 -72.14833) (xy 98.910262 -72.094345) (xy 98.925627 -72.042015) (xy 98.948283 -71.992403)
			(xy 98.977768 -71.946521) (xy 99.013483 -71.905301) (xy 99.0547 -71.869584) (xy 99.10058 -71.840095)
			(xy 99.15019 -71.817436) (xy 99.20252 -71.802067) (xy 99.256504 -71.794302) (xy 99.283774 -71.793862)
			(xy 99.284282 -71.793862) (xy 99.308631 -71.794263) (xy 99.356931 -71.800489) (xy 99.404047 -71.812804)
			(xy 99.426776 -71.821548) (xy 99.440117 -71.826443) (xy 99.468364 -71.829438) (xy 99.496343 -71.824534)
			(xy 99.521888 -71.812111) (xy 99.543022 -71.793131) (xy 99.558109 -71.769063) (xy 99.56598 -71.74177)
			(xy 99.566476 -71.727568) (xy 99.566476 -58.4073) (xy 99.566052 -58.39723) (xy 99.558335 -58.378628)
			(xy 99.55149 -58.371232) (xy 99.447604 -58.267346) (xy 99.42703 -58.259472) (xy 99.416108 -58.260234)
			(xy 99.39274 -58.260996) (xy 99.365466 -58.260535) (xy 99.311473 -58.252778) (xy 99.259134 -58.237415)
			(xy 99.209513 -58.214761) (xy 99.163622 -58.185275) (xy 99.122395 -58.149558) (xy 99.08667 -58.108337)
			(xy 99.057175 -58.062452) (xy 99.03451 -58.012836) (xy 99.019138 -57.960499) (xy 99.01137 -57.906508)
			(xy 99.010978 -57.879234) (xy 99.01174 -57.855866) (xy 99.012502 -57.844944) (xy 99.004628 -57.82437)
			(xy 97.87255 -56.692292) (xy 97.843086 -56.686196) (xy 97.828862 -56.691784) (xy 97.806428 -56.700277)
			(xy 97.759972 -56.712241) (xy 97.712385 -56.718296) (xy 97.6884 -56.718708) (xy 97.661149 -56.718222)
			(xy 97.607201 -56.710466) (xy 97.554906 -56.695111) (xy 97.505329 -56.672469) (xy 97.459479 -56.643003)
			(xy 97.418288 -56.607312) (xy 97.382597 -56.566121) (xy 97.353131 -56.520271) (xy 97.330489 -56.470694)
			(xy 97.315134 -56.418399) (xy 97.307378 -56.364451) (xy 97.306892 -56.3372) (xy 97.307268 -56.313213)
			(xy 97.313317 -56.26562) (xy 97.325295 -56.219164) (xy 97.333816 -56.196738) (xy 97.339404 -56.182514)
			(xy 97.333308 -56.15305) (xy 95.01505 -53.834792) (xy 95.007648 -53.827954) (xy 94.98905 -53.820239)
			(xy 94.978982 -53.819806) (xy 80.669384 -53.819806) (xy 80.650588 -53.827426) (xy 80.643476 -53.834792)
			(xy 78.819756 -55.658512) (xy 78.812905 -55.665908) (xy 78.805166 -55.684507) (xy 78.80477 -55.69458)
			(xy 78.80477 -55.98668) (xy 88.03716 -55.98668) (xy 88.041231 -55.931058) (xy 88.053357 -55.876621)
			(xy 88.07328 -55.82453) (xy 88.100576 -55.775895) (xy 88.134662 -55.731752) (xy 88.174811 -55.693043)
			(xy 88.220169 -55.660592) (xy 88.269769 -55.635091) (xy 88.322553 -55.617084) (xy 88.377396 -55.606954)
			(xy 88.43313 -55.604917) (xy 88.488567 -55.611017) (xy 88.542524 -55.625123) (xy 88.593853 -55.646935)
			(xy 88.641459 -55.675989) (xy 88.684327 -55.711664) (xy 88.721544 -55.753201) (xy 88.752317 -55.799714)
			(xy 88.775989 -55.850211) (xy 88.792057 -55.903618) (xy 88.800177 -55.958794) (xy 88.800686 -55.98668)
			(xy 88.800177 -56.014566) (xy 88.792057 -56.069742) (xy 88.775989 -56.123149) (xy 88.752317 -56.173646)
			(xy 88.721544 -56.220159) (xy 88.684327 -56.261696) (xy 88.641459 -56.297371) (xy 88.593853 -56.326425)
			(xy 88.542524 -56.348237) (xy 88.488567 -56.362343) (xy 88.43313 -56.368443) (xy 88.377396 -56.366406)
			(xy 88.322553 -56.356276) (xy 88.269769 -56.338269) (xy 88.220169 -56.312768) (xy 88.174811 -56.280317)
			(xy 88.134662 -56.241608) (xy 88.100576 -56.197465) (xy 88.07328 -56.14883) (xy 88.053357 -56.096739)
			(xy 88.041231 -56.042302) (xy 88.03716 -55.98668) (xy 78.80477 -55.98668) (xy 78.80477 -57.205118)
			(xy 80.25638 -57.205118) (xy 80.25692 -57.176822) (xy 80.265284 -57.120851) (xy 80.281816 -57.066726)
			(xy 80.306154 -57.015635) (xy 80.337766 -56.968694) (xy 80.375958 -56.926932) (xy 80.397604 -56.9087)
			(xy 80.406036 -56.901108) (xy 80.415795 -56.88066) (xy 80.4164 -56.86933) (xy 80.4164 -56.790336)
			(xy 80.41572 -56.779022) (xy 80.405989 -56.758588) (xy 80.397604 -56.750966) (xy 80.375941 -56.73275)
			(xy 80.337733 -56.690995) (xy 80.306112 -56.644054) (xy 80.28177 -56.592957) (xy 80.265242 -56.538826)
			(xy 80.25689 -56.482847) (xy 80.25638 -56.454548) (xy 80.256866 -56.427297) (xy 80.264622 -56.373349)
			(xy 80.279977 -56.321054) (xy 80.302619 -56.271477) (xy 80.332085 -56.225627) (xy 80.367776 -56.184436)
			(xy 80.408967 -56.148745) (xy 80.454817 -56.119279) (xy 80.504394 -56.096637) (xy 80.556689 -56.081282)
			(xy 80.610637 -56.073526) (xy 80.665139 -56.073526) (xy 80.719087 -56.081282) (xy 80.771382 -56.096637)
			(xy 80.820959 -56.119279) (xy 80.866809 -56.148745) (xy 80.908 -56.184436) (xy 80.943691 -56.225627)
			(xy 80.973157 -56.271477) (xy 80.995799 -56.321054) (xy 81.011154 -56.373349) (xy 81.01891 -56.427297)
			(xy 81.019396 -56.454548) (xy 81.018841 -56.482844) (xy 81.010482 -56.538815) (xy 81.005421 -56.555386)
			(xy 87.020906 -56.555386) (xy 87.024977 -56.499764) (xy 87.037103 -56.445327) (xy 87.057026 -56.393236)
			(xy 87.084322 -56.344601) (xy 87.118408 -56.300458) (xy 87.158557 -56.261749) (xy 87.203915 -56.229298)
			(xy 87.253515 -56.203797) (xy 87.306299 -56.18579) (xy 87.361142 -56.17566) (xy 87.416876 -56.173623)
			(xy 87.472313 -56.179723) (xy 87.52627 -56.193829) (xy 87.577599 -56.215641) (xy 87.625205 -56.244695)
			(xy 87.668073 -56.28037) (xy 87.70529 -56.321907) (xy 87.736063 -56.36842) (xy 87.759735 -56.418917)
			(xy 87.775803 -56.472324) (xy 87.783923 -56.5275) (xy 87.784432 -56.555386) (xy 87.783923 -56.583272)
			(xy 87.775803 -56.638448) (xy 87.759735 -56.691855) (xy 87.736063 -56.742352) (xy 87.70529 -56.788865)
			(xy 87.668073 -56.830402) (xy 87.625205 -56.866077) (xy 87.595261 -56.884352) (xy 90.020093 -56.884352)
			(xy 90.020093 -56.829848) (xy 90.027851 -56.775899) (xy 90.043207 -56.723603) (xy 90.06585 -56.674025)
			(xy 90.095319 -56.628175) (xy 90.131014 -56.586985) (xy 90.172207 -56.551295) (xy 90.21806 -56.521831)
			(xy 90.267641 -56.499193) (xy 90.319938 -56.483842) (xy 90.373888 -56.476091) (xy 90.40114 -56.47563)
			(xy 90.428272 -56.476087) (xy 90.481991 -56.48376) (xy 90.534082 -56.49896) (xy 90.583498 -56.521381)
			(xy 90.606626 -56.535574) (xy 90.61577 -56.541416) (xy 90.636344 -56.544718) (xy 90.729816 -56.52008)
			(xy 90.746072 -56.506872) (xy 90.751152 -56.49722) (xy 90.763029 -56.47547) (xy 90.791567 -56.434955)
			(xy 90.808048 -56.416448) (xy 90.814398 -56.40959) (xy 90.821256 -56.392572) (xy 90.823288 -56.30672)
			(xy 90.816938 -56.289194) (xy 90.811096 -56.282082) (xy 90.794181 -56.261331) (xy 90.765678 -56.216014)
			(xy 90.743784 -56.16716) (xy 90.728928 -56.115727) (xy 90.721402 -56.062723) (xy 90.720926 -56.035956)
			(xy 90.721337 -56.008702) (xy 90.7291 -55.95475) (xy 90.744463 -55.902452) (xy 90.767112 -55.852872)
			(xy 90.796586 -55.80702) (xy 90.832285 -55.76583) (xy 90.873483 -55.730139) (xy 90.919341 -55.700674)
			(xy 90.968925 -55.678036) (xy 91.021226 -55.662684) (xy 91.07518 -55.654931) (xy 91.102434 -55.654448)
			(xy 91.129806 -55.654882) (xy 91.183986 -55.662706) (xy 91.23649 -55.678202) (xy 91.286237 -55.701051)
			(xy 91.332202 -55.730783) (xy 91.353132 -55.748428) (xy 91.360244 -55.754524) (xy 91.377262 -55.760874)
			(xy 91.462606 -55.760874) (xy 91.479624 -55.754524) (xy 91.486736 -55.748428) (xy 91.507685 -55.73081)
			(xy 91.553653 -55.701094) (xy 91.603396 -55.678253) (xy 91.655893 -55.662758) (xy 91.710066 -55.654924)
			(xy 91.737434 -55.654448) (xy 91.764684 -55.654946) (xy 91.818629 -55.662706) (xy 91.870921 -55.678063)
			(xy 91.920495 -55.700705) (xy 91.966343 -55.730171) (xy 92.007532 -55.765861) (xy 92.043223 -55.807049)
			(xy 92.07269 -55.852896) (xy 92.095333 -55.90247) (xy 92.110692 -55.954761) (xy 92.118453 -56.008706)
			(xy 92.118942 -56.035956) (xy 92.118464 -56.063326) (xy 92.110651 -56.117505) (xy 92.095166 -56.170009)
			(xy 92.072326 -56.219756) (xy 92.042603 -56.265723) (xy 92.024962 -56.286654) (xy 92.018866 -56.293766)
			(xy 92.012516 -56.310784) (xy 92.012516 -56.355234) (xy 92.515688 -56.355234) (xy 92.519759 -56.299612)
			(xy 92.531885 -56.245175) (xy 92.551808 -56.193084) (xy 92.579104 -56.144449) (xy 92.61319 -56.100306)
			(xy 92.653339 -56.061597) (xy 92.698697 -56.029146) (xy 92.748297 -56.003645) (xy 92.801081 -55.985638)
			(xy 92.855924 -55.975508) (xy 92.911658 -55.973471) (xy 92.967095 -55.979571) (xy 93.021052 -55.993677)
			(xy 93.072381 -56.015489) (xy 93.119987 -56.044543) (xy 93.162855 -56.080218) (xy 93.200072 -56.121755)
			(xy 93.230845 -56.168268) (xy 93.254517 -56.218765) (xy 93.270585 -56.272172) (xy 93.278705 -56.327348)
			(xy 93.279214 -56.355234) (xy 93.278705 -56.38312) (xy 93.270585 -56.438296) (xy 93.268217 -56.446166)
			(xy 95.405954 -56.446166) (xy 95.410025 -56.390544) (xy 95.422151 -56.336107) (xy 95.442074 -56.284016)
			(xy 95.46937 -56.235381) (xy 95.503456 -56.191238) (xy 95.543605 -56.152529) (xy 95.588963 -56.120078)
			(xy 95.638563 -56.094577) (xy 95.691347 -56.07657) (xy 95.74619 -56.06644) (xy 95.801924 -56.064403)
			(xy 95.857361 -56.070503) (xy 95.911318 -56.084609) (xy 95.962647 -56.106421) (xy 96.010253 -56.135475)
			(xy 96.053121 -56.17115) (xy 96.090338 -56.212687) (xy 96.121111 -56.2592) (xy 96.144783 -56.309697)
			(xy 96.160851 -56.363104) (xy 96.168971 -56.41828) (xy 96.16948 -56.446166) (xy 96.168971 -56.474052)
			(xy 96.160851 -56.529228) (xy 96.144783 -56.582635) (xy 96.121111 -56.633132) (xy 96.090338 -56.679645)
			(xy 96.053121 -56.721182) (xy 96.010253 -56.756857) (xy 95.962647 -56.785911) (xy 95.911318 -56.807723)
			(xy 95.857361 -56.821829) (xy 95.801924 -56.827929) (xy 95.74619 -56.825892) (xy 95.691347 -56.815762)
			(xy 95.638563 -56.797755) (xy 95.588963 -56.772254) (xy 95.543605 -56.739803) (xy 95.503456 -56.701094)
			(xy 95.46937 -56.656951) (xy 95.442074 -56.608316) (xy 95.422151 -56.556225) (xy 95.410025 -56.501788)
			(xy 95.405954 -56.446166) (xy 93.268217 -56.446166) (xy 93.254517 -56.491703) (xy 93.230845 -56.5422)
			(xy 93.200072 -56.588713) (xy 93.162855 -56.63025) (xy 93.119987 -56.665925) (xy 93.072381 -56.694979)
			(xy 93.021052 -56.716791) (xy 92.967095 -56.730897) (xy 92.911658 -56.736997) (xy 92.855924 -56.73496)
			(xy 92.801081 -56.72483) (xy 92.748297 -56.706823) (xy 92.698697 -56.681322) (xy 92.653339 -56.648871)
			(xy 92.61319 -56.610162) (xy 92.579104 -56.566019) (xy 92.551808 -56.517384) (xy 92.531885 -56.465293)
			(xy 92.519759 -56.410856) (xy 92.515688 -56.355234) (xy 92.012516 -56.355234) (xy 92.012516 -56.396128)
			(xy 92.018866 -56.413146) (xy 92.024962 -56.420258) (xy 92.042589 -56.4412) (xy 92.072304 -56.487169)
			(xy 92.095143 -56.536914) (xy 92.110637 -56.589413) (xy 92.118467 -56.643587) (xy 92.118942 -56.670956)
			(xy 92.118404 -56.698206) (xy 92.110654 -56.752153) (xy 92.095305 -56.804447) (xy 92.07267 -56.854025)
			(xy 92.04321 -56.899876) (xy 92.007524 -56.941069) (xy 91.966339 -56.976763) (xy 91.920493 -57.006233)
			(xy 91.87092 -57.028878) (xy 91.818629 -57.044237) (xy 91.764684 -57.051998) (xy 91.737434 -57.052464)
			(xy 91.709558 -57.051985) (xy 91.6544 -57.043873) (xy 91.601011 -57.027817) (xy 91.550529 -57.004159)
			(xy 91.504029 -56.973402) (xy 91.482926 -56.955182) (xy 91.475814 -56.948832) (xy 91.458542 -56.942228)
			(xy 91.370912 -56.942736) (xy 91.353894 -56.949594) (xy 91.346782 -56.956198) (xy 91.325525 -56.974907)
			(xy 91.278569 -57.006553) (xy 91.22745 -57.030907) (xy 91.173291 -57.047436) (xy 91.117284 -57.055775)
			(xy 91.088972 -57.056274) (xy 91.06184 -57.055811) (xy 91.008122 -57.04814) (xy 90.95603 -57.032942)
			(xy 90.906614 -57.010523) (xy 90.883486 -56.99633) (xy 90.874342 -56.990488) (xy 90.853768 -56.987186)
			(xy 90.760296 -57.011824) (xy 90.74404 -57.025032) (xy 90.73896 -57.034684) (xy 90.726471 -57.057411)
			(xy 90.696332 -57.099611) (xy 90.660759 -57.137343) (xy 90.620405 -57.169911) (xy 90.576014 -57.196717)
			(xy 90.528402 -57.217268) (xy 90.478447 -57.231183) (xy 90.427068 -57.238209) (xy 90.40114 -57.238646)
			(xy 90.373888 -57.238109) (xy 90.319938 -57.230358) (xy 90.267641 -57.215007) (xy 90.21806 -57.192369)
			(xy 90.172207 -57.162905) (xy 90.131014 -57.127215) (xy 90.095319 -57.086025) (xy 90.06585 -57.040175)
			(xy 90.043207 -56.990597) (xy 90.027851 -56.938301) (xy 90.020093 -56.884352) (xy 87.595261 -56.884352)
			(xy 87.577599 -56.895131) (xy 87.52627 -56.916943) (xy 87.472313 -56.931049) (xy 87.416876 -56.937149)
			(xy 87.361142 -56.935112) (xy 87.306299 -56.924982) (xy 87.253515 -56.906975) (xy 87.203915 -56.881474)
			(xy 87.158557 -56.849023) (xy 87.118408 -56.810314) (xy 87.084322 -56.766171) (xy 87.057026 -56.717536)
			(xy 87.037103 -56.665445) (xy 87.024977 -56.611008) (xy 87.020906 -56.555386) (xy 81.005421 -56.555386)
			(xy 80.993953 -56.592939) (xy 80.969618 -56.644031) (xy 80.938008 -56.690972) (xy 80.899817 -56.732734)
			(xy 80.878172 -56.750966) (xy 80.869752 -56.758568) (xy 80.859988 -56.779009) (xy 80.859376 -56.790336)
			(xy 80.859376 -56.86933) (xy 80.859994 -56.880653) (xy 80.869766 -56.901087) (xy 80.878172 -56.9087)
			(xy 80.899814 -56.92694) (xy 80.938024 -56.96869) (xy 80.969649 -57.015626) (xy 80.993994 -57.066717)
			(xy 81.010527 -57.120845) (xy 81.018883 -57.17682) (xy 81.019396 -57.205118) (xy 81.01891 -57.232369)
			(xy 81.011154 -57.286317) (xy 80.995799 -57.338612) (xy 80.973157 -57.388189) (xy 80.943691 -57.434039)
			(xy 80.908 -57.47523) (xy 80.866809 -57.510921) (xy 80.820959 -57.540387) (xy 80.771382 -57.563029)
			(xy 80.719087 -57.578384) (xy 80.665139 -57.58614) (xy 80.610637 -57.58614) (xy 80.556689 -57.578384)
			(xy 80.504394 -57.563029) (xy 80.454817 -57.540387) (xy 80.408967 -57.510921) (xy 80.367776 -57.47523)
			(xy 80.332085 -57.434039) (xy 80.302619 -57.388189) (xy 80.279977 -57.338612) (xy 80.264622 -57.286317)
			(xy 80.256866 -57.232369) (xy 80.25638 -57.205118) (xy 78.80477 -57.205118) (xy 78.80477 -57.954418)
			(xy 80.890362 -57.954418) (xy 80.894433 -57.898796) (xy 80.906559 -57.844359) (xy 80.926482 -57.792268)
			(xy 80.953778 -57.743633) (xy 80.987864 -57.69949) (xy 81.028013 -57.660781) (xy 81.073371 -57.62833)
			(xy 81.122971 -57.602829) (xy 81.175755 -57.584822) (xy 81.230598 -57.574692) (xy 81.286332 -57.572655)
			(xy 81.341769 -57.578755) (xy 81.395726 -57.592861) (xy 81.447055 -57.614673) (xy 81.494661 -57.643727)
			(xy 81.537529 -57.679402) (xy 81.574746 -57.720939) (xy 81.605519 -57.767452) (xy 81.629191 -57.817949)
			(xy 81.645259 -57.871356) (xy 81.653379 -57.926532) (xy 81.653888 -57.954418) (xy 81.653379 -57.982304)
			(xy 81.645259 -58.03748) (xy 81.629191 -58.090887) (xy 81.605519 -58.141384) (xy 81.574746 -58.187897)
			(xy 81.553401 -58.21172) (xy 88.173812 -58.21172) (xy 88.177883 -58.156098) (xy 88.190009 -58.101661)
			(xy 88.209932 -58.04957) (xy 88.237228 -58.000935) (xy 88.271314 -57.956792) (xy 88.311463 -57.918083)
			(xy 88.356821 -57.885632) (xy 88.406421 -57.860131) (xy 88.459205 -57.842124) (xy 88.514048 -57.831994)
			(xy 88.569782 -57.829957) (xy 88.625219 -57.836057) (xy 88.679176 -57.850163) (xy 88.730505 -57.871975)
			(xy 88.778111 -57.901029) (xy 88.820979 -57.936704) (xy 88.858196 -57.978241) (xy 88.888969 -58.024754)
			(xy 88.912641 -58.075251) (xy 88.928709 -58.128658) (xy 88.932373 -58.153554) (xy 93.68104 -58.153554)
			(xy 93.685111 -58.097932) (xy 93.697237 -58.043495) (xy 93.71716 -57.991404) (xy 93.744456 -57.942769)
			(xy 93.778542 -57.898626) (xy 93.818691 -57.859917) (xy 93.864049 -57.827466) (xy 93.913649 -57.801965)
			(xy 93.966433 -57.783958) (xy 94.021276 -57.773828) (xy 94.07701 -57.771791) (xy 94.132447 -57.777891)
			(xy 94.186404 -57.791997) (xy 94.237733 -57.813809) (xy 94.285339 -57.842863) (xy 94.328207 -57.878538)
			(xy 94.365424 -57.920075) (xy 94.396197 -57.966588) (xy 94.419869 -58.017085) (xy 94.435937 -58.070492)
			(xy 94.444057 -58.125668) (xy 94.444566 -58.153554) (xy 94.444057 -58.18144) (xy 94.435937 -58.236616)
			(xy 94.419869 -58.290023) (xy 94.396197 -58.34052) (xy 94.365424 -58.387033) (xy 94.328207 -58.42857)
			(xy 94.285339 -58.464245) (xy 94.237733 -58.493299) (xy 94.186404 -58.515111) (xy 94.132447 -58.529217)
			(xy 94.07701 -58.535317) (xy 94.021276 -58.53328) (xy 93.966433 -58.52315) (xy 93.913649 -58.505143)
			(xy 93.864049 -58.479642) (xy 93.818691 -58.447191) (xy 93.778542 -58.408482) (xy 93.744456 -58.364339)
			(xy 93.71716 -58.315704) (xy 93.697237 -58.263613) (xy 93.685111 -58.209176) (xy 93.68104 -58.153554)
			(xy 88.932373 -58.153554) (xy 88.936829 -58.183834) (xy 88.937338 -58.21172) (xy 88.936829 -58.239606)
			(xy 88.928709 -58.294782) (xy 88.912641 -58.348189) (xy 88.888969 -58.398686) (xy 88.858196 -58.445199)
			(xy 88.820979 -58.486736) (xy 88.778111 -58.522411) (xy 88.730505 -58.551465) (xy 88.679176 -58.573277)
			(xy 88.640753 -58.583322) (xy 89.025982 -58.583322) (xy 89.030053 -58.5277) (xy 89.042179 -58.473263)
			(xy 89.062102 -58.421172) (xy 89.089398 -58.372537) (xy 89.123484 -58.328394) (xy 89.163633 -58.289685)
			(xy 89.208991 -58.257234) (xy 89.258591 -58.231733) (xy 89.311375 -58.213726) (xy 89.366218 -58.203596)
			(xy 89.421952 -58.201559) (xy 89.477389 -58.207659) (xy 89.531346 -58.221765) (xy 89.582675 -58.243577)
			(xy 89.630281 -58.272631) (xy 89.673149 -58.308306) (xy 89.710366 -58.349843) (xy 89.741139 -58.396356)
			(xy 89.764811 -58.446853) (xy 89.780879 -58.50026) (xy 89.788999 -58.555436) (xy 89.789508 -58.583322)
			(xy 89.788999 -58.611208) (xy 89.780879 -58.666384) (xy 89.764811 -58.719791) (xy 89.741139 -58.770288)
			(xy 89.710366 -58.816801) (xy 89.673149 -58.858338) (xy 89.630281 -58.894013) (xy 89.582675 -58.923067)
			(xy 89.531346 -58.944879) (xy 89.477389 -58.958985) (xy 89.421952 -58.965085) (xy 89.366218 -58.963048)
			(xy 89.311375 -58.952918) (xy 89.258591 -58.934911) (xy 89.208991 -58.90941) (xy 89.163633 -58.876959)
			(xy 89.123484 -58.83825) (xy 89.089398 -58.794107) (xy 89.062102 -58.745472) (xy 89.042179 -58.693381)
			(xy 89.030053 -58.638944) (xy 89.025982 -58.583322) (xy 88.640753 -58.583322) (xy 88.625219 -58.587383)
			(xy 88.569782 -58.593483) (xy 88.514048 -58.591446) (xy 88.459205 -58.581316) (xy 88.406421 -58.563309)
			(xy 88.356821 -58.537808) (xy 88.311463 -58.505357) (xy 88.271314 -58.466648) (xy 88.237228 -58.422505)
			(xy 88.209932 -58.37387) (xy 88.190009 -58.321779) (xy 88.177883 -58.267342) (xy 88.173812 -58.21172)
			(xy 81.553401 -58.21172) (xy 81.537529 -58.229434) (xy 81.494661 -58.265109) (xy 81.447055 -58.294163)
			(xy 81.395726 -58.315975) (xy 81.341769 -58.330081) (xy 81.286332 -58.336181) (xy 81.230598 -58.334144)
			(xy 81.175755 -58.324014) (xy 81.122971 -58.306007) (xy 81.073371 -58.280506) (xy 81.028013 -58.248055)
			(xy 80.987864 -58.209346) (xy 80.953778 -58.165203) (xy 80.926482 -58.116568) (xy 80.906559 -58.064477)
			(xy 80.894433 -58.01004) (xy 80.890362 -57.954418) (xy 78.80477 -57.954418) (xy 78.80477 -58.87974)
			(xy 80.922112 -58.87974) (xy 80.926183 -58.824118) (xy 80.938309 -58.769681) (xy 80.958232 -58.71759)
			(xy 80.985528 -58.668955) (xy 81.019614 -58.624812) (xy 81.059763 -58.586103) (xy 81.105121 -58.553652)
			(xy 81.154721 -58.528151) (xy 81.207505 -58.510144) (xy 81.262348 -58.500014) (xy 81.318082 -58.497977)
			(xy 81.373519 -58.504077) (xy 81.427476 -58.518183) (xy 81.478805 -58.539995) (xy 81.526411 -58.569049)
			(xy 81.569279 -58.604724) (xy 81.606496 -58.646261) (xy 81.637269 -58.692774) (xy 81.660941 -58.743271)
			(xy 81.677009 -58.796678) (xy 81.685129 -58.851854) (xy 81.685638 -58.87974) (xy 81.685129 -58.907626)
			(xy 81.677009 -58.962802) (xy 81.660941 -59.016209) (xy 81.637269 -59.066706) (xy 81.606496 -59.113219)
			(xy 81.569279 -59.154756) (xy 81.526411 -59.190431) (xy 81.478805 -59.219485) (xy 81.427476 -59.241297)
			(xy 81.373519 -59.255403) (xy 81.318082 -59.261503) (xy 81.262348 -59.259466) (xy 81.207505 -59.249336)
			(xy 81.154721 -59.231329) (xy 81.105121 -59.205828) (xy 81.059763 -59.173377) (xy 81.019614 -59.134668)
			(xy 80.985528 -59.090525) (xy 80.958232 -59.04189) (xy 80.938309 -58.989799) (xy 80.926183 -58.935362)
			(xy 80.922112 -58.87974) (xy 78.80477 -58.87974) (xy 78.80477 -59.43092) (xy 86.459312 -59.43092)
			(xy 86.463383 -59.375298) (xy 86.475509 -59.320861) (xy 86.495432 -59.26877) (xy 86.522728 -59.220135)
			(xy 86.556814 -59.175992) (xy 86.596963 -59.137283) (xy 86.642321 -59.104832) (xy 86.691921 -59.079331)
			(xy 86.744705 -59.061324) (xy 86.799548 -59.051194) (xy 86.855282 -59.049157) (xy 86.910719 -59.055257)
			(xy 86.964676 -59.069363) (xy 87.016005 -59.091175) (xy 87.063611 -59.120229) (xy 87.106479 -59.155904)
			(xy 87.143696 -59.197441) (xy 87.174469 -59.243954) (xy 87.198141 -59.294451) (xy 87.214209 -59.347858)
			(xy 87.222329 -59.403034) (xy 87.222838 -59.43092) (xy 87.222329 -59.458806) (xy 87.214209 -59.513982)
			(xy 87.198141 -59.567389) (xy 87.174469 -59.617886) (xy 87.143696 -59.664399) (xy 87.106479 -59.705936)
			(xy 87.063611 -59.741611) (xy 87.016005 -59.770665) (xy 86.964676 -59.792477) (xy 86.910719 -59.806583)
			(xy 86.855282 -59.812683) (xy 86.799548 -59.810646) (xy 86.744705 -59.800516) (xy 86.691921 -59.782509)
			(xy 86.642321 -59.757008) (xy 86.596963 -59.724557) (xy 86.556814 -59.685848) (xy 86.522728 -59.641705)
			(xy 86.495432 -59.59307) (xy 86.475509 -59.540979) (xy 86.463383 -59.486542) (xy 86.459312 -59.43092)
			(xy 78.80477 -59.43092) (xy 78.80477 -59.853322) (xy 89.025982 -59.853322) (xy 89.030053 -59.7977)
			(xy 89.042179 -59.743263) (xy 89.062102 -59.691172) (xy 89.089398 -59.642537) (xy 89.123484 -59.598394)
			(xy 89.163633 -59.559685) (xy 89.208991 -59.527234) (xy 89.258591 -59.501733) (xy 89.311375 -59.483726)
			(xy 89.366218 -59.473596) (xy 89.421952 -59.471559) (xy 89.477389 -59.477659) (xy 89.531346 -59.491765)
			(xy 89.582675 -59.513577) (xy 89.630281 -59.542631) (xy 89.673149 -59.578306) (xy 89.710366 -59.619843)
			(xy 89.741139 -59.666356) (xy 89.764811 -59.716853) (xy 89.780879 -59.77026) (xy 89.786075 -59.80557)
			(xy 93.68739 -59.80557) (xy 93.691461 -59.749948) (xy 93.703587 -59.695511) (xy 93.72351 -59.64342)
			(xy 93.750806 -59.594785) (xy 93.784892 -59.550642) (xy 93.825041 -59.511933) (xy 93.870399 -59.479482)
			(xy 93.919999 -59.453981) (xy 93.972783 -59.435974) (xy 94.027626 -59.425844) (xy 94.08336 -59.423807)
			(xy 94.138797 -59.429907) (xy 94.192754 -59.444013) (xy 94.244083 -59.465825) (xy 94.291689 -59.494879)
			(xy 94.334557 -59.530554) (xy 94.371774 -59.572091) (xy 94.402547 -59.618604) (xy 94.426219 -59.669101)
			(xy 94.442287 -59.722508) (xy 94.450407 -59.777684) (xy 94.450916 -59.80557) (xy 94.450407 -59.833456)
			(xy 94.442287 -59.888632) (xy 94.426219 -59.942039) (xy 94.402547 -59.992536) (xy 94.371774 -60.039049)
			(xy 94.334557 -60.080586) (xy 94.291689 -60.116261) (xy 94.244083 -60.145315) (xy 94.192754 -60.167127)
			(xy 94.138797 -60.181233) (xy 94.08336 -60.187333) (xy 94.027626 -60.185296) (xy 93.972783 -60.175166)
			(xy 93.919999 -60.157159) (xy 93.870399 -60.131658) (xy 93.825041 -60.099207) (xy 93.784892 -60.060498)
			(xy 93.750806 -60.016355) (xy 93.72351 -59.96772) (xy 93.703587 -59.915629) (xy 93.691461 -59.861192)
			(xy 93.68739 -59.80557) (xy 89.786075 -59.80557) (xy 89.788999 -59.825436) (xy 89.789508 -59.853322)
			(xy 89.788999 -59.881208) (xy 89.780879 -59.936384) (xy 89.764811 -59.989791) (xy 89.741139 -60.040288)
			(xy 89.710366 -60.086801) (xy 89.673149 -60.128338) (xy 89.630281 -60.164013) (xy 89.582675 -60.193067)
			(xy 89.531346 -60.214879) (xy 89.477389 -60.228985) (xy 89.421952 -60.235085) (xy 89.366218 -60.233048)
			(xy 89.311375 -60.222918) (xy 89.258591 -60.204911) (xy 89.208991 -60.17941) (xy 89.163633 -60.146959)
			(xy 89.123484 -60.10825) (xy 89.089398 -60.064107) (xy 89.062102 -60.015472) (xy 89.042179 -59.963381)
			(xy 89.030053 -59.908944) (xy 89.025982 -59.853322) (xy 78.80477 -59.853322) (xy 78.80477 -60.679584)
			(xy 92.469968 -60.679584) (xy 92.474039 -60.623962) (xy 92.486165 -60.569525) (xy 92.506088 -60.517434)
			(xy 92.533384 -60.468799) (xy 92.56747 -60.424656) (xy 92.607619 -60.385947) (xy 92.652977 -60.353496)
			(xy 92.702577 -60.327995) (xy 92.755361 -60.309988) (xy 92.810204 -60.299858) (xy 92.865938 -60.297821)
			(xy 92.921375 -60.303921) (xy 92.975332 -60.318027) (xy 93.026661 -60.339839) (xy 93.074267 -60.368893)
			(xy 93.117135 -60.404568) (xy 93.154352 -60.446105) (xy 93.185125 -60.492618) (xy 93.208797 -60.543115)
			(xy 93.224865 -60.596522) (xy 93.232985 -60.651698) (xy 93.233494 -60.679584) (xy 93.232985 -60.70747)
			(xy 93.224865 -60.762646) (xy 93.208797 -60.816053) (xy 93.18716 -60.86221) (xy 96.14103 -60.86221)
			(xy 96.145101 -60.806588) (xy 96.157227 -60.752151) (xy 96.17715 -60.70006) (xy 96.204446 -60.651425)
			(xy 96.238532 -60.607282) (xy 96.278681 -60.568573) (xy 96.324039 -60.536122) (xy 96.373639 -60.510621)
			(xy 96.426423 -60.492614) (xy 96.481266 -60.482484) (xy 96.537 -60.480447) (xy 96.592437 -60.486547)
			(xy 96.646394 -60.500653) (xy 96.697723 -60.522465) (xy 96.745329 -60.551519) (xy 96.788197 -60.587194)
			(xy 96.825414 -60.628731) (xy 96.856187 -60.675244) (xy 96.879859 -60.725741) (xy 96.895927 -60.779148)
			(xy 96.904047 -60.834324) (xy 96.904556 -60.86221) (xy 96.904047 -60.890096) (xy 96.895927 -60.945272)
			(xy 96.879859 -60.998679) (xy 96.856187 -61.049176) (xy 96.825414 -61.095689) (xy 96.788197 -61.137226)
			(xy 96.745329 -61.172901) (xy 96.697723 -61.201955) (xy 96.646394 -61.223767) (xy 96.592437 -61.237873)
			(xy 96.537 -61.243973) (xy 96.481266 -61.241936) (xy 96.426423 -61.231806) (xy 96.373639 -61.213799)
			(xy 96.324039 -61.188298) (xy 96.278681 -61.155847) (xy 96.238532 -61.117138) (xy 96.204446 -61.072995)
			(xy 96.17715 -61.02436) (xy 96.157227 -60.972269) (xy 96.145101 -60.917832) (xy 96.14103 -60.86221)
			(xy 93.18716 -60.86221) (xy 93.185125 -60.86655) (xy 93.154352 -60.913063) (xy 93.117135 -60.9546)
			(xy 93.074267 -60.990275) (xy 93.026661 -61.019329) (xy 92.975332 -61.041141) (xy 92.921375 -61.055247)
			(xy 92.865938 -61.061347) (xy 92.810204 -61.05931) (xy 92.755361 -61.04918) (xy 92.702577 -61.031173)
			(xy 92.652977 -61.005672) (xy 92.607619 -60.973221) (xy 92.56747 -60.934512) (xy 92.533384 -60.890369)
			(xy 92.506088 -60.841734) (xy 92.486165 -60.789643) (xy 92.474039 -60.735206) (xy 92.469968 -60.679584)
			(xy 78.80477 -60.679584) (xy 78.80477 -65.310766) (xy 78.805238 -65.32064) (xy 78.81269 -65.338929)
			(xy 78.819248 -65.346326) (xy 78.819502 -65.34658) (xy 79.531972 -66.05905) (xy 80.663032 -66.05905)
			(xy 80.667103 -66.003428) (xy 80.679229 -65.948991) (xy 80.699152 -65.8969) (xy 80.726448 -65.848265)
			(xy 80.760534 -65.804122) (xy 80.800683 -65.765413) (xy 80.846041 -65.732962) (xy 80.895641 -65.707461)
			(xy 80.948425 -65.689454) (xy 81.003268 -65.679324) (xy 81.059002 -65.677287) (xy 81.114439 -65.683387)
			(xy 81.168396 -65.697493) (xy 81.219725 -65.719305) (xy 81.267331 -65.748359) (xy 81.310199 -65.784034)
			(xy 81.347416 -65.825571) (xy 81.378189 -65.872084) (xy 81.401861 -65.922581) (xy 81.417929 -65.975988)
			(xy 81.426049 -66.031164) (xy 81.426558 -66.05905) (xy 81.426049 -66.086936) (xy 81.417929 -66.142112)
			(xy 81.401861 -66.195519) (xy 81.378189 -66.246016) (xy 81.347416 -66.292529) (xy 81.310199 -66.334066)
			(xy 81.267331 -66.369741) (xy 81.219725 -66.398795) (xy 81.168396 -66.420607) (xy 81.114439 -66.434713)
			(xy 81.059002 -66.440813) (xy 81.003268 -66.438776) (xy 80.948425 -66.428646) (xy 80.895641 -66.410639)
			(xy 80.846041 -66.385138) (xy 80.800683 -66.352687) (xy 80.760534 -66.313978) (xy 80.726448 -66.269835)
			(xy 80.699152 -66.2212) (xy 80.679229 -66.169109) (xy 80.667103 -66.114672) (xy 80.663032 -66.05905)
			(xy 79.531972 -66.05905) (xy 84.680552 -71.20763) (xy 98.65563 -71.20763) (xy 98.659701 -71.152008)
			(xy 98.671827 -71.097571) (xy 98.69175 -71.04548) (xy 98.719046 -70.996845) (xy 98.753132 -70.952702)
			(xy 98.793281 -70.913993) (xy 98.838639 -70.881542) (xy 98.888239 -70.856041) (xy 98.941023 -70.838034)
			(xy 98.995866 -70.827904) (xy 99.0516 -70.825867) (xy 99.107037 -70.831967) (xy 99.160994 -70.846073)
			(xy 99.212323 -70.867885) (xy 99.259929 -70.896939) (xy 99.302797 -70.932614) (xy 99.340014 -70.974151)
			(xy 99.370787 -71.020664) (xy 99.394459 -71.071161) (xy 99.410527 -71.124568) (xy 99.418647 -71.179744)
			(xy 99.419156 -71.20763) (xy 99.418647 -71.235516) (xy 99.410527 -71.290692) (xy 99.394459 -71.344099)
			(xy 99.370787 -71.394596) (xy 99.340014 -71.441109) (xy 99.302797 -71.482646) (xy 99.259929 -71.518321)
			(xy 99.212323 -71.547375) (xy 99.160994 -71.569187) (xy 99.107037 -71.583293) (xy 99.0516 -71.589393)
			(xy 98.995866 -71.587356) (xy 98.941023 -71.577226) (xy 98.888239 -71.559219) (xy 98.838639 -71.533718)
			(xy 98.793281 -71.501267) (xy 98.753132 -71.462558) (xy 98.719046 -71.418415) (xy 98.69175 -71.36978)
			(xy 98.671827 -71.317689) (xy 98.659701 -71.263252) (xy 98.65563 -71.20763) (xy 84.680552 -71.20763)
			(xy 85.221064 -71.748142) (xy 85.230416 -71.756632) (xy 85.254547 -71.763976) (xy 85.267038 -71.762112)
			(xy 85.267292 -71.762112) (xy 85.286255 -71.758433) (xy 85.324685 -71.754484) (xy 85.344 -71.754238)
			(xy 85.371269 -71.754724) (xy 85.425253 -71.762486) (xy 85.477583 -71.777851) (xy 85.48817 -71.782686)
			(xy 87.002618 -71.782686) (xy 87.006689 -71.727064) (xy 87.018815 -71.672627) (xy 87.038738 -71.620536)
			(xy 87.066034 -71.571901) (xy 87.10012 -71.527758) (xy 87.140269 -71.489049) (xy 87.185627 -71.456598)
			(xy 87.235227 -71.431097) (xy 87.288011 -71.41309) (xy 87.342854 -71.40296) (xy 87.398588 -71.400923)
			(xy 87.454025 -71.407023) (xy 87.507982 -71.421129) (xy 87.559311 -71.442941) (xy 87.606917 -71.471995)
			(xy 87.649785 -71.50767) (xy 87.687002 -71.549207) (xy 87.717775 -71.59572) (xy 87.741447 -71.646217)
			(xy 87.757515 -71.699624) (xy 87.765635 -71.7548) (xy 87.766144 -71.782686) (xy 87.765635 -71.810572)
			(xy 87.757515 -71.865748) (xy 87.741447 -71.919155) (xy 87.717775 -71.969652) (xy 87.687002 -72.016165)
			(xy 87.649785 -72.057702) (xy 87.606917 -72.093377) (xy 87.559311 -72.122431) (xy 87.507982 -72.144243)
			(xy 87.454025 -72.158349) (xy 87.398588 -72.164449) (xy 87.342854 -72.162412) (xy 87.288011 -72.152282)
			(xy 87.235227 -72.134275) (xy 87.185627 -72.108774) (xy 87.140269 -72.076323) (xy 87.10012 -72.037614)
			(xy 87.066034 -71.993471) (xy 87.038738 -71.944836) (xy 87.018815 -71.892745) (xy 87.006689 -71.838308)
			(xy 87.002618 -71.782686) (xy 85.48817 -71.782686) (xy 85.527193 -71.800508) (xy 85.573074 -71.829994)
			(xy 85.614291 -71.865709) (xy 85.650006 -71.906926) (xy 85.679492 -71.952807) (xy 85.702149 -72.002417)
			(xy 85.717514 -72.054747) (xy 85.725276 -72.108731) (xy 85.725762 -72.136) (xy 85.725485 -72.155251)
			(xy 85.721545 -72.193552) (xy 85.717888 -72.212454) (xy 85.717888 -72.212962) (xy 85.716074 -72.225454)
			(xy 85.723382 -72.249585) (xy 85.731858 -72.258936) (xy 88.96718 -75.494258) (xy 92.753311 -75.494258)
			(xy 92.753311 -75.439742) (xy 92.76107 -75.385782) (xy 92.776429 -75.333476) (xy 92.799077 -75.283887)
			(xy 92.828552 -75.238027) (xy 92.864253 -75.196829) (xy 92.905455 -75.161131) (xy 92.951317 -75.131661)
			(xy 93.000907 -75.109017) (xy 93.053216 -75.093663) (xy 93.107176 -75.085909) (xy 93.134434 -75.085448)
			(xy 93.161806 -75.085882) (xy 93.215986 -75.093706) (xy 93.26849 -75.109202) (xy 93.318237 -75.132051)
			(xy 93.364202 -75.161783) (xy 93.385132 -75.179428) (xy 93.392244 -75.185524) (xy 93.409262 -75.191874)
			(xy 93.494606 -75.191874) (xy 93.511624 -75.185524) (xy 93.518736 -75.179428) (xy 93.54185 -75.160632)
			(xy 93.549724 -75.155044) (xy 93.55963 -75.139296) (xy 93.576648 -75.053698) (xy 93.5736 -75.03541)
			(xy 93.568774 -75.027282) (xy 93.555984 -75.005049) (xy 93.535845 -74.957877) (xy 93.522215 -74.90843)
			(xy 93.515341 -74.857602) (xy 93.514926 -74.831956) (xy 93.515419 -74.804587) (xy 93.523229 -74.750408)
			(xy 93.538712 -74.697905) (xy 93.561548 -74.648158) (xy 93.591267 -74.60219) (xy 93.608906 -74.581258)
			(xy 93.615002 -74.574146) (xy 93.621352 -74.557128) (xy 93.621352 -74.471784) (xy 93.615002 -74.454766)
			(xy 93.608906 -74.447654) (xy 93.59128 -74.426712) (xy 93.561566 -74.380742) (xy 93.538727 -74.330997)
			(xy 93.523233 -74.278498) (xy 93.515402 -74.224324) (xy 93.514926 -74.196956) (xy 93.515412 -74.169705)
			(xy 93.523168 -74.115757) (xy 93.538523 -74.063462) (xy 93.561165 -74.013885) (xy 93.590631 -73.968035)
			(xy 93.626322 -73.926844) (xy 93.667513 -73.891153) (xy 93.713363 -73.861687) (xy 93.76294 -73.839045)
			(xy 93.815235 -73.82369) (xy 93.869183 -73.815934) (xy 93.923685 -73.815934) (xy 93.977633 -73.82369)
			(xy 94.029928 -73.839045) (xy 94.079505 -73.861687) (xy 94.125355 -73.891153) (xy 94.166546 -73.926844)
			(xy 94.202237 -73.968035) (xy 94.231703 -74.013885) (xy 94.254345 -74.063462) (xy 94.2697 -74.115757)
			(xy 94.277456 -74.169705) (xy 94.277942 -74.196956) (xy 94.277464 -74.224326) (xy 94.269651 -74.278505)
			(xy 94.254166 -74.331009) (xy 94.231326 -74.380756) (xy 94.201603 -74.426723) (xy 94.183962 -74.447654)
			(xy 94.177866 -74.454766) (xy 94.171516 -74.471784) (xy 94.171516 -74.557128) (xy 94.177866 -74.574146)
			(xy 94.183962 -74.581258) (xy 94.201589 -74.6022) (xy 94.231304 -74.648169) (xy 94.254143 -74.697914)
			(xy 94.269637 -74.750413) (xy 94.277467 -74.804587) (xy 94.277942 -74.831956) (xy 94.27736 -74.861599)
			(xy 94.268201 -74.920173) (xy 94.250096 -74.976627) (xy 94.223481 -75.029602) (xy 94.188995 -75.077826)
			(xy 94.147468 -75.120138) (xy 94.124018 -75.13828) (xy 94.116144 -75.143868) (xy 94.106238 -75.159616)
			(xy 94.08922 -75.245214) (xy 94.092268 -75.263502) (xy 94.097094 -75.27163) (xy 94.109895 -75.293856)
			(xy 94.130031 -75.341031) (xy 94.143657 -75.39048) (xy 94.150528 -75.44131) (xy 94.150942 -75.466956)
			(xy 94.150404 -75.494206) (xy 94.142654 -75.548153) (xy 94.127305 -75.600447) (xy 94.10467 -75.650025)
			(xy 94.07521 -75.695876) (xy 94.039524 -75.737069) (xy 93.998339 -75.772763) (xy 93.952493 -75.802233)
			(xy 93.90292 -75.824878) (xy 93.850629 -75.840237) (xy 93.796684 -75.847998) (xy 93.769434 -75.848464)
			(xy 93.742064 -75.847987) (xy 93.687885 -75.840173) (xy 93.635382 -75.824687) (xy 93.585635 -75.801848)
			(xy 93.539668 -75.772125) (xy 93.518736 -75.754484) (xy 93.511624 -75.748388) (xy 93.494606 -75.742038)
			(xy 93.409262 -75.742038) (xy 93.392244 -75.748388) (xy 93.385132 -75.754484) (xy 93.364197 -75.772119)
			(xy 93.318225 -75.801832) (xy 93.268478 -75.824669) (xy 93.215978 -75.840161) (xy 93.161803 -75.84799)
			(xy 93.134434 -75.848464) (xy 93.107176 -75.848091) (xy 93.053216 -75.840337) (xy 93.000907 -75.824983)
			(xy 92.951317 -75.802339) (xy 92.905455 -75.772869) (xy 92.864253 -75.737171) (xy 92.828552 -75.695973)
			(xy 92.799077 -75.650113) (xy 92.776429 -75.600524) (xy 92.76107 -75.548218) (xy 92.753311 -75.494258)
			(xy 88.96718 -75.494258) (xy 89.642696 -76.169774) (xy 89.644474 -76.171552) (xy 90.269568 -76.733654)
			(xy 90.276818 -76.739546) (xy 90.29427 -76.746171) (xy 90.303604 -76.746608)
		)
		(stroke
			(width 0)
			(type solid)
		)
		(fill yes)
		(layer "In4.Cu")
		(net "GND")
	)
	(gr_poly
		(pts
			(xy 338.698078 -159.49168) (xy 338.70795 -159.491209) (xy 338.726231 -159.483748) (xy 338.733638 -159.477202)
			(xy 338.733892 -159.476948) (xy 339.778594 -158.432246) (xy 339.779102 -158.431738) (xy 339.785688 -158.424359)
			(xy 339.793143 -158.406059) (xy 339.79358 -158.396178) (xy 339.79358 -131.788662) (xy 339.793149 -131.778595)
			(xy 339.785423 -131.760003) (xy 339.778594 -131.752594) (xy 339.231986 -131.205986) (xy 339.224591 -131.199132)
			(xy 339.205992 -131.19139) (xy 339.195918 -131.191) (xy 332.523084 -131.191) (xy 332.513015 -131.191426)
			(xy 332.494415 -131.199145) (xy 332.487016 -131.205986) (xy 331.605128 -132.087874) (xy 331.597727 -132.094712)
			(xy 331.579128 -132.102424) (xy 331.56906 -132.10286) (xy 331.554074 -132.117846) (xy 331.317092 -132.354828)
			(xy 331.310865 -132.361659) (xy 331.303327 -132.37852) (xy 331.302244 -132.396957) (xy 331.304646 -132.405882)
			(xy 331.335888 -132.50545) (xy 331.35697 -132.523992) (xy 331.371194 -132.526532) (xy 331.403315 -132.53303)
			(xy 331.464869 -132.555511) (xy 331.493622 -132.571236) (xy 331.50175 -132.575808) (xy 331.520038 -132.578602)
			(xy 331.604366 -132.56133) (xy 331.61986 -132.551424) (xy 331.625448 -132.543804) (xy 331.643599 -132.520496)
			(xy 331.685876 -132.479237) (xy 331.734004 -132.444982) (xy 331.786834 -132.418549) (xy 331.843104 -132.40057)
			(xy 331.901473 -132.391472) (xy 331.93101 -132.390896) (xy 331.958719 -132.391393) (xy 332.013553 -132.399413)
			(xy 332.06665 -132.415281) (xy 332.116893 -132.438666) (xy 332.163223 -132.469073) (xy 332.204667 -132.505864)
			(xy 332.240351 -132.548264) (xy 332.269525 -132.595381) (xy 332.291575 -132.646224) (xy 332.29931 -132.672836)
			(xy 332.301596 -132.681726) (xy 332.312518 -132.696712) (xy 332.384654 -132.743956) (xy 332.402688 -132.74802)
			(xy 332.412086 -132.74675) (xy 332.425787 -132.744856) (xy 332.453373 -132.742825) (xy 332.467204 -132.742686)
			(xy 332.494455 -132.743172) (xy 332.548403 -132.750929) (xy 332.600697 -132.766284) (xy 332.650275 -132.788926)
			(xy 332.696125 -132.818392) (xy 332.737315 -132.854083) (xy 332.773007 -132.895274) (xy 332.802473 -132.941124)
			(xy 332.825115 -132.990701) (xy 332.840471 -133.042995) (xy 332.848228 -133.096943) (xy 332.848712 -133.124194)
			(xy 332.848269 -133.150625) (xy 332.840982 -133.202981) (xy 332.826533 -133.253828) (xy 332.805199 -133.302193)
			(xy 332.777389 -133.347147) (xy 332.743636 -133.387829) (xy 332.704588 -133.423459) (xy 332.660992 -133.453353)
			(xy 332.613685 -133.47694) (xy 332.563574 -133.493765) (xy 332.511618 -133.503508) (xy 332.485238 -133.505194)
			(xy 332.475586 -133.505702) (xy 332.458568 -133.513068) (xy 332.396846 -133.574282) (xy 332.389226 -133.591046)
			(xy 332.388464 -133.600698) (xy 332.386207 -133.629445) (xy 332.374125 -133.685826) (xy 332.353698 -133.739747)
			(xy 332.325389 -133.789981) (xy 332.289844 -133.835383) (xy 332.247872 -133.874919) (xy 332.200429 -133.90769)
			(xy 332.148595 -133.932949) (xy 332.09355 -133.950121) (xy 332.036548 -133.958815) (xy 332.007718 -133.959346)
			(xy 331.982379 -133.958933) (xy 331.932148 -133.952225) (xy 331.883247 -133.938924) (xy 331.836538 -133.919266)
			(xy 331.792844 -133.893596) (xy 331.752933 -133.862366) (xy 331.734922 -133.844538) (xy 331.728064 -133.837426)
			(xy 331.7113 -133.829806) (xy 331.62367 -133.824472) (xy 331.606144 -133.83006) (xy 331.598524 -133.836156)
			(xy 331.578137 -133.851995) (xy 331.533901 -133.878612) (xy 331.486476 -133.899012) (xy 331.436731 -133.912821)
			(xy 331.385577 -133.919788) (xy 331.359764 -133.92023) (xy 331.330756 -133.919693) (xy 331.273408 -133.910914)
			(xy 331.218051 -133.89355) (xy 331.165964 -133.868) (xy 331.118348 -133.834856) (xy 331.076302 -133.794881)
			(xy 331.040796 -133.748998) (xy 331.026262 -133.723888) (xy 331.02169 -133.715506) (xy 331.007466 -133.703822)
			(xy 330.92517 -133.675374) (xy 330.906628 -133.676136) (xy 330.897738 -133.679946) (xy 330.874066 -133.689535)
			(xy 330.824801 -133.703013) (xy 330.774178 -133.709795) (xy 330.74864 -133.710172) (xy 330.722132 -133.709719)
			(xy 330.669627 -133.702379) (xy 330.618645 -133.687836) (xy 330.57017 -133.66637) (xy 330.525136 -133.638395)
			(xy 330.484412 -133.604451) (xy 330.448784 -133.565192) (xy 330.418939 -133.521376) (xy 330.406756 -133.497828)
			(xy 330.401168 -133.486398) (xy 330.380594 -133.471666) (xy 330.28509 -133.458204) (xy 330.272712 -133.457134)
			(xy 330.249403 -133.465653) (xy 330.24064 -133.47446) (xy 330.030328 -133.704584) (xy 329.249532 -134.56031)
			(xy 329.24672 -134.56357) (xy 329.242122 -134.570847) (xy 329.240388 -134.574788) (xy 328.96175 -135.228076)
			(xy 328.689716 -135.86587) (xy 328.68743 -135.872474) (xy 328.521691 -136.473946) (xy 330.23505 -136.473946)
			(xy 330.239121 -136.418324) (xy 330.251247 -136.363887) (xy 330.27117 -136.311796) (xy 330.298466 -136.263161)
			(xy 330.332552 -136.219018) (xy 330.372701 -136.180309) (xy 330.418059 -136.147858) (xy 330.467659 -136.122357)
			(xy 330.520443 -136.10435) (xy 330.575286 -136.09422) (xy 330.63102 -136.092183) (xy 330.686457 -136.098283)
			(xy 330.740414 -136.112389) (xy 330.791743 -136.134201) (xy 330.839349 -136.163255) (xy 330.882217 -136.19893)
			(xy 330.919434 -136.240467) (xy 330.950207 -136.28698) (xy 330.973879 -136.337477) (xy 330.989947 -136.390884)
			(xy 330.998067 -136.44606) (xy 330.998576 -136.473946) (xy 330.998067 -136.501832) (xy 330.989947 -136.557008)
			(xy 330.973879 -136.610415) (xy 330.950207 -136.660912) (xy 330.919434 -136.707425) (xy 330.882217 -136.748962)
			(xy 330.839349 -136.784637) (xy 330.791743 -136.813691) (xy 330.740414 -136.835503) (xy 330.686457 -136.849609)
			(xy 330.63102 -136.855709) (xy 330.575286 -136.853672) (xy 330.520443 -136.843542) (xy 330.467659 -136.825535)
			(xy 330.418059 -136.800034) (xy 330.372701 -136.767583) (xy 330.332552 -136.728874) (xy 330.298466 -136.684731)
			(xy 330.27117 -136.636096) (xy 330.251247 -136.584005) (xy 330.239121 -136.529568) (xy 330.23505 -136.473946)
			(xy 328.521691 -136.473946) (xy 328.271124 -137.383266) (xy 328.26891 -137.392691) (xy 328.270958 -137.411927)
			(xy 328.280014 -137.429022) (xy 328.287126 -137.43559) (xy 328.368406 -137.504932) (xy 328.39787 -137.508996)
			(xy 328.411332 -137.502646) (xy 328.436293 -137.49182) (xy 328.488512 -137.476543) (xy 328.54237 -137.468824)
			(xy 328.569574 -137.468356) (xy 328.596831 -137.468817) (xy 328.65079 -137.476572) (xy 328.703096 -137.491927)
			(xy 328.752684 -137.51457) (xy 328.798544 -137.54404) (xy 328.839744 -137.579737) (xy 328.875444 -137.620935)
			(xy 328.904917 -137.666793) (xy 328.927564 -137.71638) (xy 328.942923 -137.768685) (xy 328.950681 -137.822643)
			(xy 328.950681 -137.877157) (xy 328.942923 -137.931115) (xy 328.927564 -137.98342) (xy 328.904917 -138.033007)
			(xy 328.875444 -138.078865) (xy 328.839744 -138.120063) (xy 328.798544 -138.15576) (xy 328.752684 -138.18523)
			(xy 328.703096 -138.207873) (xy 328.65079 -138.223228) (xy 328.596831 -138.230983) (xy 328.569574 -138.231372)
			(xy 328.544643 -138.230966) (xy 328.495206 -138.224473) (xy 328.447034 -138.2116) (xy 328.400947 -138.192568)
			(xy 328.35773 -138.167698) (xy 328.337672 -138.152886) (xy 328.326242 -138.143996) (xy 328.297286 -138.141202)
			(xy 328.202544 -138.187938) (xy 328.194302 -138.192518) (xy 328.181596 -138.206428) (xy 328.174765 -138.223985)
			(xy 328.17435 -138.233404) (xy 328.17435 -139.43965) (xy 328.1807 -139.446) (xy 328.1807 -140.408152)
			(xy 332.324962 -140.408152) (xy 332.329033 -140.35253) (xy 332.341159 -140.298093) (xy 332.361082 -140.246002)
			(xy 332.388378 -140.197367) (xy 332.422464 -140.153224) (xy 332.462613 -140.114515) (xy 332.507971 -140.082064)
			(xy 332.557571 -140.056563) (xy 332.610355 -140.038556) (xy 332.665198 -140.028426) (xy 332.720932 -140.026389)
			(xy 332.776369 -140.032489) (xy 332.830326 -140.046595) (xy 332.881655 -140.068407) (xy 332.929261 -140.097461)
			(xy 332.972129 -140.133136) (xy 333.009346 -140.174673) (xy 333.040119 -140.221186) (xy 333.063791 -140.271683)
			(xy 333.079859 -140.32509) (xy 333.087979 -140.380266) (xy 333.088488 -140.408152) (xy 333.087979 -140.436038)
			(xy 333.079859 -140.491214) (xy 333.063791 -140.544621) (xy 333.040119 -140.595118) (xy 333.009346 -140.641631)
			(xy 332.972129 -140.683168) (xy 332.929261 -140.718843) (xy 332.881655 -140.747897) (xy 332.830326 -140.769709)
			(xy 332.776369 -140.783815) (xy 332.720932 -140.789915) (xy 332.665198 -140.787878) (xy 332.610355 -140.777748)
			(xy 332.557571 -140.759741) (xy 332.507971 -140.73424) (xy 332.462613 -140.701789) (xy 332.422464 -140.66308)
			(xy 332.388378 -140.618937) (xy 332.361082 -140.570302) (xy 332.341159 -140.518211) (xy 332.329033 -140.463774)
			(xy 332.324962 -140.408152) (xy 328.1807 -140.408152) (xy 328.1807 -142.578074) (xy 328.532234 -142.578074)
			(xy 328.536305 -142.522452) (xy 328.548431 -142.468015) (xy 328.568354 -142.415924) (xy 328.59565 -142.367289)
			(xy 328.629736 -142.323146) (xy 328.669885 -142.284437) (xy 328.715243 -142.251986) (xy 328.764843 -142.226485)
			(xy 328.817627 -142.208478) (xy 328.87247 -142.198348) (xy 328.928204 -142.196311) (xy 328.935138 -142.197074)
			(xy 332.301086 -142.197074) (xy 332.305157 -142.141452) (xy 332.317283 -142.087015) (xy 332.337206 -142.034924)
			(xy 332.364502 -141.986289) (xy 332.398588 -141.942146) (xy 332.438737 -141.903437) (xy 332.484095 -141.870986)
			(xy 332.533695 -141.845485) (xy 332.586479 -141.827478) (xy 332.641322 -141.817348) (xy 332.697056 -141.815311)
			(xy 332.752493 -141.821411) (xy 332.80645 -141.835517) (xy 332.857779 -141.857329) (xy 332.905385 -141.886383)
			(xy 332.948253 -141.922058) (xy 332.98547 -141.963595) (xy 333.016243 -142.010108) (xy 333.039915 -142.060605)
			(xy 333.055983 -142.114012) (xy 333.064103 -142.169188) (xy 333.064612 -142.197074) (xy 333.064103 -142.22496)
			(xy 333.055983 -142.280136) (xy 333.039915 -142.333543) (xy 333.016243 -142.38404) (xy 332.98547 -142.430553)
			(xy 332.948253 -142.47209) (xy 332.905385 -142.507765) (xy 332.857779 -142.536819) (xy 332.80645 -142.558631)
			(xy 332.752493 -142.572737) (xy 332.697056 -142.578837) (xy 332.641322 -142.5768) (xy 332.586479 -142.56667)
			(xy 332.533695 -142.548663) (xy 332.484095 -142.523162) (xy 332.438737 -142.490711) (xy 332.398588 -142.452002)
			(xy 332.364502 -142.407859) (xy 332.337206 -142.359224) (xy 332.317283 -142.307133) (xy 332.305157 -142.252696)
			(xy 332.301086 -142.197074) (xy 328.935138 -142.197074) (xy 328.983641 -142.202411) (xy 329.037598 -142.216517)
			(xy 329.088927 -142.238329) (xy 329.136533 -142.267383) (xy 329.179401 -142.303058) (xy 329.216618 -142.344595)
			(xy 329.247391 -142.391108) (xy 329.271063 -142.441605) (xy 329.287131 -142.495012) (xy 329.295251 -142.550188)
			(xy 329.29576 -142.578074) (xy 329.295251 -142.60596) (xy 329.287131 -142.661136) (xy 329.275822 -142.698724)
			(xy 337.332572 -142.698724) (xy 337.336643 -142.643102) (xy 337.348769 -142.588665) (xy 337.368692 -142.536574)
			(xy 337.395988 -142.487939) (xy 337.430074 -142.443796) (xy 337.470223 -142.405087) (xy 337.515581 -142.372636)
			(xy 337.565181 -142.347135) (xy 337.617965 -142.329128) (xy 337.672808 -142.318998) (xy 337.728542 -142.316961)
			(xy 337.783979 -142.323061) (xy 337.837936 -142.337167) (xy 337.889265 -142.358979) (xy 337.936871 -142.388033)
			(xy 337.979739 -142.423708) (xy 338.016956 -142.465245) (xy 338.047729 -142.511758) (xy 338.071401 -142.562255)
			(xy 338.087469 -142.615662) (xy 338.095589 -142.670838) (xy 338.096098 -142.698724) (xy 338.095589 -142.72661)
			(xy 338.087469 -142.781786) (xy 338.071401 -142.835193) (xy 338.047729 -142.88569) (xy 338.016956 -142.932203)
			(xy 337.979739 -142.97374) (xy 337.936871 -143.009415) (xy 337.889265 -143.038469) (xy 337.837936 -143.060281)
			(xy 337.783979 -143.074387) (xy 337.728542 -143.080487) (xy 337.672808 -143.07845) (xy 337.617965 -143.06832)
			(xy 337.565181 -143.050313) (xy 337.515581 -143.024812) (xy 337.470223 -142.992361) (xy 337.430074 -142.953652)
			(xy 337.395988 -142.909509) (xy 337.368692 -142.860874) (xy 337.348769 -142.808783) (xy 337.336643 -142.754346)
			(xy 337.332572 -142.698724) (xy 329.275822 -142.698724) (xy 329.271063 -142.714543) (xy 329.247391 -142.76504)
			(xy 329.216618 -142.811553) (xy 329.179401 -142.85309) (xy 329.136533 -142.888765) (xy 329.088927 -142.917819)
			(xy 329.037598 -142.939631) (xy 328.983641 -142.953737) (xy 328.928204 -142.959837) (xy 328.87247 -142.9578)
			(xy 328.817627 -142.94767) (xy 328.764843 -142.929663) (xy 328.715243 -142.904162) (xy 328.669885 -142.871711)
			(xy 328.629736 -142.833002) (xy 328.59565 -142.788859) (xy 328.568354 -142.740224) (xy 328.548431 -142.688133)
			(xy 328.536305 -142.633696) (xy 328.532234 -142.578074) (xy 328.1807 -142.578074) (xy 328.1807 -143.12138)
			(xy 328.180954 -143.126968) (xy 328.675238 -147.458684) (xy 329.095862 -151.143208) (xy 329.096878 -151.148796)
			(xy 329.25385 -151.828246) (xy 329.256904 -151.838954) (xy 329.270618 -151.856464) (xy 329.280266 -151.862028)
			(xy 329.359514 -151.902668) (xy 329.381612 -151.90343) (xy 329.392026 -151.899112) (xy 329.41548 -151.88971)
			(xy 329.464247 -151.876475) (xy 329.514335 -151.8698) (xy 329.5396 -151.869394) (xy 329.568517 -151.869928)
			(xy 329.625688 -151.878655) (xy 329.680888 -151.895909) (xy 329.732852 -151.921295) (xy 329.780391 -151.954231)
			(xy 329.822415 -151.993963) (xy 329.84059 -152.01646) (xy 329.848135 -152.025239) (xy 329.868906 -152.035403)
			(xy 329.880468 -152.036018) (xy 329.960732 -152.036018) (xy 329.972289 -152.035403) (xy 329.99305 -152.025223)
			(xy 330.00061 -152.01646) (xy 330.018797 -151.99397) (xy 330.060811 -151.95422) (xy 330.108343 -151.921269)
			(xy 330.160306 -151.895871) (xy 330.215507 -151.878608) (xy 330.272681 -151.869877) (xy 330.3016 -151.869394)
			(xy 330.328851 -151.86988) (xy 330.382799 -151.877636) (xy 330.435093 -151.892991) (xy 330.48467 -151.915632)
			(xy 330.53052 -151.945098) (xy 330.57171 -151.98079) (xy 330.607402 -152.02198) (xy 330.636868 -152.06783)
			(xy 330.659509 -152.117407) (xy 330.674864 -152.169701) (xy 330.68262 -152.223649) (xy 330.68262 -152.278151)
			(xy 330.674864 -152.332099) (xy 330.659509 -152.384393) (xy 330.636868 -152.43397) (xy 330.607402 -152.47982)
			(xy 330.57171 -152.52101) (xy 330.53052 -152.556702) (xy 330.48467 -152.586168) (xy 330.435093 -152.608809)
			(xy 330.382799 -152.624164) (xy 330.328851 -152.63192) (xy 330.3016 -152.63241) (xy 330.272683 -152.631876)
			(xy 330.215512 -152.623149) (xy 330.160312 -152.605895) (xy 330.108348 -152.58051) (xy 330.060809 -152.547574)
			(xy 330.018784 -152.507841) (xy 330.00061 -152.485344) (xy 329.993065 -152.476565) (xy 329.972294 -152.466401)
			(xy 329.960732 -152.465786) (xy 329.880468 -152.465786) (xy 329.868911 -152.466401) (xy 329.848151 -152.476582)
			(xy 329.84059 -152.485344) (xy 329.82356 -152.506422) (xy 329.784542 -152.544024) (xy 329.740604 -152.575737)
			(xy 329.692626 -152.600926) (xy 329.641572 -152.619084) (xy 329.588464 -152.629848) (xy 329.561444 -152.631902)
			(xy 329.550014 -152.63241) (xy 329.53071 -152.642824) (xy 329.477116 -152.714198) (xy 329.470972 -152.72345)
			(xy 329.466498 -152.74518) (xy 329.46848 -152.756108) (xy 329.776836 -154.090878) (xy 329.777852 -154.094434)
			(xy 329.928474 -154.58059) (xy 329.928982 -154.582622) (xy 330.334874 -155.727654) (xy 330.33716 -155.732988)
			(xy 330.599796 -156.270706) (xy 331.088238 -157.270196) (xy 331.090016 -157.273752) (xy 331.903832 -158.6611)
			(xy 331.908934 -158.668959) (xy 331.923587 -158.680611) (xy 331.941455 -158.686198) (xy 331.950822 -158.685992)
			(xy 332.055724 -158.679642) (xy 332.079092 -158.663132) (xy 332.08468 -158.649924) (xy 332.097957 -158.620825)
			(xy 332.132734 -158.567148) (xy 332.175947 -158.519997) (xy 332.200758 -158.49981) (xy 332.209537 -158.492265)
			(xy 332.219701 -158.471494) (xy 332.220316 -158.459932) (xy 332.220316 -158.379668) (xy 332.219701 -158.368111)
			(xy 332.209521 -158.347351) (xy 332.200758 -158.33979) (xy 332.179975 -158.323037) (xy 332.142845 -158.284683)
			(xy 332.111423 -158.241529) (xy 332.086324 -158.194415) (xy 332.068038 -158.144263) (xy 332.056922 -158.092051)
			(xy 332.053192 -158.0388) (xy 332.056922 -157.985549) (xy 332.068038 -157.933337) (xy 332.086324 -157.883185)
			(xy 332.111423 -157.836071) (xy 332.142845 -157.792917) (xy 332.179975 -157.754563) (xy 332.200758 -157.73781)
			(xy 332.209537 -157.730265) (xy 332.219701 -157.709494) (xy 332.220316 -157.697932) (xy 332.220316 -157.617668)
			(xy 332.219701 -157.606111) (xy 332.209521 -157.585351) (xy 332.200758 -157.57779) (xy 332.178268 -157.559603)
			(xy 332.138519 -157.517589) (xy 332.105567 -157.470056) (xy 332.080169 -157.418094) (xy 332.062907 -157.362893)
			(xy 332.054175 -157.305719) (xy 332.053692 -157.2768) (xy 332.054134 -157.250497) (xy 332.061367 -157.198391)
			(xy 332.075697 -157.147774) (xy 332.09685 -157.099608) (xy 332.124426 -157.054808) (xy 332.140814 -157.03423)
			(xy 332.149704 -157.023308) (xy 332.154022 -156.995622) (xy 332.109826 -156.88691) (xy 332.087728 -156.870146)
			(xy 332.073758 -156.868622) (xy 332.046129 -156.865026) (xy 331.992247 -156.850853) (xy 331.941 -156.828993)
			(xy 331.893478 -156.799911) (xy 331.850692 -156.764226) (xy 331.813552 -156.722696) (xy 331.782848 -156.676205)
			(xy 331.759234 -156.625742) (xy 331.743211 -156.572382) (xy 331.735121 -156.517257) (xy 331.734668 -156.4894)
			(xy 331.735202 -156.460484) (xy 331.74393 -156.403314) (xy 331.761187 -156.348117) (xy 331.786576 -156.296156)
			(xy 331.819516 -156.248622) (xy 331.859253 -156.206604) (xy 331.881734 -156.18841) (xy 331.890517 -156.180867)
			(xy 331.900685 -156.160095) (xy 331.901292 -156.148532) (xy 331.901292 -156.068268) (xy 331.900676 -156.056712)
			(xy 331.890493 -156.035955) (xy 331.881734 -156.02839) (xy 331.860952 -156.011636) (xy 331.823824 -155.973282)
			(xy 331.792405 -155.930127) (xy 331.767307 -155.883013) (xy 331.749022 -155.832862) (xy 331.737907 -155.780651)
			(xy 331.734177 -155.7274) (xy 331.737907 -155.674149) (xy 331.749022 -155.621938) (xy 331.767307 -155.571787)
			(xy 331.792405 -155.524673) (xy 331.823824 -155.481518) (xy 331.860952 -155.443164) (xy 331.881734 -155.42641)
			(xy 331.890517 -155.418867) (xy 331.900685 -155.398095) (xy 331.901292 -155.386532) (xy 331.901292 -155.306268)
			(xy 331.900676 -155.294712) (xy 331.890493 -155.273955) (xy 331.881734 -155.26639) (xy 331.860952 -155.249636)
			(xy 331.823824 -155.211282) (xy 331.792405 -155.168127) (xy 331.767307 -155.121013) (xy 331.749022 -155.070862)
			(xy 331.737907 -155.018651) (xy 331.734177 -154.9654) (xy 331.737907 -154.912149) (xy 331.749022 -154.859938)
			(xy 331.767307 -154.809787) (xy 331.792405 -154.762673) (xy 331.823824 -154.719518) (xy 331.860952 -154.681164)
			(xy 331.881734 -154.66441) (xy 331.890517 -154.656867) (xy 331.900685 -154.636095) (xy 331.901292 -154.624532)
			(xy 331.901292 -154.544268) (xy 331.900676 -154.532712) (xy 331.890493 -154.511955) (xy 331.881734 -154.50439)
			(xy 331.860952 -154.487636) (xy 331.823824 -154.449282) (xy 331.792405 -154.406127) (xy 331.767307 -154.359013)
			(xy 331.749022 -154.308862) (xy 331.737907 -154.256651) (xy 331.734177 -154.2034) (xy 331.737907 -154.150149)
			(xy 331.749022 -154.097938) (xy 331.767307 -154.047787) (xy 331.792405 -154.000673) (xy 331.823824 -153.957518)
			(xy 331.860952 -153.919164) (xy 331.881734 -153.90241) (xy 331.890517 -153.894867) (xy 331.900685 -153.874095)
			(xy 331.901292 -153.862532) (xy 331.901292 -153.782268) (xy 331.900676 -153.770712) (xy 331.890493 -153.749955)
			(xy 331.881734 -153.74239) (xy 331.859245 -153.724202) (xy 331.819498 -153.682187) (xy 331.786549 -153.634654)
			(xy 331.761153 -153.582692) (xy 331.743891 -153.527492) (xy 331.735161 -153.470318) (xy 331.734668 -153.4414)
			(xy 331.73518 -153.413582) (xy 331.743277 -153.358537) (xy 331.759286 -153.305253) (xy 331.782865 -153.254861)
			(xy 331.813516 -153.208428) (xy 331.850587 -153.166941) (xy 331.893292 -153.13128) (xy 331.940725 -153.102202)
			(xy 331.99188 -153.080323) (xy 332.04567 -153.066108) (xy 332.07325 -153.062432) (xy 332.084426 -153.061162)
			(xy 332.103222 -153.049478) (xy 332.159102 -152.967436) (xy 332.162912 -152.945592) (xy 332.159864 -152.934924)
			(xy 332.153668 -152.910436) (xy 332.147042 -152.860359) (xy 332.146656 -152.835102) (xy 332.147147 -152.807127)
			(xy 332.155323 -152.751777) (xy 332.171498 -152.698216) (xy 332.195326 -152.647593) (xy 332.21041 -152.624028)
			(xy 332.21549 -152.616154) (xy 332.219554 -152.597612) (xy 332.206346 -152.511252) (xy 332.196948 -152.494742)
			(xy 332.189582 -152.4889) (xy 332.167827 -152.470681) (xy 332.129428 -152.428905) (xy 332.097638 -152.381903)
			(xy 332.073158 -152.330712) (xy 332.056529 -152.276461) (xy 332.048116 -152.220345) (xy 332.047596 -152.191974)
			(xy 332.048082 -152.164723) (xy 332.055838 -152.110775) (xy 332.071193 -152.05848) (xy 332.093835 -152.008903)
			(xy 332.123301 -151.963053) (xy 332.158992 -151.921862) (xy 332.200183 -151.886171) (xy 332.246033 -151.856705)
			(xy 332.29561 -151.834063) (xy 332.347905 -151.818708) (xy 332.401853 -151.810952) (xy 332.456355 -151.810952)
			(xy 332.510303 -151.818708) (xy 332.562598 -151.834063) (xy 332.612175 -151.856705) (xy 332.658025 -151.886171)
			(xy 332.699216 -151.921862) (xy 332.734907 -151.963053) (xy 332.764373 -152.008903) (xy 332.787015 -152.05848)
			(xy 332.80237 -152.110775) (xy 332.810126 -152.164723) (xy 332.810612 -152.191974) (xy 332.810122 -152.21995)
			(xy 332.80195 -152.275301) (xy 332.785776 -152.328863) (xy 332.761949 -152.379487) (xy 332.746858 -152.403048)
			(xy 332.741778 -152.410922) (xy 332.737714 -152.429464) (xy 332.741482 -152.454102) (xy 334.204056 -152.454102)
			(xy 334.204555 -152.425184) (xy 334.213285 -152.368011) (xy 334.230545 -152.312811) (xy 334.25594 -152.260849)
			(xy 334.288888 -152.213316) (xy 334.328634 -152.171301) (xy 334.351122 -152.153112) (xy 334.359878 -152.145544)
			(xy 334.370064 -152.12479) (xy 334.37068 -152.113234) (xy 334.37068 -152.03297) (xy 334.370076 -152.021406)
			(xy 334.359906 -152.000634) (xy 334.351122 -151.993092) (xy 334.328639 -151.9749) (xy 334.288903 -151.932881)
			(xy 334.255963 -151.885347) (xy 334.230575 -151.833385) (xy 334.213319 -151.778188) (xy 334.20459 -151.721018)
			(xy 334.204056 -151.692102) (xy 334.204542 -151.664851) (xy 334.212298 -151.610903) (xy 334.227653 -151.558608)
			(xy 334.250295 -151.509031) (xy 334.279761 -151.463181) (xy 334.315452 -151.42199) (xy 334.356643 -151.386299)
			(xy 334.402493 -151.356833) (xy 334.45207 -151.334191) (xy 334.504365 -151.318836) (xy 334.558313 -151.31108)
			(xy 334.612815 -151.31108) (xy 334.666763 -151.318836) (xy 334.719058 -151.334191) (xy 334.768635 -151.356833)
			(xy 334.814485 -151.386299) (xy 334.855676 -151.42199) (xy 334.891367 -151.463181) (xy 334.920833 -151.509031)
			(xy 334.943475 -151.558608) (xy 334.95883 -151.610903) (xy 334.966586 -151.664851) (xy 334.967072 -151.692102)
			(xy 334.966566 -151.721019) (xy 334.957836 -151.778192) (xy 334.940576 -151.833391) (xy 334.915182 -151.885353)
			(xy 334.882236 -151.932887) (xy 334.842493 -151.974903) (xy 334.820006 -151.993092) (xy 334.811253 -152.000663)
			(xy 334.801064 -152.021415) (xy 334.800448 -152.03297) (xy 334.800448 -152.113234) (xy 334.80104 -152.124799)
			(xy 334.811218 -152.145572) (xy 334.820006 -152.153112) (xy 334.842496 -152.171295) (xy 334.882231 -152.213316)
			(xy 334.915169 -152.260853) (xy 334.940556 -152.312816) (xy 334.957811 -152.368015) (xy 334.966538 -152.425186)
			(xy 334.967072 -152.454102) (xy 336.261456 -152.454102) (xy 336.261955 -152.425184) (xy 336.270685 -152.368011)
			(xy 336.287945 -152.312811) (xy 336.31334 -152.260849) (xy 336.346288 -152.213316) (xy 336.386034 -152.171301)
			(xy 336.408522 -152.153112) (xy 336.417278 -152.145544) (xy 336.427464 -152.12479) (xy 336.42808 -152.113234)
			(xy 336.42808 -152.03297) (xy 336.427476 -152.021406) (xy 336.417306 -152.000634) (xy 336.408522 -151.993092)
			(xy 336.386039 -151.9749) (xy 336.346303 -151.932881) (xy 336.313363 -151.885347) (xy 336.287975 -151.833385)
			(xy 336.270719 -151.778188) (xy 336.26199 -151.721018) (xy 336.261456 -151.692102) (xy 336.261942 -151.664851)
			(xy 336.269698 -151.610903) (xy 336.285053 -151.558608) (xy 336.307695 -151.509031) (xy 336.337161 -151.463181)
			(xy 336.372852 -151.42199) (xy 336.414043 -151.386299) (xy 336.459893 -151.356833) (xy 336.50947 -151.334191)
			(xy 336.561765 -151.318836) (xy 336.615713 -151.31108) (xy 336.670215 -151.31108) (xy 336.724163 -151.318836)
			(xy 336.776458 -151.334191) (xy 336.826035 -151.356833) (xy 336.871885 -151.386299) (xy 336.913076 -151.42199)
			(xy 336.948767 -151.463181) (xy 336.978233 -151.509031) (xy 337.000875 -151.558608) (xy 337.01623 -151.610903)
			(xy 337.023986 -151.664851) (xy 337.024472 -151.692102) (xy 337.023966 -151.721019) (xy 337.015236 -151.778192)
			(xy 336.997976 -151.833391) (xy 336.972582 -151.885353) (xy 336.939636 -151.932887) (xy 336.899893 -151.974903)
			(xy 336.877406 -151.993092) (xy 336.868653 -152.000663) (xy 336.858464 -152.021415) (xy 336.857848 -152.03297)
			(xy 336.857848 -152.113234) (xy 336.85844 -152.124799) (xy 336.868618 -152.145572) (xy 336.877406 -152.153112)
			(xy 336.899896 -152.171295) (xy 336.939631 -152.213316) (xy 336.972569 -152.260853) (xy 336.997956 -152.312816)
			(xy 337.015211 -152.368015) (xy 337.023938 -152.425186) (xy 337.024472 -152.454102) (xy 337.023986 -152.481353)
			(xy 337.01623 -152.535301) (xy 337.000875 -152.587596) (xy 336.978233 -152.637173) (xy 336.948767 -152.683023)
			(xy 336.913076 -152.724214) (xy 336.871885 -152.759905) (xy 336.826035 -152.789371) (xy 336.776458 -152.812013)
			(xy 336.724163 -152.827368) (xy 336.670215 -152.835124) (xy 336.615713 -152.835124) (xy 336.561765 -152.827368)
			(xy 336.50947 -152.812013) (xy 336.459893 -152.789371) (xy 336.414043 -152.759905) (xy 336.372852 -152.724214)
			(xy 336.337161 -152.683023) (xy 336.307695 -152.637173) (xy 336.285053 -152.587596) (xy 336.269698 -152.535301)
			(xy 336.261942 -152.481353) (xy 336.261456 -152.454102) (xy 334.967072 -152.454102) (xy 334.966586 -152.481353)
			(xy 334.95883 -152.535301) (xy 334.943475 -152.587596) (xy 334.920833 -152.637173) (xy 334.891367 -152.683023)
			(xy 334.855676 -152.724214) (xy 334.814485 -152.759905) (xy 334.768635 -152.789371) (xy 334.719058 -152.812013)
			(xy 334.666763 -152.827368) (xy 334.612815 -152.835124) (xy 334.558313 -152.835124) (xy 334.504365 -152.827368)
			(xy 334.45207 -152.812013) (xy 334.402493 -152.789371) (xy 334.356643 -152.759905) (xy 334.315452 -152.724214)
			(xy 334.279761 -152.683023) (xy 334.250295 -152.637173) (xy 334.227653 -152.587596) (xy 334.212298 -152.535301)
			(xy 334.204542 -152.481353) (xy 334.204056 -152.454102) (xy 332.741482 -152.454102) (xy 332.750922 -152.515824)
			(xy 332.76032 -152.532334) (xy 332.767686 -152.538176) (xy 332.789443 -152.556394) (xy 332.827848 -152.598168)
			(xy 332.859644 -152.645169) (xy 332.884129 -152.69636) (xy 332.900764 -152.750612) (xy 332.909181 -152.806729)
			(xy 332.909672 -152.835102) (xy 332.909218 -152.862473) (xy 332.901442 -152.916659) (xy 332.894178 -152.943052)
			(xy 332.89113 -152.953212) (xy 332.893416 -152.973532) (xy 332.940914 -153.055828) (xy 332.957424 -153.06802)
			(xy 332.967584 -153.07056) (xy 332.992435 -153.076983) (xy 333.040272 -153.095594) (xy 333.085185 -153.120443)
			(xy 333.126366 -153.151083) (xy 333.163073 -153.186962) (xy 333.179166 -153.206958) (xy 333.186709 -153.215741)
			(xy 333.20748 -153.225915) (xy 333.219044 -153.226516) (xy 333.299308 -153.226516) (xy 333.310868 -153.225906)
			(xy 333.331636 -153.215732) (xy 333.339186 -153.206958) (xy 333.357375 -153.184472) (xy 333.399391 -153.144732)
			(xy 333.446925 -153.11179) (xy 333.498888 -153.086402) (xy 333.554088 -153.06915) (xy 333.611259 -153.06043)
			(xy 333.640176 -153.059892) (xy 333.66743 -153.060354) (xy 333.721383 -153.068108) (xy 333.773684 -153.083462)
			(xy 333.823267 -153.106103) (xy 333.869123 -153.13557) (xy 333.910319 -153.171264) (xy 333.946015 -153.212457)
			(xy 333.975486 -153.258312) (xy 333.99813 -153.307893) (xy 334.013487 -153.360193) (xy 334.021245 -153.414146)
			(xy 334.021684 -153.4414) (xy 334.02115 -153.470317) (xy 334.012423 -153.527487) (xy 333.995168 -153.582686)
			(xy 333.969781 -153.63465) (xy 333.936844 -153.682187) (xy 333.89711 -153.724209) (xy 333.874618 -153.74239)
			(xy 333.865828 -153.749929) (xy 333.855649 -153.770702) (xy 333.85506 -153.782268) (xy 333.85506 -153.862532)
			(xy 333.855674 -153.87409) (xy 333.865851 -153.894854) (xy 333.874618 -153.90241) (xy 333.895402 -153.919163)
			(xy 333.932535 -153.957515) (xy 333.963958 -154.000669) (xy 333.989059 -154.047783) (xy 334.007346 -154.097935)
			(xy 334.018463 -154.150148) (xy 334.022193 -154.2034) (xy 334.018463 -154.256652) (xy 334.007346 -154.308865)
			(xy 333.989059 -154.359017) (xy 333.963958 -154.406131) (xy 333.932535 -154.449285) (xy 333.895402 -154.487637)
			(xy 333.874618 -154.50439) (xy 333.865828 -154.511929) (xy 333.855649 -154.532702) (xy 333.85506 -154.544268)
			(xy 333.85506 -154.624532) (xy 333.855674 -154.63609) (xy 333.865851 -154.656854) (xy 333.874618 -154.66441)
			(xy 333.895402 -154.681163) (xy 333.932535 -154.719515) (xy 333.963958 -154.762669) (xy 333.989059 -154.809783)
			(xy 334.007346 -154.859935) (xy 334.018463 -154.912148) (xy 334.022193 -154.9654) (xy 334.018463 -155.018652)
			(xy 334.007346 -155.070865) (xy 333.989059 -155.121017) (xy 333.963958 -155.168131) (xy 333.932535 -155.211285)
			(xy 333.895402 -155.249637) (xy 333.874618 -155.26639) (xy 333.865828 -155.273929) (xy 333.855649 -155.294702)
			(xy 333.85506 -155.306268) (xy 333.85506 -155.386532) (xy 333.855674 -155.39809) (xy 333.865851 -155.418854)
			(xy 333.874618 -155.42641) (xy 333.895402 -155.443163) (xy 333.932535 -155.481515) (xy 333.963958 -155.524669)
			(xy 333.989059 -155.571783) (xy 334.007346 -155.621935) (xy 334.018463 -155.674148) (xy 334.022193 -155.7274)
			(xy 334.018463 -155.780652) (xy 334.007346 -155.832865) (xy 333.989059 -155.883017) (xy 333.963958 -155.930131)
			(xy 333.932535 -155.973285) (xy 333.895402 -156.011637) (xy 333.874618 -156.02839) (xy 333.865828 -156.035929)
			(xy 333.855649 -156.056702) (xy 333.85506 -156.068268) (xy 333.85506 -156.148532) (xy 333.855674 -156.16009)
			(xy 333.865851 -156.180854) (xy 333.874618 -156.18841) (xy 333.897104 -156.2066) (xy 333.936846 -156.248616)
			(xy 333.969791 -156.29615) (xy 333.995183 -156.348112) (xy 334.012442 -156.403311) (xy 334.021172 -156.460483)
			(xy 334.021684 -156.4894) (xy 334.021221 -156.516652) (xy 334.013464 -156.570602) (xy 333.998107 -156.622898)
			(xy 333.975464 -156.672477) (xy 333.945996 -156.718328) (xy 333.910302 -156.759519) (xy 333.869109 -156.79521)
			(xy 333.823256 -156.824676) (xy 333.773676 -156.847316) (xy 333.721378 -156.862669) (xy 333.667428 -156.870422)
			(xy 333.640176 -156.870908) (xy 333.61126 -156.870372) (xy 333.554091 -156.861642) (xy 333.498893 -156.844386)
			(xy 333.446932 -156.818998) (xy 333.399396 -156.786061) (xy 333.357374 -156.746328) (xy 333.339186 -156.723842)
			(xy 333.331646 -156.71505) (xy 333.310876 -156.704856) (xy 333.299308 -156.704284) (xy 333.219044 -156.704284)
			(xy 333.207489 -156.704903) (xy 333.186737 -156.71509) (xy 333.179166 -156.723842) (xy 333.162413 -156.744625)
			(xy 333.124059 -156.781755) (xy 333.080905 -156.813177) (xy 333.033791 -156.838276) (xy 332.983639 -156.856562)
			(xy 332.931428 -156.867679) (xy 332.878176 -156.871409) (xy 332.824924 -156.867679) (xy 332.772713 -156.856562)
			(xy 332.722561 -156.838276) (xy 332.675447 -156.813177) (xy 332.632293 -156.781755) (xy 332.593939 -156.744625)
			(xy 332.577186 -156.723842) (xy 332.569646 -156.71505) (xy 332.548876 -156.704856) (xy 332.537308 -156.704284)
			(xy 332.457044 -156.704284) (xy 332.445489 -156.704903) (xy 332.424737 -156.71509) (xy 332.417166 -156.723842)
			(xy 332.410562 -156.73197) (xy 332.401672 -156.742892) (xy 332.397354 -156.770578) (xy 332.44155 -156.87929)
			(xy 332.463648 -156.896054) (xy 332.477618 -156.897578) (xy 332.505248 -156.901172) (xy 332.559133 -156.915343)
			(xy 332.610383 -156.937201) (xy 332.657908 -156.966282) (xy 332.700697 -157.001967) (xy 332.73784 -157.043497)
			(xy 332.768546 -157.089989) (xy 332.792162 -157.140453) (xy 332.808186 -157.193816) (xy 332.816277 -157.248942)
			(xy 332.816708 -157.2768) (xy 332.816174 -157.305717) (xy 332.807447 -157.362888) (xy 332.790193 -157.418088)
			(xy 332.764808 -157.470052) (xy 332.731871 -157.517591) (xy 332.692139 -157.559615) (xy 332.669642 -157.57779)
			(xy 332.660863 -157.585335) (xy 332.650699 -157.606106) (xy 332.650084 -157.617668) (xy 332.650084 -157.697932)
			(xy 332.650699 -157.709489) (xy 332.660879 -157.730249) (xy 332.669642 -157.73781) (xy 332.690425 -157.754563)
			(xy 332.727555 -157.792917) (xy 332.758977 -157.836071) (xy 332.784076 -157.883185) (xy 332.802362 -157.933337)
			(xy 332.813478 -157.985549) (xy 332.817208 -158.0388) (xy 334.466192 -158.0388) (xy 334.469922 -157.985549)
			(xy 334.481038 -157.933337) (xy 334.499324 -157.883185) (xy 334.524423 -157.836071) (xy 334.555845 -157.792917)
			(xy 334.592975 -157.754563) (xy 334.613758 -157.73781) (xy 334.622521 -157.730249) (xy 334.632701 -157.709489)
			(xy 334.633316 -157.697932) (xy 334.633316 -157.617668) (xy 334.632701 -157.606106) (xy 334.622537 -157.585335)
			(xy 334.613758 -157.57779) (xy 334.591261 -157.559615) (xy 334.551529 -157.517591) (xy 334.518592 -157.470052)
			(xy 334.493207 -157.418088) (xy 334.475953 -157.362888) (xy 334.467226 -157.305717) (xy 334.466692 -157.2768)
			(xy 334.467178 -157.249549) (xy 334.474934 -157.195601) (xy 334.490289 -157.143306) (xy 334.512931 -157.093729)
			(xy 334.542397 -157.047879) (xy 334.578088 -157.006688) (xy 334.619279 -156.970997) (xy 334.665129 -156.941531)
			(xy 334.714706 -156.918889) (xy 334.767001 -156.903534) (xy 334.820949 -156.895778) (xy 334.8482 -156.895292)
			(xy 334.877119 -156.895775) (xy 334.934293 -156.904507) (xy 334.989494 -156.921769) (xy 335.041456 -156.947167)
			(xy 335.088989 -156.980119) (xy 335.131003 -157.019868) (xy 335.14919 -157.042358) (xy 335.156751 -157.051121)
			(xy 335.177511 -157.061301) (xy 335.189068 -157.061916) (xy 335.269332 -157.061916) (xy 335.280894 -157.061301)
			(xy 335.301665 -157.051137) (xy 335.30921 -157.042358) (xy 335.327385 -157.019861) (xy 335.369409 -156.980129)
			(xy 335.416948 -156.947192) (xy 335.468912 -156.921807) (xy 335.524112 -156.904553) (xy 335.581283 -156.895826)
			(xy 335.6102 -156.895292) (xy 335.637451 -156.895778) (xy 335.691399 -156.903534) (xy 335.743694 -156.918889)
			(xy 335.793271 -156.941531) (xy 335.839121 -156.970997) (xy 335.880312 -157.006688) (xy 335.916003 -157.047879)
			(xy 335.945469 -157.093729) (xy 335.968111 -157.143306) (xy 335.983466 -157.195601) (xy 335.991222 -157.249549)
			(xy 335.991708 -157.2768) (xy 335.991225 -157.305719) (xy 335.982493 -157.362893) (xy 335.965231 -157.418094)
			(xy 335.939833 -157.470056) (xy 335.906881 -157.517589) (xy 335.867132 -157.559603) (xy 335.844642 -157.57779)
			(xy 335.835879 -157.585351) (xy 335.825699 -157.606111) (xy 335.825084 -157.617668) (xy 335.825084 -157.697932)
			(xy 335.825699 -157.709494) (xy 335.835863 -157.730265) (xy 335.844642 -157.73781) (xy 335.865425 -157.754563)
			(xy 335.902555 -157.792917) (xy 335.933977 -157.836071) (xy 335.959076 -157.883185) (xy 335.977362 -157.933337)
			(xy 335.988478 -157.985549) (xy 335.992208 -158.0388) (xy 335.988478 -158.092051) (xy 335.977362 -158.144263)
			(xy 335.959076 -158.194415) (xy 335.933977 -158.241529) (xy 335.902555 -158.284683) (xy 335.865425 -158.323037)
			(xy 335.844642 -158.33979) (xy 335.835879 -158.347351) (xy 335.825699 -158.368111) (xy 335.825084 -158.379668)
			(xy 335.825084 -158.459932) (xy 335.825699 -158.471494) (xy 335.835863 -158.492265) (xy 335.844642 -158.49981)
			(xy 335.867139 -158.517985) (xy 335.906871 -158.560009) (xy 335.939808 -158.607548) (xy 335.965193 -158.659512)
			(xy 335.982447 -158.714712) (xy 335.991174 -158.771883) (xy 335.991708 -158.8008) (xy 335.991222 -158.828051)
			(xy 335.983466 -158.881999) (xy 335.968111 -158.934294) (xy 335.945469 -158.983871) (xy 335.916003 -159.029721)
			(xy 335.880312 -159.070912) (xy 335.839121 -159.106603) (xy 335.793271 -159.136069) (xy 335.743694 -159.158711)
			(xy 335.691399 -159.174066) (xy 335.637451 -159.181822) (xy 335.6102 -159.182308) (xy 335.581281 -159.181825)
			(xy 335.524107 -159.173093) (xy 335.468906 -159.155831) (xy 335.416944 -159.130433) (xy 335.369411 -159.097481)
			(xy 335.327397 -159.057732) (xy 335.30921 -159.035242) (xy 335.301649 -159.026479) (xy 335.280889 -159.016299)
			(xy 335.269332 -159.015684) (xy 335.189068 -159.015684) (xy 335.177506 -159.016299) (xy 335.156735 -159.026463)
			(xy 335.14919 -159.035242) (xy 335.131015 -159.057739) (xy 335.088991 -159.097471) (xy 335.041452 -159.130408)
			(xy 334.989488 -159.155793) (xy 334.934288 -159.173047) (xy 334.877117 -159.181774) (xy 334.8482 -159.182308)
			(xy 334.820949 -159.181822) (xy 334.767001 -159.174066) (xy 334.714706 -159.158711) (xy 334.665129 -159.136069)
			(xy 334.619279 -159.106603) (xy 334.578088 -159.070912) (xy 334.542397 -159.029721) (xy 334.512931 -158.983871)
			(xy 334.490289 -158.934294) (xy 334.474934 -158.881999) (xy 334.467178 -158.828051) (xy 334.466692 -158.8008)
			(xy 334.467175 -158.771881) (xy 334.475907 -158.714707) (xy 334.493169 -158.659506) (xy 334.518567 -158.607544)
			(xy 334.551519 -158.560011) (xy 334.591268 -158.517997) (xy 334.613758 -158.49981) (xy 334.622521 -158.492249)
			(xy 334.632701 -158.471489) (xy 334.633316 -158.459932) (xy 334.633316 -158.379668) (xy 334.632701 -158.368106)
			(xy 334.622537 -158.347335) (xy 334.613758 -158.33979) (xy 334.592975 -158.323037) (xy 334.555845 -158.284683)
			(xy 334.524423 -158.241529) (xy 334.499324 -158.194415) (xy 334.481038 -158.144263) (xy 334.469922 -158.092051)
			(xy 334.466192 -158.0388) (xy 332.817208 -158.0388) (xy 332.813478 -158.092051) (xy 332.802362 -158.144263)
			(xy 332.784076 -158.194415) (xy 332.758977 -158.241529) (xy 332.727555 -158.284683) (xy 332.690425 -158.323037)
			(xy 332.669642 -158.33979) (xy 332.660863 -158.347335) (xy 332.650699 -158.368106) (xy 332.650084 -158.379668)
			(xy 332.650084 -158.459932) (xy 332.650699 -158.471489) (xy 332.660879 -158.492249) (xy 332.669642 -158.49981)
			(xy 332.692132 -158.517997) (xy 332.731881 -158.560011) (xy 332.764833 -158.607544) (xy 332.790231 -158.659506)
			(xy 332.807493 -158.714707) (xy 332.816225 -158.771881) (xy 332.816708 -158.8008) (xy 332.816222 -158.828051)
			(xy 332.808466 -158.881999) (xy 332.793111 -158.934294) (xy 332.770469 -158.983871) (xy 332.741003 -159.029721)
			(xy 332.705312 -159.070912) (xy 332.664121 -159.106603) (xy 332.618271 -159.136069) (xy 332.568694 -159.158711)
			(xy 332.516399 -159.174066) (xy 332.462451 -159.181822) (xy 332.4352 -159.182308) (xy 332.417928 -159.1818)
			(xy 332.40345 -159.181292) (xy 332.378558 -159.195008) (xy 332.326996 -159.286702) (xy 332.322733 -159.29503)
			(xy 332.319932 -159.313511) (xy 332.323964 -159.331763) (xy 332.328774 -159.339788) (xy 332.350618 -159.3723)
			(xy 332.354957 -159.378342) (xy 332.366445 -159.387781) (xy 332.373224 -159.390842) (xy 332.603602 -159.487616)
			(xy 332.608283 -159.489459) (xy 332.618132 -159.491502) (xy 332.62316 -159.49168)
		)
		(stroke
			(width 0)
			(type solid)
		)
		(fill yes)
		(layer "In4.Cu")
		(net "GND")
	)
	(gr_poly
		(pts
			(xy 225.78822 -79.237078) (xy 225.795823 -79.23556) (xy 225.809651 -79.228567) (xy 225.815398 -79.223362)
			(xy 226.634294 -78.404466) (xy 226.641136 -78.397066) (xy 226.648859 -78.378468) (xy 226.64928 -78.368398)
			(xy 226.64928 -63.043562) (xy 226.64166 -63.024766) (xy 226.634294 -63.017654) (xy 221.411546 -57.794906)
			(xy 221.404145 -57.788067) (xy 221.385547 -57.780352) (xy 221.375478 -57.77992) (xy 215.649048 -57.77992)
			(xy 215.639022 -57.780332) (xy 215.620492 -57.787994) (xy 215.60631 -57.802169) (xy 215.598637 -57.820694)
			(xy 215.598248 -57.83072) (xy 215.598248 -58.74258) (xy 215.598297 -58.746249) (xy 215.599322 -58.753515)
			(xy 215.60028 -58.757058) (xy 215.606376 -58.777124) (xy 215.609932 -58.782966) (xy 215.623531 -58.80575)
			(xy 215.644993 -58.854276) (xy 215.650655 -58.874152) (xy 219.970348 -58.874152) (xy 219.974419 -58.81853)
			(xy 219.986545 -58.764093) (xy 220.006468 -58.712002) (xy 220.033764 -58.663367) (xy 220.06785 -58.619224)
			(xy 220.107999 -58.580515) (xy 220.153357 -58.548064) (xy 220.202957 -58.522563) (xy 220.255741 -58.504556)
			(xy 220.310584 -58.494426) (xy 220.366318 -58.492389) (xy 220.421755 -58.498489) (xy 220.475712 -58.512595)
			(xy 220.527041 -58.534407) (xy 220.574647 -58.563461) (xy 220.617515 -58.599136) (xy 220.654732 -58.640673)
			(xy 220.685505 -58.687186) (xy 220.709177 -58.737683) (xy 220.725245 -58.79109) (xy 220.733365 -58.846266)
			(xy 220.733874 -58.874152) (xy 220.733365 -58.902038) (xy 220.725245 -58.957214) (xy 220.709177 -59.010621)
			(xy 220.685505 -59.061118) (xy 220.654732 -59.107631) (xy 220.617515 -59.149168) (xy 220.574647 -59.184843)
			(xy 220.527041 -59.213897) (xy 220.475712 -59.235709) (xy 220.421755 -59.249815) (xy 220.366318 -59.255915)
			(xy 220.310584 -59.253878) (xy 220.255741 -59.243748) (xy 220.202957 -59.225741) (xy 220.153357 -59.20024)
			(xy 220.107999 -59.167789) (xy 220.06785 -59.12908) (xy 220.033764 -59.084937) (xy 220.006468 -59.036302)
			(xy 219.986545 -58.984211) (xy 219.974419 -58.929774) (xy 219.970348 -58.874152) (xy 215.650655 -58.874152)
			(xy 215.65953 -58.905307) (xy 215.666863 -58.957858) (xy 215.667336 -58.984388) (xy 215.66685 -59.011657)
			(xy 215.659088 -59.065641) (xy 215.643723 -59.117971) (xy 215.621066 -59.167581) (xy 215.59158 -59.213462)
			(xy 215.555865 -59.254679) (xy 215.514648 -59.290394) (xy 215.468767 -59.31988) (xy 215.419157 -59.342537)
			(xy 215.366827 -59.357902) (xy 215.312843 -59.365664) (xy 215.258305 -59.365664) (xy 215.204321 -59.357902)
			(xy 215.151991 -59.342537) (xy 215.102381 -59.31988) (xy 215.0565 -59.290394) (xy 215.015283 -59.254679)
			(xy 214.979568 -59.213462) (xy 214.950082 -59.167581) (xy 214.927425 -59.117971) (xy 214.91206 -59.065641)
			(xy 214.904298 -59.011657) (xy 214.903812 -58.984388) (xy 214.904267 -58.957857) (xy 214.911611 -58.905307)
			(xy 214.926155 -58.854278) (xy 214.94762 -58.805753) (xy 214.961216 -58.782966) (xy 214.964772 -58.777124)
			(xy 214.970868 -58.757058) (xy 214.971834 -58.753517) (xy 214.972857 -58.74625) (xy 214.9729 -58.74258)
			(xy 214.9729 -58.53557) (xy 214.972323 -58.520604) (xy 214.963553 -58.49198) (xy 214.946864 -58.467127)
			(xy 214.923688 -58.448178) (xy 214.896015 -58.43676) (xy 214.86622 -58.433852) (xy 214.836861 -58.439704)
			(xy 214.810459 -58.453815) (xy 214.799418 -58.463942) (xy 211.57819 -61.68517) (xy 211.571345 -61.692568)
			(xy 211.563622 -61.711167) (xy 211.563204 -61.721238) (xy 211.563204 -66.562478) (xy 216.490548 -66.562478)
			(xy 216.494619 -66.506856) (xy 216.506745 -66.452419) (xy 216.526668 -66.400328) (xy 216.553964 -66.351693)
			(xy 216.58805 -66.30755) (xy 216.628199 -66.268841) (xy 216.673557 -66.23639) (xy 216.723157 -66.210889)
			(xy 216.775941 -66.192882) (xy 216.830784 -66.182752) (xy 216.886518 -66.180715) (xy 216.941955 -66.186815)
			(xy 216.995912 -66.200921) (xy 217.047241 -66.222733) (xy 217.094847 -66.251787) (xy 217.137715 -66.287462)
			(xy 217.174932 -66.328999) (xy 217.205705 -66.375512) (xy 217.229377 -66.426009) (xy 217.245445 -66.479416)
			(xy 217.253565 -66.534592) (xy 217.254074 -66.562478) (xy 217.253565 -66.590364) (xy 217.245445 -66.64554)
			(xy 217.229377 -66.698947) (xy 217.205705 -66.749444) (xy 217.174932 -66.795957) (xy 217.137715 -66.837494)
			(xy 217.094847 -66.873169) (xy 217.047241 -66.902223) (xy 216.995912 -66.924035) (xy 216.941955 -66.938141)
			(xy 216.886518 -66.944241) (xy 216.830784 -66.942204) (xy 216.775941 -66.932074) (xy 216.723157 -66.914067)
			(xy 216.673557 -66.888566) (xy 216.628199 -66.856115) (xy 216.58805 -66.817406) (xy 216.553964 -66.773263)
			(xy 216.526668 -66.724628) (xy 216.506745 -66.672537) (xy 216.494619 -66.6181) (xy 216.490548 -66.562478)
			(xy 211.563204 -66.562478) (xy 211.563204 -67.79895) (xy 211.563434 -67.806659) (xy 211.567958 -67.821396)
			(xy 211.572094 -67.827906) (xy 211.591398 -67.855592) (xy 211.60232 -67.864482) (xy 211.609432 -67.86753)
			(xy 211.635023 -67.878823) (xy 211.682866 -67.907804) (xy 211.725962 -67.943462) (xy 211.763388 -67.985032)
			(xy 211.79434 -68.031623) (xy 211.818156 -68.082236) (xy 211.834323 -68.135784) (xy 211.842495 -68.191119)
			(xy 211.842496 -68.230496) (xy 212.039452 -68.230496) (xy 212.043523 -68.174874) (xy 212.055649 -68.120437)
			(xy 212.075572 -68.068346) (xy 212.102868 -68.019711) (xy 212.136954 -67.975568) (xy 212.177103 -67.936859)
			(xy 212.222461 -67.904408) (xy 212.272061 -67.878907) (xy 212.324845 -67.8609) (xy 212.379688 -67.85077)
			(xy 212.435422 -67.848733) (xy 212.490859 -67.854833) (xy 212.544816 -67.868939) (xy 212.596145 -67.890751)
			(xy 212.643751 -67.919805) (xy 212.685319 -67.954398) (xy 220.014036 -67.954398) (xy 220.018107 -67.898776)
			(xy 220.030233 -67.844339) (xy 220.050156 -67.792248) (xy 220.077452 -67.743613) (xy 220.111538 -67.69947)
			(xy 220.151687 -67.660761) (xy 220.197045 -67.62831) (xy 220.246645 -67.602809) (xy 220.299429 -67.584802)
			(xy 220.354272 -67.574672) (xy 220.410006 -67.572635) (xy 220.465443 -67.578735) (xy 220.5194 -67.592841)
			(xy 220.570729 -67.614653) (xy 220.618335 -67.643707) (xy 220.661203 -67.679382) (xy 220.69842 -67.720919)
			(xy 220.729193 -67.767432) (xy 220.752865 -67.817929) (xy 220.768933 -67.871336) (xy 220.776297 -67.921378)
			(xy 223.481898 -67.921378) (xy 223.485969 -67.865756) (xy 223.498095 -67.811319) (xy 223.518018 -67.759228)
			(xy 223.545314 -67.710593) (xy 223.5794 -67.66645) (xy 223.619549 -67.627741) (xy 223.664907 -67.59529)
			(xy 223.714507 -67.569789) (xy 223.767291 -67.551782) (xy 223.822134 -67.541652) (xy 223.877868 -67.539615)
			(xy 223.933305 -67.545715) (xy 223.987262 -67.559821) (xy 224.038591 -67.581633) (xy 224.086197 -67.610687)
			(xy 224.129065 -67.646362) (xy 224.166282 -67.687899) (xy 224.197055 -67.734412) (xy 224.220727 -67.784909)
			(xy 224.236795 -67.838316) (xy 224.244915 -67.893492) (xy 224.245424 -67.921378) (xy 224.244915 -67.949264)
			(xy 224.236795 -68.00444) (xy 224.220727 -68.057847) (xy 224.197055 -68.108344) (xy 224.166282 -68.154857)
			(xy 224.129065 -68.196394) (xy 224.086197 -68.232069) (xy 224.038591 -68.261123) (xy 223.987262 -68.282935)
			(xy 223.933305 -68.297041) (xy 223.877868 -68.303141) (xy 223.822134 -68.301104) (xy 223.767291 -68.290974)
			(xy 223.714507 -68.272967) (xy 223.664907 -68.247466) (xy 223.619549 -68.215015) (xy 223.5794 -68.176306)
			(xy 223.545314 -68.132163) (xy 223.518018 -68.083528) (xy 223.498095 -68.031437) (xy 223.485969 -67.977)
			(xy 223.481898 -67.921378) (xy 220.776297 -67.921378) (xy 220.777053 -67.926512) (xy 220.777562 -67.954398)
			(xy 220.777053 -67.982284) (xy 220.768933 -68.03746) (xy 220.752865 -68.090867) (xy 220.729193 -68.141364)
			(xy 220.69842 -68.187877) (xy 220.661203 -68.229414) (xy 220.618335 -68.265089) (xy 220.570729 -68.294143)
			(xy 220.5194 -68.315955) (xy 220.465443 -68.330061) (xy 220.410006 -68.336161) (xy 220.354272 -68.334124)
			(xy 220.299429 -68.323994) (xy 220.246645 -68.305987) (xy 220.197045 -68.280486) (xy 220.151687 -68.248035)
			(xy 220.111538 -68.209326) (xy 220.077452 -68.165183) (xy 220.050156 -68.116548) (xy 220.030233 -68.064457)
			(xy 220.018107 -68.01002) (xy 220.014036 -67.954398) (xy 212.685319 -67.954398) (xy 212.686619 -67.95548)
			(xy 212.723836 -67.997017) (xy 212.754609 -68.04353) (xy 212.778281 -68.094027) (xy 212.794349 -68.147434)
			(xy 212.802469 -68.20261) (xy 212.802978 -68.230496) (xy 212.802469 -68.258382) (xy 212.794349 -68.313558)
			(xy 212.78625 -68.340478) (xy 216.437716 -68.340478) (xy 216.441787 -68.284856) (xy 216.453913 -68.230419)
			(xy 216.473836 -68.178328) (xy 216.501132 -68.129693) (xy 216.535218 -68.08555) (xy 216.575367 -68.046841)
			(xy 216.620725 -68.01439) (xy 216.670325 -67.988889) (xy 216.723109 -67.970882) (xy 216.777952 -67.960752)
			(xy 216.833686 -67.958715) (xy 216.889123 -67.964815) (xy 216.94308 -67.978921) (xy 216.994409 -68.000733)
			(xy 217.042015 -68.029787) (xy 217.084883 -68.065462) (xy 217.1221 -68.106999) (xy 217.152873 -68.153512)
			(xy 217.176545 -68.204009) (xy 217.192613 -68.257416) (xy 217.200733 -68.312592) (xy 217.201242 -68.340478)
			(xy 217.200733 -68.368364) (xy 217.192613 -68.42354) (xy 217.176545 -68.476947) (xy 217.152873 -68.527444)
			(xy 217.1221 -68.573957) (xy 217.084883 -68.615494) (xy 217.042015 -68.651169) (xy 216.994409 -68.680223)
			(xy 216.94308 -68.702035) (xy 216.889123 -68.716141) (xy 216.833686 -68.722241) (xy 216.777952 -68.720204)
			(xy 216.723109 -68.710074) (xy 216.670325 -68.692067) (xy 216.620725 -68.666566) (xy 216.575367 -68.634115)
			(xy 216.535218 -68.595406) (xy 216.501132 -68.551263) (xy 216.473836 -68.502628) (xy 216.453913 -68.450537)
			(xy 216.441787 -68.3961) (xy 216.437716 -68.340478) (xy 212.78625 -68.340478) (xy 212.778281 -68.366965)
			(xy 212.754609 -68.417462) (xy 212.723836 -68.463975) (xy 212.686619 -68.505512) (xy 212.643751 -68.541187)
			(xy 212.596145 -68.570241) (xy 212.544816 -68.592053) (xy 212.490859 -68.606159) (xy 212.435422 -68.612259)
			(xy 212.379688 -68.610222) (xy 212.324845 -68.600092) (xy 212.272061 -68.582085) (xy 212.222461 -68.556584)
			(xy 212.177103 -68.524133) (xy 212.136954 -68.485424) (xy 212.102868 -68.441281) (xy 212.075572 -68.392646)
			(xy 212.055649 -68.340555) (xy 212.043523 -68.286118) (xy 212.039452 -68.230496) (xy 211.842496 -68.230496)
			(xy 211.842497 -68.247055) (xy 211.834328 -68.302391) (xy 211.818165 -68.35594) (xy 211.794353 -68.406554)
			(xy 211.763404 -68.453147) (xy 211.725981 -68.49472) (xy 211.682887 -68.530381) (xy 211.635046 -68.559365)
			(xy 211.609432 -68.570602) (xy 211.60232 -68.57365) (xy 211.591398 -68.58254) (xy 211.572094 -68.610226)
			(xy 211.567957 -68.616736) (xy 211.563422 -68.631472) (xy 211.563204 -68.639182) (xy 211.563204 -69.368162)
			(xy 218.846398 -69.368162) (xy 218.850469 -69.31254) (xy 218.862595 -69.258103) (xy 218.882518 -69.206012)
			(xy 218.909814 -69.157377) (xy 218.9439 -69.113234) (xy 218.984049 -69.074525) (xy 219.029407 -69.042074)
			(xy 219.079007 -69.016573) (xy 219.131791 -68.998566) (xy 219.186634 -68.988436) (xy 219.242368 -68.986399)
			(xy 219.297805 -68.992499) (xy 219.351762 -69.006605) (xy 219.403091 -69.028417) (xy 219.450697 -69.057471)
			(xy 219.493565 -69.093146) (xy 219.530782 -69.134683) (xy 219.561555 -69.181196) (xy 219.585227 -69.231693)
			(xy 219.601295 -69.2851) (xy 219.609415 -69.340276) (xy 219.609924 -69.368162) (xy 220.116398 -69.368162)
			(xy 220.120469 -69.31254) (xy 220.132595 -69.258103) (xy 220.152518 -69.206012) (xy 220.179814 -69.157377)
			(xy 220.2139 -69.113234) (xy 220.254049 -69.074525) (xy 220.299407 -69.042074) (xy 220.349007 -69.016573)
			(xy 220.401791 -68.998566) (xy 220.456634 -68.988436) (xy 220.512368 -68.986399) (xy 220.567805 -68.992499)
			(xy 220.621762 -69.006605) (xy 220.673091 -69.028417) (xy 220.720697 -69.057471) (xy 220.763565 -69.093146)
			(xy 220.800782 -69.134683) (xy 220.831555 -69.181196) (xy 220.855227 -69.231693) (xy 220.871295 -69.2851)
			(xy 220.879415 -69.340276) (xy 220.879924 -69.368162) (xy 220.879415 -69.396048) (xy 220.871295 -69.451224)
			(xy 220.855227 -69.504631) (xy 220.831555 -69.555128) (xy 220.800782 -69.601641) (xy 220.763565 -69.643178)
			(xy 220.720697 -69.678853) (xy 220.673091 -69.707907) (xy 220.648332 -69.718428) (xy 224.155508 -69.718428)
			(xy 224.155975 -69.691825) (xy 224.163353 -69.639132) (xy 224.177984 -69.587977) (xy 224.199583 -69.539352)
			(xy 224.227732 -69.494201) (xy 224.261884 -69.453402) (xy 224.301375 -69.417745) (xy 224.323148 -69.402452)
			(xy 224.334654 -69.394148) (xy 224.352868 -69.372401) (xy 224.36439 -69.346479) (xy 224.36833 -69.318388)
			(xy 224.364383 -69.290297) (xy 224.352855 -69.264378) (xy 224.334636 -69.242635) (xy 224.323148 -69.234304)
			(xy 224.301373 -69.219016) (xy 224.261893 -69.183349) (xy 224.22775 -69.142544) (xy 224.199605 -69.097393)
			(xy 224.178003 -69.048771) (xy 224.163364 -68.997619) (xy 224.155971 -68.94493) (xy 224.155508 -68.918328)
			(xy 224.155994 -68.891077) (xy 224.16375 -68.837129) (xy 224.179105 -68.784834) (xy 224.201747 -68.735257)
			(xy 224.231213 -68.689407) (xy 224.266904 -68.648216) (xy 224.308095 -68.612525) (xy 224.353945 -68.583059)
			(xy 224.403522 -68.560417) (xy 224.455817 -68.545062) (xy 224.509765 -68.537306) (xy 224.564267 -68.537306)
			(xy 224.618215 -68.545062) (xy 224.67051 -68.560417) (xy 224.720087 -68.583059) (xy 224.765937 -68.612525)
			(xy 224.807128 -68.648216) (xy 224.842819 -68.689407) (xy 224.872285 -68.735257) (xy 224.894927 -68.784834)
			(xy 224.910282 -68.837129) (xy 224.918038 -68.891077) (xy 224.918524 -68.918328) (xy 224.918054 -68.944932)
			(xy 224.91068 -68.997625) (xy 224.896052 -69.048782) (xy 224.874454 -69.097408) (xy 224.846305 -69.142559)
			(xy 224.812152 -69.183358) (xy 224.772658 -69.219012) (xy 224.750884 -69.234304) (xy 224.739427 -69.242667)
			(xy 224.721227 -69.264405) (xy 224.709711 -69.290312) (xy 224.705769 -69.318388) (xy 224.709704 -69.346464)
			(xy 224.721214 -69.372374) (xy 224.739408 -69.394117) (xy 224.750884 -69.402452) (xy 224.772646 -69.417758)
			(xy 224.812124 -69.453423) (xy 224.846267 -69.494225) (xy 224.874413 -69.539373) (xy 224.896017 -69.587992)
			(xy 224.91066 -69.639141) (xy 224.918058 -69.691827) (xy 224.918524 -69.718428) (xy 224.918038 -69.745679)
			(xy 224.910282 -69.799627) (xy 224.894927 -69.851922) (xy 224.872285 -69.901499) (xy 224.842819 -69.947349)
			(xy 224.807128 -69.98854) (xy 224.765937 -70.024231) (xy 224.720087 -70.053697) (xy 224.67051 -70.076339)
			(xy 224.618215 -70.091694) (xy 224.564267 -70.09945) (xy 224.509765 -70.09945) (xy 224.455817 -70.091694)
			(xy 224.403522 -70.076339) (xy 224.353945 -70.053697) (xy 224.308095 -70.024231) (xy 224.266904 -69.98854)
			(xy 224.231213 -69.947349) (xy 224.201747 -69.901499) (xy 224.179105 -69.851922) (xy 224.16375 -69.799627)
			(xy 224.155994 -69.745679) (xy 224.155508 -69.718428) (xy 220.648332 -69.718428) (xy 220.621762 -69.729719)
			(xy 220.567805 -69.743825) (xy 220.512368 -69.749925) (xy 220.456634 -69.747888) (xy 220.401791 -69.737758)
			(xy 220.349007 -69.719751) (xy 220.299407 -69.69425) (xy 220.254049 -69.661799) (xy 220.2139 -69.62309)
			(xy 220.179814 -69.578947) (xy 220.152518 -69.530312) (xy 220.132595 -69.478221) (xy 220.120469 -69.423784)
			(xy 220.116398 -69.368162) (xy 219.609924 -69.368162) (xy 219.609415 -69.396048) (xy 219.601295 -69.451224)
			(xy 219.585227 -69.504631) (xy 219.561555 -69.555128) (xy 219.530782 -69.601641) (xy 219.493565 -69.643178)
			(xy 219.450697 -69.678853) (xy 219.403091 -69.707907) (xy 219.351762 -69.729719) (xy 219.297805 -69.743825)
			(xy 219.242368 -69.749925) (xy 219.186634 -69.747888) (xy 219.131791 -69.737758) (xy 219.079007 -69.719751)
			(xy 219.029407 -69.69425) (xy 218.984049 -69.661799) (xy 218.9439 -69.62309) (xy 218.909814 -69.578947)
			(xy 218.882518 -69.530312) (xy 218.862595 -69.478221) (xy 218.850469 -69.423784) (xy 218.846398 -69.368162)
			(xy 211.563204 -69.368162) (xy 211.563204 -70.024244) (xy 212.007956 -70.024244) (xy 212.012027 -69.968622)
			(xy 212.024153 -69.914185) (xy 212.044076 -69.862094) (xy 212.071372 -69.813459) (xy 212.105458 -69.769316)
			(xy 212.145607 -69.730607) (xy 212.190965 -69.698156) (xy 212.240565 -69.672655) (xy 212.293349 -69.654648)
			(xy 212.348192 -69.644518) (xy 212.403926 -69.642481) (xy 212.459363 -69.648581) (xy 212.51332 -69.662687)
			(xy 212.564649 -69.684499) (xy 212.612255 -69.713553) (xy 212.655123 -69.749228) (xy 212.69234 -69.790765)
			(xy 212.723113 -69.837278) (xy 212.746785 -69.887775) (xy 212.762853 -69.941182) (xy 212.770973 -69.996358)
			(xy 212.771482 -70.024244) (xy 212.770973 -70.05213) (xy 212.762853 -70.107306) (xy 212.746785 -70.160713)
			(xy 212.723113 -70.21121) (xy 212.69234 -70.257723) (xy 212.655123 -70.29926) (xy 212.612255 -70.334935)
			(xy 212.564649 -70.363989) (xy 212.51332 -70.385801) (xy 212.459363 -70.399907) (xy 212.403926 -70.406007)
			(xy 212.348192 -70.40397) (xy 212.293349 -70.39384) (xy 212.240565 -70.375833) (xy 212.190965 -70.350332)
			(xy 212.145607 -70.317881) (xy 212.105458 -70.279172) (xy 212.071372 -70.235029) (xy 212.044076 -70.186394)
			(xy 212.024153 -70.134303) (xy 212.012027 -70.079866) (xy 212.007956 -70.024244) (xy 211.563204 -70.024244)
			(xy 211.563204 -71.238364) (xy 211.563639 -71.248429) (xy 211.57137 -71.267016) (xy 211.57819 -71.274432)
			(xy 211.784214 -71.480426) (xy 214.549988 -71.480426) (xy 214.554059 -71.424804) (xy 214.566185 -71.370367)
			(xy 214.586108 -71.318276) (xy 214.613404 -71.269641) (xy 214.64749 -71.225498) (xy 214.687639 -71.186789)
			(xy 214.732997 -71.154338) (xy 214.782597 -71.128837) (xy 214.835381 -71.11083) (xy 214.890224 -71.1007)
			(xy 214.945958 -71.098663) (xy 215.001395 -71.104763) (xy 215.055352 -71.118869) (xy 215.058611 -71.120254)
			(xy 218.878402 -71.120254) (xy 218.882473 -71.064632) (xy 218.894599 -71.010195) (xy 218.914522 -70.958104)
			(xy 218.941818 -70.909469) (xy 218.975904 -70.865326) (xy 219.016053 -70.826617) (xy 219.061411 -70.794166)
			(xy 219.111011 -70.768665) (xy 219.163795 -70.750658) (xy 219.218638 -70.740528) (xy 219.274372 -70.738491)
			(xy 219.329809 -70.744591) (xy 219.383766 -70.758697) (xy 219.435095 -70.780509) (xy 219.455313 -70.792848)
			(xy 224.154744 -70.792848) (xy 224.158817 -70.737189) (xy 224.170952 -70.682716) (xy 224.190888 -70.63059)
			(xy 224.218202 -70.581922) (xy 224.25231 -70.53775) (xy 224.292487 -70.499015) (xy 224.337875 -70.466543)
			(xy 224.387507 -70.441025) (xy 224.440327 -70.423006) (xy 224.495206 -70.412869) (xy 224.550977 -70.410831)
			(xy 224.606451 -70.416934) (xy 224.660444 -70.43105) (xy 224.711807 -70.452877) (xy 224.759445 -70.48195)
			(xy 224.802341 -70.517649) (xy 224.839583 -70.559213) (xy 224.870377 -70.605757) (xy 224.894065 -70.656288)
			(xy 224.910143 -70.70973) (xy 224.918269 -70.764944) (xy 224.918778 -70.792848) (xy 224.918269 -70.820752)
			(xy 224.910143 -70.875966) (xy 224.894065 -70.929408) (xy 224.870377 -70.979939) (xy 224.839583 -71.026483)
			(xy 224.802341 -71.068047) (xy 224.759445 -71.103746) (xy 224.711807 -71.132819) (xy 224.660444 -71.154646)
			(xy 224.606451 -71.168762) (xy 224.550977 -71.174865) (xy 224.495206 -71.172827) (xy 224.440327 -71.16269)
			(xy 224.387507 -71.144671) (xy 224.337875 -71.119153) (xy 224.292487 -71.086681) (xy 224.25231 -71.047946)
			(xy 224.218202 -71.003774) (xy 224.190888 -70.955106) (xy 224.170952 -70.90298) (xy 224.158817 -70.848507)
			(xy 224.154744 -70.792848) (xy 219.455313 -70.792848) (xy 219.482701 -70.809563) (xy 219.525569 -70.845238)
			(xy 219.562786 -70.886775) (xy 219.593559 -70.933288) (xy 219.617231 -70.983785) (xy 219.633299 -71.037192)
			(xy 219.641419 -71.092368) (xy 219.641928 -71.120254) (xy 219.641419 -71.14814) (xy 219.633299 -71.203316)
			(xy 219.617231 -71.256723) (xy 219.593559 -71.30722) (xy 219.562786 -71.353733) (xy 219.525569 -71.39527)
			(xy 219.482701 -71.430945) (xy 219.435095 -71.459999) (xy 219.383766 -71.481811) (xy 219.329809 -71.495917)
			(xy 219.274372 -71.502017) (xy 219.218638 -71.49998) (xy 219.163795 -71.48985) (xy 219.111011 -71.471843)
			(xy 219.061411 -71.446342) (xy 219.016053 -71.413891) (xy 218.975904 -71.375182) (xy 218.941818 -71.331039)
			(xy 218.914522 -71.282404) (xy 218.894599 -71.230313) (xy 218.882473 -71.175876) (xy 218.878402 -71.120254)
			(xy 215.058611 -71.120254) (xy 215.106681 -71.140681) (xy 215.154287 -71.169735) (xy 215.197155 -71.20541)
			(xy 215.234372 -71.246947) (xy 215.265145 -71.29346) (xy 215.288817 -71.343957) (xy 215.304885 -71.397364)
			(xy 215.313005 -71.45254) (xy 215.313514 -71.480426) (xy 215.313005 -71.508312) (xy 215.304885 -71.563488)
			(xy 215.288817 -71.616895) (xy 215.265145 -71.667392) (xy 215.234372 -71.713905) (xy 215.197155 -71.755442)
			(xy 215.154287 -71.791117) (xy 215.106681 -71.820171) (xy 215.055352 -71.841983) (xy 215.001395 -71.856089)
			(xy 214.945958 -71.862189) (xy 214.890224 -71.860152) (xy 214.835381 -71.850022) (xy 214.782597 -71.832015)
			(xy 214.732997 -71.806514) (xy 214.687639 -71.774063) (xy 214.64749 -71.735354) (xy 214.613404 -71.691211)
			(xy 214.586108 -71.642576) (xy 214.566185 -71.590485) (xy 214.554059 -71.536048) (xy 214.549988 -71.480426)
			(xy 211.784214 -71.480426) (xy 212.649463 -72.34555) (xy 222.48952 -72.34555) (xy 222.493593 -72.289891)
			(xy 222.505728 -72.235418) (xy 222.525664 -72.183292) (xy 222.552978 -72.134624) (xy 222.587086 -72.090452)
			(xy 222.627263 -72.051717) (xy 222.672651 -72.019245) (xy 222.722283 -71.993727) (xy 222.775103 -71.975708)
			(xy 222.829982 -71.965571) (xy 222.885753 -71.963533) (xy 222.941227 -71.969636) (xy 222.99522 -71.983752)
			(xy 223.046583 -72.005579) (xy 223.094221 -72.034652) (xy 223.137117 -72.070351) (xy 223.174359 -72.111915)
			(xy 223.205153 -72.158459) (xy 223.228841 -72.20899) (xy 223.234468 -72.227694) (xy 224.601784 -72.227694)
			(xy 224.605857 -72.172035) (xy 224.617992 -72.117562) (xy 224.637928 -72.065436) (xy 224.665242 -72.016768)
			(xy 224.69935 -71.972596) (xy 224.739527 -71.933861) (xy 224.784915 -71.901389) (xy 224.834547 -71.875871)
			(xy 224.887367 -71.857852) (xy 224.942246 -71.847715) (xy 224.998017 -71.845677) (xy 225.053491 -71.85178)
			(xy 225.107484 -71.865896) (xy 225.158847 -71.887723) (xy 225.206485 -71.916796) (xy 225.249381 -71.952495)
			(xy 225.286623 -71.994059) (xy 225.317417 -72.040603) (xy 225.341105 -72.091134) (xy 225.357183 -72.144576)
			(xy 225.365309 -72.19979) (xy 225.365818 -72.227694) (xy 225.365309 -72.255598) (xy 225.357183 -72.310812)
			(xy 225.341105 -72.364254) (xy 225.317417 -72.414785) (xy 225.286623 -72.461329) (xy 225.249381 -72.502893)
			(xy 225.206485 -72.538592) (xy 225.158847 -72.567665) (xy 225.107484 -72.589492) (xy 225.053491 -72.603608)
			(xy 224.998017 -72.609711) (xy 224.942246 -72.607673) (xy 224.887367 -72.597536) (xy 224.834547 -72.579517)
			(xy 224.784915 -72.553999) (xy 224.739527 -72.521527) (xy 224.69935 -72.482792) (xy 224.665242 -72.43862)
			(xy 224.637928 -72.389952) (xy 224.617992 -72.337826) (xy 224.605857 -72.283353) (xy 224.601784 -72.227694)
			(xy 223.234468 -72.227694) (xy 223.244919 -72.262432) (xy 223.253045 -72.317646) (xy 223.253554 -72.34555)
			(xy 223.253045 -72.373454) (xy 223.244919 -72.428668) (xy 223.228841 -72.48211) (xy 223.205153 -72.532641)
			(xy 223.174359 -72.579185) (xy 223.137117 -72.620749) (xy 223.094221 -72.656448) (xy 223.046583 -72.685521)
			(xy 222.99522 -72.707348) (xy 222.941227 -72.721464) (xy 222.885753 -72.727567) (xy 222.829982 -72.725529)
			(xy 222.775103 -72.715392) (xy 222.722283 -72.697373) (xy 222.672651 -72.671855) (xy 222.627263 -72.639383)
			(xy 222.587086 -72.600648) (xy 222.552978 -72.556476) (xy 222.525664 -72.507808) (xy 222.505728 -72.455682)
			(xy 222.493593 -72.401209) (xy 222.48952 -72.34555) (xy 212.649463 -72.34555) (xy 213.33079 -73.026778)
			(xy 213.35422 -73.050908) (xy 213.867998 -73.050908) (xy 213.872069 -72.995286) (xy 213.884195 -72.940849)
			(xy 213.904118 -72.888758) (xy 213.931414 -72.840123) (xy 213.9655 -72.79598) (xy 214.005649 -72.757271)
			(xy 214.051007 -72.72482) (xy 214.100607 -72.699319) (xy 214.153391 -72.681312) (xy 214.208234 -72.671182)
			(xy 214.263968 -72.669145) (xy 214.319405 -72.675245) (xy 214.373362 -72.689351) (xy 214.424691 -72.711163)
			(xy 214.472297 -72.740217) (xy 214.49311 -72.757538) (xy 217.103958 -72.757538) (xy 217.108029 -72.701916)
			(xy 217.120155 -72.647479) (xy 217.140078 -72.595388) (xy 217.167374 -72.546753) (xy 217.20146 -72.50261)
			(xy 217.241609 -72.463901) (xy 217.286967 -72.43145) (xy 217.336567 -72.405949) (xy 217.389351 -72.387942)
			(xy 217.444194 -72.377812) (xy 217.499928 -72.375775) (xy 217.555365 -72.381875) (xy 217.609322 -72.395981)
			(xy 217.660651 -72.417793) (xy 217.708257 -72.446847) (xy 217.751125 -72.482522) (xy 217.788342 -72.524059)
			(xy 217.819115 -72.570572) (xy 217.842787 -72.621069) (xy 217.858855 -72.674476) (xy 217.866975 -72.729652)
			(xy 217.867484 -72.757538) (xy 217.866975 -72.785424) (xy 217.858855 -72.8406) (xy 217.856793 -72.847454)
			(xy 219.739208 -72.847454) (xy 219.743279 -72.791832) (xy 219.755405 -72.737395) (xy 219.775328 -72.685304)
			(xy 219.802624 -72.636669) (xy 219.83671 -72.592526) (xy 219.876859 -72.553817) (xy 219.922217 -72.521366)
			(xy 219.971817 -72.495865) (xy 220.024601 -72.477858) (xy 220.079444 -72.467728) (xy 220.135178 -72.465691)
			(xy 220.190615 -72.471791) (xy 220.244572 -72.485897) (xy 220.295901 -72.507709) (xy 220.343507 -72.536763)
			(xy 220.386375 -72.572438) (xy 220.423592 -72.613975) (xy 220.454365 -72.660488) (xy 220.478037 -72.710985)
			(xy 220.494105 -72.764392) (xy 220.502225 -72.819568) (xy 220.502734 -72.847454) (xy 220.502225 -72.87534)
			(xy 220.497133 -72.909938) (xy 221.675704 -72.909938) (xy 221.679777 -72.854279) (xy 221.691912 -72.799806)
			(xy 221.711848 -72.74768) (xy 221.739162 -72.699012) (xy 221.77327 -72.65484) (xy 221.813447 -72.616105)
			(xy 221.858835 -72.583633) (xy 221.908467 -72.558115) (xy 221.961287 -72.540096) (xy 222.016166 -72.529959)
			(xy 222.071937 -72.527921) (xy 222.127411 -72.534024) (xy 222.181404 -72.54814) (xy 222.232767 -72.569967)
			(xy 222.280405 -72.59904) (xy 222.323301 -72.634739) (xy 222.360543 -72.676303) (xy 222.391337 -72.722847)
			(xy 222.415025 -72.773378) (xy 222.431103 -72.82682) (xy 222.439229 -72.882034) (xy 222.439738 -72.909938)
			(xy 222.439229 -72.937842) (xy 222.431103 -72.993056) (xy 222.415025 -73.046498) (xy 222.391337 -73.097029)
			(xy 222.360543 -73.143573) (xy 222.323301 -73.185137) (xy 222.280405 -73.220836) (xy 222.232767 -73.249909)
			(xy 222.181404 -73.271736) (xy 222.127411 -73.285852) (xy 222.071937 -73.291955) (xy 222.016166 -73.289917)
			(xy 221.961287 -73.27978) (xy 221.908467 -73.261761) (xy 221.858835 -73.236243) (xy 221.813447 -73.203771)
			(xy 221.77327 -73.165036) (xy 221.739162 -73.120864) (xy 221.711848 -73.072196) (xy 221.691912 -73.02007)
			(xy 221.679777 -72.965597) (xy 221.675704 -72.909938) (xy 220.497133 -72.909938) (xy 220.494105 -72.930516)
			(xy 220.478037 -72.983923) (xy 220.454365 -73.03442) (xy 220.423592 -73.080933) (xy 220.386375 -73.12247)
			(xy 220.343507 -73.158145) (xy 220.295901 -73.187199) (xy 220.244572 -73.209011) (xy 220.190615 -73.223117)
			(xy 220.135178 -73.229217) (xy 220.079444 -73.22718) (xy 220.024601 -73.21705) (xy 219.971817 -73.199043)
			(xy 219.922217 -73.173542) (xy 219.876859 -73.141091) (xy 219.83671 -73.102382) (xy 219.802624 -73.058239)
			(xy 219.775328 -73.009604) (xy 219.755405 -72.957513) (xy 219.743279 -72.903076) (xy 219.739208 -72.847454)
			(xy 217.856793 -72.847454) (xy 217.842787 -72.894007) (xy 217.819115 -72.944504) (xy 217.788342 -72.991017)
			(xy 217.751125 -73.032554) (xy 217.708257 -73.068229) (xy 217.660651 -73.097283) (xy 217.609322 -73.119095)
			(xy 217.555365 -73.133201) (xy 217.499928 -73.139301) (xy 217.444194 -73.137264) (xy 217.389351 -73.127134)
			(xy 217.336567 -73.109127) (xy 217.286967 -73.083626) (xy 217.241609 -73.051175) (xy 217.20146 -73.012466)
			(xy 217.167374 -72.968323) (xy 217.140078 -72.919688) (xy 217.120155 -72.867597) (xy 217.108029 -72.81316)
			(xy 217.103958 -72.757538) (xy 214.49311 -72.757538) (xy 214.515165 -72.775892) (xy 214.552382 -72.817429)
			(xy 214.583155 -72.863942) (xy 214.606827 -72.914439) (xy 214.622895 -72.967846) (xy 214.631015 -73.023022)
			(xy 214.631524 -73.050908) (xy 214.631015 -73.078794) (xy 214.622895 -73.13397) (xy 214.606827 -73.187377)
			(xy 214.583155 -73.237874) (xy 214.552382 -73.284387) (xy 214.515165 -73.325924) (xy 214.472297 -73.361599)
			(xy 214.424691 -73.390653) (xy 214.373362 -73.412465) (xy 214.319405 -73.426571) (xy 214.263968 -73.432671)
			(xy 214.208234 -73.430634) (xy 214.153391 -73.420504) (xy 214.100607 -73.402497) (xy 214.051007 -73.376996)
			(xy 214.005649 -73.344545) (xy 213.9655 -73.305836) (xy 213.931414 -73.261693) (xy 213.904118 -73.213058)
			(xy 213.884195 -73.160967) (xy 213.872069 -73.10653) (xy 213.867998 -73.050908) (xy 213.35422 -73.050908)
			(xy 213.35477 -73.051474) (xy 213.397189 -73.105688) (xy 213.432725 -73.164643) (xy 213.460855 -73.227471)
			(xy 213.471506 -73.260204) (xy 213.473284 -73.2663) (xy 213.479634 -73.276714) (xy 214.363554 -74.160634)
			(xy 214.3704 -74.168032) (xy 214.378129 -74.186631) (xy 214.37854 -74.196702) (xy 214.37854 -74.422)
			(xy 225.169728 -74.422) (xy 225.173801 -74.366341) (xy 225.185936 -74.311868) (xy 225.205872 -74.259742)
			(xy 225.233186 -74.211074) (xy 225.267294 -74.166902) (xy 225.307471 -74.128167) (xy 225.352859 -74.095695)
			(xy 225.402491 -74.070177) (xy 225.455311 -74.052158) (xy 225.51019 -74.042021) (xy 225.565961 -74.039983)
			(xy 225.621435 -74.046086) (xy 225.675428 -74.060202) (xy 225.726791 -74.082029) (xy 225.774429 -74.111102)
			(xy 225.817325 -74.146801) (xy 225.854567 -74.188365) (xy 225.885361 -74.234909) (xy 225.909049 -74.28544)
			(xy 225.925127 -74.338882) (xy 225.933253 -74.394096) (xy 225.933762 -74.422) (xy 225.933253 -74.449904)
			(xy 225.925127 -74.505118) (xy 225.909049 -74.55856) (xy 225.885361 -74.609091) (xy 225.854567 -74.655635)
			(xy 225.817325 -74.697199) (xy 225.774429 -74.732898) (xy 225.726791 -74.761971) (xy 225.675428 -74.783798)
			(xy 225.621435 -74.797914) (xy 225.565961 -74.804017) (xy 225.51019 -74.801979) (xy 225.455311 -74.791842)
			(xy 225.402491 -74.773823) (xy 225.352859 -74.748305) (xy 225.307471 -74.715833) (xy 225.267294 -74.677098)
			(xy 225.233186 -74.632926) (xy 225.205872 -74.584258) (xy 225.185936 -74.532132) (xy 225.173801 -74.477659)
			(xy 225.169728 -74.422) (xy 214.37854 -74.422) (xy 214.37854 -75.080451) (xy 220.769668 -75.080451)
			(xy 220.769668 -75.025949) (xy 220.777424 -74.972) (xy 220.792779 -74.919705) (xy 220.81542 -74.870128)
			(xy 220.844886 -74.824277) (xy 220.880577 -74.783086) (xy 220.921767 -74.747393) (xy 220.967617 -74.717926)
			(xy 221.017194 -74.695283) (xy 221.069489 -74.679927) (xy 221.123437 -74.672169) (xy 221.150688 -74.671682)
			(xy 221.177857 -74.672139) (xy 221.231644 -74.679865) (xy 221.283789 -74.695147) (xy 221.333237 -74.717677)
			(xy 221.378986 -74.746997) (xy 221.399862 -74.764392) (xy 221.406974 -74.770488) (xy 221.423992 -74.776838)
			(xy 221.483936 -74.776838) (xy 221.483936 -74.765662) (xy 221.516702 -74.765662) (xy 221.525135 -74.765362)
			(xy 221.541099 -74.759927) (xy 221.547944 -74.754994) (xy 221.548452 -74.754486) (xy 221.56877 -74.73888)
			(xy 221.612781 -74.712656) (xy 221.659908 -74.692562) (xy 221.709302 -74.678961) (xy 221.760072 -74.672098)
			(xy 221.785688 -74.671682) (xy 221.812941 -74.672164) (xy 221.866892 -74.67992) (xy 221.919189 -74.695274)
			(xy 221.96877 -74.717916) (xy 222.014623 -74.747383) (xy 222.055816 -74.783075) (xy 222.09151 -74.824267)
			(xy 222.120979 -74.87012) (xy 222.143621 -74.919699) (xy 222.158978 -74.971997) (xy 222.166735 -75.025947)
			(xy 222.166735 -75.080453) (xy 222.158978 -75.134403) (xy 222.143621 -75.186701) (xy 222.120979 -75.23628)
			(xy 222.09151 -75.282133) (xy 222.055816 -75.323325) (xy 222.014623 -75.359017) (xy 221.96877 -75.388484)
			(xy 221.919189 -75.411126) (xy 221.866892 -75.42648) (xy 221.812941 -75.434236) (xy 221.785688 -75.434698)
			(xy 221.75852 -75.434201) (xy 221.704735 -75.426486) (xy 221.65259 -75.411213) (xy 221.603142 -75.388692)
			(xy 221.557391 -75.359379) (xy 221.536514 -75.341988) (xy 221.529402 -75.335892) (xy 221.512384 -75.329542)
			(xy 221.45244 -75.329542) (xy 221.45244 -75.340718) (xy 221.419674 -75.340718) (xy 221.411238 -75.340992)
			(xy 221.395274 -75.346443) (xy 221.388432 -75.351386) (xy 221.387924 -75.351894) (xy 221.367612 -75.367508)
			(xy 221.323599 -75.393732) (xy 221.276471 -75.413824) (xy 221.227076 -75.427423) (xy 221.176304 -75.434284)
			(xy 221.150688 -75.434698) (xy 221.123437 -75.434231) (xy 221.069489 -75.426473) (xy 221.017194 -75.411117)
			(xy 220.967617 -75.388474) (xy 220.921767 -75.359007) (xy 220.880577 -75.323314) (xy 220.844886 -75.282123)
			(xy 220.81542 -75.236272) (xy 220.792779 -75.186695) (xy 220.777424 -75.1344) (xy 220.769668 -75.080451)
			(xy 214.37854 -75.080451) (xy 214.37854 -76.121768) (xy 216.910156 -76.121768) (xy 216.914227 -76.066146)
			(xy 216.926353 -76.011709) (xy 216.946276 -75.959618) (xy 216.973572 -75.910983) (xy 217.007658 -75.86684)
			(xy 217.047807 -75.828131) (xy 217.093165 -75.79568) (xy 217.142765 -75.770179) (xy 217.195549 -75.752172)
			(xy 217.250392 -75.742042) (xy 217.306126 -75.740005) (xy 217.361563 -75.746105) (xy 217.41552 -75.760211)
			(xy 217.466849 -75.782023) (xy 217.514455 -75.811077) (xy 217.557323 -75.846752) (xy 217.59454 -75.888289)
			(xy 217.625313 -75.934802) (xy 217.648985 -75.985299) (xy 217.665053 -76.038706) (xy 217.673173 -76.093882)
			(xy 217.673682 -76.121768) (xy 217.673173 -76.149654) (xy 217.665053 -76.20483) (xy 217.648985 -76.258237)
			(xy 217.625313 -76.308734) (xy 217.59454 -76.355247) (xy 217.557323 -76.396784) (xy 217.514455 -76.432459)
			(xy 217.466849 -76.461513) (xy 217.41552 -76.483325) (xy 217.361563 -76.497431) (xy 217.306126 -76.503531)
			(xy 217.250392 -76.501494) (xy 217.195549 -76.491364) (xy 217.142765 -76.473357) (xy 217.093165 -76.447856)
			(xy 217.047807 -76.415405) (xy 217.007658 -76.376696) (xy 216.973572 -76.332553) (xy 216.946276 -76.283918)
			(xy 216.926353 -76.231827) (xy 216.914227 -76.17739) (xy 216.910156 -76.121768) (xy 214.37854 -76.121768)
			(xy 214.37854 -76.804551) (xy 220.600997 -76.804551) (xy 220.600997 -76.750049) (xy 220.608754 -76.696101)
			(xy 220.62411 -76.643806) (xy 220.646753 -76.594229) (xy 220.67622 -76.54838) (xy 220.711914 -76.507191)
			(xy 220.753105 -76.471501) (xy 220.798958 -76.442037) (xy 220.848536 -76.419399) (xy 220.900832 -76.404047)
			(xy 220.954781 -76.396295) (xy 220.982032 -76.395834) (xy 221.009199 -76.396335) (xy 221.062984 -76.404052)
			(xy 221.115128 -76.419325) (xy 221.164576 -76.441844) (xy 221.210328 -76.471154) (xy 221.231206 -76.488544)
			(xy 221.238318 -76.49464) (xy 221.255336 -76.50099) (xy 221.31528 -76.50099) (xy 221.31528 -76.489814)
			(xy 221.348046 -76.489814) (xy 221.356482 -76.489543) (xy 221.372446 -76.484089) (xy 221.379288 -76.479146)
			(xy 221.379796 -76.478638) (xy 221.400094 -76.463005) (xy 221.444111 -76.436787) (xy 221.491244 -76.416699)
			(xy 221.540641 -76.403104) (xy 221.591415 -76.396247) (xy 221.617032 -76.395834) (xy 221.644285 -76.396238)
			(xy 221.698235 -76.403999) (xy 221.750532 -76.419359) (xy 221.80011 -76.442004) (xy 221.845962 -76.471475)
			(xy 221.887153 -76.50717) (xy 221.922845 -76.548364) (xy 221.952311 -76.594218) (xy 221.974952 -76.643798)
			(xy 221.990308 -76.696096) (xy 221.998064 -76.750047) (xy 221.998064 -76.804553) (xy 221.990308 -76.858504)
			(xy 221.974952 -76.910802) (xy 221.952311 -76.960382) (xy 221.922845 -77.006236) (xy 221.887153 -77.04743)
			(xy 221.845962 -77.083125) (xy 221.80011 -77.112596) (xy 221.750532 -77.135241) (xy 221.698235 -77.150601)
			(xy 221.644285 -77.158362) (xy 221.617032 -77.15885) (xy 221.589864 -77.158373) (xy 221.536078 -77.150651)
			(xy 221.483934 -77.135373) (xy 221.434486 -77.112848) (xy 221.388735 -77.083532) (xy 221.367858 -77.06614)
			(xy 221.360746 -77.060044) (xy 221.343728 -77.053694) (xy 221.283784 -77.053694) (xy 221.283784 -77.06487)
			(xy 221.251018 -77.06487) (xy 221.24258 -77.065127) (xy 221.226617 -77.070591) (xy 221.219776 -77.075538)
			(xy 221.219268 -77.076046) (xy 221.198947 -77.091647) (xy 221.154936 -77.117871) (xy 221.10781 -77.137966)
			(xy 221.058417 -77.151568) (xy 221.007648 -77.158433) (xy 220.982032 -77.15885) (xy 220.954781 -77.158305)
			(xy 220.900832 -77.150553) (xy 220.848536 -77.135201) (xy 220.798958 -77.112563) (xy 220.753105 -77.083099)
			(xy 220.711914 -77.047409) (xy 220.67622 -77.00622) (xy 220.646753 -76.960371) (xy 220.62411 -76.910794)
			(xy 220.608754 -76.858499) (xy 220.600997 -76.804551) (xy 214.37854 -76.804551) (xy 214.37854 -77.4319)
			(xy 218.076016 -77.4319) (xy 218.080087 -77.376278) (xy 218.092213 -77.321841) (xy 218.112136 -77.26975)
			(xy 218.139432 -77.221115) (xy 218.173518 -77.176972) (xy 218.213667 -77.138263) (xy 218.259025 -77.105812)
			(xy 218.308625 -77.080311) (xy 218.361409 -77.062304) (xy 218.416252 -77.052174) (xy 218.471986 -77.050137)
			(xy 218.527423 -77.056237) (xy 218.58138 -77.070343) (xy 218.632709 -77.092155) (xy 218.680315 -77.121209)
			(xy 218.723183 -77.156884) (xy 218.7604 -77.198421) (xy 218.791173 -77.244934) (xy 218.814845 -77.295431)
			(xy 218.830913 -77.348838) (xy 218.839033 -77.404014) (xy 218.839542 -77.4319) (xy 218.839033 -77.459786)
			(xy 218.830913 -77.514962) (xy 218.814845 -77.568369) (xy 218.791173 -77.618866) (xy 218.7604 -77.665379)
			(xy 218.723183 -77.706916) (xy 218.680315 -77.742591) (xy 218.632709 -77.771645) (xy 218.58138 -77.793457)
			(xy 218.527423 -77.807563) (xy 218.471986 -77.813663) (xy 218.416252 -77.811626) (xy 218.361409 -77.801496)
			(xy 218.308625 -77.783489) (xy 218.259025 -77.757988) (xy 218.213667 -77.725537) (xy 218.173518 -77.686828)
			(xy 218.139432 -77.642685) (xy 218.112136 -77.59405) (xy 218.092213 -77.541959) (xy 218.080087 -77.487522)
			(xy 218.076016 -77.4319) (xy 214.37854 -77.4319) (xy 214.37854 -77.639418) (xy 214.378968 -77.649486)
			(xy 214.386691 -77.668082) (xy 214.393526 -77.675486) (xy 215.940894 -79.222854) (xy 215.94829 -79.229706)
			(xy 215.966888 -79.23745) (xy 215.976962 -79.23784) (xy 225.779838 -79.23784)
		)
		(stroke
			(width 0)
			(type solid)
		)
		(fill yes)
		(layer "In4.Cu")
		(net "GND")
	)
	(gr_poly
		(pts
			(xy 398.413478 -331.59192) (xy 398.418433 -331.591804) (xy 398.428156 -331.589889) (xy 398.432782 -331.58811)
			(xy 398.45869 -331.577442) (xy 398.465548 -331.571092) (xy 398.488819 -331.549894) (xy 398.539687 -331.512809)
			(xy 398.594747 -331.482294) (xy 398.653157 -331.458817) (xy 398.714019 -331.442738) (xy 398.776403 -331.434304)
			(xy 398.83935 -331.433644) (xy 398.870678 -331.436726) (xy 398.884549 -331.437918) (xy 398.912038 -331.43357)
			(xy 398.93733 -331.421956) (xy 398.958543 -331.40394) (xy 398.974099 -331.380862) (xy 398.98284 -331.354439)
			(xy 398.984117 -331.326638) (xy 398.977835 -331.299525) (xy 398.971516 -331.28712) (xy 398.96923 -331.28331)
			(xy 398.968722 -331.282548) (xy 398.952772 -331.257585) (xy 398.926152 -331.204661) (xy 398.90587 -331.149)
			(xy 398.892202 -331.091357) (xy 398.885333 -331.032515) (xy 398.884902 -331.002894) (xy 398.884902 -331.00264)
			(xy 398.885345 -330.97189) (xy 398.892753 -330.910838) (xy 398.907467 -330.851125) (xy 398.92927 -330.79362)
			(xy 398.957846 -330.739163) (xy 398.992778 -330.688547) (xy 399.033557 -330.64251) (xy 399.079587 -330.601725)
			(xy 399.130197 -330.566786) (xy 399.184651 -330.538202) (xy 399.242152 -330.516389) (xy 399.301864 -330.501667)
			(xy 399.362914 -330.49425) (xy 399.393664 -330.493878) (xy 399.426819 -330.49441) (xy 399.492567 -330.503019)
			(xy 399.556639 -330.520096) (xy 399.617951 -330.545352) (xy 399.675462 -330.578358) (xy 399.728198 -330.618555)
			(xy 399.775265 -330.665263) (xy 399.815866 -330.717689) (xy 399.849313 -330.774945) (xy 399.875039 -330.83606)
			(xy 399.892607 -330.9) (xy 399.901721 -330.96568) (xy 399.902426 -330.99883) (xy 399.902426 -331.002894)
			(xy 399.902009 -331.032273) (xy 399.895236 -331.09064) (xy 399.881779 -331.147837) (xy 399.8722 -331.175614)
			(xy 399.870676 -331.179678) (xy 399.866078 -331.193404) (xy 399.86394 -331.222259) (xy 399.869982 -331.250555)
			(xy 399.88372 -331.27602) (xy 399.90405 -331.296608) (xy 399.92934 -331.310665) (xy 399.957557 -331.317064)
			(xy 399.972022 -331.316584) (xy 399.976848 -331.316076) (xy 399.978118 -331.315822) (xy 399.99724 -331.313078)
			(xy 400.035763 -331.310156) (xy 400.05508 -331.30998) (xy 400.056096 -331.30998) (xy 400.088769 -331.310477)
			(xy 400.153579 -331.318835) (xy 400.216784 -331.335426) (xy 400.277343 -331.359977) (xy 400.334258 -331.392083)
			(xy 400.386592 -331.431216) (xy 400.433481 -331.47673) (xy 400.474154 -331.527876) (xy 400.491452 -331.555598)
			(xy 400.495008 -331.561186) (xy 400.503644 -331.569822) (xy 400.529298 -331.584808) (xy 400.529552 -331.584808)
			(xy 400.529552 -331.585062) (xy 400.535489 -331.588228) (xy 400.548482 -331.591699) (xy 400.555206 -331.59192)
			(xy 403.28215 -331.59192) (xy 403.311868 -331.562456) (xy 403.311868 -331.541374) (xy 403.312492 -331.50948)
			(xy 403.32072 -331.446221) (xy 403.336792 -331.384486) (xy 403.360455 -331.325246) (xy 403.391339 -331.269428)
			(xy 403.428958 -331.217909) (xy 403.472724 -331.171497) (xy 403.521948 -331.130921) (xy 403.575858 -331.096817)
			(xy 403.63361 -331.06972) (xy 403.694295 -331.050056) (xy 403.756963 -331.038132) (xy 403.82063 -331.034137)
			(xy 403.884297 -331.038132) (xy 403.946965 -331.050056) (xy 404.00765 -331.06972) (xy 404.065402 -331.096817)
			(xy 404.119312 -331.130921) (xy 404.168536 -331.171497) (xy 404.212302 -331.217909) (xy 404.249921 -331.269428)
			(xy 404.280805 -331.325246) (xy 404.304468 -331.384486) (xy 404.32054 -331.446221) (xy 404.328768 -331.50948)
			(xy 404.329392 -331.541374) (xy 404.329392 -331.562456) (xy 404.35911 -331.59192) (xy 405.763476 -331.59192)
			(xy 405.775194 -331.591335) (xy 405.796244 -331.581028) (xy 405.803862 -331.572108) (xy 405.824562 -331.546035)
			(xy 405.871643 -331.498968) (xy 405.924462 -331.458445) (xy 405.982117 -331.425161) (xy 406.043622 -331.399684)
			(xy 406.107925 -331.382449) (xy 406.173928 -331.373752) (xy 406.207214 -331.373226) (xy 406.238922 -331.373712)
			(xy 406.301844 -331.381613) (xy 406.33269 -331.388974) (xy 406.345898 -331.392276) (xy 406.371552 -331.385164)
			(xy 408.459178 -329.297538) (xy 408.459686 -329.29703) (xy 408.466262 -329.289646) (xy 408.473701 -329.271348)
			(xy 408.474164 -329.26147) (xy 408.474164 -327.840594) (xy 408.47459 -327.830526) (xy 408.482313 -327.811929)
			(xy 408.48915 -327.804526) (xy 408.981656 -327.31202) (xy 408.982164 -327.311512) (xy 408.98874 -327.304129)
			(xy 408.996176 -327.28583) (xy 408.996642 -327.275952) (xy 408.996642 -326.173084) (xy 408.996214 -326.163016)
			(xy 408.988489 -326.144422) (xy 408.981656 -326.137016) (xy 408.77236 -325.92772) (xy 408.765248 -325.920354)
			(xy 408.746452 -325.912734) (xy 408.35834 -325.912734) (xy 408.348276 -325.912298) (xy 408.329694 -325.904561)
			(xy 408.322272 -325.897748) (xy 406.977596 -324.553072) (xy 406.970755 -324.545672) (xy 406.963031 -324.527074)
			(xy 406.96261 -324.517004) (xy 406.96261 -323.534278) (xy 406.962181 -323.52346) (xy 406.953374 -323.503704)
			(xy 406.945592 -323.496178) (xy 406.914815 -323.468232) (xy 406.858885 -323.406724) (xy 406.809972 -323.339502)
			(xy 406.768654 -323.267361) (xy 406.751536 -323.229478) (xy 406.738842 -323.199563) (xy 406.717988 -323.138011)
			(xy 406.70988 -323.106542) (xy 406.706324 -323.092064) (xy 406.684988 -323.071744) (xy 406.581102 -323.05117)
			(xy 406.571512 -323.049698) (xy 406.552454 -323.053252) (xy 406.536083 -323.063637) (xy 406.530048 -323.071236)
			(xy 406.522682 -323.081142) (xy 406.502153 -323.107486) (xy 406.455306 -323.155087) (xy 406.402634 -323.196152)
			(xy 406.345044 -323.229973) (xy 406.283524 -323.255971) (xy 406.219132 -323.273697) (xy 406.152974 -323.282848)
			(xy 406.119584 -323.28358) (xy 406.10536 -323.283326) (xy 406.077311 -323.282337) (xy 406.02167 -323.274966)
			(xy 405.967177 -323.26152) (xy 405.914493 -323.242163) (xy 405.889206 -323.229986) (xy 405.88184 -323.227954)
			(xy 405.863144 -323.256202) (xy 405.819432 -323.307951) (xy 405.769231 -323.353432) (xy 405.713431 -323.391839)
			(xy 405.653022 -323.42249) (xy 405.621236 -323.434202) (xy 405.620728 -323.434456) (xy 405.616918 -323.435726)
			(xy 405.614378 -323.436742) (xy 405.607774 -323.43979) (xy 405.605742 -323.440806) (xy 405.604726 -323.441314)
			(xy 405.576358 -323.456497) (xy 405.516614 -323.480388) (xy 405.454336 -323.496563) (xy 405.390517 -323.504762)
			(xy 405.358346 -323.505322) (xy 405.357838 -323.505322) (xy 405.3242 -323.504765) (xy 405.257517 -323.495857)
			(xy 405.192595 -323.478219) (xy 405.130571 -323.452159) (xy 405.072533 -323.418135) (xy 405.045672 -323.39788)
			(xy 405.039068 -323.3928) (xy 405.021542 -323.386704) (xy 405.014113 -323.384438) (xy 404.998595 -323.384049)
			(xy 404.991062 -323.385942) (xy 404.981664 -323.388482) (xy 404.975822 -323.391784) (xy 404.94683 -323.407778)
			(xy 404.88559 -323.432957) (xy 404.821601 -323.44998) (xy 404.755945 -323.45856) (xy 404.722838 -323.459094)
			(xy 404.690332 -323.458581) (xy 404.625848 -323.450301) (xy 404.562946 -323.433871) (xy 404.50265 -323.409558)
			(xy 404.445944 -323.377761) (xy 404.419562 -323.358764) (xy 404.412704 -323.353684) (xy 404.397718 -323.348604)
			(xy 404.393823 -323.347422) (xy 404.385785 -323.346142) (xy 404.381716 -323.346064) (xy 404.372826 -323.346064)
			(xy 404.354538 -323.351906) (xy 404.348442 -323.355716) (xy 404.347934 -323.35597) (xy 404.323078 -323.371697)
			(xy 404.270446 -323.397961) (xy 404.215138 -323.417985) (xy 404.157891 -323.431502) (xy 404.099468 -323.438332)
			(xy 404.070058 -323.438774) (xy 404.039313 -323.438308) (xy 403.978272 -323.430891) (xy 403.91857 -323.416172)
			(xy 403.861077 -323.394364) (xy 403.806631 -323.365785) (xy 403.756028 -323.330853) (xy 403.710003 -323.290076)
			(xy 403.669229 -323.244049) (xy 403.634299 -323.193443) (xy 403.605724 -323.138996) (xy 403.583919 -323.081502)
			(xy 403.569203 -323.021799) (xy 403.561791 -322.960757) (xy 403.561296 -322.930012) (xy 403.561759 -322.899264)
			(xy 403.56917 -322.838217) (xy 403.583885 -322.778508) (xy 403.605689 -322.721008) (xy 403.634266 -322.666555)
			(xy 403.669197 -322.615944) (xy 403.709973 -322.569912) (xy 403.756001 -322.52913) (xy 403.806609 -322.494194)
			(xy 403.861059 -322.465612) (xy 403.918556 -322.443801) (xy 403.978264 -322.42908) (xy 404.03931 -322.421663)
			(xy 404.070058 -322.42125) (xy 404.102562 -322.421769) (xy 404.16704 -322.430061) (xy 404.229935 -322.446502)
			(xy 404.290222 -322.470825) (xy 404.346918 -322.502632) (xy 404.373334 -322.52158) (xy 404.380192 -322.52666)
			(xy 404.395178 -322.53174) (xy 404.399073 -322.532923) (xy 404.407111 -322.534205) (xy 404.41118 -322.53428)
			(xy 404.42007 -322.53428) (xy 404.438358 -322.528438) (xy 404.444454 -322.524628) (xy 404.444962 -322.524374)
			(xy 404.471665 -322.507514) (xy 404.528416 -322.479805) (xy 404.588159 -322.459331) (xy 404.649976 -322.446408)
			(xy 404.712917 -322.441233) (xy 404.776015 -322.443887) (xy 404.8383 -322.454329) (xy 404.898814 -322.472399)
			(xy 404.956626 -322.497817) (xy 405.010849 -322.530194) (xy 405.03602 -322.549266) (xy 405.042878 -322.5546)
			(xy 405.059896 -322.560442) (xy 405.066951 -322.562566) (xy 405.081668 -322.563091) (xy 405.088852 -322.561458)
			(xy 405.100282 -322.55841) (xy 405.106378 -322.555108) (xy 405.106886 -322.554854) (xy 405.126514 -322.543896)
			(xy 405.16734 -322.525071) (xy 405.18842 -322.517262) (xy 405.190198 -322.516754) (xy 405.192484 -322.515738)
			(xy 405.201374 -322.511674) (xy 405.203914 -322.510404) (xy 405.205184 -322.509896) (xy 405.207978 -322.508372)
			(xy 405.236177 -322.493395) (xy 405.295509 -322.469803) (xy 405.357326 -322.453814) (xy 405.420656 -322.44568)
			(xy 405.45258 -322.445126) (xy 405.459438 -322.445126) (xy 405.50211 -322.447412) (xy 405.527652 -322.450194)
			(xy 405.578041 -322.460245) (xy 405.602694 -322.467478) (xy 405.61006 -322.469764) (xy 405.65578 -322.469764)
			(xy 405.666671 -322.469254) (xy 405.686502 -322.460244) (xy 405.700823 -322.443832) (xy 405.707064 -322.422963)
			(xy 405.706072 -322.412106) (xy 405.699976 -322.367148) (xy 405.690832 -322.350638) (xy 405.683466 -322.344542)
			(xy 405.65949 -322.323779) (xy 405.616361 -322.277274) (xy 405.579347 -322.225769) (xy 405.549021 -322.170062)
			(xy 405.525856 -322.111018) (xy 405.51021 -322.049553) (xy 405.502325 -321.986619) (xy 405.501856 -321.954906)
			(xy 405.502301 -321.924159) (xy 405.509713 -321.863112) (xy 405.524429 -321.803405) (xy 405.546236 -321.745906)
			(xy 405.574814 -321.691455) (xy 405.609747 -321.640847) (xy 405.650526 -321.594818) (xy 405.696556 -321.55404)
			(xy 405.747166 -321.519108) (xy 405.801617 -321.490531) (xy 405.859116 -321.468726) (xy 405.918824 -321.454011)
			(xy 405.979871 -321.446601) (xy 406.010618 -321.446144) (xy 406.04356 -321.446665) (xy 406.108892 -321.455171)
			(xy 406.17258 -321.472037) (xy 406.233559 -321.496983) (xy 406.290807 -321.529589) (xy 406.343369 -321.569312)
			(xy 406.390365 -321.615487) (xy 406.431007 -321.66734) (xy 406.464618 -321.724006) (xy 406.490634 -321.784535)
			(xy 406.50862 -321.847916) (xy 406.518275 -321.913089) (xy 406.51938 -321.946016) (xy 406.51938 -321.953382)
			(xy 406.51938 -321.954906) (xy 406.51889 -321.986305) (xy 406.51116 -322.048625) (xy 406.495831 -322.109523)
			(xy 406.473135 -322.168075) (xy 406.443415 -322.223395) (xy 406.425654 -322.249292) (xy 406.420066 -322.257166)
			(xy 406.415494 -322.275454) (xy 406.426924 -322.362068) (xy 406.436068 -322.378832) (xy 406.443434 -322.384928)
			(xy 406.469008 -322.40717) (xy 406.514637 -322.457286) (xy 406.55323 -322.513002) (xy 406.569164 -322.542916)
			(xy 406.585166 -322.576952) (xy 406.590754 -322.589906) (xy 406.61336 -322.606416) (xy 406.62733 -322.607686)
			(xy 406.630378 -322.60794) (xy 406.721818 -322.610988) (xy 406.731517 -322.610888) (xy 406.749753 -322.604324)
			(xy 406.764273 -322.591486) (xy 406.769062 -322.583048) (xy 406.769062 -322.582794) (xy 406.784302 -322.554092)
			(xy 406.78735 -322.548758) (xy 406.80902 -322.511681) (xy 406.859476 -322.442183) (xy 406.917432 -322.378804)
			(xy 406.949402 -322.35013) (xy 406.956168 -322.343658) (xy 406.964895 -322.32711) (xy 406.96642 -322.317872)
			(xy 406.966674 -322.315332) (xy 406.967944 -322.296536) (xy 406.968198 -322.28409) (xy 406.968951 -322.274495)
			(xy 406.97666 -322.256877) (xy 406.983184 -322.2498) (xy 407.70302 -321.529964) (xy 407.710417 -321.523114)
			(xy 407.729015 -321.515377) (xy 407.739088 -321.514978) (xy 415.380932 -321.514978) (xy 415.390808 -321.514515)
			(xy 415.409101 -321.507066) (xy 415.416492 -321.5005) (xy 415.416746 -321.500246) (xy 415.975038 -320.941954)
			(xy 415.975546 -320.941446) (xy 415.982129 -320.934065) (xy 415.98958 -320.915766) (xy 415.990024 -320.905886)
			(xy 415.990024 -320.23431) (xy 415.989603 -320.224238) (xy 415.981894 -320.205629) (xy 415.975038 -320.198242)
			(xy 415.753042 -319.976246) (xy 415.74593 -319.96888) (xy 415.727134 -319.96126) (xy 395.982698 -319.96126)
			(xy 395.972629 -319.961685) (xy 395.954031 -319.969407) (xy 395.94663 -319.976246) (xy 395.009878 -320.912998)
			(xy 395.002512 -320.92011) (xy 394.994892 -320.938906) (xy 394.994892 -320.969132) (xy 394.99667 -320.982086)
			(xy 394.998194 -320.988182) (xy 395.001242 -320.994024) (xy 395.001496 -320.994532) (xy 395.016609 -321.023037)
			(xy 395.038093 -321.083867) (xy 395.049049 -321.147443) (xy 395.049756 -321.179698) (xy 395.049756 -321.180206)
			(xy 395.049756 -321.18046) (xy 395.049756 -321.185286) (xy 395.049502 -321.19062) (xy 395.049502 -321.190874)
			(xy 395.048282 -321.217619) (xy 395.039283 -321.270396) (xy 395.023001 -321.321399) (xy 394.999754 -321.369627)
			(xy 394.969998 -321.414135) (xy 394.934317 -321.45405) (xy 394.89341 -321.48859) (xy 394.84808 -321.517077)
			(xy 394.799215 -321.538954) (xy 394.747773 -321.55379) (xy 394.694763 -321.561295) (xy 394.667994 -321.561714)
			(xy 394.66774 -321.561714) (xy 394.642617 -321.561335) (xy 394.592803 -321.554777) (xy 394.544282 -321.54173)
			(xy 394.497896 -321.522421) (xy 394.47597 -321.510152) (xy 394.470382 -321.50685) (xy 394.456412 -321.50304)
			(xy 394.444371 -321.500475) (xy 394.420338 -321.505632) (xy 394.410438 -321.512946) (xy 394.408152 -321.514724)
			(xy 394.078714 -321.844162) (xy 394.068494 -321.855125) (xy 394.054359 -321.881537) (xy 394.048496 -321.910914)
			(xy 394.051408 -321.940728) (xy 394.062845 -321.968415) (xy 394.081824 -321.991593) (xy 394.106711 -322.008267)
			(xy 394.135365 -322.017003) (xy 394.150342 -322.017644) (xy 394.732002 -322.017644) (xy 394.739622 -322.015358)
			(xy 394.776712 -322.00446) (xy 394.853117 -321.992721) (xy 394.891768 -321.99199) (xy 394.922517 -321.992452)
			(xy 394.983566 -321.999861) (xy 395.043277 -322.014574) (xy 395.10078 -322.036377) (xy 395.155235 -322.064953)
			(xy 395.205849 -322.099883) (xy 395.251883 -322.14066) (xy 395.292667 -322.186688) (xy 395.327606 -322.237296)
			(xy 395.35619 -322.291747) (xy 395.378002 -322.349246) (xy 395.392725 -322.408955) (xy 395.400143 -322.470003)
			(xy 395.40053 -322.500752) (xy 395.399814 -322.537745) (xy 395.388979 -322.610936) (xy 395.37894 -322.646548)
			(xy 395.376908 -322.65366) (xy 395.374622 -322.66128) (xy 395.374622 -322.833238) (xy 395.375086 -322.843113)
			(xy 395.382537 -322.861405) (xy 395.3891 -322.868798) (xy 395.389354 -322.869052) (xy 395.588744 -323.068442)
			(xy 395.589252 -323.06895) (xy 395.596633 -323.075533) (xy 395.614932 -323.082984) (xy 395.624812 -323.083428)
			(xy 396.293594 -323.083428) (xy 396.308134 -323.08287) (xy 396.336017 -323.074601) (xy 396.360445 -323.058817)
			(xy 396.37944 -323.036793) (xy 396.391466 -323.010313) (xy 396.395551 -322.981518) (xy 396.391364 -322.952738)
			(xy 396.379243 -322.9263) (xy 396.370048 -322.915026) (xy 396.367762 -322.91274) (xy 396.344876 -322.888839)
			(xy 396.304839 -322.836149) (xy 396.271968 -322.778716) (xy 396.246815 -322.717508) (xy 396.229804 -322.653557)
			(xy 396.221223 -322.587941) (xy 396.220696 -322.554854) (xy 396.221198 -322.522877) (xy 396.229213 -322.459427)
			(xy 396.245118 -322.397482) (xy 396.268661 -322.33802) (xy 396.299471 -322.281976) (xy 396.337063 -322.230236)
			(xy 396.380842 -322.183616) (xy 396.43012 -322.14285) (xy 396.484118 -322.108582) (xy 396.541985 -322.081351)
			(xy 396.602809 -322.061588) (xy 396.66563 -322.049605) (xy 396.729458 -322.045589) (xy 396.793286 -322.049605)
			(xy 396.856107 -322.061588) (xy 396.916931 -322.081351) (xy 396.974798 -322.108582) (xy 397.028796 -322.14285)
			(xy 397.078074 -322.183616) (xy 397.121853 -322.230236) (xy 397.159445 -322.281976) (xy 397.190255 -322.33802)
			(xy 397.213798 -322.397482) (xy 397.229703 -322.459427) (xy 397.237718 -322.522877) (xy 397.23822 -322.554854)
			(xy 397.23772 -322.587178) (xy 397.229539 -322.651307) (xy 397.213302 -322.713883) (xy 397.18927 -322.773899)
			(xy 397.157832 -322.830388) (xy 397.119493 -322.882441) (xy 397.07487 -322.929219) (xy 397.024682 -322.969969)
			(xy 397.024034 -322.970371) (xy 397.696938 -322.970371) (xy 397.696938 -322.906417) (xy 397.704953 -322.842967)
			(xy 397.720858 -322.781022) (xy 397.744401 -322.72156) (xy 397.775211 -322.665516) (xy 397.812803 -322.613776)
			(xy 397.856582 -322.567156) (xy 397.90586 -322.52639) (xy 397.959858 -322.492122) (xy 398.017725 -322.464891)
			(xy 398.078549 -322.445128) (xy 398.14137 -322.433145) (xy 398.205198 -322.429129) (xy 398.269026 -322.433145)
			(xy 398.331847 -322.445128) (xy 398.392671 -322.464891) (xy 398.450538 -322.492122) (xy 398.504536 -322.52639)
			(xy 398.553814 -322.567156) (xy 398.597593 -322.613776) (xy 398.635185 -322.665516) (xy 398.665995 -322.72156)
			(xy 398.689538 -322.781022) (xy 398.699032 -322.818) (xy 400.068333 -322.818) (xy 400.072348 -322.754175)
			(xy 400.084331 -322.691357) (xy 400.104092 -322.630536) (xy 400.131319 -322.572671) (xy 400.165584 -322.518674)
			(xy 400.206347 -322.469397) (xy 400.252963 -322.425618) (xy 400.304698 -322.388026) (xy 400.360737 -322.357214)
			(xy 400.420196 -322.333669) (xy 400.482137 -322.31776) (xy 400.545583 -322.30974) (xy 400.577558 -322.309236)
			(xy 400.611869 -322.309831) (xy 400.679867 -322.319059) (xy 400.746006 -322.337352) (xy 400.809081 -322.364379)
			(xy 400.867947 -322.399647) (xy 400.921531 -322.442515) (xy 400.945604 -322.46697) (xy 400.946112 -322.467478)
			(xy 400.949414 -322.47078) (xy 400.956817 -322.477616) (xy 400.975414 -322.485339) (xy 400.985482 -322.485766)
			(xy 401.069048 -322.485766) (xy 401.078954 -322.481448) (xy 401.088352 -322.477384) (xy 401.095464 -322.470018)
			(xy 401.098004 -322.467478) (xy 401.098512 -322.46697) (xy 401.122602 -322.442531) (xy 401.176181 -322.399656)
			(xy 401.235042 -322.36438) (xy 401.298114 -322.337345) (xy 401.36425 -322.319041) (xy 401.432247 -322.309803)
			(xy 401.466558 -322.309236) (xy 401.498956 -322.30971) (xy 401.563228 -322.317933) (xy 401.625936 -322.334251)
			(xy 401.686064 -322.358401) (xy 401.742638 -322.38999) (xy 401.794743 -322.428508) (xy 401.841534 -322.47333)
			(xy 401.86229 -322.498212) (xy 401.868894 -322.506594) (xy 401.887436 -322.516246) (xy 401.981924 -322.523358)
			(xy 402.001736 -322.5165) (xy 402.009356 -322.509388) (xy 402.032894 -322.488476) (xy 402.084185 -322.451957)
			(xy 402.139591 -322.422047) (xy 402.198264 -322.399204) (xy 402.259309 -322.383777) (xy 402.32179 -322.376003)
			(xy 402.353272 -322.37553) (xy 402.384581 -322.375978) (xy 402.44673 -322.383638) (xy 402.50747 -322.398859)
			(xy 402.565887 -322.42141) (xy 402.621099 -322.450952) (xy 402.672273 -322.487039) (xy 402.718638 -322.529127)
			(xy 402.759494 -322.57658) (xy 402.794225 -322.628684) (xy 402.808694 -322.656454) (xy 402.812758 -322.664836)
			(xy 402.826474 -322.677536) (xy 402.90496 -322.709032) (xy 402.922994 -322.70954) (xy 402.931884 -322.706492)
			(xy 402.961997 -322.696687) (xy 403.024429 -322.686092) (xy 403.05609 -322.68541) (xy 403.083358 -322.685934)
			(xy 403.137339 -322.693693) (xy 403.189666 -322.709056) (xy 403.239274 -322.731709) (xy 403.285154 -322.761191)
			(xy 403.326371 -322.796902) (xy 403.362086 -322.838116) (xy 403.391573 -322.883993) (xy 403.414231 -322.933599)
			(xy 403.429599 -322.985924) (xy 403.437364 -323.039904) (xy 403.437852 -323.067172) (xy 403.437372 -323.094443)
			(xy 403.429614 -323.14843) (xy 403.414251 -323.200763) (xy 403.391596 -323.250376) (xy 403.36211 -323.296261)
			(xy 403.326394 -323.337481) (xy 403.285175 -323.373199) (xy 403.239292 -323.402687) (xy 403.189679 -323.425344)
			(xy 403.137347 -323.44071) (xy 403.083361 -323.448471) (xy 403.05609 -323.448934) (xy 403.029297 -323.448468)
			(xy 402.976238 -323.440962) (xy 402.924749 -323.426113) (xy 402.875842 -323.404213) (xy 402.830476 -323.375691)
			(xy 402.789542 -323.341108) (xy 402.771356 -323.321426) (xy 402.765006 -323.314314) (xy 402.75637 -323.309742)
			(xy 402.752271 -323.307818) (xy 402.743585 -323.305265) (xy 402.739098 -323.304662) (xy 402.664676 -323.295772)
			(xy 402.64715 -323.30009) (xy 402.63953 -323.30517) (xy 402.614138 -323.32185) (xy 402.560164 -323.349738)
			(xy 402.503256 -323.371012) (xy 402.444224 -323.38537) (xy 402.383903 -323.392607) (xy 402.353526 -323.393054)
			(xy 402.353272 -323.393054) (xy 402.320874 -323.392562) (xy 402.256603 -323.384343) (xy 402.193896 -323.368028)
			(xy 402.133768 -323.343881) (xy 402.077193 -323.312295) (xy 402.025088 -323.273779) (xy 401.978296 -323.228959)
			(xy 401.95754 -323.204078) (xy 401.950936 -323.195696) (xy 401.932394 -323.186044) (xy 401.837906 -323.178932)
			(xy 401.818094 -323.18579) (xy 401.810474 -323.192902) (xy 401.786978 -323.213862) (xy 401.735676 -323.250374)
			(xy 401.680261 -323.280275) (xy 401.621579 -323.303108) (xy 401.560529 -323.318526) (xy 401.498042 -323.326291)
			(xy 401.466558 -323.32676) (xy 401.432245 -323.326222) (xy 401.364244 -323.316982) (xy 401.298105 -323.298678)
			(xy 401.235029 -323.271641) (xy 401.176165 -323.236363) (xy 401.122583 -323.193485) (xy 401.098512 -323.169026)
			(xy 401.098004 -323.168518) (xy 401.094702 -323.165216) (xy 401.087294 -323.158386) (xy 401.068701 -323.15066)
			(xy 401.058634 -323.15023) (xy 400.975068 -323.15023) (xy 400.965162 -323.154548) (xy 400.956272 -323.158358)
			(xy 400.946112 -323.168518) (xy 400.945604 -323.169026) (xy 400.921553 -323.193505) (xy 400.867965 -323.236376)
			(xy 400.809096 -323.271647) (xy 400.746017 -323.298675) (xy 400.679874 -323.31697) (xy 400.611871 -323.326199)
			(xy 400.577558 -323.32676) (xy 400.545583 -323.32626) (xy 400.482137 -323.31824) (xy 400.420196 -323.302331)
			(xy 400.360737 -323.278786) (xy 400.304698 -323.247974) (xy 400.252963 -323.210382) (xy 400.206347 -323.166603)
			(xy 400.165584 -323.117326) (xy 400.131319 -323.063329) (xy 400.104092 -323.005464) (xy 400.084331 -322.944643)
			(xy 400.072348 -322.881825) (xy 400.068333 -322.818) (xy 398.699032 -322.818) (xy 398.705443 -322.842967)
			(xy 398.713458 -322.906417) (xy 398.71396 -322.938394) (xy 398.713458 -322.970371) (xy 398.705443 -323.033821)
			(xy 398.689538 -323.095766) (xy 398.665995 -323.155228) (xy 398.635185 -323.211272) (xy 398.597593 -323.263012)
			(xy 398.553814 -323.309632) (xy 398.504536 -323.350398) (xy 398.450538 -323.384666) (xy 398.392671 -323.411897)
			(xy 398.331847 -323.43166) (xy 398.269026 -323.443643) (xy 398.205198 -323.447659) (xy 398.14137 -323.443643)
			(xy 398.078549 -323.43166) (xy 398.017725 -323.411897) (xy 397.959858 -323.384666) (xy 397.90586 -323.350398)
			(xy 397.856582 -323.309632) (xy 397.812803 -323.263012) (xy 397.775211 -323.211272) (xy 397.744401 -323.155228)
			(xy 397.720858 -323.095766) (xy 397.704953 -323.033821) (xy 397.696938 -322.970371) (xy 397.024034 -322.970371)
			(xy 396.969738 -323.004036) (xy 396.940532 -323.017896) (xy 396.939262 -323.018404) (xy 396.936976 -323.01942)
			(xy 396.924154 -323.025461) (xy 396.902225 -323.0434) (xy 396.886062 -323.066669) (xy 396.876904 -323.09348)
			(xy 396.875457 -323.121775) (xy 396.881831 -323.149381) (xy 396.895536 -323.174178) (xy 396.905226 -323.18452)
			(xy 397.3957 -323.675248) (xy 397.751046 -324.030594) (xy 397.757863 -324.037936) (xy 397.765606 -324.056399)
			(xy 397.766032 -324.066408) (xy 397.766032 -325.99884) (xy 398.057368 -325.99884) (xy 398.061441 -325.943181)
			(xy 398.073576 -325.888708) (xy 398.093512 -325.836582) (xy 398.120826 -325.787914) (xy 398.154934 -325.743742)
			(xy 398.195111 -325.705007) (xy 398.240499 -325.672535) (xy 398.290131 -325.647017) (xy 398.342951 -325.628998)
			(xy 398.39783 -325.618861) (xy 398.453601 -325.616823) (xy 398.509075 -325.622926) (xy 398.563068 -325.637042)
			(xy 398.614431 -325.658869) (xy 398.662069 -325.687942) (xy 398.704965 -325.723641) (xy 398.742207 -325.765205)
			(xy 398.773001 -325.811749) (xy 398.796689 -325.86228) (xy 398.812767 -325.915722) (xy 398.820893 -325.970936)
			(xy 398.821244 -325.990177) (xy 399.330412 -325.990177) (xy 399.330412 -325.926223) (xy 399.338427 -325.862773)
			(xy 399.354332 -325.800828) (xy 399.377875 -325.741366) (xy 399.408685 -325.685322) (xy 399.446277 -325.633582)
			(xy 399.490056 -325.586962) (xy 399.539334 -325.546196) (xy 399.593332 -325.511928) (xy 399.651199 -325.484697)
			(xy 399.712023 -325.464934) (xy 399.774844 -325.452951) (xy 399.838672 -325.448935) (xy 399.9025 -325.452951)
			(xy 399.965321 -325.464934) (xy 400.026145 -325.484697) (xy 400.084012 -325.511928) (xy 400.13801 -325.546196)
			(xy 400.187288 -325.586962) (xy 400.231067 -325.633582) (xy 400.268659 -325.685322) (xy 400.299469 -325.741366)
			(xy 400.323012 -325.800828) (xy 400.338917 -325.862773) (xy 400.346932 -325.926223) (xy 400.347434 -325.9582)
			(xy 400.346932 -325.990177) (xy 400.338917 -326.053627) (xy 400.323012 -326.115572) (xy 400.299469 -326.175034)
			(xy 400.268659 -326.231078) (xy 400.231067 -326.282818) (xy 400.187288 -326.329438) (xy 400.13801 -326.370204)
			(xy 400.084012 -326.404472) (xy 400.026145 -326.431703) (xy 399.979469 -326.446869) (xy 402.1554 -326.446869)
			(xy 402.1554 -326.382915) (xy 402.163415 -326.319465) (xy 402.17932 -326.25752) (xy 402.202863 -326.198058)
			(xy 402.233673 -326.142014) (xy 402.271265 -326.090274) (xy 402.315044 -326.043654) (xy 402.364322 -326.002888)
			(xy 402.41832 -325.96862) (xy 402.476187 -325.941389) (xy 402.537011 -325.921626) (xy 402.599832 -325.909643)
			(xy 402.66366 -325.905627) (xy 402.727488 -325.909643) (xy 402.790309 -325.921626) (xy 402.851133 -325.941389)
			(xy 402.909 -325.96862) (xy 402.962998 -326.002888) (xy 403.012276 -326.043654) (xy 403.056055 -326.090274)
			(xy 403.093647 -326.142014) (xy 403.124457 -326.198058) (xy 403.148 -326.25752) (xy 403.163905 -326.319465)
			(xy 403.17192 -326.382915) (xy 403.172422 -326.414892) (xy 403.17192 -326.446869) (xy 403.163905 -326.510319)
			(xy 403.148 -326.572264) (xy 403.124457 -326.631726) (xy 403.093647 -326.68777) (xy 403.070823 -326.719184)
			(xy 404.96744 -326.719184) (xy 404.967898 -326.687878) (xy 404.975584 -326.625739) (xy 404.990836 -326.565013)
			(xy 405.013425 -326.506617) (xy 405.04301 -326.451435) (xy 405.079142 -326.4003) (xy 405.121277 -326.353986)
			(xy 405.168776 -326.313192) (xy 405.220923 -326.278535) (xy 405.276928 -326.25054) (xy 405.306276 -326.239632)
			(xy 405.31288 -326.236838) (xy 405.324631 -326.23034) (xy 405.344386 -326.212159) (xy 405.358725 -326.18946)
			(xy 405.366658 -326.163811) (xy 405.367637 -326.13698) (xy 405.361595 -326.110821) (xy 405.34895 -326.087137)
			(xy 405.340058 -326.077072) (xy 405.337518 -326.074532) (xy 405.315801 -326.053887) (xy 405.276884 -326.008322)
			(xy 405.243593 -325.958499) (xy 405.216391 -325.905107) (xy 405.195653 -325.848888) (xy 405.181668 -325.79062)
			(xy 405.174629 -325.731113) (xy 405.174196 -325.701152) (xy 405.174698 -325.669175) (xy 405.182713 -325.605725)
			(xy 405.198618 -325.54378) (xy 405.222161 -325.484318) (xy 405.252971 -325.428274) (xy 405.290563 -325.376534)
			(xy 405.334342 -325.329914) (xy 405.38362 -325.289148) (xy 405.437618 -325.25488) (xy 405.495485 -325.227649)
			(xy 405.556309 -325.207886) (xy 405.61913 -325.195903) (xy 405.682958 -325.191887) (xy 405.746786 -325.195903)
			(xy 405.809607 -325.207886) (xy 405.870431 -325.227649) (xy 405.928298 -325.25488) (xy 405.982296 -325.289148)
			(xy 406.031574 -325.329914) (xy 406.075353 -325.376534) (xy 406.112945 -325.428274) (xy 406.143755 -325.484318)
			(xy 406.167298 -325.54378) (xy 406.183203 -325.605725) (xy 406.191218 -325.669175) (xy 406.19172 -325.701152)
			(xy 406.191232 -325.732458) (xy 406.183554 -325.794597) (xy 406.168307 -325.855323) (xy 406.145723 -325.91372)
			(xy 406.116142 -325.968903) (xy 406.080013 -326.020038) (xy 406.03788 -326.066353) (xy 405.990382 -326.107147)
			(xy 405.938237 -326.141803) (xy 405.882232 -326.169797) (xy 405.852884 -326.180704) (xy 405.84628 -326.183498)
			(xy 405.834583 -326.190087) (xy 405.814823 -326.208246) (xy 405.800478 -326.230926) (xy 405.792536 -326.25656)
			(xy 405.791547 -326.283378) (xy 405.797579 -326.309528) (xy 405.810215 -326.333203) (xy 405.819102 -326.343264)
			(xy 405.821642 -326.345804) (xy 405.84334 -326.366468) (xy 405.882256 -326.412031) (xy 405.915547 -326.461851)
			(xy 405.942752 -326.51524) (xy 405.963493 -326.571455) (xy 405.977483 -326.629719) (xy 405.984226 -326.686672)
			(xy 407.364692 -326.686672) (xy 407.365194 -326.654695) (xy 407.373209 -326.591245) (xy 407.389114 -326.5293)
			(xy 407.412657 -326.469838) (xy 407.443467 -326.413794) (xy 407.481059 -326.362054) (xy 407.524838 -326.315434)
			(xy 407.574116 -326.274668) (xy 407.628114 -326.2404) (xy 407.685981 -326.213169) (xy 407.746805 -326.193406)
			(xy 407.809626 -326.181423) (xy 407.873454 -326.177407) (xy 407.937282 -326.181423) (xy 408.000103 -326.193406)
			(xy 408.060927 -326.213169) (xy 408.118794 -326.2404) (xy 408.172792 -326.274668) (xy 408.22207 -326.315434)
			(xy 408.265849 -326.362054) (xy 408.303441 -326.413794) (xy 408.334251 -326.469838) (xy 408.357794 -326.5293)
			(xy 408.373699 -326.591245) (xy 408.381714 -326.654695) (xy 408.382216 -326.686672) (xy 408.381767 -326.717457)
			(xy 408.374322 -326.778576) (xy 408.359562 -326.838352) (xy 408.337703 -326.895912) (xy 408.309062 -326.950416)
			(xy 408.274059 -327.001069) (xy 408.233203 -327.047132) (xy 408.187092 -327.087933) (xy 408.161998 -327.105772)
			(xy 408.154632 -327.110852) (xy 408.144726 -327.124822) (xy 408.131518 -327.169526) (xy 408.132534 -327.186798)
			(xy 408.135836 -327.194926) (xy 408.136344 -327.19645) (xy 408.139392 -327.20407) (xy 408.14759 -327.22613)
			(xy 408.159117 -327.271759) (xy 408.164938 -327.318461) (xy 408.1653 -327.341992) (xy 408.164768 -327.369259)
			(xy 408.157009 -327.423239) (xy 408.141646 -327.475566) (xy 408.118994 -327.525173) (xy 408.089512 -327.571053)
			(xy 408.053802 -327.612269) (xy 408.012589 -327.647985) (xy 407.966714 -327.677472) (xy 407.917109 -327.70013)
			(xy 407.864784 -327.715499) (xy 407.810805 -327.723265) (xy 407.783538 -327.723754) (xy 407.756268 -327.723263)
			(xy 407.702281 -327.715506) (xy 407.649949 -327.700144) (xy 407.600335 -327.67749) (xy 407.554451 -327.648006)
			(xy 407.51323 -327.612291) (xy 407.477512 -327.571073) (xy 407.448024 -327.525191) (xy 407.425366 -327.47558)
			(xy 407.41 -327.423248) (xy 407.402239 -327.369262) (xy 407.401776 -327.341992) (xy 407.40221 -327.316481)
			(xy 407.408997 -327.265912) (xy 407.422462 -327.216699) (xy 407.442364 -327.169718) (xy 407.46835 -327.125809)
			(xy 407.483818 -327.105518) (xy 407.489152 -327.09866) (xy 407.49474 -327.082404) (xy 407.494486 -327.047098)
			(xy 407.494994 -327.0377) (xy 407.489152 -327.019666) (xy 407.482802 -327.0123) (xy 407.464246 -326.989411)
			(xy 407.431975 -326.940106) (xy 407.405618 -326.887404) (xy 407.385526 -326.832008) (xy 407.37197 -326.774663)
			(xy 407.36513 -326.716135) (xy 407.364692 -326.686672) (xy 405.984226 -326.686672) (xy 405.984528 -326.689224)
			(xy 405.984964 -326.719184) (xy 405.984462 -326.751161) (xy 405.976447 -326.814611) (xy 405.960542 -326.876556)
			(xy 405.936999 -326.936018) (xy 405.906189 -326.992062) (xy 405.868597 -327.043802) (xy 405.824818 -327.090422)
			(xy 405.77554 -327.131188) (xy 405.721542 -327.165456) (xy 405.663675 -327.192687) (xy 405.602851 -327.21245)
			(xy 405.54003 -327.224433) (xy 405.476202 -327.228449) (xy 405.412374 -327.224433) (xy 405.349553 -327.21245)
			(xy 405.288729 -327.192687) (xy 405.230862 -327.165456) (xy 405.176864 -327.131188) (xy 405.127586 -327.090422)
			(xy 405.083807 -327.043802) (xy 405.046215 -326.992062) (xy 405.015405 -326.936018) (xy 404.991862 -326.876556)
			(xy 404.975957 -326.814611) (xy 404.967942 -326.751161) (xy 404.96744 -326.719184) (xy 403.070823 -326.719184)
			(xy 403.056055 -326.73951) (xy 403.012276 -326.78613) (xy 402.962998 -326.826896) (xy 402.909 -326.861164)
			(xy 402.851133 -326.888395) (xy 402.790309 -326.908158) (xy 402.727488 -326.920141) (xy 402.66366 -326.924157)
			(xy 402.599832 -326.920141) (xy 402.537011 -326.908158) (xy 402.476187 -326.888395) (xy 402.41832 -326.861164)
			(xy 402.364322 -326.826896) (xy 402.315044 -326.78613) (xy 402.271265 -326.73951) (xy 402.233673 -326.68777)
			(xy 402.202863 -326.631726) (xy 402.17932 -326.572264) (xy 402.163415 -326.510319) (xy 402.1554 -326.446869)
			(xy 399.979469 -326.446869) (xy 399.965321 -326.451466) (xy 399.9025 -326.463449) (xy 399.838672 -326.467465)
			(xy 399.774844 -326.463449) (xy 399.712023 -326.451466) (xy 399.651199 -326.431703) (xy 399.593332 -326.404472)
			(xy 399.539334 -326.370204) (xy 399.490056 -326.329438) (xy 399.446277 -326.282818) (xy 399.408685 -326.231078)
			(xy 399.377875 -326.175034) (xy 399.354332 -326.115572) (xy 399.338427 -326.053627) (xy 399.330412 -325.990177)
			(xy 398.821244 -325.990177) (xy 398.821402 -325.99884) (xy 398.820893 -326.026744) (xy 398.812767 -326.081958)
			(xy 398.796689 -326.1354) (xy 398.773001 -326.185931) (xy 398.742207 -326.232475) (xy 398.704965 -326.274039)
			(xy 398.662069 -326.309738) (xy 398.614431 -326.338811) (xy 398.563068 -326.360638) (xy 398.509075 -326.374754)
			(xy 398.453601 -326.380857) (xy 398.39783 -326.378819) (xy 398.342951 -326.368682) (xy 398.290131 -326.350663)
			(xy 398.240499 -326.325145) (xy 398.195111 -326.292673) (xy 398.154934 -326.253938) (xy 398.120826 -326.209766)
			(xy 398.093512 -326.161098) (xy 398.073576 -326.108972) (xy 398.061441 -326.054499) (xy 398.057368 -325.99884)
			(xy 397.766032 -325.99884) (xy 397.766032 -327.6346) (xy 400.942835 -327.6346) (xy 400.946851 -327.570774)
			(xy 400.958834 -327.507954) (xy 400.978596 -327.447132) (xy 401.005825 -327.389265) (xy 401.040091 -327.335268)
			(xy 401.080855 -327.285991) (xy 401.127474 -327.242212) (xy 401.179211 -327.20462) (xy 401.235252 -327.173809)
			(xy 401.294713 -327.150265) (xy 401.356656 -327.134359) (xy 401.420104 -327.126341) (xy 401.45208 -327.125838)
			(xy 401.482693 -327.126294) (xy 401.543473 -327.133684) (xy 401.602928 -327.148313) (xy 401.660198 -327.169969)
			(xy 401.687538 -327.18375) (xy 401.687792 -327.18375) (xy 401.696174 -327.188068) (xy 401.714716 -327.190354)
			(xy 401.722844 -327.188322) (xy 401.723352 -327.188322) (xy 401.760182 -327.179686) (xy 401.775168 -327.170288)
			(xy 401.780502 -327.163176) (xy 401.79869 -327.14034) (xy 401.840826 -327.099938) (xy 401.888625 -327.066424)
			(xy 401.940969 -327.04058) (xy 401.996639 -327.02301) (xy 402.054336 -327.014123) (xy 402.083524 -327.01357)
			(xy 402.083778 -327.01357) (xy 402.111052 -327.013968) (xy 402.165046 -327.021728) (xy 402.217386 -327.037094)
			(xy 402.267006 -327.059752) (xy 402.312896 -327.089242) (xy 402.354122 -327.124962) (xy 402.389845 -327.166186)
			(xy 402.419337 -327.212075) (xy 402.441998 -327.261694) (xy 402.457367 -327.314032) (xy 402.46513 -327.368026)
			(xy 402.46513 -327.422574) (xy 402.457367 -327.476568) (xy 402.441998 -327.528906) (xy 402.419337 -327.578525)
			(xy 402.389845 -327.624414) (xy 402.354122 -327.665638) (xy 402.312896 -327.701358) (xy 402.267006 -327.730848)
			(xy 402.217386 -327.753506) (xy 402.165046 -327.768872) (xy 402.111052 -327.776632) (xy 402.083778 -327.777094)
			(xy 402.065371 -327.77688) (xy 402.02873 -327.773314) (xy 402.010626 -327.769982) (xy 402.001736 -327.768204)
			(xy 401.98421 -327.770998) (xy 401.9423 -327.794112) (xy 401.936204 -327.80097) (xy 401.93341 -327.804419)
			(xy 401.928931 -327.812077) (xy 401.927314 -327.81621) (xy 401.915957 -327.844717) (xy 401.887314 -327.898987)
			(xy 401.852352 -327.949419) (xy 401.811577 -327.995278) (xy 401.765581 -328.0359) (xy 401.715034 -328.070694)
			(xy 401.660668 -328.099155) (xy 401.603273 -328.12087) (xy 401.543683 -328.135524) (xy 401.482763 -328.142903)
			(xy 401.45208 -328.143362) (xy 401.420104 -328.142859) (xy 401.356656 -328.134841) (xy 401.294713 -328.118935)
			(xy 401.235252 -328.095391) (xy 401.179211 -328.06458) (xy 401.127474 -328.026988) (xy 401.080855 -327.983209)
			(xy 401.040091 -327.933932) (xy 401.005825 -327.879935) (xy 400.978596 -327.822068) (xy 400.958834 -327.761246)
			(xy 400.946851 -327.698426) (xy 400.942835 -327.6346) (xy 397.766032 -327.6346) (xy 397.766032 -327.958196)
			(xy 397.765675 -327.966646) (xy 397.760091 -327.982602) (xy 397.75511 -327.989438) (xy 397.754856 -327.989692)
			(xy 397.74991 -327.996533) (xy 397.744449 -328.012497) (xy 397.744188 -328.020934) (xy 397.744188 -328.022204)
			(xy 397.744677 -328.032212) (xy 397.752337 -328.050704) (xy 397.766489 -328.064859) (xy 397.78498 -328.072522)
			(xy 397.794988 -328.073004) (xy 397.805656 -328.073004) (xy 397.815308 -328.06894) (xy 397.847366 -328.05557)
			(xy 397.914219 -328.036722) (xy 397.983017 -328.027157) (xy 398.017746 -328.026522) (xy 398.018 -328.026522)
			(xy 398.049978 -328.027024) (xy 398.11343 -328.03504) (xy 398.175376 -328.050945) (xy 398.234841 -328.074489)
			(xy 398.290886 -328.1053) (xy 398.342628 -328.142892) (xy 398.38925 -328.186673) (xy 398.430017 -328.235952)
			(xy 398.464286 -328.289952) (xy 398.491517 -328.347821) (xy 398.511281 -328.408647) (xy 398.523265 -328.47147)
			(xy 398.527281 -328.5353) (xy 398.523265 -328.59913) (xy 398.511281 -328.661953) (xy 398.491517 -328.722779)
			(xy 398.464286 -328.780648) (xy 398.430017 -328.834648) (xy 398.38925 -328.883927) (xy 398.342628 -328.927708)
			(xy 398.290886 -328.9653) (xy 398.234841 -328.996111) (xy 398.175376 -329.019655) (xy 398.11343 -329.03556)
			(xy 398.049978 -329.043576) (xy 398.018 -329.044046) (xy 397.987253 -329.0436) (xy 397.926207 -329.036188)
			(xy 397.8665 -329.021471) (xy 397.809002 -328.999665) (xy 397.754552 -328.971086) (xy 397.703943 -328.936153)
			(xy 397.657915 -328.895374) (xy 397.617137 -328.849344) (xy 397.582206 -328.798735) (xy 397.553629 -328.744284)
			(xy 397.531824 -328.686785) (xy 397.517109 -328.627077) (xy 397.509699 -328.566031) (xy 397.509238 -328.535284)
			(xy 397.509331 -328.523455) (xy 397.510476 -328.499823) (xy 397.511524 -328.48804) (xy 397.512333 -328.474215)
			(xy 397.507381 -328.44698) (xy 397.495297 -328.422075) (xy 397.476969 -328.40133) (xy 397.453743 -328.386268)
			(xy 397.427326 -328.377997) (xy 397.399658 -328.377124) (xy 397.372772 -328.383713) (xy 397.348643 -328.397279)
			(xy 397.33855 -328.40676) (xy 396.726156 -329.019154) (xy 396.719348 -329.026499) (xy 396.711626 -329.044963)
			(xy 396.71117 -329.054968) (xy 396.71117 -329.320117) (xy 399.42998 -329.320117) (xy 399.42998 -329.256163)
			(xy 399.437995 -329.192713) (xy 399.4539 -329.130768) (xy 399.477443 -329.071306) (xy 399.508253 -329.015262)
			(xy 399.545845 -328.963522) (xy 399.589624 -328.916902) (xy 399.638902 -328.876136) (xy 399.6929 -328.841868)
			(xy 399.750767 -328.814637) (xy 399.811591 -328.794874) (xy 399.874412 -328.782891) (xy 399.93824 -328.778875)
			(xy 400.002068 -328.782891) (xy 400.064889 -328.794874) (xy 400.125713 -328.814637) (xy 400.18358 -328.841868)
			(xy 400.237578 -328.876136) (xy 400.286856 -328.916902) (xy 400.330635 -328.963522) (xy 400.368227 -329.015262)
			(xy 400.399037 -329.071306) (xy 400.403821 -329.083389) (xy 402.378158 -329.083389) (xy 402.378158 -329.019435)
			(xy 402.386173 -328.955985) (xy 402.402078 -328.89404) (xy 402.425621 -328.834578) (xy 402.456431 -328.778534)
			(xy 402.494023 -328.726794) (xy 402.537802 -328.680174) (xy 402.58708 -328.639408) (xy 402.641078 -328.60514)
			(xy 402.698945 -328.577909) (xy 402.759769 -328.558146) (xy 402.82259 -328.546163) (xy 402.886418 -328.542147)
			(xy 402.950246 -328.546163) (xy 403.013067 -328.558146) (xy 403.073891 -328.577909) (xy 403.131758 -328.60514)
			(xy 403.185756 -328.639408) (xy 403.235034 -328.680174) (xy 403.278813 -328.726794) (xy 403.316405 -328.778534)
			(xy 403.347215 -328.834578) (xy 403.370758 -328.89404) (xy 403.386663 -328.955985) (xy 403.392621 -329.003152)
			(xy 404.630634 -329.003152) (xy 404.634707 -328.947493) (xy 404.646842 -328.89302) (xy 404.666778 -328.840894)
			(xy 404.694092 -328.792226) (xy 404.7282 -328.748054) (xy 404.768377 -328.709319) (xy 404.813765 -328.676847)
			(xy 404.863397 -328.651329) (xy 404.916217 -328.63331) (xy 404.971096 -328.623173) (xy 405.026867 -328.621135)
			(xy 405.082341 -328.627238) (xy 405.136334 -328.641354) (xy 405.187697 -328.663181) (xy 405.235335 -328.692254)
			(xy 405.278231 -328.727953) (xy 405.315473 -328.769517) (xy 405.346267 -328.816061) (xy 405.369955 -328.866592)
			(xy 405.386033 -328.920034) (xy 405.394159 -328.975248) (xy 405.394668 -329.003152) (xy 405.394159 -329.031056)
			(xy 405.386033 -329.08627) (xy 405.369955 -329.139712) (xy 405.346267 -329.190243) (xy 405.315473 -329.236787)
			(xy 405.278231 -329.278351) (xy 405.235335 -329.31405) (xy 405.187697 -329.343123) (xy 405.136334 -329.36495)
			(xy 405.082341 -329.379066) (xy 405.026867 -329.385169) (xy 404.971096 -329.383131) (xy 404.916217 -329.372994)
			(xy 404.863397 -329.354975) (xy 404.813765 -329.329457) (xy 404.768377 -329.296985) (xy 404.7282 -329.25825)
			(xy 404.694092 -329.214078) (xy 404.666778 -329.16541) (xy 404.646842 -329.113284) (xy 404.634707 -329.058811)
			(xy 404.630634 -329.003152) (xy 403.392621 -329.003152) (xy 403.394678 -329.019435) (xy 403.39518 -329.051412)
			(xy 403.394678 -329.083389) (xy 403.386663 -329.146839) (xy 403.370758 -329.208784) (xy 403.347215 -329.268246)
			(xy 403.316405 -329.32429) (xy 403.278813 -329.37603) (xy 403.235034 -329.42265) (xy 403.185756 -329.463416)
			(xy 403.131758 -329.497684) (xy 403.073891 -329.524915) (xy 403.013067 -329.544678) (xy 402.950246 -329.556661)
			(xy 402.886418 -329.560677) (xy 402.82259 -329.556661) (xy 402.759769 -329.544678) (xy 402.698945 -329.524915)
			(xy 402.641078 -329.497684) (xy 402.58708 -329.463416) (xy 402.537802 -329.42265) (xy 402.494023 -329.37603)
			(xy 402.456431 -329.32429) (xy 402.425621 -329.268246) (xy 402.402078 -329.208784) (xy 402.386173 -329.146839)
			(xy 402.378158 -329.083389) (xy 400.403821 -329.083389) (xy 400.42258 -329.130768) (xy 400.438485 -329.192713)
			(xy 400.4465 -329.256163) (xy 400.447002 -329.28814) (xy 400.4465 -329.320117) (xy 400.438485 -329.383567)
			(xy 400.42258 -329.445512) (xy 400.399037 -329.504974) (xy 400.368227 -329.561018) (xy 400.330635 -329.612758)
			(xy 400.286856 -329.659378) (xy 400.237578 -329.700144) (xy 400.18358 -329.734412) (xy 400.125713 -329.761643)
			(xy 400.064889 -329.781406) (xy 400.002068 -329.793389) (xy 399.93824 -329.797405) (xy 399.874412 -329.793389)
			(xy 399.811591 -329.781406) (xy 399.750767 -329.761643) (xy 399.6929 -329.734412) (xy 399.638902 -329.700144)
			(xy 399.589624 -329.659378) (xy 399.545845 -329.612758) (xy 399.508253 -329.561018) (xy 399.477443 -329.504974)
			(xy 399.4539 -329.445512) (xy 399.437995 -329.383567) (xy 399.42998 -329.320117) (xy 396.71117 -329.320117)
			(xy 396.71117 -331.54112) (xy 396.711661 -331.551127) (xy 396.719323 -331.569617) (xy 396.733474 -331.583771)
			(xy 396.751963 -331.591437) (xy 396.76197 -331.59192)
		)
		(stroke
			(width 0)
			(type solid)
		)
		(fill yes)
		(layer "In4.Cu")
		(net "PVDD18_S5_P0")
	)
	(gr_poly
		(pts
			(xy 101.525832 -256.861564) (xy 101.537903 -256.860897) (xy 101.559387 -256.84989) (xy 101.56698 -256.840482)
			(xy 101.621082 -256.765552) (xy 101.624892 -256.741422) (xy 101.621082 -256.729738) (xy 101.613966 -256.706571)
			(xy 101.606314 -256.658718) (xy 101.605842 -256.634488) (xy 101.606364 -256.609233) (xy 101.614677 -256.559411)
			(xy 101.631078 -256.511637) (xy 101.655119 -256.467214) (xy 101.686143 -256.427354) (xy 101.723305 -256.393144)
			(xy 101.765591 -256.365518) (xy 101.811847 -256.345228) (xy 101.860812 -256.332828) (xy 101.91115 -256.328657)
			(xy 101.961488 -256.332828) (xy 102.010453 -256.345228) (xy 102.056709 -256.365518) (xy 102.098995 -256.393144)
			(xy 102.136157 -256.427354) (xy 102.167181 -256.467214) (xy 102.191222 -256.511637) (xy 102.207623 -256.559411)
			(xy 102.215936 -256.609233) (xy 102.216458 -256.634488) (xy 102.215994 -256.658719) (xy 102.208339 -256.706572)
			(xy 102.201218 -256.729738) (xy 102.197408 -256.741422) (xy 102.201218 -256.765552) (xy 102.25532 -256.840482)
			(xy 102.262932 -256.849865) (xy 102.284406 -256.860865) (xy 102.296468 -256.861564) (xy 102.465632 -256.861564)
			(xy 102.477703 -256.860897) (xy 102.499187 -256.84989) (xy 102.50678 -256.840482) (xy 102.560882 -256.765298)
			(xy 102.564692 -256.741168) (xy 102.560882 -256.729484) (xy 102.553566 -256.706026) (xy 102.545661 -256.657531)
			(xy 102.545134 -256.632964) (xy 102.545656 -256.607709) (xy 102.553969 -256.557887) (xy 102.57037 -256.510113)
			(xy 102.594411 -256.46569) (xy 102.625435 -256.42583) (xy 102.662597 -256.39162) (xy 102.704883 -256.363994)
			(xy 102.751139 -256.343704) (xy 102.800104 -256.331304) (xy 102.850442 -256.327133) (xy 102.90078 -256.331304)
			(xy 102.949745 -256.343704) (xy 102.996001 -256.363994) (xy 103.038287 -256.39162) (xy 103.075449 -256.42583)
			(xy 103.106473 -256.46569) (xy 103.130514 -256.510113) (xy 103.146915 -256.557887) (xy 103.155228 -256.607709)
			(xy 103.15575 -256.632964) (xy 103.155236 -256.657532) (xy 103.147321 -256.706026) (xy 103.140002 -256.729484)
			(xy 103.136192 -256.741168) (xy 103.140002 -256.765298) (xy 103.194104 -256.840482) (xy 103.201715 -256.849868)
			(xy 103.223189 -256.860875) (xy 103.235252 -256.861564) (xy 105.88371 -256.861564) (xy 105.893554 -256.861041)
			(xy 105.911736 -256.853476) (xy 105.919016 -256.846832) (xy 106.016552 -256.749296) (xy 106.023262 -256.742057)
			(xy 106.030853 -256.723852) (xy 106.031284 -256.71399) (xy 106.031284 -255.739646) (xy 106.030851 -255.729581)
			(xy 106.023121 -255.710992) (xy 106.016298 -255.703578) (xy 103.974392 -253.661672) (xy 103.94188 -253.656592)
			(xy 103.927148 -253.664212) (xy 103.90549 -253.674797) (xy 103.859666 -253.689753) (xy 103.812058 -253.697306)
			(xy 103.787956 -253.69774) (xy 103.782622 -253.69774) (xy 103.756564 -253.696752) (xy 103.705343 -253.686994)
			(xy 103.656522 -253.668682) (xy 103.611519 -253.642345) (xy 103.571642 -253.60875) (xy 103.538048 -253.568871)
			(xy 103.511713 -253.523867) (xy 103.493402 -253.475046) (xy 103.483647 -253.423824) (xy 103.482648 -253.397766)
			(xy 103.482648 -253.393956) (xy 103.482648 -253.392432) (xy 103.483104 -253.368332) (xy 103.49067 -253.32073)
			(xy 103.505604 -253.274902) (xy 103.516176 -253.25324) (xy 103.523796 -253.238508) (xy 103.518716 -253.205996)
			(xy 102.856538 -252.543818) (xy 102.849367 -252.537191) (xy 102.831452 -252.529471) (xy 102.811949 -252.529042)
			(xy 102.80269 -252.532134) (xy 102.704392 -252.56871) (xy 102.686612 -252.592078) (xy 102.685596 -252.607064)
			(xy 102.683214 -252.632364) (xy 102.671118 -252.681716) (xy 102.651016 -252.728384) (xy 102.623463 -252.771079)
			(xy 102.589221 -252.808622) (xy 102.549234 -252.839976) (xy 102.504607 -252.864275) (xy 102.456573 -252.880848)
			(xy 102.406457 -252.889238) (xy 102.38105 -252.889766) (xy 102.357063 -252.889292) (xy 102.309679 -252.881779)
			(xy 102.264055 -252.866947) (xy 102.221312 -252.84516) (xy 102.182504 -252.816955) (xy 102.148585 -252.783026)
			(xy 102.120392 -252.744209) (xy 102.098618 -252.70146) (xy 102.083799 -252.655831) (xy 102.076301 -252.608446)
			(xy 102.075742 -252.584458) (xy 102.07625 -252.559053) (xy 102.084664 -252.508945) (xy 102.101254 -252.460919)
			(xy 102.125561 -252.416301) (xy 102.156917 -252.376319) (xy 102.194456 -252.342078) (xy 102.237143 -252.314519)
			(xy 102.283802 -252.294404) (xy 102.333146 -252.282287) (xy 102.358444 -252.279912) (xy 102.37343 -252.278896)
			(xy 102.396798 -252.261116) (xy 102.433374 -252.162818) (xy 102.43637 -252.153543) (xy 102.435912 -252.134074)
			(xy 102.428268 -252.116161) (xy 102.42169 -252.10897) (xy 102.285546 -251.972826) (xy 102.277826 -251.965767)
			(xy 102.258414 -251.958027) (xy 102.247954 -251.95784) (xy 102.165404 -251.96038) (xy 102.146608 -251.969016)
			(xy 102.139496 -251.977144) (xy 102.121958 -251.996089) (xy 102.081684 -252.028382) (xy 102.036552 -252.05344)
			(xy 101.987849 -252.070551) (xy 101.936961 -252.079225) (xy 101.91115 -252.07976) (xy 101.887163 -252.079286)
			(xy 101.83978 -252.071773) (xy 101.794156 -252.056941) (xy 101.751413 -252.035154) (xy 101.712606 -252.006949)
			(xy 101.678688 -251.97302) (xy 101.650495 -251.934203) (xy 101.628722 -251.891454) (xy 101.613904 -251.845825)
			(xy 101.606407 -251.798439) (xy 101.605842 -251.774452) (xy 101.605981 -251.761689) (xy 101.608144 -251.736255)
			(xy 101.61016 -251.723652) (xy 101.609906 -251.723652) (xy 101.614757 -251.698184) (xy 101.63188 -251.649254)
			(xy 101.657012 -251.603914) (xy 101.689432 -251.563463) (xy 101.708458 -251.545852) (xy 101.716586 -251.53874)
			(xy 101.725222 -251.520198) (xy 101.727762 -251.437648) (xy 101.727576 -251.427186) (xy 101.719849 -251.407765)
			(xy 101.712776 -251.400056) (xy 101.571552 -251.258832) (xy 101.544374 -251.251974) (xy 101.530658 -251.256292)
			(xy 101.508777 -251.262575) (xy 101.463758 -251.269336) (xy 101.440996 -251.269754) (xy 101.417004 -251.269283)
			(xy 101.36961 -251.261777) (xy 101.323973 -251.24695) (xy 101.281218 -251.225167) (xy 101.242396 -251.196964)
			(xy 101.208463 -251.163036) (xy 101.180255 -251.124218) (xy 101.158466 -251.081466) (xy 101.143633 -251.035831)
			(xy 101.13612 -250.988438) (xy 101.135688 -250.964446) (xy 101.136105 -250.941684) (xy 101.142858 -250.896663)
			(xy 101.14915 -250.874784) (xy 101.153468 -250.861068) (xy 101.14661 -250.83389) (xy 101.03739 -250.72467)
			(xy 101.029994 -250.717818) (xy 101.011395 -250.710076) (xy 101.001322 -250.709684) (xy 100.491798 -250.709684)
			(xy 100.481964 -250.709142) (xy 100.463812 -250.701545) (xy 100.456492 -250.694952) (xy 100.196396 -250.434856)
			(xy 100.165662 -250.42876) (xy 100.151438 -250.43511) (xy 100.132337 -250.442912) (xy 100.092563 -250.453887)
			(xy 100.051673 -250.459407) (xy 100.031042 -250.459748) (xy 100.007046 -250.459305) (xy 99.959643 -250.451804)
			(xy 99.913997 -250.436979) (xy 99.871232 -250.415197) (xy 99.832401 -250.386993) (xy 99.798461 -250.353061)
			(xy 99.770246 -250.314238) (xy 99.748452 -250.271479) (xy 99.733615 -250.225837) (xy 99.726101 -250.178436)
			(xy 99.725734 -250.15444) (xy 99.726059 -250.133809) (xy 99.731586 -250.092919) (xy 99.742573 -250.053147)
			(xy 99.750372 -250.034044) (xy 99.756722 -250.01982) (xy 99.750626 -249.989086) (xy 98.85553 -249.09399)
			(xy 98.848132 -249.087145) (xy 98.829533 -249.079422) (xy 98.819462 -249.079004) (xy 98.05162 -249.079004)
			(xy 98.038887 -249.079706) (xy 98.016492 -249.091836) (xy 98.008948 -249.102118) (xy 97.956624 -249.18289)
			(xy 97.954592 -249.20829) (xy 97.959926 -249.220228) (xy 97.968264 -249.239863) (xy 97.980028 -249.280865)
			(xy 97.985973 -249.323106) (xy 97.986342 -249.344434) (xy 97.98582 -249.369689) (xy 97.977507 -249.419511)
			(xy 97.961106 -249.467285) (xy 97.937065 -249.511708) (xy 97.906041 -249.551568) (xy 97.868879 -249.585778)
			(xy 97.826593 -249.613404) (xy 97.780337 -249.633694) (xy 97.731372 -249.646094) (xy 97.681034 -249.650265)
			(xy 97.630696 -249.646094) (xy 97.581731 -249.633694) (xy 97.535475 -249.613404) (xy 97.493189 -249.585778)
			(xy 97.456027 -249.551568) (xy 97.425003 -249.511708) (xy 97.400962 -249.467285) (xy 97.384561 -249.419511)
			(xy 97.376248 -249.369689) (xy 97.375726 -249.344434) (xy 97.37608 -249.323104) (xy 97.382018 -249.28086)
			(xy 97.393784 -249.239855) (xy 97.402142 -249.220228) (xy 97.407476 -249.20829) (xy 97.405444 -249.18289)
			(xy 97.35312 -249.102118) (xy 97.34826 -249.095181) (xy 97.334925 -249.084754) (xy 97.318913 -249.079263)
			(xy 97.310448 -249.079004) (xy 96.620838 -249.079004) (xy 96.611 -249.079539) (xy 96.592837 -249.087124)
			(xy 96.585532 -249.093736) (xy 96.394016 -249.285252) (xy 96.387306 -249.292491) (xy 96.379722 -249.310696)
			(xy 96.379284 -249.320558) (xy 96.379284 -249.850402) (xy 96.39427 -249.874786) (xy 96.407478 -249.881136)
			(xy 96.428894 -249.892361) (xy 96.468191 -249.92053) (xy 96.50256 -249.954537) (xy 96.531145 -249.993532)
			(xy 96.553232 -250.036543) (xy 96.568269 -250.082496) (xy 96.575881 -250.130243) (xy 96.575879 -250.15444)
			(xy 97.84513 -250.15444) (xy 97.84909 -250.105386) (xy 97.860867 -250.057602) (xy 97.880158 -250.012326)
			(xy 97.906461 -249.97073) (xy 97.939096 -249.933893) (xy 97.977217 -249.902768) (xy 98.019838 -249.878161)
			(xy 98.065854 -249.860709) (xy 98.114073 -249.850865) (xy 98.163248 -249.848884) (xy 98.212103 -249.854816)
			(xy 98.259374 -249.868508) (xy 98.303836 -249.889606) (xy 98.344339 -249.917562) (xy 98.379832 -249.951654)
			(xy 98.409397 -249.990998) (xy 98.432268 -250.034575) (xy 98.447852 -250.081256) (xy 98.455747 -250.129833)
			(xy 98.456242 -250.15444) (xy 98.455747 -250.179047) (xy 98.447852 -250.227624) (xy 98.432268 -250.274305)
			(xy 98.409397 -250.317882) (xy 98.379832 -250.357226) (xy 98.344339 -250.391318) (xy 98.303836 -250.419274)
			(xy 98.259374 -250.440372) (xy 98.212103 -250.454064) (xy 98.163248 -250.459996) (xy 98.114073 -250.458015)
			(xy 98.065854 -250.448171) (xy 98.019838 -250.430719) (xy 97.977217 -250.406112) (xy 97.939096 -250.374987)
			(xy 97.906461 -250.33815) (xy 97.880158 -250.296554) (xy 97.860867 -250.251278) (xy 97.84909 -250.203494)
			(xy 97.84513 -250.15444) (xy 96.575879 -250.15444) (xy 96.575878 -250.178593) (xy 96.568261 -250.226339)
			(xy 96.553218 -250.27229) (xy 96.531126 -250.315298) (xy 96.502537 -250.35429) (xy 96.468163 -250.388293)
			(xy 96.428863 -250.416457) (xy 96.407478 -250.427744) (xy 96.39427 -250.434094) (xy 96.379284 -250.458478)
			(xy 96.379284 -250.964446) (xy 97.37523 -250.964446) (xy 97.37919 -250.915392) (xy 97.390967 -250.867608)
			(xy 97.410258 -250.822332) (xy 97.436561 -250.780736) (xy 97.469196 -250.743899) (xy 97.507317 -250.712774)
			(xy 97.549938 -250.688167) (xy 97.595954 -250.670715) (xy 97.644173 -250.660871) (xy 97.693348 -250.65889)
			(xy 97.742203 -250.664822) (xy 97.789474 -250.678514) (xy 97.833936 -250.699612) (xy 97.874439 -250.727568)
			(xy 97.909932 -250.76166) (xy 97.939497 -250.801004) (xy 97.962368 -250.844581) (xy 97.977952 -250.891262)
			(xy 97.985847 -250.939839) (xy 97.986342 -250.964446) (xy 99.255338 -250.964446) (xy 99.259298 -250.915392)
			(xy 99.271075 -250.867608) (xy 99.290366 -250.822332) (xy 99.316669 -250.780736) (xy 99.349304 -250.743899)
			(xy 99.387425 -250.712774) (xy 99.430046 -250.688167) (xy 99.476062 -250.670715) (xy 99.524281 -250.660871)
			(xy 99.573456 -250.65889) (xy 99.622311 -250.664822) (xy 99.669582 -250.678514) (xy 99.714044 -250.699612)
			(xy 99.754547 -250.727568) (xy 99.79004 -250.76166) (xy 99.819605 -250.801004) (xy 99.842476 -250.844581)
			(xy 99.85806 -250.891262) (xy 99.865955 -250.939839) (xy 99.86645 -250.964446) (xy 99.865955 -250.989053)
			(xy 99.85806 -251.03763) (xy 99.842476 -251.084311) (xy 99.819605 -251.127888) (xy 99.79004 -251.167232)
			(xy 99.754547 -251.201324) (xy 99.714044 -251.22928) (xy 99.669582 -251.250378) (xy 99.622311 -251.26407)
			(xy 99.573456 -251.270002) (xy 99.524281 -251.268021) (xy 99.476062 -251.258177) (xy 99.430046 -251.240725)
			(xy 99.387425 -251.216118) (xy 99.349304 -251.184993) (xy 99.316669 -251.148156) (xy 99.290366 -251.10656)
			(xy 99.271075 -251.061284) (xy 99.259298 -251.0135) (xy 99.255338 -250.964446) (xy 97.986342 -250.964446)
			(xy 97.985847 -250.989053) (xy 97.977952 -251.03763) (xy 97.962368 -251.084311) (xy 97.939497 -251.127888)
			(xy 97.909932 -251.167232) (xy 97.874439 -251.201324) (xy 97.833936 -251.22928) (xy 97.789474 -251.250378)
			(xy 97.742203 -251.26407) (xy 97.693348 -251.270002) (xy 97.644173 -251.268021) (xy 97.595954 -251.258177)
			(xy 97.549938 -251.240725) (xy 97.507317 -251.216118) (xy 97.469196 -251.184993) (xy 97.436561 -251.148156)
			(xy 97.410258 -251.10656) (xy 97.390967 -251.061284) (xy 97.37919 -251.0135) (xy 97.37523 -250.964446)
			(xy 96.379284 -250.964446) (xy 96.379284 -251.470414) (xy 96.39427 -251.494798) (xy 96.407478 -251.501148)
			(xy 96.428901 -251.512373) (xy 96.468211 -251.540545) (xy 96.502594 -251.574556) (xy 96.531192 -251.613558)
			(xy 96.553289 -251.656576) (xy 96.568336 -251.702539) (xy 96.575956 -251.750297) (xy 96.575958 -251.774452)
			(xy 97.84513 -251.774452) (xy 97.84909 -251.725398) (xy 97.860867 -251.677614) (xy 97.880158 -251.632338)
			(xy 97.906461 -251.590742) (xy 97.939096 -251.553905) (xy 97.977217 -251.52278) (xy 98.019838 -251.498173)
			(xy 98.065854 -251.480721) (xy 98.114073 -251.470877) (xy 98.163248 -251.468896) (xy 98.212103 -251.474828)
			(xy 98.259374 -251.48852) (xy 98.303836 -251.509618) (xy 98.344339 -251.537574) (xy 98.379832 -251.571666)
			(xy 98.409397 -251.61101) (xy 98.432268 -251.654587) (xy 98.447852 -251.701268) (xy 98.455747 -251.749845)
			(xy 98.456242 -251.774452) (xy 99.725238 -251.774452) (xy 99.729198 -251.725398) (xy 99.740975 -251.677614)
			(xy 99.760266 -251.632338) (xy 99.786569 -251.590742) (xy 99.819204 -251.553905) (xy 99.857325 -251.52278)
			(xy 99.899946 -251.498173) (xy 99.945962 -251.480721) (xy 99.994181 -251.470877) (xy 100.043356 -251.468896)
			(xy 100.092211 -251.474828) (xy 100.139482 -251.48852) (xy 100.183944 -251.509618) (xy 100.224447 -251.537574)
			(xy 100.25994 -251.571666) (xy 100.289505 -251.61101) (xy 100.312376 -251.654587) (xy 100.32796 -251.701268)
			(xy 100.335855 -251.749845) (xy 100.33635 -251.774452) (xy 100.335855 -251.799059) (xy 100.32796 -251.847636)
			(xy 100.312376 -251.894317) (xy 100.289505 -251.937894) (xy 100.25994 -251.977238) (xy 100.224447 -252.01133)
			(xy 100.183944 -252.039286) (xy 100.139482 -252.060384) (xy 100.092211 -252.074076) (xy 100.043356 -252.080008)
			(xy 99.994181 -252.078027) (xy 99.945962 -252.068183) (xy 99.899946 -252.050731) (xy 99.857325 -252.026124)
			(xy 99.819204 -251.994999) (xy 99.786569 -251.958162) (xy 99.760266 -251.916566) (xy 99.740975 -251.87129)
			(xy 99.729198 -251.823506) (xy 99.725238 -251.774452) (xy 98.456242 -251.774452) (xy 98.455747 -251.799059)
			(xy 98.447852 -251.847636) (xy 98.432268 -251.894317) (xy 98.409397 -251.937894) (xy 98.379832 -251.977238)
			(xy 98.344339 -252.01133) (xy 98.303836 -252.039286) (xy 98.259374 -252.060384) (xy 98.212103 -252.074076)
			(xy 98.163248 -252.080008) (xy 98.114073 -252.078027) (xy 98.065854 -252.068183) (xy 98.019838 -252.050731)
			(xy 97.977217 -252.026124) (xy 97.939096 -251.994999) (xy 97.906461 -251.958162) (xy 97.880158 -251.916566)
			(xy 97.860867 -251.87129) (xy 97.84909 -251.823506) (xy 97.84513 -251.774452) (xy 96.575958 -251.774452)
			(xy 96.57596 -251.79866) (xy 96.568346 -251.846419) (xy 96.553306 -251.892384) (xy 96.531214 -251.935406)
			(xy 96.502622 -251.974412) (xy 96.468244 -252.008427) (xy 96.428938 -252.036604) (xy 96.407478 -252.047756)
			(xy 96.39427 -252.054106) (xy 96.379284 -252.07849) (xy 96.379284 -252.584458) (xy 97.37523 -252.584458)
			(xy 97.37919 -252.535404) (xy 97.390967 -252.48762) (xy 97.410258 -252.442344) (xy 97.436561 -252.400748)
			(xy 97.469196 -252.363911) (xy 97.507317 -252.332786) (xy 97.549938 -252.308179) (xy 97.595954 -252.290727)
			(xy 97.644173 -252.280883) (xy 97.693348 -252.278902) (xy 97.742203 -252.284834) (xy 97.789474 -252.298526)
			(xy 97.833936 -252.319624) (xy 97.874439 -252.34758) (xy 97.909932 -252.381672) (xy 97.939497 -252.421016)
			(xy 97.962368 -252.464593) (xy 97.977952 -252.511274) (xy 97.985847 -252.559851) (xy 97.986342 -252.584458)
			(xy 99.255338 -252.584458) (xy 99.259298 -252.535404) (xy 99.271075 -252.48762) (xy 99.290366 -252.442344)
			(xy 99.316669 -252.400748) (xy 99.349304 -252.363911) (xy 99.387425 -252.332786) (xy 99.430046 -252.308179)
			(xy 99.476062 -252.290727) (xy 99.524281 -252.280883) (xy 99.573456 -252.278902) (xy 99.622311 -252.284834)
			(xy 99.669582 -252.298526) (xy 99.714044 -252.319624) (xy 99.754547 -252.34758) (xy 99.79004 -252.381672)
			(xy 99.819605 -252.421016) (xy 99.842476 -252.464593) (xy 99.85806 -252.511274) (xy 99.865955 -252.559851)
			(xy 99.86645 -252.584458) (xy 101.135192 -252.584458) (xy 101.139152 -252.535404) (xy 101.150929 -252.48762)
			(xy 101.17022 -252.442344) (xy 101.196523 -252.400748) (xy 101.229158 -252.363911) (xy 101.267279 -252.332786)
			(xy 101.3099 -252.308179) (xy 101.355916 -252.290727) (xy 101.404135 -252.280883) (xy 101.45331 -252.278902)
			(xy 101.502165 -252.284834) (xy 101.549436 -252.298526) (xy 101.593898 -252.319624) (xy 101.634401 -252.34758)
			(xy 101.669894 -252.381672) (xy 101.699459 -252.421016) (xy 101.72233 -252.464593) (xy 101.737914 -252.511274)
			(xy 101.745809 -252.559851) (xy 101.746304 -252.584458) (xy 101.745809 -252.609065) (xy 101.737914 -252.657642)
			(xy 101.72233 -252.704323) (xy 101.699459 -252.7479) (xy 101.669894 -252.787244) (xy 101.634401 -252.821336)
			(xy 101.593898 -252.849292) (xy 101.549436 -252.87039) (xy 101.502165 -252.884082) (xy 101.45331 -252.890014)
			(xy 101.404135 -252.888033) (xy 101.355916 -252.878189) (xy 101.3099 -252.860737) (xy 101.267279 -252.83613)
			(xy 101.229158 -252.805005) (xy 101.196523 -252.768168) (xy 101.17022 -252.726572) (xy 101.150929 -252.681296)
			(xy 101.139152 -252.633512) (xy 101.135192 -252.584458) (xy 99.86645 -252.584458) (xy 99.865955 -252.609065)
			(xy 99.85806 -252.657642) (xy 99.842476 -252.704323) (xy 99.819605 -252.7479) (xy 99.79004 -252.787244)
			(xy 99.754547 -252.821336) (xy 99.714044 -252.849292) (xy 99.669582 -252.87039) (xy 99.622311 -252.884082)
			(xy 99.573456 -252.890014) (xy 99.524281 -252.888033) (xy 99.476062 -252.878189) (xy 99.430046 -252.860737)
			(xy 99.387425 -252.83613) (xy 99.349304 -252.805005) (xy 99.316669 -252.768168) (xy 99.290366 -252.726572)
			(xy 99.271075 -252.681296) (xy 99.259298 -252.633512) (xy 99.255338 -252.584458) (xy 97.986342 -252.584458)
			(xy 97.985847 -252.609065) (xy 97.977952 -252.657642) (xy 97.962368 -252.704323) (xy 97.939497 -252.7479)
			(xy 97.909932 -252.787244) (xy 97.874439 -252.821336) (xy 97.833936 -252.849292) (xy 97.789474 -252.87039)
			(xy 97.742203 -252.884082) (xy 97.693348 -252.890014) (xy 97.644173 -252.888033) (xy 97.595954 -252.878189)
			(xy 97.549938 -252.860737) (xy 97.507317 -252.83613) (xy 97.469196 -252.805005) (xy 97.436561 -252.768168)
			(xy 97.410258 -252.726572) (xy 97.390967 -252.681296) (xy 97.37919 -252.633512) (xy 97.37523 -252.584458)
			(xy 96.379284 -252.584458) (xy 96.379284 -253.090426) (xy 96.39427 -253.11481) (xy 96.407478 -253.12116)
			(xy 96.4289 -253.132385) (xy 96.468208 -253.160556) (xy 96.50259 -253.194567) (xy 96.531185 -253.233568)
			(xy 96.553282 -253.276586) (xy 96.568327 -253.322547) (xy 96.575946 -253.370303) (xy 96.575947 -253.394464)
			(xy 97.84513 -253.394464) (xy 97.84909 -253.34541) (xy 97.860867 -253.297626) (xy 97.880158 -253.25235)
			(xy 97.906461 -253.210754) (xy 97.939096 -253.173917) (xy 97.977217 -253.142792) (xy 98.019838 -253.118185)
			(xy 98.065854 -253.100733) (xy 98.114073 -253.090889) (xy 98.163248 -253.088908) (xy 98.212103 -253.09484)
			(xy 98.259374 -253.108532) (xy 98.303836 -253.12963) (xy 98.344339 -253.157586) (xy 98.379832 -253.191678)
			(xy 98.409397 -253.231022) (xy 98.432268 -253.274599) (xy 98.447852 -253.32128) (xy 98.455747 -253.369857)
			(xy 98.456242 -253.394464) (xy 99.725238 -253.394464) (xy 99.729198 -253.34541) (xy 99.740975 -253.297626)
			(xy 99.760266 -253.25235) (xy 99.786569 -253.210754) (xy 99.819204 -253.173917) (xy 99.857325 -253.142792)
			(xy 99.899946 -253.118185) (xy 99.945962 -253.100733) (xy 99.994181 -253.090889) (xy 100.043356 -253.088908)
			(xy 100.092211 -253.09484) (xy 100.139482 -253.108532) (xy 100.183944 -253.12963) (xy 100.224447 -253.157586)
			(xy 100.25994 -253.191678) (xy 100.289505 -253.231022) (xy 100.312376 -253.274599) (xy 100.32796 -253.32128)
			(xy 100.335855 -253.369857) (xy 100.33635 -253.394464) (xy 100.665292 -253.394464) (xy 100.669252 -253.34541)
			(xy 100.681029 -253.297626) (xy 100.70032 -253.25235) (xy 100.726623 -253.210754) (xy 100.759258 -253.173917)
			(xy 100.797379 -253.142792) (xy 100.84 -253.118185) (xy 100.886016 -253.100733) (xy 100.934235 -253.090889)
			(xy 100.98341 -253.088908) (xy 101.032265 -253.09484) (xy 101.079536 -253.108532) (xy 101.123998 -253.12963)
			(xy 101.164501 -253.157586) (xy 101.199994 -253.191678) (xy 101.229559 -253.231022) (xy 101.25243 -253.274599)
			(xy 101.268014 -253.32128) (xy 101.275909 -253.369857) (xy 101.276404 -253.394464) (xy 101.605346 -253.394464)
			(xy 101.609306 -253.34541) (xy 101.621083 -253.297626) (xy 101.640374 -253.25235) (xy 101.666677 -253.210754)
			(xy 101.699312 -253.173917) (xy 101.737433 -253.142792) (xy 101.780054 -253.118185) (xy 101.82607 -253.100733)
			(xy 101.874289 -253.090889) (xy 101.923464 -253.088908) (xy 101.972319 -253.09484) (xy 102.01959 -253.108532)
			(xy 102.064052 -253.12963) (xy 102.104555 -253.157586) (xy 102.140048 -253.191678) (xy 102.169613 -253.231022)
			(xy 102.192484 -253.274599) (xy 102.208068 -253.32128) (xy 102.215963 -253.369857) (xy 102.216458 -253.394464)
			(xy 102.215963 -253.419071) (xy 102.208068 -253.467648) (xy 102.192484 -253.514329) (xy 102.169613 -253.557906)
			(xy 102.140048 -253.59725) (xy 102.104555 -253.631342) (xy 102.064052 -253.659298) (xy 102.01959 -253.680396)
			(xy 101.972319 -253.694088) (xy 101.923464 -253.70002) (xy 101.874289 -253.698039) (xy 101.82607 -253.688195)
			(xy 101.780054 -253.670743) (xy 101.737433 -253.646136) (xy 101.699312 -253.615011) (xy 101.666677 -253.578174)
			(xy 101.640374 -253.536578) (xy 101.621083 -253.491302) (xy 101.609306 -253.443518) (xy 101.605346 -253.394464)
			(xy 101.276404 -253.394464) (xy 101.275909 -253.419071) (xy 101.268014 -253.467648) (xy 101.25243 -253.514329)
			(xy 101.229559 -253.557906) (xy 101.199994 -253.59725) (xy 101.164501 -253.631342) (xy 101.123998 -253.659298)
			(xy 101.079536 -253.680396) (xy 101.032265 -253.694088) (xy 100.98341 -253.70002) (xy 100.934235 -253.698039)
			(xy 100.886016 -253.688195) (xy 100.84 -253.670743) (xy 100.797379 -253.646136) (xy 100.759258 -253.615011)
			(xy 100.726623 -253.578174) (xy 100.70032 -253.536578) (xy 100.681029 -253.491302) (xy 100.669252 -253.443518)
			(xy 100.665292 -253.394464) (xy 100.33635 -253.394464) (xy 100.335855 -253.419071) (xy 100.32796 -253.467648)
			(xy 100.312376 -253.514329) (xy 100.289505 -253.557906) (xy 100.25994 -253.59725) (xy 100.224447 -253.631342)
			(xy 100.183944 -253.659298) (xy 100.139482 -253.680396) (xy 100.092211 -253.694088) (xy 100.043356 -253.70002)
			(xy 99.994181 -253.698039) (xy 99.945962 -253.688195) (xy 99.899946 -253.670743) (xy 99.857325 -253.646136)
			(xy 99.819204 -253.615011) (xy 99.786569 -253.578174) (xy 99.760266 -253.536578) (xy 99.740975 -253.491302)
			(xy 99.729198 -253.443518) (xy 99.725238 -253.394464) (xy 98.456242 -253.394464) (xy 98.455747 -253.419071)
			(xy 98.447852 -253.467648) (xy 98.432268 -253.514329) (xy 98.409397 -253.557906) (xy 98.379832 -253.59725)
			(xy 98.344339 -253.631342) (xy 98.303836 -253.659298) (xy 98.259374 -253.680396) (xy 98.212103 -253.694088)
			(xy 98.163248 -253.70002) (xy 98.114073 -253.698039) (xy 98.065854 -253.688195) (xy 98.019838 -253.670743)
			(xy 97.977217 -253.646136) (xy 97.939096 -253.615011) (xy 97.906461 -253.578174) (xy 97.880158 -253.536578)
			(xy 97.860867 -253.491302) (xy 97.84909 -253.443518) (xy 97.84513 -253.394464) (xy 96.575947 -253.394464)
			(xy 96.575949 -253.418664) (xy 96.568335 -253.466422) (xy 96.553294 -253.512385) (xy 96.531202 -253.555405)
			(xy 96.502611 -253.594409) (xy 96.468233 -253.628423) (xy 96.428927 -253.656598) (xy 96.407478 -253.667768)
			(xy 96.39427 -253.674118) (xy 96.379284 -253.698502) (xy 96.379284 -254.20447) (xy 97.37523 -254.20447)
			(xy 97.37919 -254.155416) (xy 97.390967 -254.107632) (xy 97.410258 -254.062356) (xy 97.436561 -254.02076)
			(xy 97.469196 -253.983923) (xy 97.507317 -253.952798) (xy 97.549938 -253.928191) (xy 97.595954 -253.910739)
			(xy 97.644173 -253.900895) (xy 97.693348 -253.898914) (xy 97.742203 -253.904846) (xy 97.789474 -253.918538)
			(xy 97.833936 -253.939636) (xy 97.874439 -253.967592) (xy 97.909932 -254.001684) (xy 97.939497 -254.041028)
			(xy 97.962368 -254.084605) (xy 97.977952 -254.131286) (xy 97.985847 -254.179863) (xy 97.986342 -254.20447)
			(xy 99.255338 -254.20447) (xy 99.259298 -254.155416) (xy 99.271075 -254.107632) (xy 99.290366 -254.062356)
			(xy 99.316669 -254.02076) (xy 99.349304 -253.983923) (xy 99.387425 -253.952798) (xy 99.430046 -253.928191)
			(xy 99.476062 -253.910739) (xy 99.524281 -253.900895) (xy 99.573456 -253.898914) (xy 99.622311 -253.904846)
			(xy 99.669582 -253.918538) (xy 99.714044 -253.939636) (xy 99.754547 -253.967592) (xy 99.79004 -254.001684)
			(xy 99.819605 -254.041028) (xy 99.842476 -254.084605) (xy 99.85806 -254.131286) (xy 99.865955 -254.179863)
			(xy 99.86645 -254.20447) (xy 101.135192 -254.20447) (xy 101.139152 -254.155416) (xy 101.150929 -254.107632)
			(xy 101.17022 -254.062356) (xy 101.196523 -254.02076) (xy 101.229158 -253.983923) (xy 101.267279 -253.952798)
			(xy 101.3099 -253.928191) (xy 101.355916 -253.910739) (xy 101.404135 -253.900895) (xy 101.45331 -253.898914)
			(xy 101.502165 -253.904846) (xy 101.549436 -253.918538) (xy 101.593898 -253.939636) (xy 101.634401 -253.967592)
			(xy 101.669894 -254.001684) (xy 101.699459 -254.041028) (xy 101.72233 -254.084605) (xy 101.737914 -254.131286)
			(xy 101.745809 -254.179863) (xy 101.746304 -254.20447) (xy 102.075246 -254.20447) (xy 102.079206 -254.155416)
			(xy 102.090983 -254.107632) (xy 102.110274 -254.062356) (xy 102.136577 -254.02076) (xy 102.169212 -253.983923)
			(xy 102.207333 -253.952798) (xy 102.249954 -253.928191) (xy 102.29597 -253.910739) (xy 102.344189 -253.900895)
			(xy 102.393364 -253.898914) (xy 102.442219 -253.904846) (xy 102.48949 -253.918538) (xy 102.533952 -253.939636)
			(xy 102.574455 -253.967592) (xy 102.609948 -254.001684) (xy 102.639513 -254.041028) (xy 102.662384 -254.084605)
			(xy 102.677968 -254.131286) (xy 102.685863 -254.179863) (xy 102.686358 -254.20447) (xy 102.685863 -254.229077)
			(xy 102.677968 -254.277654) (xy 102.662384 -254.324335) (xy 102.639513 -254.367912) (xy 102.609948 -254.407256)
			(xy 102.574455 -254.441348) (xy 102.533952 -254.469304) (xy 102.48949 -254.490402) (xy 102.442219 -254.504094)
			(xy 102.393364 -254.510026) (xy 102.344189 -254.508045) (xy 102.29597 -254.498201) (xy 102.249954 -254.480749)
			(xy 102.207333 -254.456142) (xy 102.169212 -254.425017) (xy 102.136577 -254.38818) (xy 102.110274 -254.346584)
			(xy 102.090983 -254.301308) (xy 102.079206 -254.253524) (xy 102.075246 -254.20447) (xy 101.746304 -254.20447)
			(xy 101.745809 -254.229077) (xy 101.737914 -254.277654) (xy 101.72233 -254.324335) (xy 101.699459 -254.367912)
			(xy 101.669894 -254.407256) (xy 101.634401 -254.441348) (xy 101.593898 -254.469304) (xy 101.549436 -254.490402)
			(xy 101.502165 -254.504094) (xy 101.45331 -254.510026) (xy 101.404135 -254.508045) (xy 101.355916 -254.498201)
			(xy 101.3099 -254.480749) (xy 101.267279 -254.456142) (xy 101.229158 -254.425017) (xy 101.196523 -254.38818)
			(xy 101.17022 -254.346584) (xy 101.150929 -254.301308) (xy 101.139152 -254.253524) (xy 101.135192 -254.20447)
			(xy 99.86645 -254.20447) (xy 99.865955 -254.229077) (xy 99.85806 -254.277654) (xy 99.842476 -254.324335)
			(xy 99.819605 -254.367912) (xy 99.79004 -254.407256) (xy 99.754547 -254.441348) (xy 99.714044 -254.469304)
			(xy 99.669582 -254.490402) (xy 99.622311 -254.504094) (xy 99.573456 -254.510026) (xy 99.524281 -254.508045)
			(xy 99.476062 -254.498201) (xy 99.430046 -254.480749) (xy 99.387425 -254.456142) (xy 99.349304 -254.425017)
			(xy 99.316669 -254.38818) (xy 99.290366 -254.346584) (xy 99.271075 -254.301308) (xy 99.259298 -254.253524)
			(xy 99.255338 -254.20447) (xy 97.986342 -254.20447) (xy 97.985847 -254.229077) (xy 97.977952 -254.277654)
			(xy 97.962368 -254.324335) (xy 97.939497 -254.367912) (xy 97.909932 -254.407256) (xy 97.874439 -254.441348)
			(xy 97.833936 -254.469304) (xy 97.789474 -254.490402) (xy 97.742203 -254.504094) (xy 97.693348 -254.510026)
			(xy 97.644173 -254.508045) (xy 97.595954 -254.498201) (xy 97.549938 -254.480749) (xy 97.507317 -254.456142)
			(xy 97.469196 -254.425017) (xy 97.436561 -254.38818) (xy 97.410258 -254.346584) (xy 97.390967 -254.301308)
			(xy 97.37919 -254.253524) (xy 97.37523 -254.20447) (xy 96.379284 -254.20447) (xy 96.379284 -254.710438)
			(xy 96.39427 -254.734822) (xy 96.407478 -254.741172) (xy 96.428899 -254.752397) (xy 96.468206 -254.780568)
			(xy 96.502585 -254.814578) (xy 96.531179 -254.853578) (xy 96.553274 -254.896595) (xy 96.568318 -254.942554)
			(xy 96.575936 -254.99031) (xy 96.575937 -255.014476) (xy 97.84513 -255.014476) (xy 97.84909 -254.965422)
			(xy 97.860867 -254.917638) (xy 97.880158 -254.872362) (xy 97.906461 -254.830766) (xy 97.939096 -254.793929)
			(xy 97.977217 -254.762804) (xy 98.019838 -254.738197) (xy 98.065854 -254.720745) (xy 98.114073 -254.710901)
			(xy 98.163248 -254.70892) (xy 98.212103 -254.714852) (xy 98.259374 -254.728544) (xy 98.303836 -254.749642)
			(xy 98.344339 -254.777598) (xy 98.379832 -254.81169) (xy 98.409397 -254.851034) (xy 98.432268 -254.894611)
			(xy 98.447852 -254.941292) (xy 98.455747 -254.989869) (xy 98.456242 -255.014476) (xy 99.725238 -255.014476)
			(xy 99.729198 -254.965422) (xy 99.740975 -254.917638) (xy 99.760266 -254.872362) (xy 99.786569 -254.830766)
			(xy 99.819204 -254.793929) (xy 99.857325 -254.762804) (xy 99.899946 -254.738197) (xy 99.945962 -254.720745)
			(xy 99.994181 -254.710901) (xy 100.043356 -254.70892) (xy 100.092211 -254.714852) (xy 100.139482 -254.728544)
			(xy 100.183944 -254.749642) (xy 100.224447 -254.777598) (xy 100.25994 -254.81169) (xy 100.289505 -254.851034)
			(xy 100.312376 -254.894611) (xy 100.32796 -254.941292) (xy 100.335855 -254.989869) (xy 100.33635 -255.014476)
			(xy 100.665292 -255.014476) (xy 100.669252 -254.965422) (xy 100.681029 -254.917638) (xy 100.70032 -254.872362)
			(xy 100.726623 -254.830766) (xy 100.759258 -254.793929) (xy 100.797379 -254.762804) (xy 100.84 -254.738197)
			(xy 100.886016 -254.720745) (xy 100.934235 -254.710901) (xy 100.98341 -254.70892) (xy 101.032265 -254.714852)
			(xy 101.079536 -254.728544) (xy 101.123998 -254.749642) (xy 101.164501 -254.777598) (xy 101.199994 -254.81169)
			(xy 101.229559 -254.851034) (xy 101.25243 -254.894611) (xy 101.268014 -254.941292) (xy 101.275909 -254.989869)
			(xy 101.276404 -255.014476) (xy 101.605346 -255.014476) (xy 101.609306 -254.965422) (xy 101.621083 -254.917638)
			(xy 101.640374 -254.872362) (xy 101.666677 -254.830766) (xy 101.699312 -254.793929) (xy 101.737433 -254.762804)
			(xy 101.780054 -254.738197) (xy 101.82607 -254.720745) (xy 101.874289 -254.710901) (xy 101.923464 -254.70892)
			(xy 101.972319 -254.714852) (xy 102.01959 -254.728544) (xy 102.064052 -254.749642) (xy 102.104555 -254.777598)
			(xy 102.140048 -254.81169) (xy 102.169613 -254.851034) (xy 102.192484 -254.894611) (xy 102.208068 -254.941292)
			(xy 102.215963 -254.989869) (xy 102.216458 -255.014476) (xy 102.215963 -255.039083) (xy 102.208068 -255.08766)
			(xy 102.192484 -255.134341) (xy 102.169613 -255.177918) (xy 102.140048 -255.217262) (xy 102.104555 -255.251354)
			(xy 102.064052 -255.27931) (xy 102.01959 -255.300408) (xy 101.972319 -255.3141) (xy 101.923464 -255.320032)
			(xy 101.874289 -255.318051) (xy 101.82607 -255.308207) (xy 101.780054 -255.290755) (xy 101.737433 -255.266148)
			(xy 101.699312 -255.235023) (xy 101.666677 -255.198186) (xy 101.640374 -255.15659) (xy 101.621083 -255.111314)
			(xy 101.609306 -255.06353) (xy 101.605346 -255.014476) (xy 101.276404 -255.014476) (xy 101.275909 -255.039083)
			(xy 101.268014 -255.08766) (xy 101.25243 -255.134341) (xy 101.229559 -255.177918) (xy 101.199994 -255.217262)
			(xy 101.164501 -255.251354) (xy 101.123998 -255.27931) (xy 101.079536 -255.300408) (xy 101.032265 -255.3141)
			(xy 100.98341 -255.320032) (xy 100.934235 -255.318051) (xy 100.886016 -255.308207) (xy 100.84 -255.290755)
			(xy 100.797379 -255.266148) (xy 100.759258 -255.235023) (xy 100.726623 -255.198186) (xy 100.70032 -255.15659)
			(xy 100.681029 -255.111314) (xy 100.669252 -255.06353) (xy 100.665292 -255.014476) (xy 100.33635 -255.014476)
			(xy 100.335855 -255.039083) (xy 100.32796 -255.08766) (xy 100.312376 -255.134341) (xy 100.289505 -255.177918)
			(xy 100.25994 -255.217262) (xy 100.224447 -255.251354) (xy 100.183944 -255.27931) (xy 100.139482 -255.300408)
			(xy 100.092211 -255.3141) (xy 100.043356 -255.320032) (xy 99.994181 -255.318051) (xy 99.945962 -255.308207)
			(xy 99.899946 -255.290755) (xy 99.857325 -255.266148) (xy 99.819204 -255.235023) (xy 99.786569 -255.198186)
			(xy 99.760266 -255.15659) (xy 99.740975 -255.111314) (xy 99.729198 -255.06353) (xy 99.725238 -255.014476)
			(xy 98.456242 -255.014476) (xy 98.455747 -255.039083) (xy 98.447852 -255.08766) (xy 98.432268 -255.134341)
			(xy 98.409397 -255.177918) (xy 98.379832 -255.217262) (xy 98.344339 -255.251354) (xy 98.303836 -255.27931)
			(xy 98.259374 -255.300408) (xy 98.212103 -255.3141) (xy 98.163248 -255.320032) (xy 98.114073 -255.318051)
			(xy 98.065854 -255.308207) (xy 98.019838 -255.290755) (xy 97.977217 -255.266148) (xy 97.939096 -255.235023)
			(xy 97.906461 -255.198186) (xy 97.880158 -255.15659) (xy 97.860867 -255.111314) (xy 97.84909 -255.06353)
			(xy 97.84513 -255.014476) (xy 96.575937 -255.014476) (xy 96.575938 -255.038669) (xy 96.568323 -255.086425)
			(xy 96.553282 -255.132385) (xy 96.53119 -255.175404) (xy 96.502599 -255.214406) (xy 96.468222 -255.248418)
			(xy 96.428917 -255.276592) (xy 96.407478 -255.28778) (xy 96.39427 -255.29413) (xy 96.379284 -255.318514)
			(xy 96.379284 -255.951482) (xy 96.379722 -255.961546) (xy 96.387455 -255.98013) (xy 96.39427 -255.98755)
			(xy 96.491298 -256.084578) (xy 96.498695 -256.091427) (xy 96.517294 -256.099166) (xy 96.527366 -256.099564)
			(xy 97.31502 -256.099564) (xy 97.323585 -256.099188) (xy 97.339738 -256.093472) (xy 97.353126 -256.082777)
			(xy 97.357946 -256.075688) (xy 97.409762 -255.993646) (xy 97.411032 -255.967738) (xy 97.405444 -255.9558)
			(xy 97.396069 -255.935191) (xy 97.382827 -255.891896) (xy 97.376126 -255.847119) (xy 97.375726 -255.824482)
			(xy 97.376248 -255.799227) (xy 97.384561 -255.749405) (xy 97.400962 -255.701631) (xy 97.425003 -255.657208)
			(xy 97.456027 -255.617348) (xy 97.493189 -255.583138) (xy 97.535475 -255.555512) (xy 97.581731 -255.535222)
			(xy 97.630696 -255.522822) (xy 97.681034 -255.518651) (xy 97.731372 -255.522822) (xy 97.780337 -255.535222)
			(xy 97.826593 -255.555512) (xy 97.868879 -255.583138) (xy 97.906041 -255.617348) (xy 97.937065 -255.657208)
			(xy 97.961106 -255.701631) (xy 97.977507 -255.749405) (xy 97.98582 -255.799227) (xy 97.986342 -255.824482)
			(xy 97.985931 -255.847119) (xy 97.979239 -255.891896) (xy 97.966001 -255.935192) (xy 97.956624 -255.9558)
			(xy 97.951036 -255.967738) (xy 97.952306 -255.993646) (xy 98.004122 -256.075688) (xy 98.008932 -256.082796)
			(xy 98.022299 -256.093541) (xy 98.038473 -256.099245) (xy 98.047048 -256.099564) (xy 99.195128 -256.099564)
			(xy 99.203693 -256.099187) (xy 99.219844 -256.093469) (xy 99.23323 -256.082774) (xy 99.238054 -256.075688)
			(xy 99.28987 -255.993646) (xy 99.29114 -255.967738) (xy 99.285552 -255.9558) (xy 99.276177 -255.935191)
			(xy 99.262934 -255.891896) (xy 99.256233 -255.847119) (xy 99.255834 -255.824482) (xy 99.256356 -255.799227)
			(xy 99.264669 -255.749405) (xy 99.28107 -255.701631) (xy 99.305111 -255.657208) (xy 99.336135 -255.617348)
			(xy 99.373297 -255.583138) (xy 99.415583 -255.555512) (xy 99.461839 -255.535222) (xy 99.510804 -255.522822)
			(xy 99.561142 -255.518651) (xy 99.61148 -255.522822) (xy 99.660445 -255.535222) (xy 99.706701 -255.555512)
			(xy 99.748987 -255.583138) (xy 99.786149 -255.617348) (xy 99.817173 -255.657208) (xy 99.841214 -255.701631)
			(xy 99.857615 -255.749405) (xy 99.865928 -255.799227) (xy 99.86645 -255.824482) (xy 99.866039 -255.847119)
			(xy 99.859347 -255.891897) (xy 99.84611 -255.935192) (xy 99.836732 -255.9558) (xy 99.831144 -255.967738)
			(xy 99.832414 -255.993646) (xy 99.88423 -256.075688) (xy 99.88904 -256.082795) (xy 99.902408 -256.093538)
			(xy 99.918582 -256.099239) (xy 99.927156 -256.099564) (xy 100.134928 -256.099564) (xy 100.143493 -256.099187)
			(xy 100.159644 -256.093469) (xy 100.17303 -256.082774) (xy 100.177854 -256.075688) (xy 100.22967 -255.993646)
			(xy 100.23094 -255.967738) (xy 100.225352 -255.9558) (xy 100.215977 -255.935191) (xy 100.202734 -255.891896)
			(xy 100.196033 -255.847119) (xy 100.195634 -255.824482) (xy 100.196156 -255.799227) (xy 100.204469 -255.749405)
			(xy 100.22087 -255.701631) (xy 100.244911 -255.657208) (xy 100.275935 -255.617348) (xy 100.313097 -255.583138)
			(xy 100.355383 -255.555512) (xy 100.401639 -255.535222) (xy 100.450604 -255.522822) (xy 100.500942 -255.518651)
			(xy 100.55128 -255.522822) (xy 100.600245 -255.535222) (xy 100.646501 -255.555512) (xy 100.688787 -255.583138)
			(xy 100.725949 -255.617348) (xy 100.756973 -255.657208) (xy 100.781014 -255.701631) (xy 100.797415 -255.749405)
			(xy 100.805728 -255.799227) (xy 100.80625 -255.824482) (xy 101.135192 -255.824482) (xy 101.139152 -255.775428)
			(xy 101.150929 -255.727644) (xy 101.17022 -255.682368) (xy 101.196523 -255.640772) (xy 101.229158 -255.603935)
			(xy 101.267279 -255.57281) (xy 101.3099 -255.548203) (xy 101.355916 -255.530751) (xy 101.404135 -255.520907)
			(xy 101.45331 -255.518926) (xy 101.502165 -255.524858) (xy 101.549436 -255.53855) (xy 101.593898 -255.559648)
			(xy 101.634401 -255.587604) (xy 101.669894 -255.621696) (xy 101.699459 -255.66104) (xy 101.72233 -255.704617)
			(xy 101.737914 -255.751298) (xy 101.745809 -255.799875) (xy 101.746304 -255.824482) (xy 102.075246 -255.824482)
			(xy 102.079206 -255.775428) (xy 102.090983 -255.727644) (xy 102.110274 -255.682368) (xy 102.136577 -255.640772)
			(xy 102.169212 -255.603935) (xy 102.207333 -255.57281) (xy 102.249954 -255.548203) (xy 102.29597 -255.530751)
			(xy 102.344189 -255.520907) (xy 102.393364 -255.518926) (xy 102.442219 -255.524858) (xy 102.48949 -255.53855)
			(xy 102.533952 -255.559648) (xy 102.574455 -255.587604) (xy 102.609948 -255.621696) (xy 102.639513 -255.66104)
			(xy 102.662384 -255.704617) (xy 102.677968 -255.751298) (xy 102.685863 -255.799875) (xy 102.686317 -255.82245)
			(xy 103.011998 -255.82245) (xy 103.015958 -255.773396) (xy 103.027735 -255.725612) (xy 103.047026 -255.680336)
			(xy 103.073329 -255.63874) (xy 103.105964 -255.601903) (xy 103.144085 -255.570778) (xy 103.186706 -255.546171)
			(xy 103.232722 -255.528719) (xy 103.280941 -255.518875) (xy 103.330116 -255.516894) (xy 103.378971 -255.522826)
			(xy 103.426242 -255.536518) (xy 103.470704 -255.557616) (xy 103.511207 -255.585572) (xy 103.5467 -255.619664)
			(xy 103.576265 -255.659008) (xy 103.599136 -255.702585) (xy 103.61472 -255.749266) (xy 103.622615 -255.797843)
			(xy 103.62311 -255.82245) (xy 103.952052 -255.82245) (xy 103.956012 -255.773396) (xy 103.967789 -255.725612)
			(xy 103.98708 -255.680336) (xy 104.013383 -255.63874) (xy 104.046018 -255.601903) (xy 104.084139 -255.570778)
			(xy 104.12676 -255.546171) (xy 104.172776 -255.528719) (xy 104.220995 -255.518875) (xy 104.27017 -255.516894)
			(xy 104.319025 -255.522826) (xy 104.366296 -255.536518) (xy 104.410758 -255.557616) (xy 104.451261 -255.585572)
			(xy 104.486754 -255.619664) (xy 104.516319 -255.659008) (xy 104.53919 -255.702585) (xy 104.554774 -255.749266)
			(xy 104.562669 -255.797843) (xy 104.563164 -255.82245) (xy 104.562669 -255.847057) (xy 104.554774 -255.895634)
			(xy 104.53919 -255.942315) (xy 104.516319 -255.985892) (xy 104.486754 -256.025236) (xy 104.451261 -256.059328)
			(xy 104.410758 -256.087284) (xy 104.366296 -256.108382) (xy 104.319025 -256.122074) (xy 104.27017 -256.128006)
			(xy 104.220995 -256.126025) (xy 104.172776 -256.116181) (xy 104.12676 -256.098729) (xy 104.084139 -256.074122)
			(xy 104.046018 -256.042997) (xy 104.013383 -256.00616) (xy 103.98708 -255.964564) (xy 103.967789 -255.919288)
			(xy 103.956012 -255.871504) (xy 103.952052 -255.82245) (xy 103.62311 -255.82245) (xy 103.622615 -255.847057)
			(xy 103.61472 -255.895634) (xy 103.599136 -255.942315) (xy 103.576265 -255.985892) (xy 103.5467 -256.025236)
			(xy 103.511207 -256.059328) (xy 103.470704 -256.087284) (xy 103.426242 -256.108382) (xy 103.378971 -256.122074)
			(xy 103.330116 -256.128006) (xy 103.280941 -256.126025) (xy 103.232722 -256.116181) (xy 103.186706 -256.098729)
			(xy 103.144085 -256.074122) (xy 103.105964 -256.042997) (xy 103.073329 -256.00616) (xy 103.047026 -255.964564)
			(xy 103.027735 -255.919288) (xy 103.015958 -255.871504) (xy 103.011998 -255.82245) (xy 102.686317 -255.82245)
			(xy 102.686358 -255.824482) (xy 102.685863 -255.849089) (xy 102.677968 -255.897666) (xy 102.662384 -255.944347)
			(xy 102.639513 -255.987924) (xy 102.609948 -256.027268) (xy 102.574455 -256.06136) (xy 102.533952 -256.089316)
			(xy 102.48949 -256.110414) (xy 102.442219 -256.124106) (xy 102.393364 -256.130038) (xy 102.344189 -256.128057)
			(xy 102.29597 -256.118213) (xy 102.249954 -256.100761) (xy 102.207333 -256.076154) (xy 102.169212 -256.045029)
			(xy 102.136577 -256.008192) (xy 102.110274 -255.966596) (xy 102.090983 -255.92132) (xy 102.079206 -255.873536)
			(xy 102.075246 -255.824482) (xy 101.746304 -255.824482) (xy 101.745809 -255.849089) (xy 101.737914 -255.897666)
			(xy 101.72233 -255.944347) (xy 101.699459 -255.987924) (xy 101.669894 -256.027268) (xy 101.634401 -256.06136)
			(xy 101.593898 -256.089316) (xy 101.549436 -256.110414) (xy 101.502165 -256.124106) (xy 101.45331 -256.130038)
			(xy 101.404135 -256.128057) (xy 101.355916 -256.118213) (xy 101.3099 -256.100761) (xy 101.267279 -256.076154)
			(xy 101.229158 -256.045029) (xy 101.196523 -256.008192) (xy 101.17022 -255.966596) (xy 101.150929 -255.92132)
			(xy 101.139152 -255.873536) (xy 101.135192 -255.824482) (xy 100.80625 -255.824482) (xy 100.80611 -255.837245)
			(xy 100.803944 -255.862678) (xy 100.801932 -255.875282) (xy 100.797002 -255.90114) (xy 100.779469 -255.950769)
			(xy 100.753697 -255.996663) (xy 100.720449 -256.037467) (xy 100.680705 -256.071977) (xy 100.63564 -256.099173)
			(xy 100.586585 -256.118251) (xy 100.560886 -256.123948) (xy 100.54717 -256.126742) (xy 100.526596 -256.145538)
			(xy 100.497132 -256.242312) (xy 100.49484 -256.251226) (xy 100.496037 -256.269579) (xy 100.503594 -256.286346)
			(xy 100.509832 -256.293112) (xy 100.624386 -256.407666) (xy 100.631609 -256.414317) (xy 100.64964 -256.422039)
			(xy 100.659438 -256.422652) (xy 100.738178 -256.424176) (xy 100.756212 -256.417318) (xy 100.763578 -256.41046)
			(xy 100.78062 -256.395273) (xy 100.818365 -256.369606) (xy 100.859509 -256.349838) (xy 100.903135 -256.33641)
			(xy 100.948273 -256.32962) (xy 100.971096 -256.32918) (xy 100.995088 -256.32965) (xy 101.042481 -256.337156)
			(xy 101.088116 -256.351983) (xy 101.13087 -256.373766) (xy 101.16969 -256.401969) (xy 101.203621 -256.435898)
			(xy 101.231826 -256.474716) (xy 101.253611 -256.517469) (xy 101.26844 -256.563104) (xy 101.275948 -256.610496)
			(xy 101.276404 -256.634488) (xy 101.27594 -256.658719) (xy 101.268286 -256.706573) (xy 101.261164 -256.729738)
			(xy 101.257354 -256.741422) (xy 101.261164 -256.765552) (xy 101.315266 -256.840482) (xy 101.322881 -256.849857)
			(xy 101.344356 -256.860838) (xy 101.356414 -256.861564)
		)
		(stroke
			(width 0)
			(type solid)
		)
		(fill yes)
		(layer "In4.Cu")
		(net "PVDD18_S5_P1")
	)
	(gr_poly
		(pts
			(xy 439.158888 -101.081586) (xy 439.168759 -101.081113) (xy 439.187039 -101.07365) (xy 439.194448 -101.067108)
			(xy 439.194702 -101.066854) (xy 439.48604 -100.775516) (xy 439.49288 -100.768116) (xy 439.500593 -100.749517)
			(xy 439.501026 -100.739448) (xy 439.501026 -96.408494) (xy 439.500579 -96.398683) (xy 439.493228 -96.38049)
			(xy 439.479597 -96.366376) (xy 439.4708 -96.362012) (xy 439.371994 -96.318324) (xy 439.342276 -96.32315)
			(xy 439.3311 -96.33331) (xy 439.307628 -96.354135) (xy 439.256452 -96.39045) (xy 439.201195 -96.420187)
			(xy 439.142697 -96.442895) (xy 439.081849 -96.458229) (xy 439.019575 -96.465954) (xy 438.9882 -96.466406)
			(xy 438.956239 -96.465904) (xy 438.892821 -96.457893) (xy 438.830908 -96.441996) (xy 438.771475 -96.418465)
			(xy 438.71546 -96.38767) (xy 438.663746 -96.350098) (xy 438.617149 -96.30634) (xy 438.576403 -96.257088)
			(xy 438.542152 -96.203117) (xy 438.514936 -96.145279) (xy 438.495183 -96.084485) (xy 438.483205 -96.021696)
			(xy 438.479192 -95.9579) (xy 438.483205 -95.894104) (xy 438.495183 -95.831315) (xy 438.514936 -95.770521)
			(xy 438.542152 -95.712683) (xy 438.576403 -95.658712) (xy 438.617149 -95.60946) (xy 438.663746 -95.565702)
			(xy 438.71546 -95.52813) (xy 438.771475 -95.497335) (xy 438.830908 -95.473804) (xy 438.892821 -95.457907)
			(xy 438.956239 -95.449896) (xy 438.9882 -95.44939) (xy 439.019507 -95.449852) (xy 439.081652 -95.457505)
			(xy 439.142386 -95.472732) (xy 439.200791 -95.495302) (xy 439.255982 -95.524873) (xy 439.307123 -95.560998)
			(xy 439.330592 -95.581724) (xy 439.331354 -95.582486) (xy 439.333386 -95.58401) (xy 439.344562 -95.593154)
			(xy 439.37301 -95.596964) (xy 439.4708 -95.553784) (xy 439.47959 -95.549405) (xy 439.493237 -95.535308)
			(xy 439.50058 -95.517113) (xy 439.501026 -95.507302) (xy 439.501026 -78.107286) (xy 439.500568 -78.097777)
			(xy 439.49366 -78.080055) (xy 439.487564 -78.072742) (xy 439.467244 -78.050644) (xy 439.461087 -78.04442)
			(xy 439.445628 -78.03623) (xy 439.437018 -78.034642) (xy 439.435748 -78.034642) (xy 439.408441 -78.030687)
			(xy 439.355275 -78.015936) (xy 439.304786 -77.993685) (xy 439.258027 -77.964398) (xy 439.21597 -77.928685)
			(xy 439.179492 -77.887289) (xy 439.149352 -77.841074) (xy 439.12618 -77.791001) (xy 439.110457 -77.738115)
			(xy 439.10251 -77.683515) (xy 439.101992 -77.655928) (xy 439.102526 -77.626981) (xy 439.111267 -77.56975)
			(xy 439.128553 -77.514496) (xy 439.153987 -77.462487) (xy 439.186985 -77.414917) (xy 439.22679 -77.372877)
			(xy 439.249312 -77.354684) (xy 439.258151 -77.347097) (xy 439.268357 -77.326187) (xy 439.26887 -77.314552)
			(xy 439.26887 -77.235304) (xy 439.268293 -77.223685) (xy 439.258098 -77.202799) (xy 439.249312 -77.195172)
			(xy 439.226799 -77.17697) (xy 439.187006 -77.134923) (xy 439.154016 -77.087352) (xy 439.128582 -77.035347)
			(xy 439.111289 -76.980099) (xy 439.102533 -76.922873) (xy 439.101992 -76.893928) (xy 439.102417 -76.868213)
			(xy 439.109332 -76.81725) (xy 439.123028 -76.767677) (xy 439.143256 -76.720392) (xy 439.169651 -76.676251)
			(xy 439.201733 -76.636054) (xy 439.238922 -76.600529) (xy 439.259472 -76.585064) (xy 439.264806 -76.57973)
			(xy 439.265314 -76.579222) (xy 439.27153 -76.572157) (xy 439.278815 -76.554824) (xy 439.279538 -76.54544)
			(xy 439.282078 -76.454254) (xy 439.272426 -76.433172) (xy 439.263028 -76.425552) (xy 439.241444 -76.40731)
			(xy 439.203368 -76.365552) (xy 439.17186 -76.318639) (xy 439.147608 -76.267597) (xy 439.13114 -76.213538)
			(xy 439.122816 -76.157644) (xy 439.122312 -76.129388) (xy 439.122842 -76.100439) (xy 439.131575 -76.043203)
			(xy 439.148855 -75.987944) (xy 439.174285 -75.935929) (xy 439.207281 -75.888353) (xy 439.247085 -75.846308)
			(xy 439.269632 -75.828144) (xy 439.278461 -75.820553) (xy 439.288647 -75.799643) (xy 439.28919 -75.788012)
			(xy 439.28919 -75.708764) (xy 439.288626 -75.697138) (xy 439.278449 -75.676229) (xy 439.269632 -75.668632)
			(xy 439.248825 -75.651869) (xy 439.211649 -75.613491) (xy 439.180188 -75.570303) (xy 439.155058 -75.52315)
			(xy 439.136749 -75.472953) (xy 439.125619 -75.420694) (xy 439.121885 -75.367393) (xy 439.125621 -75.314092)
			(xy 439.136753 -75.261833) (xy 439.155064 -75.211636) (xy 439.180196 -75.164484) (xy 439.211658 -75.121298)
			(xy 439.248836 -75.082921) (xy 439.269632 -75.066144) (xy 439.278461 -75.058553) (xy 439.288647 -75.037643)
			(xy 439.28919 -75.026012) (xy 439.28919 -74.946764) (xy 439.288626 -74.935138) (xy 439.278449 -74.914229)
			(xy 439.269632 -74.906632) (xy 439.24712 -74.88843) (xy 439.20733 -74.846383) (xy 439.174342 -74.798811)
			(xy 439.148913 -74.746806) (xy 439.131625 -74.691557) (xy 439.122874 -74.634333) (xy 439.122312 -74.605388)
			(xy 439.1228 -74.577788) (xy 439.130754 -74.523164) (xy 439.146492 -74.470255) (xy 439.169689 -74.420166)
			(xy 439.199859 -74.37394) (xy 439.236373 -74.332542) (xy 439.278469 -74.296836) (xy 439.32527 -74.267567)
			(xy 439.375799 -74.245344) (xy 439.429002 -74.230632) (xy 439.456322 -74.226674) (xy 439.45683 -74.226674)
			(xy 439.465861 -74.225084) (xy 439.482017 -74.216441) (xy 439.494112 -74.202676) (xy 439.500605 -74.185542)
			(xy 439.501026 -74.176382) (xy 439.501026 -64.351408) (xy 439.500605 -64.341337) (xy 439.492896 -64.322728)
			(xy 439.48604 -64.31534) (xy 428.830486 -53.659786) (xy 428.823632 -53.652391) (xy 428.81589 -53.633792)
			(xy 428.8155 -53.623718) (xy 428.8155 -48.951642) (xy 428.815934 -48.941577) (xy 428.823663 -48.922987)
			(xy 428.830486 -48.915574) (xy 433.39258 -44.35348) (xy 433.399308 -44.346047) (xy 433.406964 -44.327541)
			(xy 433.406975 -44.307514) (xy 433.399339 -44.288999) (xy 433.39258 -44.281598) (xy 433.00777 -43.896788)
			(xy 433.0065 -43.895518) (xy 433.005738 -43.894756) (xy 433.000658 -43.889676) (xy 432.992784 -43.87088)
			(xy 432.992784 -43.86326) (xy 432.992784 -38.636956) (xy 432.992784 -38.626796) (xy 433.000658 -38.608)
			(xy 433.005738 -38.60292) (xy 433.0065 -38.602158) (xy 433.00777 -38.600888) (xy 433.502562 -38.106096)
			(xy 433.503578 -38.10508) (xy 433.50434 -38.104318) (xy 433.509674 -38.098984) (xy 433.52847 -38.091364)
			(xy 437.498998 -38.091364) (xy 437.507952 -38.090383) (xy 437.524347 -38.082957) (xy 437.531002 -38.076886)
			(xy 439.671714 -35.936174) (xy 439.678566 -35.928778) (xy 439.686304 -35.910179) (xy 439.6867 -35.900106)
			(xy 439.6867 -32.761936) (xy 439.687135 -32.751871) (xy 439.694866 -32.733283) (xy 439.701686 -32.725868)
			(xy 440.187588 -32.239966) (xy 440.19443 -32.232566) (xy 440.202154 -32.213968) (xy 440.202574 -32.203898)
			(xy 440.202574 -17.177512) (xy 440.202153 -17.167441) (xy 440.194438 -17.148836) (xy 440.187588 -17.141444)
			(xy 439.31205 -16.265906) (xy 439.292492 -16.258032) (xy 439.281824 -16.25854) (xy 439.266584 -16.258794)
			(xy 439.235253 -16.258142) (xy 439.173439 -16.247861) (xy 439.114137 -16.227612) (xy 439.086244 -16.213328)
			(xy 439.074174 -16.20733) (xy 439.047925 -16.201254) (xy 439.021 -16.202248) (xy 438.99527 -16.210243)
			(xy 438.972523 -16.224684) (xy 438.954341 -16.244567) (xy 438.941985 -16.268511) (xy 438.936316 -16.294851)
			(xy 438.936638 -16.308324) (xy 438.937146 -16.327882) (xy 438.937146 -16.328136) (xy 438.93666 -16.355405)
			(xy 438.928898 -16.409389) (xy 438.913533 -16.461719) (xy 438.890876 -16.511329) (xy 438.86139 -16.55721)
			(xy 438.825675 -16.598427) (xy 438.784458 -16.634142) (xy 438.738577 -16.663628) (xy 438.688967 -16.686285)
			(xy 438.636637 -16.70165) (xy 438.582653 -16.709412) (xy 438.528115 -16.709412) (xy 438.474131 -16.70165)
			(xy 438.421801 -16.686285) (xy 438.372191 -16.663628) (xy 438.32631 -16.634142) (xy 438.285093 -16.598427)
			(xy 438.249378 -16.55721) (xy 438.219892 -16.511329) (xy 438.197235 -16.461719) (xy 438.18187 -16.409389)
			(xy 438.174108 -16.355405) (xy 438.173622 -16.328136) (xy 438.174116 -16.300771) (xy 438.181973 -16.246606)
			(xy 438.197475 -16.194115) (xy 438.220304 -16.144372) (xy 438.249994 -16.098392) (xy 438.267602 -16.077438)
			(xy 438.276844 -16.06611) (xy 438.289031 -16.03955) (xy 438.293212 -16.010627) (xy 438.289046 -15.981703)
			(xy 438.276873 -15.955135) (xy 438.267602 -15.943834) (xy 438.249966 -15.9229) (xy 438.220251 -15.87693)
			(xy 438.197415 -15.827183) (xy 438.181929 -15.774681) (xy 438.17411 -15.720505) (xy 438.173622 -15.693136)
			(xy 438.174097 -15.666271) (xy 438.181664 -15.613075) (xy 438.196611 -15.561465) (xy 438.218642 -15.512458)
			(xy 438.247324 -15.467023) (xy 438.282091 -15.426056) (xy 438.301892 -15.407894) (xy 438.311916 -15.39836)
			(xy 438.326894 -15.375115) (xy 438.335091 -15.348705) (xy 438.335906 -15.321065) (xy 438.32928 -15.294218)
			(xy 438.315699 -15.27013) (xy 438.30621 -15.260066) (xy 438.19191 -15.145766) (xy 438.185068 -15.138366)
			(xy 438.177344 -15.119768) (xy 438.176924 -15.109698) (xy 438.176924 -13.507974) (xy 438.173368 -13.495274)
			(xy 438.169812 -13.489178) (xy 438.152794 -13.460476) (xy 438.126124 -13.447014) (xy 438.111138 -13.448538)
			(xy 438.100884 -13.449595) (xy 438.080298 -13.450739) (xy 438.06999 -13.450824) (xy 438.046571 -13.450467)
			(xy 438.000085 -13.444734) (xy 437.97728 -13.439394) (xy 437.973343 -13.438522) (xy 437.965304 -13.437885)
			(xy 437.961278 -13.438124) (xy 437.933084 -13.43914) (xy 437.932576 -13.43914) (xy 437.905308 -13.438652)
			(xy 437.851328 -13.430887) (xy 437.799003 -13.41552) (xy 437.749397 -13.392862) (xy 437.703521 -13.363375)
			(xy 437.662308 -13.327659) (xy 437.626597 -13.286442) (xy 437.597116 -13.240562) (xy 437.574464 -13.190954)
			(xy 437.559103 -13.138627) (xy 437.551345 -13.084646) (xy 437.550814 -13.057378) (xy 437.551383 -13.027634)
			(xy 437.560608 -12.968866) (xy 437.578832 -12.912239) (xy 437.591708 -12.88542) (xy 437.597453 -12.873065)
			(xy 437.602848 -12.846366) (xy 437.600983 -12.819193) (xy 437.59199 -12.793482) (xy 437.576512 -12.771069)
			(xy 437.555653 -12.753554) (xy 437.543448 -12.747498) (xy 437.518957 -12.735684) (xy 437.473301 -12.706151)
			(xy 437.432298 -12.670439) (xy 437.396778 -12.629269) (xy 437.367459 -12.583476) (xy 437.344935 -12.533986)
			(xy 437.329661 -12.4818) (xy 437.321947 -12.427975) (xy 437.321452 -12.400788) (xy 437.321916 -12.373518)
			(xy 437.32968 -12.319533) (xy 437.345047 -12.267203) (xy 437.367706 -12.217592) (xy 437.397194 -12.171711)
			(xy 437.432912 -12.130493) (xy 437.474132 -12.094778) (xy 437.520015 -12.065293) (xy 437.569627 -12.042638)
			(xy 437.621959 -12.027274) (xy 437.675944 -12.019514) (xy 437.703214 -12.019026) (xy 437.7343 -12.01966)
			(xy 437.795646 -12.029772) (xy 437.854547 -12.049678) (xy 437.882284 -12.06373) (xy 437.892193 -12.068407)
			(xy 437.914044 -12.069708) (xy 437.934449 -12.061787) (xy 437.942482 -12.054332) (xy 437.97184 -12.024962)
			(xy 438.035158 -11.971224) (xy 438.103216 -11.923632) (xy 438.139078 -11.902694) (xy 438.148476 -11.895836)
			(xy 438.151256 -11.893238) (xy 438.156099 -11.887371) (xy 438.158128 -11.884152) (xy 438.169812 -11.864086)
			(xy 438.170066 -11.863832) (xy 438.17323 -11.857895) (xy 438.176697 -11.844902) (xy 438.176924 -11.838178)
			(xy 438.176924 -11.173714) (xy 438.176417 -11.163664) (xy 438.168694 -11.145105) (xy 438.161938 -11.137646)
			(xy 436.685944 -9.661652) (xy 436.678545 -9.654809) (xy 436.659946 -9.647086) (xy 436.649876 -9.646666)
			(xy 433.979574 -9.646666) (xy 433.969567 -9.647158) (xy 433.951079 -9.654821) (xy 433.936925 -9.668972)
			(xy 433.92926 -9.687459) (xy 433.928774 -9.697466) (xy 433.928774 -9.961372) (xy 433.928337 -9.971436)
			(xy 433.920601 -9.990019) (xy 433.913788 -9.99744) (xy 433.47894 -10.432288) (xy 433.472087 -10.439684)
			(xy 433.464342 -10.458282) (xy 433.463954 -10.468356) (xy 433.463954 -12.108688) (xy 433.464054 -12.112833)
			(xy 433.465464 -12.121002) (xy 433.466748 -12.124944) (xy 433.474368 -12.147296) (xy 433.478686 -12.153138)
			(xy 433.495409 -12.177551) (xy 433.521912 -12.230458) (xy 433.539926 -12.286823) (xy 433.549021 -12.345293)
			(xy 433.549552 -12.37488) (xy 433.549012 -12.404466) (xy 433.539911 -12.462933) (xy 433.521894 -12.519294)
			(xy 433.495391 -12.572197) (xy 433.478686 -12.596622) (xy 433.474368 -12.602464) (xy 433.466748 -12.624816)
			(xy 433.465482 -12.628762) (xy 433.464073 -12.636929) (xy 433.463954 -12.641072) (xy 433.463954 -16.614902)
			(xy 433.464379 -16.624971) (xy 433.4721 -16.64357) (xy 433.47894 -16.65097) (xy 434.065934 -17.237964)
			(xy 435.623714 -17.237964) (xy 435.627785 -17.182342) (xy 435.639911 -17.127905) (xy 435.659834 -17.075814)
			(xy 435.68713 -17.027179) (xy 435.721216 -16.983036) (xy 435.761365 -16.944327) (xy 435.806723 -16.911876)
			(xy 435.856323 -16.886375) (xy 435.909107 -16.868368) (xy 435.96395 -16.858238) (xy 436.019684 -16.856201)
			(xy 436.075121 -16.862301) (xy 436.129078 -16.876407) (xy 436.180407 -16.898219) (xy 436.228013 -16.927273)
			(xy 436.270881 -16.962948) (xy 436.308098 -17.004485) (xy 436.338871 -17.050998) (xy 436.362543 -17.101495)
			(xy 436.378611 -17.154902) (xy 436.386731 -17.210078) (xy 436.38724 -17.237964) (xy 436.386731 -17.26585)
			(xy 436.381527 -17.30121) (xy 436.916066 -17.30121) (xy 436.920137 -17.245588) (xy 436.932263 -17.191151)
			(xy 436.952186 -17.13906) (xy 436.979482 -17.090425) (xy 437.013568 -17.046282) (xy 437.053717 -17.007573)
			(xy 437.099075 -16.975122) (xy 437.148675 -16.949621) (xy 437.201459 -16.931614) (xy 437.256302 -16.921484)
			(xy 437.312036 -16.919447) (xy 437.367473 -16.925547) (xy 437.42143 -16.939653) (xy 437.472759 -16.961465)
			(xy 437.520365 -16.990519) (xy 437.563233 -17.026194) (xy 437.60045 -17.067731) (xy 437.631223 -17.114244)
			(xy 437.654895 -17.164741) (xy 437.670963 -17.218148) (xy 437.679083 -17.273324) (xy 437.679592 -17.30121)
			(xy 437.679083 -17.329096) (xy 437.670963 -17.384272) (xy 437.654895 -17.437679) (xy 437.631223 -17.488176)
			(xy 437.60045 -17.534689) (xy 437.563233 -17.576226) (xy 437.520365 -17.611901) (xy 437.472759 -17.640955)
			(xy 437.42143 -17.662767) (xy 437.367473 -17.676873) (xy 437.312036 -17.682973) (xy 437.256302 -17.680936)
			(xy 437.201459 -17.670806) (xy 437.148675 -17.652799) (xy 437.099075 -17.627298) (xy 437.053717 -17.594847)
			(xy 437.013568 -17.556138) (xy 436.979482 -17.511995) (xy 436.952186 -17.46336) (xy 436.932263 -17.411269)
			(xy 436.920137 -17.356832) (xy 436.916066 -17.30121) (xy 436.381527 -17.30121) (xy 436.378611 -17.321026)
			(xy 436.362543 -17.374433) (xy 436.338871 -17.42493) (xy 436.308098 -17.471443) (xy 436.270881 -17.51298)
			(xy 436.228013 -17.548655) (xy 436.180407 -17.577709) (xy 436.129078 -17.599521) (xy 436.075121 -17.613627)
			(xy 436.019684 -17.619727) (xy 435.96395 -17.61769) (xy 435.909107 -17.60756) (xy 435.856323 -17.589553)
			(xy 435.806723 -17.564052) (xy 435.761365 -17.531601) (xy 435.721216 -17.492892) (xy 435.68713 -17.448749)
			(xy 435.659834 -17.400114) (xy 435.639911 -17.348023) (xy 435.627785 -17.293586) (xy 435.623714 -17.237964)
			(xy 434.065934 -17.237964) (xy 434.849524 -18.021554) (xy 434.85637 -18.028952) (xy 434.864097 -18.047551)
			(xy 434.86451 -18.057622) (xy 434.86451 -18.438622) (xy 435.446676 -18.438622) (xy 435.450747 -18.383)
			(xy 435.462873 -18.328563) (xy 435.482796 -18.276472) (xy 435.510092 -18.227837) (xy 435.544178 -18.183694)
			(xy 435.584327 -18.144985) (xy 435.629685 -18.112534) (xy 435.679285 -18.087033) (xy 435.732069 -18.069026)
			(xy 435.786912 -18.058896) (xy 435.842646 -18.056859) (xy 435.898083 -18.062959) (xy 435.95204 -18.077065)
			(xy 436.003369 -18.098877) (xy 436.050975 -18.127931) (xy 436.093843 -18.163606) (xy 436.13106 -18.205143)
			(xy 436.161833 -18.251656) (xy 436.185505 -18.302153) (xy 436.201573 -18.35556) (xy 436.209693 -18.410736)
			(xy 436.210202 -18.438622) (xy 436.209693 -18.466508) (xy 436.201573 -18.521684) (xy 436.185505 -18.575091)
			(xy 436.161833 -18.625588) (xy 436.13106 -18.672101) (xy 436.093843 -18.713638) (xy 436.050975 -18.749313)
			(xy 436.003369 -18.778367) (xy 435.95204 -18.800179) (xy 435.898083 -18.814285) (xy 435.842646 -18.820385)
			(xy 435.786912 -18.818348) (xy 435.732069 -18.808218) (xy 435.679285 -18.790211) (xy 435.629685 -18.76471)
			(xy 435.584327 -18.732259) (xy 435.544178 -18.69355) (xy 435.510092 -18.649407) (xy 435.482796 -18.600772)
			(xy 435.462873 -18.548681) (xy 435.450747 -18.494244) (xy 435.446676 -18.438622) (xy 434.86451 -18.438622)
			(xy 434.86451 -20.62734) (xy 434.864744 -20.635372) (xy 434.869653 -20.650662) (xy 434.874162 -20.657312)
			(xy 434.889353 -20.679088) (xy 434.914208 -20.726006) (xy 434.932312 -20.775918) (xy 434.943315 -20.82786)
			(xy 434.947004 -20.880826) (xy 434.943308 -20.933791) (xy 434.932297 -20.985732) (xy 434.914187 -21.035642)
			(xy 434.889325 -21.082556) (xy 434.874162 -21.104352) (xy 434.869722 -21.111038) (xy 434.864797 -21.126304)
			(xy 434.86451 -21.134324) (xy 434.86451 -23.74385) (xy 436.799732 -23.74385) (xy 436.799732 -23.659154)
			(xy 436.807783 -23.57484) (xy 436.823812 -23.491674) (xy 436.847673 -23.410407) (xy 436.879152 -23.331777)
			(xy 436.917963 -23.256496) (xy 436.963753 -23.185244) (xy 437.016109 -23.118668) (xy 437.074557 -23.05737)
			(xy 437.138567 -23.001905) (xy 437.207559 -22.952776) (xy 437.280909 -22.910427) (xy 437.357952 -22.875243)
			(xy 437.437991 -22.847541) (xy 437.5203 -22.827573) (xy 437.604135 -22.81552) (xy 437.688736 -22.81149)
			(xy 437.773337 -22.81552) (xy 437.857172 -22.827573) (xy 437.939481 -22.847541) (xy 438.01952 -22.875243)
			(xy 438.096563 -22.910427) (xy 438.169913 -22.952776) (xy 438.238905 -23.001905) (xy 438.302915 -23.05737)
			(xy 438.361363 -23.118668) (xy 438.413719 -23.185244) (xy 438.459509 -23.256496) (xy 438.49832 -23.331777)
			(xy 438.529799 -23.410407) (xy 438.55366 -23.491674) (xy 438.569689 -23.57484) (xy 438.57774 -23.659154)
			(xy 438.578244 -23.701502) (xy 438.57774 -23.74385) (xy 438.569689 -23.828164) (xy 438.55366 -23.91133)
			(xy 438.529799 -23.992597) (xy 438.49832 -24.071227) (xy 438.459509 -24.146508) (xy 438.413719 -24.21776)
			(xy 438.361363 -24.284336) (xy 438.302915 -24.345634) (xy 438.238905 -24.401099) (xy 438.169913 -24.450228)
			(xy 438.096563 -24.492577) (xy 438.01952 -24.527761) (xy 437.939481 -24.555463) (xy 437.857172 -24.575431)
			(xy 437.773337 -24.587484) (xy 437.688736 -24.591515) (xy 437.604135 -24.587484) (xy 437.5203 -24.575431)
			(xy 437.437991 -24.555463) (xy 437.357952 -24.527761) (xy 437.280909 -24.492577) (xy 437.207559 -24.450228)
			(xy 437.138567 -24.401099) (xy 437.074557 -24.345634) (xy 437.016109 -24.284336) (xy 436.963753 -24.21776)
			(xy 436.917963 -24.146508) (xy 436.879152 -24.071227) (xy 436.847673 -23.992597) (xy 436.823812 -23.91133)
			(xy 436.807783 -23.828164) (xy 436.799732 -23.74385) (xy 434.86451 -23.74385) (xy 434.86451 -26.142442)
			(xy 435.367682 -26.142442) (xy 435.371753 -26.08682) (xy 435.383879 -26.032383) (xy 435.403802 -25.980292)
			(xy 435.431098 -25.931657) (xy 435.465184 -25.887514) (xy 435.505333 -25.848805) (xy 435.550691 -25.816354)
			(xy 435.600291 -25.790853) (xy 435.653075 -25.772846) (xy 435.707918 -25.762716) (xy 435.763652 -25.760679)
			(xy 435.819089 -25.766779) (xy 435.873046 -25.780885) (xy 435.924375 -25.802697) (xy 435.971981 -25.831751)
			(xy 435.976005 -25.8351) (xy 436.747874 -25.8351) (xy 436.751904 -25.750495) (xy 436.763959 -25.666657)
			(xy 436.783928 -25.584344) (xy 436.811632 -25.504303) (xy 436.846818 -25.427257) (xy 436.88917 -25.353905)
			(xy 436.938302 -25.28491) (xy 436.99377 -25.220899) (xy 437.055072 -25.16245) (xy 437.121652 -25.110094)
			(xy 437.192908 -25.064303) (xy 437.268194 -25.025493) (xy 437.346828 -24.994015) (xy 437.428098 -24.970155)
			(xy 437.511269 -24.954129) (xy 437.595586 -24.94608) (xy 437.637936 -24.945594) (xy 437.68033 -24.94608)
			(xy 437.764734 -24.954152) (xy 437.847987 -24.970218) (xy 437.929333 -24.994134) (xy 438.008034 -25.025682)
			(xy 438.083376 -25.064575) (xy 438.154675 -25.110462) (xy 438.221284 -25.162924) (xy 438.282599 -25.221487)
			(xy 438.338063 -25.285619) (xy 438.387172 -25.354738) (xy 438.429482 -25.428216) (xy 438.464608 -25.505386)
			(xy 438.492231 -25.585549) (xy 438.512101 -25.667977) (xy 438.518554 -25.70988) (xy 438.52032 -25.719246)
			(xy 438.529708 -25.735818) (xy 438.536842 -25.742138) (xy 438.560718 -25.761442) (xy 438.568108 -25.766912)
			(xy 438.58556 -25.772645) (xy 438.594754 -25.772618) (xy 438.610756 -25.772364) (xy 438.638009 -25.77288)
			(xy 438.691961 -25.780632) (xy 438.74426 -25.795983) (xy 438.793842 -25.818621) (xy 438.839697 -25.848086)
			(xy 438.880892 -25.883777) (xy 438.916588 -25.924967) (xy 438.946058 -25.970819) (xy 438.968702 -26.020399)
			(xy 438.984059 -26.072696) (xy 438.991817 -26.126647) (xy 438.991817 -26.181153) (xy 438.984059 -26.235104)
			(xy 438.968702 -26.287401) (xy 438.946058 -26.336981) (xy 438.916588 -26.382833) (xy 438.880892 -26.424023)
			(xy 438.839697 -26.459714) (xy 438.793842 -26.489179) (xy 438.74426 -26.511817) (xy 438.691961 -26.527168)
			(xy 438.638009 -26.53492) (xy 438.610756 -26.53538) (xy 438.584987 -26.534971) (xy 438.533915 -26.528056)
			(xy 438.484238 -26.514333) (xy 438.43686 -26.494049) (xy 438.392641 -26.467575) (xy 438.37225 -26.451814)
			(xy 438.364865 -26.446336) (xy 438.347409 -26.440606) (xy 438.338214 -26.440638) (xy 438.30748 -26.442162)
			(xy 438.298013 -26.442969) (xy 438.28066 -26.450681) (xy 438.273698 -26.457148) (xy 438.24234 -26.488413)
			(xy 438.17443 -26.54525) (xy 438.101208 -26.595056) (xy 438.023398 -26.637338) (xy 437.941772 -26.671679)
			(xy 437.857137 -26.697737) (xy 437.770331 -26.715255) (xy 437.682214 -26.72406) (xy 437.637936 -26.72461)
			(xy 437.595586 -26.72412) (xy 437.511269 -26.716071) (xy 437.428098 -26.700045) (xy 437.346828 -26.676185)
			(xy 437.268194 -26.644707) (xy 437.192908 -26.605897) (xy 437.121652 -26.560106) (xy 437.055072 -26.50775)
			(xy 436.99377 -26.449301) (xy 436.938302 -26.38529) (xy 436.88917 -26.316295) (xy 436.846818 -26.242943)
			(xy 436.811632 -26.165897) (xy 436.783928 -26.085856) (xy 436.763959 -26.003543) (xy 436.751904 -25.919705)
			(xy 436.747874 -25.8351) (xy 435.976005 -25.8351) (xy 436.014849 -25.867426) (xy 436.052066 -25.908963)
			(xy 436.082839 -25.955476) (xy 436.106511 -26.005973) (xy 436.122579 -26.05938) (xy 436.130699 -26.114556)
			(xy 436.131208 -26.142442) (xy 436.130699 -26.170328) (xy 436.122579 -26.225504) (xy 436.106511 -26.278911)
			(xy 436.082839 -26.329408) (xy 436.052066 -26.375921) (xy 436.014849 -26.417458) (xy 435.971981 -26.453133)
			(xy 435.924375 -26.482187) (xy 435.873046 -26.503999) (xy 435.819089 -26.518105) (xy 435.763652 -26.524205)
			(xy 435.707918 -26.522168) (xy 435.653075 -26.512038) (xy 435.600291 -26.494031) (xy 435.550691 -26.46853)
			(xy 435.505333 -26.436079) (xy 435.465184 -26.39737) (xy 435.431098 -26.353227) (xy 435.403802 -26.304592)
			(xy 435.383879 -26.252501) (xy 435.371753 -26.198064) (xy 435.367682 -26.142442) (xy 434.86451 -26.142442)
			(xy 434.86451 -27.944826) (xy 434.864991 -27.955574) (xy 434.873811 -27.975175) (xy 434.881528 -27.982672)
			(xy 434.946552 -28.040584) (xy 434.966872 -28.046934) (xy 434.977794 -28.045664) (xy 434.988867 -28.044461)
			(xy 435.011106 -28.043188) (xy 435.022244 -28.043124) (xy 435.049491 -28.043613) (xy 435.103429 -28.051374)
			(xy 435.155714 -28.066732) (xy 435.205282 -28.089373) (xy 435.251123 -28.118838) (xy 435.292304 -28.154527)
			(xy 435.327988 -28.195713) (xy 435.357448 -28.241557) (xy 435.380084 -28.291127) (xy 435.395435 -28.343414)
			(xy 435.40319 -28.397353) (xy 435.40319 -28.451847) (xy 435.395435 -28.505786) (xy 435.380084 -28.558073)
			(xy 435.357448 -28.607643) (xy 435.327988 -28.653487) (xy 435.292304 -28.694673) (xy 435.251123 -28.730362)
			(xy 435.205282 -28.759827) (xy 435.155714 -28.782468) (xy 435.103429 -28.797826) (xy 435.049491 -28.805587)
			(xy 435.022244 -28.80614) (xy 434.994095 -28.805633) (xy 434.938409 -28.797354) (xy 434.884544 -28.780984)
			(xy 434.833668 -28.756879) (xy 434.786885 -28.725561) (xy 434.745211 -28.687709) (xy 434.709549 -28.644147)
			(xy 434.680674 -28.595817) (xy 434.659213 -28.543771) (xy 434.651912 -28.51658) (xy 434.648864 -28.504388)
			(xy 434.626258 -28.478734) (xy 434.621326 -28.473497) (xy 434.609214 -28.465745) (xy 434.602382 -28.463494)
			(xy 434.528214 -28.44165) (xy 434.51936 -28.439464) (xy 434.501185 -28.440809) (xy 434.484627 -28.448421)
			(xy 434.477922 -28.454604) (xy 432.983894 -29.948632) (xy 434.589426 -29.948632) (xy 434.593497 -29.89301)
			(xy 434.605623 -29.838573) (xy 434.625546 -29.786482) (xy 434.652842 -29.737847) (xy 434.686928 -29.693704)
			(xy 434.727077 -29.654995) (xy 434.772435 -29.622544) (xy 434.822035 -29.597043) (xy 434.874819 -29.579036)
			(xy 434.929662 -29.568906) (xy 434.985396 -29.566869) (xy 435.040833 -29.572969) (xy 435.09479 -29.587075)
			(xy 435.146119 -29.608887) (xy 435.193725 -29.637941) (xy 435.20233 -29.645102) (xy 436.348378 -29.645102)
			(xy 436.348804 -29.613822) (xy 436.356469 -29.551734) (xy 436.371694 -29.491056) (xy 436.394249 -29.432704)
			(xy 436.423795 -29.377562) (xy 436.459884 -29.326461) (xy 436.501971 -29.280175) (xy 436.549419 -29.239404)
			(xy 436.5752 -29.221684) (xy 436.585357 -29.214228) (xy 436.597345 -29.1921) (xy 436.59806 -29.17952)
			(xy 436.59806 -29.094684) (xy 436.597344 -29.082107) (xy 436.585344 -29.05999) (xy 436.5752 -29.05252)
			(xy 436.549404 -29.034826) (xy 436.501977 -28.994036) (xy 436.45991 -28.947738) (xy 436.423836 -28.896631)
			(xy 436.394302 -28.841487) (xy 436.371752 -28.783137) (xy 436.356527 -28.722463) (xy 436.348856 -28.66038)
			(xy 436.348378 -28.629102) (xy 436.34888 -28.597141) (xy 436.356891 -28.533723) (xy 436.372788 -28.471809)
			(xy 436.39632 -28.412376) (xy 436.427114 -28.356361) (xy 436.464687 -28.304646) (xy 436.508444 -28.258049)
			(xy 436.557697 -28.217304) (xy 436.611668 -28.183053) (xy 436.669507 -28.155836) (xy 436.7303 -28.136083)
			(xy 436.79309 -28.124105) (xy 436.856886 -28.120092) (xy 436.920682 -28.124105) (xy 436.983472 -28.136083)
			(xy 437.044265 -28.155836) (xy 437.102104 -28.183053) (xy 437.156075 -28.217304) (xy 437.205328 -28.258049)
			(xy 437.249085 -28.304646) (xy 437.286658 -28.356361) (xy 437.317452 -28.412376) (xy 437.340984 -28.471809)
			(xy 437.356881 -28.533723) (xy 437.364892 -28.597141) (xy 437.365394 -28.629102) (xy 437.364939 -28.660381)
			(xy 437.361651 -28.687014) (xy 438.775092 -28.687014) (xy 438.779163 -28.631392) (xy 438.791289 -28.576955)
			(xy 438.811212 -28.524864) (xy 438.838508 -28.476229) (xy 438.872594 -28.432086) (xy 438.912743 -28.393377)
			(xy 438.958101 -28.360926) (xy 439.007701 -28.335425) (xy 439.060485 -28.317418) (xy 439.115328 -28.307288)
			(xy 439.171062 -28.305251) (xy 439.226499 -28.311351) (xy 439.280456 -28.325457) (xy 439.331785 -28.347269)
			(xy 439.379391 -28.376323) (xy 439.422259 -28.411998) (xy 439.459476 -28.453535) (xy 439.490249 -28.500048)
			(xy 439.513921 -28.550545) (xy 439.529989 -28.603952) (xy 439.538109 -28.659128) (xy 439.538618 -28.687014)
			(xy 439.538109 -28.7149) (xy 439.529989 -28.770076) (xy 439.513921 -28.823483) (xy 439.490249 -28.87398)
			(xy 439.459476 -28.920493) (xy 439.422259 -28.96203) (xy 439.379391 -28.997705) (xy 439.331785 -29.026759)
			(xy 439.280456 -29.048571) (xy 439.226499 -29.062677) (xy 439.171062 -29.068777) (xy 439.115328 -29.06674)
			(xy 439.060485 -29.05661) (xy 439.007701 -29.038603) (xy 438.958101 -29.013102) (xy 438.912743 -28.980651)
			(xy 438.872594 -28.941942) (xy 438.838508 -28.897799) (xy 438.811212 -28.849164) (xy 438.791289 -28.797073)
			(xy 438.779163 -28.742636) (xy 438.775092 -28.687014) (xy 437.361651 -28.687014) (xy 437.357275 -28.722466)
			(xy 437.342052 -28.783143) (xy 437.319499 -28.841493) (xy 437.289958 -28.896635) (xy 437.253874 -28.947736)
			(xy 437.211793 -28.994024) (xy 437.16435 -29.034798) (xy 437.138572 -29.05252) (xy 437.128408 -29.059967)
			(xy 437.116425 -29.082102) (xy 437.115712 -29.094684) (xy 437.115712 -29.17952) (xy 437.116397 -29.192102)
			(xy 437.128416 -29.21422) (xy 437.138572 -29.221684) (xy 437.164317 -29.239449) (xy 437.211746 -29.280228)
			(xy 437.253817 -29.326515) (xy 437.289895 -29.377611) (xy 437.319436 -29.432745) (xy 437.341994 -29.491085)
			(xy 437.357229 -29.551751) (xy 437.36491 -29.613827) (xy 437.365394 -29.645102) (xy 437.364892 -29.677063)
			(xy 437.356881 -29.740481) (xy 437.340984 -29.802395) (xy 437.317452 -29.861828) (xy 437.286658 -29.917843)
			(xy 437.249085 -29.969558) (xy 437.205328 -30.016155) (xy 437.20405 -30.017212) (xy 438.795666 -30.017212)
			(xy 438.799737 -29.96159) (xy 438.811863 -29.907153) (xy 438.831786 -29.855062) (xy 438.859082 -29.806427)
			(xy 438.893168 -29.762284) (xy 438.933317 -29.723575) (xy 438.978675 -29.691124) (xy 439.028275 -29.665623)
			(xy 439.081059 -29.647616) (xy 439.135902 -29.637486) (xy 439.191636 -29.635449) (xy 439.247073 -29.641549)
			(xy 439.30103 -29.655655) (xy 439.352359 -29.677467) (xy 439.399965 -29.706521) (xy 439.442833 -29.742196)
			(xy 439.48005 -29.783733) (xy 439.510823 -29.830246) (xy 439.534495 -29.880743) (xy 439.550563 -29.93415)
			(xy 439.558683 -29.989326) (xy 439.559192 -30.017212) (xy 439.558683 -30.045098) (xy 439.550563 -30.100274)
			(xy 439.534495 -30.153681) (xy 439.510823 -30.204178) (xy 439.48005 -30.250691) (xy 439.442833 -30.292228)
			(xy 439.399965 -30.327903) (xy 439.352359 -30.356957) (xy 439.30103 -30.378769) (xy 439.247073 -30.392875)
			(xy 439.191636 -30.398975) (xy 439.135902 -30.396938) (xy 439.081059 -30.386808) (xy 439.028275 -30.368801)
			(xy 438.978675 -30.3433) (xy 438.933317 -30.310849) (xy 438.893168 -30.27214) (xy 438.859082 -30.227997)
			(xy 438.831786 -30.179362) (xy 438.811863 -30.127271) (xy 438.799737 -30.072834) (xy 438.795666 -30.017212)
			(xy 437.20405 -30.017212) (xy 437.156075 -30.0569) (xy 437.102104 -30.091151) (xy 437.044265 -30.118368)
			(xy 436.983472 -30.138121) (xy 436.920682 -30.150099) (xy 436.856886 -30.154113) (xy 436.79309 -30.150099)
			(xy 436.7303 -30.138121) (xy 436.669507 -30.118368) (xy 436.611668 -30.091151) (xy 436.557697 -30.0569)
			(xy 436.508444 -30.016155) (xy 436.464687 -29.969558) (xy 436.427114 -29.917843) (xy 436.39632 -29.861828)
			(xy 436.372788 -29.802395) (xy 436.356891 -29.740481) (xy 436.34888 -29.677063) (xy 436.348378 -29.645102)
			(xy 435.20233 -29.645102) (xy 435.236593 -29.673616) (xy 435.27381 -29.715153) (xy 435.304583 -29.761666)
			(xy 435.328255 -29.812163) (xy 435.344323 -29.86557) (xy 435.352443 -29.920746) (xy 435.352952 -29.948632)
			(xy 435.352443 -29.976518) (xy 435.344323 -30.031694) (xy 435.328255 -30.085101) (xy 435.304583 -30.135598)
			(xy 435.27381 -30.182111) (xy 435.236593 -30.223648) (xy 435.193725 -30.259323) (xy 435.146119 -30.288377)
			(xy 435.09479 -30.310189) (xy 435.040833 -30.324295) (xy 434.985396 -30.330395) (xy 434.929662 -30.328358)
			(xy 434.874819 -30.318228) (xy 434.822035 -30.300221) (xy 434.772435 -30.27472) (xy 434.727077 -30.242269)
			(xy 434.686928 -30.20356) (xy 434.652842 -30.159417) (xy 434.625546 -30.110782) (xy 434.605623 -30.058691)
			(xy 434.593497 -30.004254) (xy 434.589426 -29.948632) (xy 432.983894 -29.948632) (xy 431.135536 -31.79699)
			(xy 431.128684 -31.804386) (xy 431.12094 -31.822985) (xy 431.12055 -31.833058) (xy 431.12055 -33.745932)
			(xy 434.821328 -33.745932) (xy 434.825399 -33.69031) (xy 434.837525 -33.635873) (xy 434.857448 -33.583782)
			(xy 434.884744 -33.535147) (xy 434.91883 -33.491004) (xy 434.958979 -33.452295) (xy 435.004337 -33.419844)
			(xy 435.053937 -33.394343) (xy 435.106721 -33.376336) (xy 435.161564 -33.366206) (xy 435.217298 -33.364169)
			(xy 435.272735 -33.370269) (xy 435.326692 -33.384375) (xy 435.378021 -33.406187) (xy 435.425627 -33.435241)
			(xy 435.468495 -33.470916) (xy 435.505712 -33.512453) (xy 435.536485 -33.558966) (xy 435.560157 -33.609463)
			(xy 435.576225 -33.66287) (xy 435.584345 -33.718046) (xy 435.584854 -33.745932) (xy 435.584345 -33.773818)
			(xy 435.576225 -33.828994) (xy 435.560157 -33.882401) (xy 435.536485 -33.932898) (xy 435.505712 -33.979411)
			(xy 435.468495 -34.020948) (xy 435.425627 -34.056623) (xy 435.378021 -34.085677) (xy 435.326692 -34.107489)
			(xy 435.272735 -34.121595) (xy 435.217298 -34.127695) (xy 435.161564 -34.125658) (xy 435.106721 -34.115528)
			(xy 435.053937 -34.097521) (xy 435.004337 -34.07202) (xy 434.958979 -34.039569) (xy 434.91883 -34.00086)
			(xy 434.884744 -33.956717) (xy 434.857448 -33.908082) (xy 434.837525 -33.855991) (xy 434.825399 -33.801554)
			(xy 434.821328 -33.745932) (xy 431.12055 -33.745932) (xy 431.12055 -34.384742) (xy 435.833518 -34.384742)
			(xy 435.837589 -34.32912) (xy 435.849715 -34.274683) (xy 435.869638 -34.222592) (xy 435.896934 -34.173957)
			(xy 435.93102 -34.129814) (xy 435.971169 -34.091105) (xy 436.016527 -34.058654) (xy 436.066127 -34.033153)
			(xy 436.118911 -34.015146) (xy 436.173754 -34.005016) (xy 436.229488 -34.002979) (xy 436.284925 -34.009079)
			(xy 436.338882 -34.023185) (xy 436.390211 -34.044997) (xy 436.437817 -34.074051) (xy 436.480685 -34.109726)
			(xy 436.517902 -34.151263) (xy 436.548675 -34.197776) (xy 436.572347 -34.248273) (xy 436.588415 -34.30168)
			(xy 436.596535 -34.356856) (xy 436.597044 -34.384742) (xy 436.849518 -34.384742) (xy 436.853589 -34.32912)
			(xy 436.865715 -34.274683) (xy 436.885638 -34.222592) (xy 436.912934 -34.173957) (xy 436.94702 -34.129814)
			(xy 436.987169 -34.091105) (xy 437.032527 -34.058654) (xy 437.082127 -34.033153) (xy 437.134911 -34.015146)
			(xy 437.189754 -34.005016) (xy 437.245488 -34.002979) (xy 437.300925 -34.009079) (xy 437.354882 -34.023185)
			(xy 437.406211 -34.044997) (xy 437.453817 -34.074051) (xy 437.496685 -34.109726) (xy 437.533902 -34.151263)
			(xy 437.564675 -34.197776) (xy 437.588347 -34.248273) (xy 437.604415 -34.30168) (xy 437.612535 -34.356856)
			(xy 437.613044 -34.384742) (xy 437.612535 -34.412628) (xy 437.604415 -34.467804) (xy 437.588347 -34.521211)
			(xy 437.564675 -34.571708) (xy 437.533902 -34.618221) (xy 437.496685 -34.659758) (xy 437.453817 -34.695433)
			(xy 437.406211 -34.724487) (xy 437.354882 -34.746299) (xy 437.300925 -34.760405) (xy 437.245488 -34.766505)
			(xy 437.189754 -34.764468) (xy 437.134911 -34.754338) (xy 437.082127 -34.736331) (xy 437.032527 -34.71083)
			(xy 436.987169 -34.678379) (xy 436.94702 -34.63967) (xy 436.912934 -34.595527) (xy 436.885638 -34.546892)
			(xy 436.865715 -34.494801) (xy 436.853589 -34.440364) (xy 436.849518 -34.384742) (xy 436.597044 -34.384742)
			(xy 436.596535 -34.412628) (xy 436.588415 -34.467804) (xy 436.572347 -34.521211) (xy 436.548675 -34.571708)
			(xy 436.517902 -34.618221) (xy 436.480685 -34.659758) (xy 436.437817 -34.695433) (xy 436.390211 -34.724487)
			(xy 436.338882 -34.746299) (xy 436.284925 -34.760405) (xy 436.229488 -34.766505) (xy 436.173754 -34.764468)
			(xy 436.118911 -34.754338) (xy 436.066127 -34.736331) (xy 436.016527 -34.71083) (xy 435.971169 -34.678379)
			(xy 435.93102 -34.63967) (xy 435.896934 -34.595527) (xy 435.869638 -34.546892) (xy 435.849715 -34.494801)
			(xy 435.837589 -34.440364) (xy 435.833518 -34.384742) (xy 431.12055 -34.384742) (xy 431.12055 -35.889438)
			(xy 435.636668 -35.889438) (xy 435.640739 -35.833816) (xy 435.652865 -35.779379) (xy 435.672788 -35.727288)
			(xy 435.700084 -35.678653) (xy 435.73417 -35.63451) (xy 435.774319 -35.595801) (xy 435.819677 -35.56335)
			(xy 435.869277 -35.537849) (xy 435.922061 -35.519842) (xy 435.976904 -35.509712) (xy 436.032638 -35.507675)
			(xy 436.088075 -35.513775) (xy 436.142032 -35.527881) (xy 436.193361 -35.549693) (xy 436.240967 -35.578747)
			(xy 436.283835 -35.614422) (xy 436.321052 -35.655959) (xy 436.351825 -35.702472) (xy 436.375497 -35.752969)
			(xy 436.391565 -35.806376) (xy 436.399685 -35.861552) (xy 436.400194 -35.889438) (xy 436.399685 -35.917324)
			(xy 436.391565 -35.9725) (xy 436.375497 -36.025907) (xy 436.351825 -36.076404) (xy 436.321052 -36.122917)
			(xy 436.283835 -36.164454) (xy 436.240967 -36.200129) (xy 436.193361 -36.229183) (xy 436.142032 -36.250995)
			(xy 436.088075 -36.265101) (xy 436.032638 -36.271201) (xy 435.976904 -36.269164) (xy 435.922061 -36.259034)
			(xy 435.869277 -36.241027) (xy 435.819677 -36.215526) (xy 435.774319 -36.183075) (xy 435.73417 -36.144366)
			(xy 435.700084 -36.100223) (xy 435.672788 -36.051588) (xy 435.652865 -35.999497) (xy 435.640739 -35.94506)
			(xy 435.636668 -35.889438) (xy 431.12055 -35.889438) (xy 431.12055 -36.47694) (xy 432.718462 -36.47694)
			(xy 432.722533 -36.421318) (xy 432.734659 -36.366881) (xy 432.754582 -36.31479) (xy 432.781878 -36.266155)
			(xy 432.815964 -36.222012) (xy 432.856113 -36.183303) (xy 432.901471 -36.150852) (xy 432.951071 -36.125351)
			(xy 433.003855 -36.107344) (xy 433.058698 -36.097214) (xy 433.114432 -36.095177) (xy 433.169869 -36.101277)
			(xy 433.223826 -36.115383) (xy 433.275155 -36.137195) (xy 433.322761 -36.166249) (xy 433.365629 -36.201924)
			(xy 433.402846 -36.243461) (xy 433.433619 -36.289974) (xy 433.457291 -36.340471) (xy 433.473359 -36.393878)
			(xy 433.481479 -36.449054) (xy 433.481988 -36.47694) (xy 433.481479 -36.504826) (xy 433.473359 -36.560002)
			(xy 433.457291 -36.613409) (xy 433.433619 -36.663906) (xy 433.402846 -36.710419) (xy 433.365629 -36.751956)
			(xy 433.322761 -36.787631) (xy 433.275155 -36.816685) (xy 433.223826 -36.838497) (xy 433.169869 -36.852603)
			(xy 433.114432 -36.858703) (xy 433.058698 -36.856666) (xy 433.003855 -36.846536) (xy 432.951071 -36.828529)
			(xy 432.901471 -36.803028) (xy 432.856113 -36.770577) (xy 432.815964 -36.731868) (xy 432.781878 -36.687725)
			(xy 432.754582 -36.63909) (xy 432.734659 -36.586999) (xy 432.722533 -36.532562) (xy 432.718462 -36.47694)
			(xy 431.12055 -36.47694) (xy 431.12055 -42.294048) (xy 431.120117 -42.304113) (xy 431.112384 -42.3227)
			(xy 431.105564 -42.330116) (xy 430.883822 -42.551858) (xy 430.88052 -42.557192) (xy 430.864397 -42.582336)
			(xy 430.82559 -42.627737) (xy 430.780182 -42.666536) (xy 430.755044 -42.682668) (xy 430.74971 -42.68597)
			(xy 425.302426 -48.133254) (xy 425.295585 -48.140654) (xy 425.287867 -48.159253) (xy 425.28744 -48.169322)
			(xy 425.28744 -50.323242) (xy 425.287748 -50.331922) (xy 425.293479 -50.348305) (xy 425.304368 -50.36182)
			(xy 425.31157 -50.366676) (xy 425.338829 -50.384096) (xy 425.389122 -50.424785) (xy 425.433845 -50.471527)
			(xy 425.472277 -50.523565) (xy 425.503794 -50.58006) (xy 425.527889 -50.640096) (xy 425.544171 -50.702705)
			(xy 425.552376 -50.766874) (xy 425.552374 -50.831566) (xy 425.544163 -50.895734) (xy 425.527876 -50.958341)
			(xy 425.503777 -51.018377) (xy 425.472255 -51.074868) (xy 425.43382 -51.126904) (xy 425.389092 -51.173642)
			(xy 425.338796 -51.214327) (xy 425.31157 -51.2318) (xy 425.304379 -51.236662) (xy 425.293519 -51.250188)
			(xy 425.287784 -51.26656) (xy 425.28744 -51.275234) (xy 425.28744 -52.438554) (xy 426.035468 -52.438554)
			(xy 426.039539 -52.382932) (xy 426.051665 -52.328495) (xy 426.071588 -52.276404) (xy 426.098884 -52.227769)
			(xy 426.13297 -52.183626) (xy 426.173119 -52.144917) (xy 426.218477 -52.112466) (xy 426.268077 -52.086965)
			(xy 426.320861 -52.068958) (xy 426.375704 -52.058828) (xy 426.431438 -52.056791) (xy 426.486875 -52.062891)
			(xy 426.540832 -52.076997) (xy 426.592161 -52.098809) (xy 426.639767 -52.127863) (xy 426.682635 -52.163538)
			(xy 426.719852 -52.205075) (xy 426.750625 -52.251588) (xy 426.774297 -52.302085) (xy 426.790365 -52.355492)
			(xy 426.798485 -52.410668) (xy 426.798994 -52.438554) (xy 426.798485 -52.46644) (xy 426.790365 -52.521616)
			(xy 426.774297 -52.575023) (xy 426.750625 -52.62552) (xy 426.719852 -52.672033) (xy 426.682635 -52.71357)
			(xy 426.639767 -52.749245) (xy 426.592161 -52.778299) (xy 426.540832 -52.800111) (xy 426.486875 -52.814217)
			(xy 426.431438 -52.820317) (xy 426.375704 -52.81828) (xy 426.320861 -52.80815) (xy 426.268077 -52.790143)
			(xy 426.218477 -52.764642) (xy 426.173119 -52.732191) (xy 426.13297 -52.693482) (xy 426.098884 -52.649339)
			(xy 426.071588 -52.600704) (xy 426.051665 -52.548613) (xy 426.039539 -52.494176) (xy 426.035468 -52.438554)
			(xy 425.28744 -52.438554) (xy 425.28744 -55.821326) (xy 425.287497 -55.8256) (xy 425.288899 -55.83403)
			(xy 425.290234 -55.83809) (xy 425.298362 -55.86095) (xy 425.303188 -55.8673) (xy 425.321331 -55.892312)
			(xy 425.350148 -55.94697) (xy 425.369796 -56.005551) (xy 425.379765 -56.06653) (xy 425.380404 -56.097424)
			(xy 425.380404 -56.097678) (xy 426.955964 -56.097678) (xy 426.960035 -56.042056) (xy 426.972161 -55.987619)
			(xy 426.992084 -55.935528) (xy 427.01938 -55.886893) (xy 427.053466 -55.84275) (xy 427.093615 -55.804041)
			(xy 427.138973 -55.77159) (xy 427.188573 -55.746089) (xy 427.241357 -55.728082) (xy 427.2962 -55.717952)
			(xy 427.351934 -55.715915) (xy 427.407371 -55.722015) (xy 427.461328 -55.736121) (xy 427.512657 -55.757933)
			(xy 427.560263 -55.786987) (xy 427.603131 -55.822662) (xy 427.640348 -55.864199) (xy 427.671121 -55.910712)
			(xy 427.694793 -55.961209) (xy 427.710861 -56.014616) (xy 427.718981 -56.069792) (xy 427.71949 -56.097678)
			(xy 427.718981 -56.125564) (xy 427.710861 -56.18074) (xy 427.694793 -56.234147) (xy 427.671121 -56.284644)
			(xy 427.640348 -56.331157) (xy 427.603131 -56.372694) (xy 427.560263 -56.408369) (xy 427.512657 -56.437423)
			(xy 427.461328 -56.459235) (xy 427.407371 -56.473341) (xy 427.351934 -56.479441) (xy 427.2962 -56.477404)
			(xy 427.241357 -56.467274) (xy 427.188573 -56.449267) (xy 427.138973 -56.423766) (xy 427.093615 -56.391315)
			(xy 427.053466 -56.352606) (xy 427.01938 -56.308463) (xy 426.992084 -56.259828) (xy 426.972161 -56.207737)
			(xy 426.960035 -56.1533) (xy 426.955964 -56.097678) (xy 425.380404 -56.097678) (xy 425.380404 -56.098186)
			(xy 425.379664 -56.132131) (xy 425.367649 -56.198948) (xy 425.356528 -56.231028) (xy 425.351448 -56.244744)
			(xy 425.357036 -56.272938) (xy 425.367196 -56.283606) (xy 425.368212 -56.284622) (xy 426.868844 -57.785254)
			(xy 426.879564 -57.79524) (xy 426.905329 -57.809164) (xy 426.933983 -57.81522) (xy 426.963178 -57.812913)
			(xy 426.990524 -57.802431) (xy 427.013782 -57.784632) (xy 427.022768 -57.773062) (xy 427.038232 -57.752524)
			(xy 427.073786 -57.715388) (xy 427.113998 -57.683355) (xy 427.158142 -57.657004) (xy 427.205421 -57.63681)
			(xy 427.254981 -57.623138) (xy 427.305926 -57.616235) (xy 427.331632 -57.615836) (xy 427.3589 -57.616325)
			(xy 427.41288 -57.62409) (xy 427.465206 -57.639458) (xy 427.514812 -57.662116) (xy 427.560689 -57.691603)
			(xy 427.601903 -57.727318) (xy 427.637615 -57.768535) (xy 427.667098 -57.814414) (xy 427.689752 -57.864022)
			(xy 427.705116 -57.916349) (xy 427.712878 -57.97033) (xy 427.713394 -57.997598) (xy 427.712976 -58.023303)
			(xy 427.706081 -58.07425) (xy 427.692415 -58.123811) (xy 427.672225 -58.171091) (xy 427.645876 -58.215236)
			(xy 427.613844 -58.255449) (xy 427.576709 -58.291002) (xy 427.556168 -58.306462) (xy 427.544579 -58.315447)
			(xy 427.526702 -58.338677) (xy 427.516172 -58.366032) (xy 427.51386 -58.395253) (xy 427.519958 -58.423923)
			(xy 427.53396 -58.449675) (xy 427.543976 -58.460386) (xy 428.366682 -59.283092) (xy 428.377212 -59.292921)
			(xy 428.402443 -59.306789) (xy 428.430542 -59.313059) (xy 428.459275 -59.311233) (xy 428.486355 -59.301456)
			(xy 428.509628 -59.284506) (xy 428.527241 -59.261731) (xy 428.533052 -59.248548) (xy 428.544651 -59.22048)
			(xy 428.573593 -59.167084) (xy 428.608686 -59.117514) (xy 428.649432 -59.072475) (xy 428.69525 -59.032607)
			(xy 428.745489 -58.998478) (xy 428.799433 -58.970574) (xy 428.856317 -58.94929) (xy 428.91533 -58.934931)
			(xy 428.975633 -58.9277) (xy 429.006 -58.927238) (xy 429.037275 -58.927722) (xy 429.099353 -58.935403)
			(xy 429.16002 -58.950636) (xy 429.218362 -58.973192) (xy 429.273499 -59.002731) (xy 429.324598 -59.038807)
			(xy 429.370889 -59.080875) (xy 429.411674 -59.128301) (xy 429.429418 -59.15406) (xy 429.437751 -59.165689)
			(xy 429.459587 -59.184156) (xy 429.485684 -59.195848) (xy 429.514 -59.199849) (xy 429.542316 -59.195848)
			(xy 429.568413 -59.184156) (xy 429.590249 -59.165689) (xy 429.598582 -59.15406) (xy 429.616303 -59.128281)
			(xy 429.657076 -59.080836) (xy 429.703363 -59.038752) (xy 429.754464 -59.002666) (xy 429.809606 -58.973122)
			(xy 429.867957 -58.950568) (xy 429.928634 -58.935344) (xy 429.990721 -58.927681) (xy 430.022 -58.927238)
			(xy 430.053977 -58.92774) (xy 430.117427 -58.935755) (xy 430.179372 -58.95166) (xy 430.238834 -58.975203)
			(xy 430.294878 -59.006013) (xy 430.346618 -59.043605) (xy 430.393238 -59.087384) (xy 430.434004 -59.136662)
			(xy 430.468272 -59.19066) (xy 430.495503 -59.248527) (xy 430.515266 -59.309351) (xy 430.527249 -59.372172)
			(xy 430.531265 -59.436) (xy 430.527249 -59.499828) (xy 430.515266 -59.562649) (xy 430.495503 -59.623473)
			(xy 430.468272 -59.68134) (xy 430.434004 -59.735338) (xy 430.393238 -59.784616) (xy 430.346618 -59.828395)
			(xy 430.294878 -59.865987) (xy 430.238834 -59.896797) (xy 430.179372 -59.92034) (xy 430.117427 -59.936245)
			(xy 430.053977 -59.94426) (xy 430.022 -59.944762) (xy 429.990725 -59.944278) (xy 429.928647 -59.936597)
			(xy 429.86798 -59.921364) (xy 429.809638 -59.898808) (xy 429.754501 -59.869269) (xy 429.703402 -59.833193)
			(xy 429.657111 -59.791125) (xy 429.616326 -59.743699) (xy 429.598582 -59.71794) (xy 429.590249 -59.706311)
			(xy 429.568413 -59.687844) (xy 429.542316 -59.676152) (xy 429.514 -59.672151) (xy 429.485684 -59.676152)
			(xy 429.459587 -59.687844) (xy 429.437751 -59.706311) (xy 429.429418 -59.71794) (xy 429.41195 -59.743358)
			(xy 429.371813 -59.790189) (xy 429.326313 -59.831828) (xy 429.276117 -59.867666) (xy 429.22196 -59.897179)
			(xy 429.193452 -59.908948) (xy 429.180242 -59.914701) (xy 429.157472 -59.932335) (xy 429.140527 -59.955622)
			(xy 429.130753 -59.982713) (xy 429.128927 -60.011454) (xy 429.135192 -60.039564) (xy 429.149053 -60.064809)
			(xy 429.158908 -60.075318) (xy 433.255928 -64.172338) (xy 433.262776 -64.179735) (xy 433.270508 -64.198334)
			(xy 433.270914 -64.208406) (xy 433.270914 -74.439272) (xy 437.38495 -74.439272) (xy 437.389021 -74.38365)
			(xy 437.401147 -74.329213) (xy 437.42107 -74.277122) (xy 437.448366 -74.228487) (xy 437.482452 -74.184344)
			(xy 437.522601 -74.145635) (xy 437.567959 -74.113184) (xy 437.617559 -74.087683) (xy 437.670343 -74.069676)
			(xy 437.725186 -74.059546) (xy 437.78092 -74.057509) (xy 437.836357 -74.063609) (xy 437.890314 -74.077715)
			(xy 437.941643 -74.099527) (xy 437.989249 -74.128581) (xy 438.032117 -74.164256) (xy 438.069334 -74.205793)
			(xy 438.100107 -74.252306) (xy 438.123779 -74.302803) (xy 438.139847 -74.35621) (xy 438.147967 -74.411386)
			(xy 438.148476 -74.439272) (xy 438.147967 -74.467158) (xy 438.139847 -74.522334) (xy 438.123779 -74.575741)
			(xy 438.100107 -74.626238) (xy 438.069334 -74.672751) (xy 438.032117 -74.714288) (xy 437.989249 -74.749963)
			(xy 437.941643 -74.779017) (xy 437.890314 -74.800829) (xy 437.836357 -74.814935) (xy 437.78092 -74.821035)
			(xy 437.725186 -74.818998) (xy 437.670343 -74.808868) (xy 437.617559 -74.790861) (xy 437.567959 -74.76536)
			(xy 437.522601 -74.732909) (xy 437.482452 -74.6942) (xy 437.448366 -74.650057) (xy 437.42107 -74.601422)
			(xy 437.401147 -74.549331) (xy 437.389021 -74.494894) (xy 437.38495 -74.439272) (xy 433.270914 -74.439272)
			(xy 433.270914 -91.270836) (xy 437.855358 -91.270836) (xy 437.859429 -91.215214) (xy 437.871555 -91.160777)
			(xy 437.891478 -91.108686) (xy 437.918774 -91.060051) (xy 437.95286 -91.015908) (xy 437.993009 -90.977199)
			(xy 438.038367 -90.944748) (xy 438.087967 -90.919247) (xy 438.140751 -90.90124) (xy 438.195594 -90.89111)
			(xy 438.251328 -90.889073) (xy 438.306765 -90.895173) (xy 438.360722 -90.909279) (xy 438.412051 -90.931091)
			(xy 438.459657 -90.960145) (xy 438.502525 -90.99582) (xy 438.539742 -91.037357) (xy 438.570515 -91.08387)
			(xy 438.594187 -91.134367) (xy 438.610255 -91.187774) (xy 438.618375 -91.24295) (xy 438.618884 -91.270836)
			(xy 438.618375 -91.298722) (xy 438.610255 -91.353898) (xy 438.594187 -91.407305) (xy 438.570515 -91.457802)
			(xy 438.539742 -91.504315) (xy 438.502525 -91.545852) (xy 438.459657 -91.581527) (xy 438.412051 -91.610581)
			(xy 438.360722 -91.632393) (xy 438.306765 -91.646499) (xy 438.251328 -91.652599) (xy 438.195594 -91.650562)
			(xy 438.140751 -91.640432) (xy 438.087967 -91.622425) (xy 438.038367 -91.596924) (xy 437.993009 -91.564473)
			(xy 437.95286 -91.525764) (xy 437.918774 -91.481621) (xy 437.891478 -91.432986) (xy 437.871555 -91.380895)
			(xy 437.859429 -91.326458) (xy 437.855358 -91.270836) (xy 433.270914 -91.270836) (xy 433.270914 -94.275148)
			(xy 436.294782 -94.275148) (xy 436.298853 -94.219526) (xy 436.310979 -94.165089) (xy 436.330902 -94.112998)
			(xy 436.358198 -94.064363) (xy 436.392284 -94.02022) (xy 436.432433 -93.981511) (xy 436.477791 -93.94906)
			(xy 436.527391 -93.923559) (xy 436.580175 -93.905552) (xy 436.635018 -93.895422) (xy 436.690752 -93.893385)
			(xy 436.746189 -93.899485) (xy 436.800146 -93.913591) (xy 436.851475 -93.935403) (xy 436.899081 -93.964457)
			(xy 436.941949 -94.000132) (xy 436.979166 -94.041669) (xy 437.009939 -94.088182) (xy 437.033611 -94.138679)
			(xy 437.049679 -94.192086) (xy 437.057799 -94.247262) (xy 437.058308 -94.275148) (xy 437.057799 -94.303034)
			(xy 437.049679 -94.35821) (xy 437.033611 -94.411617) (xy 437.009939 -94.462114) (xy 436.982394 -94.503748)
			(xy 437.869582 -94.503748) (xy 437.873653 -94.448126) (xy 437.885779 -94.393689) (xy 437.905702 -94.341598)
			(xy 437.932998 -94.292963) (xy 437.967084 -94.24882) (xy 438.007233 -94.210111) (xy 438.052591 -94.17766)
			(xy 438.102191 -94.152159) (xy 438.154975 -94.134152) (xy 438.209818 -94.124022) (xy 438.265552 -94.121985)
			(xy 438.320989 -94.128085) (xy 438.374946 -94.142191) (xy 438.426275 -94.164003) (xy 438.473881 -94.193057)
			(xy 438.516749 -94.228732) (xy 438.553966 -94.270269) (xy 438.584739 -94.316782) (xy 438.608411 -94.367279)
			(xy 438.624479 -94.420686) (xy 438.632599 -94.475862) (xy 438.633108 -94.503748) (xy 438.632599 -94.531634)
			(xy 438.624479 -94.58681) (xy 438.608411 -94.640217) (xy 438.584739 -94.690714) (xy 438.553966 -94.737227)
			(xy 438.516749 -94.778764) (xy 438.473881 -94.814439) (xy 438.426275 -94.843493) (xy 438.374946 -94.865305)
			(xy 438.320989 -94.879411) (xy 438.265552 -94.885511) (xy 438.209818 -94.883474) (xy 438.154975 -94.873344)
			(xy 438.102191 -94.855337) (xy 438.052591 -94.829836) (xy 438.007233 -94.797385) (xy 437.967084 -94.758676)
			(xy 437.932998 -94.714533) (xy 437.905702 -94.665898) (xy 437.885779 -94.613807) (xy 437.873653 -94.55937)
			(xy 437.869582 -94.503748) (xy 436.982394 -94.503748) (xy 436.979166 -94.508627) (xy 436.941949 -94.550164)
			(xy 436.899081 -94.585839) (xy 436.851475 -94.614893) (xy 436.800146 -94.636705) (xy 436.746189 -94.650811)
			(xy 436.690752 -94.656911) (xy 436.635018 -94.654874) (xy 436.580175 -94.644744) (xy 436.527391 -94.626737)
			(xy 436.477791 -94.601236) (xy 436.432433 -94.568785) (xy 436.392284 -94.530076) (xy 436.358198 -94.485933)
			(xy 436.330902 -94.437298) (xy 436.310979 -94.385207) (xy 436.298853 -94.33077) (xy 436.294782 -94.275148)
			(xy 433.270914 -94.275148) (xy 433.270914 -95.113348) (xy 436.853582 -95.113348) (xy 436.857653 -95.057726)
			(xy 436.869779 -95.003289) (xy 436.889702 -94.951198) (xy 436.916998 -94.902563) (xy 436.951084 -94.85842)
			(xy 436.991233 -94.819711) (xy 437.036591 -94.78726) (xy 437.086191 -94.761759) (xy 437.138975 -94.743752)
			(xy 437.193818 -94.733622) (xy 437.249552 -94.731585) (xy 437.304989 -94.737685) (xy 437.358946 -94.751791)
			(xy 437.410275 -94.773603) (xy 437.457881 -94.802657) (xy 437.500749 -94.838332) (xy 437.537966 -94.879869)
			(xy 437.568739 -94.926382) (xy 437.592411 -94.976879) (xy 437.608479 -95.030286) (xy 437.616599 -95.085462)
			(xy 437.617108 -95.113348) (xy 437.616599 -95.141234) (xy 437.608479 -95.19641) (xy 437.592411 -95.249817)
			(xy 437.568739 -95.300314) (xy 437.537966 -95.346827) (xy 437.500749 -95.388364) (xy 437.457881 -95.424039)
			(xy 437.410275 -95.453093) (xy 437.358946 -95.474905) (xy 437.304989 -95.489011) (xy 437.249552 -95.495111)
			(xy 437.193818 -95.493074) (xy 437.138975 -95.482944) (xy 437.086191 -95.464937) (xy 437.036591 -95.439436)
			(xy 436.991233 -95.406985) (xy 436.951084 -95.368276) (xy 436.916998 -95.324133) (xy 436.889702 -95.275498)
			(xy 436.869779 -95.223407) (xy 436.857653 -95.16897) (xy 436.853582 -95.113348) (xy 433.270914 -95.113348)
			(xy 433.270914 -97.450148) (xy 437.894982 -97.450148) (xy 437.899053 -97.394526) (xy 437.911179 -97.340089)
			(xy 437.931102 -97.287998) (xy 437.958398 -97.239363) (xy 437.992484 -97.19522) (xy 438.032633 -97.156511)
			(xy 438.077991 -97.12406) (xy 438.127591 -97.098559) (xy 438.180375 -97.080552) (xy 438.235218 -97.070422)
			(xy 438.290952 -97.068385) (xy 438.346389 -97.074485) (xy 438.400346 -97.088591) (xy 438.451675 -97.110403)
			(xy 438.499281 -97.139457) (xy 438.542149 -97.175132) (xy 438.579366 -97.216669) (xy 438.610139 -97.263182)
			(xy 438.633811 -97.313679) (xy 438.649879 -97.367086) (xy 438.657999 -97.422262) (xy 438.658508 -97.450148)
			(xy 438.657999 -97.478034) (xy 438.649879 -97.53321) (xy 438.633811 -97.586617) (xy 438.610139 -97.637114)
			(xy 438.579366 -97.683627) (xy 438.542149 -97.725164) (xy 438.499281 -97.760839) (xy 438.451675 -97.789893)
			(xy 438.400346 -97.811705) (xy 438.346389 -97.825811) (xy 438.290952 -97.831911) (xy 438.235218 -97.829874)
			(xy 438.180375 -97.819744) (xy 438.127591 -97.801737) (xy 438.077991 -97.776236) (xy 438.032633 -97.743785)
			(xy 437.992484 -97.705076) (xy 437.958398 -97.660933) (xy 437.931102 -97.612298) (xy 437.911179 -97.560207)
			(xy 437.899053 -97.50577) (xy 437.894982 -97.450148) (xy 433.270914 -97.450148) (xy 433.270914 -100.210874)
			(xy 433.271351 -100.220938) (xy 433.279086 -100.239522) (xy 433.2859 -100.246942) (xy 434.105558 -101.0666)
			(xy 434.11296 -101.073437) (xy 434.131558 -101.081151) (xy 434.141626 -101.081586)
		)
		(stroke
			(width 0)
			(type solid)
		)
		(fill yes)
		(layer "In4.Cu")
		(net "P3V3_OCP_SFF")
	)
	(gr_poly
		(pts
			(xy 341.554054 -256.09931) (xy 341.563678 -256.098906) (xy 341.581577 -256.09183) (xy 341.59561 -256.078657)
			(xy 341.600028 -256.0701) (xy 341.609934 -256.049272) (xy 341.612616 -256.043093) (xy 341.614947 -256.029831)
			(xy 341.614506 -256.02311) (xy 341.614506 -256.021078) (xy 341.598373 -255.999945) (xy 341.572678 -255.953405)
			(xy 341.555134 -255.903221) (xy 341.546233 -255.850809) (xy 341.545672 -255.824228) (xy 341.546158 -255.799438)
			(xy 341.553914 -255.75047) (xy 341.569235 -255.703317) (xy 341.591744 -255.659142) (xy 341.620886 -255.619031)
			(xy 341.655943 -255.583974) (xy 341.696054 -255.554832) (xy 341.740229 -255.532323) (xy 341.787382 -255.517002)
			(xy 341.83635 -255.509246) (xy 341.88593 -255.509246) (xy 341.934898 -255.517002) (xy 341.982051 -255.532323)
			(xy 342.026226 -255.554832) (xy 342.066337 -255.583974) (xy 342.101394 -255.619031) (xy 342.130536 -255.659142)
			(xy 342.153045 -255.703317) (xy 342.168366 -255.75047) (xy 342.176122 -255.799438) (xy 342.176608 -255.824228)
			(xy 342.176178 -255.848548) (xy 342.168745 -255.896615) (xy 342.154016 -255.942969) (xy 342.143588 -255.964944)
			(xy 342.137746 -255.976882) (xy 342.139016 -256.003552) (xy 342.184228 -256.075688) (xy 342.189108 -256.082759)
			(xy 342.202583 -256.0934) (xy 342.218821 -256.098983) (xy 342.227408 -256.09931) (xy 342.434926 -256.09931)
			(xy 342.44347 -256.09898) (xy 342.459604 -256.093348) (xy 342.472987 -256.082721) (xy 342.477852 -256.075688)
			(xy 342.529922 -255.993392) (xy 342.531446 -255.967738) (xy 342.525604 -255.9558) (xy 342.516227 -255.935147)
			(xy 342.50299 -255.891766) (xy 342.496304 -255.846906) (xy 342.495886 -255.824228) (xy 342.496408 -255.798973)
			(xy 342.504721 -255.749151) (xy 342.521122 -255.701377) (xy 342.545163 -255.656954) (xy 342.576187 -255.617094)
			(xy 342.613349 -255.582884) (xy 342.655635 -255.555258) (xy 342.701891 -255.534968) (xy 342.750856 -255.522568)
			(xy 342.801194 -255.518397) (xy 342.851532 -255.522568) (xy 342.900497 -255.534968) (xy 342.946753 -255.555258)
			(xy 342.989039 -255.582884) (xy 343.026201 -255.617094) (xy 343.057225 -255.656954) (xy 343.081266 -255.701377)
			(xy 343.097667 -255.749151) (xy 343.10598 -255.798973) (xy 343.106502 -255.824228) (xy 343.106113 -255.846909)
			(xy 343.099443 -255.891777) (xy 343.086195 -255.93516) (xy 343.076784 -255.9558) (xy 343.070942 -255.967738)
			(xy 343.072466 -255.993392) (xy 343.124536 -256.075688) (xy 343.129388 -256.082727) (xy 343.14278 -256.093336)
			(xy 343.158919 -256.098943) (xy 343.167462 -256.09931) (xy 343.374726 -256.09931) (xy 343.383318 -256.099023)
			(xy 343.399561 -256.093427) (xy 343.41304 -256.082774) (xy 343.417906 -256.075688) (xy 343.463118 -256.003552)
			(xy 343.464642 -255.976882) (xy 343.458546 -255.964944) (xy 343.448092 -255.942974) (xy 343.433303 -255.896622)
			(xy 343.42578 -255.848554) (xy 343.425272 -255.824228) (xy 343.425759 -255.799418) (xy 343.433521 -255.75041)
			(xy 343.448854 -255.70322) (xy 343.471381 -255.659009) (xy 343.500546 -255.618866) (xy 343.535632 -255.58378)
			(xy 343.575775 -255.554615) (xy 343.619986 -255.532088) (xy 343.667176 -255.516755) (xy 343.716184 -255.508993)
			(xy 343.765804 -255.508993) (xy 343.814812 -255.516755) (xy 343.862002 -255.532088) (xy 343.906213 -255.554615)
			(xy 343.946356 -255.58378) (xy 343.981442 -255.618866) (xy 344.010607 -255.659009) (xy 344.033134 -255.70322)
			(xy 344.048467 -255.75041) (xy 344.056229 -255.799418) (xy 344.056716 -255.824228) (xy 344.056252 -255.848558)
			(xy 344.048746 -255.896636) (xy 344.03393 -255.942986) (xy 344.023442 -255.964944) (xy 344.0176 -255.976882)
			(xy 344.01887 -256.003552) (xy 344.064082 -256.075688) (xy 344.06896 -256.082765) (xy 344.082433 -256.093418)
			(xy 344.098672 -256.099015) (xy 344.107262 -256.09931) (xy 345.254834 -256.09931) (xy 345.263378 -256.098978)
			(xy 345.27951 -256.093345) (xy 345.29289 -256.082717) (xy 345.29776 -256.075688) (xy 345.34983 -255.993392)
			(xy 345.351354 -255.967738) (xy 345.345512 -255.9558) (xy 345.336135 -255.935148) (xy 345.322897 -255.891766)
			(xy 345.316211 -255.846906) (xy 345.315794 -255.824228) (xy 345.316316 -255.798973) (xy 345.324629 -255.749151)
			(xy 345.34103 -255.701377) (xy 345.365071 -255.656954) (xy 345.396095 -255.617094) (xy 345.433257 -255.582884)
			(xy 345.475543 -255.555258) (xy 345.521799 -255.534968) (xy 345.570764 -255.522568) (xy 345.621102 -255.518397)
			(xy 345.67144 -255.522568) (xy 345.720405 -255.534968) (xy 345.766661 -255.555258) (xy 345.808947 -255.582884)
			(xy 345.846109 -255.617094) (xy 345.877133 -255.656954) (xy 345.901174 -255.701377) (xy 345.917575 -255.749151)
			(xy 345.925888 -255.798973) (xy 345.92641 -255.824228) (xy 345.926021 -255.846909) (xy 345.919351 -255.891777)
			(xy 345.906103 -255.93516) (xy 345.896692 -255.9558) (xy 345.89085 -255.967738) (xy 345.892374 -255.993392)
			(xy 345.944444 -256.075688) (xy 345.949292 -256.082737) (xy 345.96268 -256.09337) (xy 345.978822 -256.099006)
			(xy 345.98737 -256.09931) (xy 347.134942 -256.09931) (xy 347.143485 -256.098977) (xy 347.159615 -256.093342)
			(xy 347.172993 -256.082713) (xy 347.177868 -256.075688) (xy 347.229938 -255.993392) (xy 347.231462 -255.967738)
			(xy 347.22562 -255.9558) (xy 347.216242 -255.935148) (xy 347.203005 -255.891766) (xy 347.196318 -255.846906)
			(xy 347.195902 -255.824228) (xy 347.196424 -255.798973) (xy 347.204737 -255.749151) (xy 347.221138 -255.701377)
			(xy 347.245179 -255.656954) (xy 347.276203 -255.617094) (xy 347.313365 -255.582884) (xy 347.355651 -255.555258)
			(xy 347.401907 -255.534968) (xy 347.450872 -255.522568) (xy 347.50121 -255.518397) (xy 347.551548 -255.522568)
			(xy 347.600513 -255.534968) (xy 347.646769 -255.555258) (xy 347.689055 -255.582884) (xy 347.726217 -255.617094)
			(xy 347.757241 -255.656954) (xy 347.781282 -255.701377) (xy 347.797683 -255.749151) (xy 347.805996 -255.798973)
			(xy 347.806518 -255.824228) (xy 347.806129 -255.846909) (xy 347.799459 -255.891777) (xy 347.786212 -255.935161)
			(xy 347.7768 -255.9558) (xy 347.770958 -255.967738) (xy 347.772482 -255.993392) (xy 347.824552 -256.075688)
			(xy 347.8294 -256.082736) (xy 347.842789 -256.093367) (xy 347.85893 -256.099) (xy 347.867478 -256.09931)
			(xy 348.074742 -256.09931) (xy 348.083285 -256.098977) (xy 348.099415 -256.093342) (xy 348.112793 -256.082713)
			(xy 348.117668 -256.075688) (xy 348.169738 -255.993392) (xy 348.171262 -255.967738) (xy 348.16542 -255.9558)
			(xy 348.156042 -255.935148) (xy 348.142805 -255.891766) (xy 348.136118 -255.846906) (xy 348.135702 -255.824228)
			(xy 348.136146 -255.800234) (xy 348.143649 -255.752835) (xy 348.158476 -255.707195) (xy 348.18026 -255.664435)
			(xy 348.208465 -255.625611) (xy 348.242397 -255.591677) (xy 348.28122 -255.563469) (xy 348.323978 -255.541683)
			(xy 348.369618 -255.526854) (xy 348.417016 -255.519348) (xy 348.44101 -255.51892) (xy 348.450111 -255.51896)
			(xy 348.468284 -255.519977) (xy 348.477332 -255.520952) (xy 348.488 -255.522476) (xy 348.508828 -255.515872)
			(xy 348.572328 -255.459484) (xy 348.579944 -255.451917) (xy 348.588735 -255.432357) (xy 348.589346 -255.421638)
			(xy 348.589346 -252.879352) (xy 348.589854 -252.878844) (xy 348.589854 -252.868176) (xy 349.298006 -252.160024)
			(xy 349.304725 -252.152788) (xy 349.312333 -252.134583) (xy 349.312738 -252.124718) (xy 349.312738 -251.458476)
			(xy 349.312309 -251.448409) (xy 349.304581 -251.429817) (xy 349.297752 -251.422408) (xy 349.085916 -251.210572)
			(xy 349.082187 -251.207049) (xy 349.073614 -251.201416) (xy 349.068898 -251.199396) (xy 349.056198 -251.194316)
			(xy 349.05155 -251.192276) (xy 349.043101 -251.18665) (xy 349.039434 -251.18314) (xy 348.454472 -250.598178)
			(xy 348.44736 -250.590812) (xy 348.428564 -250.583192) (xy 348.262448 -250.583192) (xy 348.252609 -250.582659)
			(xy 348.234444 -250.575076) (xy 348.227142 -250.56846) (xy 348.10573 -250.447048) (xy 348.078298 -250.440444)
			(xy 348.064582 -250.444762) (xy 348.041826 -250.451631) (xy 347.994875 -250.459039) (xy 347.97111 -250.459494)
			(xy 347.945196 -250.458947) (xy 347.894112 -250.450201) (xy 347.845237 -250.432957) (xy 347.799973 -250.407711)
			(xy 347.759621 -250.375187) (xy 347.725337 -250.336319) (xy 347.698106 -250.292221) (xy 347.67871 -250.24416)
			(xy 347.667703 -250.193514) (xy 347.666056 -250.167648) (xy 347.665548 -250.157742) (xy 347.665548 -250.154186)
			(xy 347.666017 -250.130421) (xy 347.673412 -250.083469) (xy 347.68028 -250.060714) (xy 347.684852 -250.046744)
			(xy 347.678248 -250.019566) (xy 346.838778 -249.180096) (xy 346.831666 -249.17273) (xy 346.81287 -249.16511)
			(xy 346.01912 -249.16511) (xy 346.00783 -249.16571) (xy 345.987396 -249.175324) (xy 345.97975 -249.183652)
			(xy 345.92387 -249.251724) (xy 345.918282 -249.273568) (xy 345.920568 -249.284998) (xy 345.923289 -249.299642)
			(xy 345.926211 -249.329286) (xy 345.92641 -249.34418) (xy 345.925888 -249.369435) (xy 345.917575 -249.419257)
			(xy 345.901174 -249.467031) (xy 345.877133 -249.511454) (xy 345.846109 -249.551314) (xy 345.808947 -249.585524)
			(xy 345.766661 -249.61315) (xy 345.720405 -249.63344) (xy 345.67144 -249.64584) (xy 345.621102 -249.650011)
			(xy 345.570764 -249.64584) (xy 345.521799 -249.63344) (xy 345.475543 -249.61315) (xy 345.433257 -249.585524)
			(xy 345.396095 -249.551314) (xy 345.365071 -249.511454) (xy 345.34103 -249.467031) (xy 345.324629 -249.419257)
			(xy 345.316316 -249.369435) (xy 345.315794 -249.34418) (xy 345.315984 -249.329286) (xy 345.318908 -249.299641)
			(xy 345.321636 -249.284998) (xy 345.323922 -249.273568) (xy 345.318334 -249.251724) (xy 345.262454 -249.183652)
			(xy 345.254833 -249.175286) (xy 345.234388 -249.165655) (xy 345.223084 -249.16511) (xy 344.139012 -249.16511)
			(xy 344.127722 -249.165712) (xy 344.107291 -249.175328) (xy 344.099642 -249.183652) (xy 344.05189 -249.241818)
			(xy 344.046556 -249.264424) (xy 344.049096 -249.275854) (xy 344.052624 -249.292716) (xy 344.056438 -249.326955)
			(xy 344.056716 -249.34418) (xy 344.056229 -249.36899) (xy 344.048467 -249.417998) (xy 344.033134 -249.465188)
			(xy 344.010607 -249.509399) (xy 343.981442 -249.549542) (xy 343.946356 -249.584628) (xy 343.906213 -249.613793)
			(xy 343.862002 -249.63632) (xy 343.814812 -249.651653) (xy 343.765804 -249.659415) (xy 343.716184 -249.659415)
			(xy 343.667176 -249.651653) (xy 343.619986 -249.63632) (xy 343.575775 -249.613793) (xy 343.535632 -249.584628)
			(xy 343.500546 -249.549542) (xy 343.471381 -249.509399) (xy 343.448854 -249.465188) (xy 343.433521 -249.417998)
			(xy 343.425759 -249.36899) (xy 343.425272 -249.34418) (xy 343.42553 -249.326954) (xy 343.429352 -249.292714)
			(xy 343.432892 -249.275854) (xy 343.435432 -249.264424) (xy 343.430098 -249.241564) (xy 343.382346 -249.183652)
			(xy 343.374725 -249.175287) (xy 343.354279 -249.16566) (xy 343.342976 -249.16511) (xy 343.199212 -249.16511)
			(xy 343.187922 -249.165712) (xy 343.167491 -249.175328) (xy 343.159842 -249.183652) (xy 343.103962 -249.251724)
			(xy 343.098374 -249.273568) (xy 343.10066 -249.284998) (xy 343.103381 -249.299642) (xy 343.106303 -249.329286)
			(xy 343.106502 -249.34418) (xy 343.10598 -249.369435) (xy 343.097667 -249.419257) (xy 343.081266 -249.467031)
			(xy 343.057225 -249.511454) (xy 343.026201 -249.551314) (xy 342.989039 -249.585524) (xy 342.946753 -249.61315)
			(xy 342.900497 -249.63344) (xy 342.851532 -249.64584) (xy 342.801194 -249.650011) (xy 342.750856 -249.64584)
			(xy 342.701891 -249.63344) (xy 342.655635 -249.61315) (xy 342.613349 -249.585524) (xy 342.576187 -249.551314)
			(xy 342.545163 -249.511454) (xy 342.521122 -249.467031) (xy 342.504721 -249.419257) (xy 342.496408 -249.369435)
			(xy 342.495886 -249.34418) (xy 342.496076 -249.329286) (xy 342.499 -249.299641) (xy 342.501728 -249.284998)
			(xy 342.504014 -249.273568) (xy 342.498426 -249.251724) (xy 342.442546 -249.183652) (xy 342.434925 -249.175287)
			(xy 342.414479 -249.16566) (xy 342.403176 -249.16511) (xy 342.259158 -249.16511) (xy 342.247874 -249.165722)
			(xy 342.227459 -249.175352) (xy 342.219788 -249.183652) (xy 342.163908 -249.251724) (xy 342.15832 -249.273568)
			(xy 342.160606 -249.284998) (xy 342.163328 -249.299642) (xy 342.16625 -249.329286) (xy 342.166448 -249.34418)
			(xy 342.165926 -249.369435) (xy 342.157613 -249.419257) (xy 342.141212 -249.467031) (xy 342.117171 -249.511454)
			(xy 342.086147 -249.551314) (xy 342.048985 -249.585524) (xy 342.006699 -249.61315) (xy 341.960443 -249.63344)
			(xy 341.911478 -249.64584) (xy 341.86114 -249.650011) (xy 341.810802 -249.64584) (xy 341.761837 -249.63344)
			(xy 341.715581 -249.61315) (xy 341.673295 -249.585524) (xy 341.636133 -249.551314) (xy 341.605109 -249.511454)
			(xy 341.581068 -249.467031) (xy 341.564667 -249.419257) (xy 341.556354 -249.369435) (xy 341.555832 -249.34418)
			(xy 341.556022 -249.329286) (xy 341.558946 -249.299641) (xy 341.561674 -249.284998) (xy 341.56396 -249.273568)
			(xy 341.558372 -249.251724) (xy 341.502492 -249.183652) (xy 341.494874 -249.175279) (xy 341.474428 -249.165633)
			(xy 341.463122 -249.16511) (xy 341.447628 -249.16511) (xy 341.437791 -249.165647) (xy 341.419631 -249.173235)
			(xy 341.412322 -249.179842) (xy 341.23249 -249.359674) (xy 341.22487 -249.374914) (xy 341.223854 -249.383296)
			(xy 341.221568 -249.39879) (xy 341.221314 -249.399044) (xy 341.218161 -249.415461) (xy 341.208745 -249.447538)
			(xy 341.202518 -249.463052) (xy 341.198454 -249.47245) (xy 341.198454 -249.758708) (xy 341.199091 -249.770122)
			(xy 341.208999 -249.790689) (xy 341.217504 -249.798332) (xy 341.287862 -249.854466) (xy 341.30996 -249.859546)
			(xy 341.321644 -249.856752) (xy 341.33874 -249.853052) (xy 341.373496 -249.8491) (xy 341.390986 -249.848878)
			(xy 341.416246 -249.84937) (xy 341.466076 -249.857683) (xy 341.513859 -249.874085) (xy 341.55829 -249.898128)
			(xy 341.598157 -249.929156) (xy 341.632374 -249.966324) (xy 341.660006 -250.008616) (xy 341.6803 -250.05488)
			(xy 341.692702 -250.103853) (xy 341.696873 -250.154186) (xy 342.025236 -250.154186) (xy 342.029196 -250.105132)
			(xy 342.040973 -250.057348) (xy 342.060264 -250.012072) (xy 342.086567 -249.970476) (xy 342.119202 -249.933639)
			(xy 342.157323 -249.902514) (xy 342.199944 -249.877907) (xy 342.24596 -249.860455) (xy 342.294179 -249.850611)
			(xy 342.343354 -249.84863) (xy 342.392209 -249.854562) (xy 342.43948 -249.868254) (xy 342.483942 -249.889352)
			(xy 342.524445 -249.917308) (xy 342.559938 -249.9514) (xy 342.589503 -249.990744) (xy 342.612374 -250.034321)
			(xy 342.627958 -250.081002) (xy 342.635853 -250.129579) (xy 342.636348 -250.154186) (xy 342.954859 -250.154186)
			(xy 342.958954 -250.103458) (xy 342.971133 -250.054044) (xy 342.991081 -250.007224) (xy 343.018282 -249.96421)
			(xy 343.05203 -249.926116) (xy 343.091452 -249.893929) (xy 343.135526 -249.868483) (xy 343.183112 -249.850436)
			(xy 343.232976 -249.840256) (xy 343.283828 -249.838207) (xy 343.334349 -249.844341) (xy 343.383233 -249.858501)
			(xy 343.429212 -249.880318) (xy 343.471096 -249.909228) (xy 343.5078 -249.944483) (xy 343.538373 -249.985169)
			(xy 343.562024 -250.030232) (xy 343.57814 -250.078506) (xy 343.586304 -250.12874) (xy 343.586816 -250.154186)
			(xy 343.905344 -250.154186) (xy 343.909304 -250.105132) (xy 343.921081 -250.057348) (xy 343.940372 -250.012072)
			(xy 343.966675 -249.970476) (xy 343.99931 -249.933639) (xy 344.037431 -249.902514) (xy 344.080052 -249.877907)
			(xy 344.126068 -249.860455) (xy 344.174287 -249.850611) (xy 344.223462 -249.84863) (xy 344.272317 -249.854562)
			(xy 344.319588 -249.868254) (xy 344.36405 -249.889352) (xy 344.404553 -249.917308) (xy 344.440046 -249.9514)
			(xy 344.469611 -249.990744) (xy 344.492482 -250.034321) (xy 344.508066 -250.081002) (xy 344.515961 -250.129579)
			(xy 344.516456 -250.154186) (xy 345.785198 -250.154186) (xy 345.789158 -250.105132) (xy 345.800935 -250.057348)
			(xy 345.820226 -250.012072) (xy 345.846529 -249.970476) (xy 345.879164 -249.933639) (xy 345.917285 -249.902514)
			(xy 345.959906 -249.877907) (xy 346.005922 -249.860455) (xy 346.054141 -249.850611) (xy 346.103316 -249.84863)
			(xy 346.152171 -249.854562) (xy 346.199442 -249.868254) (xy 346.243904 -249.889352) (xy 346.284407 -249.917308)
			(xy 346.3199 -249.9514) (xy 346.349465 -249.990744) (xy 346.372336 -250.034321) (xy 346.38792 -250.081002)
			(xy 346.395815 -250.129579) (xy 346.39631 -250.154186) (xy 346.395815 -250.178793) (xy 346.38792 -250.22737)
			(xy 346.372336 -250.274051) (xy 346.349465 -250.317628) (xy 346.3199 -250.356972) (xy 346.284407 -250.391064)
			(xy 346.243904 -250.41902) (xy 346.199442 -250.440118) (xy 346.152171 -250.45381) (xy 346.103316 -250.459742)
			(xy 346.054141 -250.457761) (xy 346.005922 -250.447917) (xy 345.959906 -250.430465) (xy 345.917285 -250.405858)
			(xy 345.879164 -250.374733) (xy 345.846529 -250.337896) (xy 345.820226 -250.2963) (xy 345.800935 -250.251024)
			(xy 345.789158 -250.20324) (xy 345.785198 -250.154186) (xy 344.516456 -250.154186) (xy 344.515961 -250.178793)
			(xy 344.508066 -250.22737) (xy 344.492482 -250.274051) (xy 344.469611 -250.317628) (xy 344.440046 -250.356972)
			(xy 344.404553 -250.391064) (xy 344.36405 -250.41902) (xy 344.319588 -250.440118) (xy 344.272317 -250.45381)
			(xy 344.223462 -250.459742) (xy 344.174287 -250.457761) (xy 344.126068 -250.447917) (xy 344.080052 -250.430465)
			(xy 344.037431 -250.405858) (xy 343.99931 -250.374733) (xy 343.966675 -250.337896) (xy 343.940372 -250.2963)
			(xy 343.921081 -250.251024) (xy 343.909304 -250.20324) (xy 343.905344 -250.154186) (xy 343.586816 -250.154186)
			(xy 343.586304 -250.179632) (xy 343.57814 -250.229866) (xy 343.562024 -250.27814) (xy 343.538373 -250.323203)
			(xy 343.5078 -250.363889) (xy 343.471096 -250.399144) (xy 343.429212 -250.428054) (xy 343.383233 -250.449871)
			(xy 343.334349 -250.464031) (xy 343.283828 -250.470165) (xy 343.232976 -250.468116) (xy 343.183112 -250.457936)
			(xy 343.135526 -250.439889) (xy 343.091452 -250.414443) (xy 343.05203 -250.382256) (xy 343.018282 -250.344162)
			(xy 342.991081 -250.301148) (xy 342.971133 -250.254328) (xy 342.958954 -250.204914) (xy 342.954859 -250.154186)
			(xy 342.636348 -250.154186) (xy 342.635853 -250.178793) (xy 342.627958 -250.22737) (xy 342.612374 -250.274051)
			(xy 342.589503 -250.317628) (xy 342.559938 -250.356972) (xy 342.524445 -250.391064) (xy 342.483942 -250.41902)
			(xy 342.43948 -250.440118) (xy 342.392209 -250.45381) (xy 342.343354 -250.459742) (xy 342.294179 -250.457761)
			(xy 342.24596 -250.447917) (xy 342.199944 -250.430465) (xy 342.157323 -250.405858) (xy 342.119202 -250.374733)
			(xy 342.086567 -250.337896) (xy 342.060264 -250.2963) (xy 342.040973 -250.251024) (xy 342.029196 -250.20324)
			(xy 342.025236 -250.154186) (xy 341.696873 -250.154186) (xy 341.696874 -250.1542) (xy 341.692702 -250.204547)
			(xy 341.6803 -250.25352) (xy 341.660006 -250.299784) (xy 341.632374 -250.342076) (xy 341.598157 -250.379244)
			(xy 341.55829 -250.410272) (xy 341.513859 -250.434315) (xy 341.466076 -250.450717) (xy 341.416246 -250.45903)
			(xy 341.390986 -250.459494) (xy 341.373495 -250.459283) (xy 341.338736 -250.45534) (xy 341.321644 -250.45162)
			(xy 341.30996 -250.448826) (xy 341.287862 -250.453906) (xy 341.217504 -250.51004) (xy 341.209004 -250.517677)
			(xy 341.199138 -250.538254) (xy 341.198454 -250.549664) (xy 341.198454 -250.835922) (xy 341.202518 -250.84532)
			(xy 341.213079 -250.872154) (xy 341.225059 -250.928555) (xy 341.225787 -250.964192) (xy 341.555336 -250.964192)
			(xy 341.559296 -250.915138) (xy 341.571073 -250.867354) (xy 341.590364 -250.822078) (xy 341.616667 -250.780482)
			(xy 341.649302 -250.743645) (xy 341.687423 -250.71252) (xy 341.730044 -250.687913) (xy 341.77606 -250.670461)
			(xy 341.824279 -250.660617) (xy 341.873454 -250.658636) (xy 341.922309 -250.664568) (xy 341.96958 -250.67826)
			(xy 342.014042 -250.699358) (xy 342.054545 -250.727314) (xy 342.090038 -250.761406) (xy 342.119603 -250.80075)
			(xy 342.142474 -250.844327) (xy 342.158058 -250.891008) (xy 342.165953 -250.939585) (xy 342.166448 -250.964192)
			(xy 342.49539 -250.964192) (xy 342.49935 -250.915138) (xy 342.511127 -250.867354) (xy 342.530418 -250.822078)
			(xy 342.556721 -250.780482) (xy 342.589356 -250.743645) (xy 342.627477 -250.71252) (xy 342.670098 -250.687913)
			(xy 342.716114 -250.670461) (xy 342.764333 -250.660617) (xy 342.813508 -250.658636) (xy 342.862363 -250.664568)
			(xy 342.909634 -250.67826) (xy 342.954096 -250.699358) (xy 342.994599 -250.727314) (xy 343.030092 -250.761406)
			(xy 343.059657 -250.80075) (xy 343.082528 -250.844327) (xy 343.098112 -250.891008) (xy 343.106007 -250.939585)
			(xy 343.106502 -250.964192) (xy 343.424759 -250.964192) (xy 343.428854 -250.913464) (xy 343.441033 -250.86405)
			(xy 343.460981 -250.81723) (xy 343.488182 -250.774216) (xy 343.52193 -250.736122) (xy 343.561352 -250.703935)
			(xy 343.605426 -250.678489) (xy 343.653012 -250.660442) (xy 343.702876 -250.650262) (xy 343.753728 -250.648213)
			(xy 343.804249 -250.654347) (xy 343.853133 -250.668507) (xy 343.899112 -250.690324) (xy 343.940996 -250.719234)
			(xy 343.9777 -250.754489) (xy 344.008273 -250.795175) (xy 344.031924 -250.840238) (xy 344.04804 -250.888512)
			(xy 344.056204 -250.938746) (xy 344.056716 -250.964192) (xy 345.315298 -250.964192) (xy 345.319258 -250.915138)
			(xy 345.331035 -250.867354) (xy 345.350326 -250.822078) (xy 345.376629 -250.780482) (xy 345.409264 -250.743645)
			(xy 345.447385 -250.71252) (xy 345.490006 -250.687913) (xy 345.536022 -250.670461) (xy 345.584241 -250.660617)
			(xy 345.633416 -250.658636) (xy 345.682271 -250.664568) (xy 345.729542 -250.67826) (xy 345.774004 -250.699358)
			(xy 345.814507 -250.727314) (xy 345.85 -250.761406) (xy 345.879565 -250.80075) (xy 345.902436 -250.844327)
			(xy 345.91802 -250.891008) (xy 345.925915 -250.939585) (xy 345.92641 -250.964192) (xy 347.195406 -250.964192)
			(xy 347.199366 -250.915138) (xy 347.211143 -250.867354) (xy 347.230434 -250.822078) (xy 347.256737 -250.780482)
			(xy 347.289372 -250.743645) (xy 347.327493 -250.71252) (xy 347.370114 -250.687913) (xy 347.41613 -250.670461)
			(xy 347.464349 -250.660617) (xy 347.513524 -250.658636) (xy 347.562379 -250.664568) (xy 347.60965 -250.67826)
			(xy 347.654112 -250.699358) (xy 347.694615 -250.727314) (xy 347.730108 -250.761406) (xy 347.759673 -250.80075)
			(xy 347.782544 -250.844327) (xy 347.798128 -250.891008) (xy 347.806023 -250.939585) (xy 347.806518 -250.964192)
			(xy 347.806023 -250.988799) (xy 347.798128 -251.037376) (xy 347.782544 -251.084057) (xy 347.759673 -251.127634)
			(xy 347.730108 -251.166978) (xy 347.694615 -251.20107) (xy 347.654112 -251.229026) (xy 347.60965 -251.250124)
			(xy 347.562379 -251.263816) (xy 347.513524 -251.269748) (xy 347.464349 -251.267767) (xy 347.41613 -251.257923)
			(xy 347.370114 -251.240471) (xy 347.327493 -251.215864) (xy 347.289372 -251.184739) (xy 347.256737 -251.147902)
			(xy 347.230434 -251.106306) (xy 347.211143 -251.06103) (xy 347.199366 -251.013246) (xy 347.195406 -250.964192)
			(xy 345.92641 -250.964192) (xy 345.925915 -250.988799) (xy 345.91802 -251.037376) (xy 345.902436 -251.084057)
			(xy 345.879565 -251.127634) (xy 345.85 -251.166978) (xy 345.814507 -251.20107) (xy 345.774004 -251.229026)
			(xy 345.729542 -251.250124) (xy 345.682271 -251.263816) (xy 345.633416 -251.269748) (xy 345.584241 -251.267767)
			(xy 345.536022 -251.257923) (xy 345.490006 -251.240471) (xy 345.447385 -251.215864) (xy 345.409264 -251.184739)
			(xy 345.376629 -251.147902) (xy 345.350326 -251.106306) (xy 345.331035 -251.06103) (xy 345.319258 -251.013246)
			(xy 345.315298 -250.964192) (xy 344.056716 -250.964192) (xy 344.056204 -250.989638) (xy 344.04804 -251.039872)
			(xy 344.031924 -251.088146) (xy 344.008273 -251.133209) (xy 343.9777 -251.173895) (xy 343.940996 -251.20915)
			(xy 343.899112 -251.23806) (xy 343.853133 -251.259877) (xy 343.804249 -251.274037) (xy 343.753728 -251.280171)
			(xy 343.702876 -251.278122) (xy 343.653012 -251.267942) (xy 343.605426 -251.249895) (xy 343.561352 -251.224449)
			(xy 343.52193 -251.192262) (xy 343.488182 -251.154168) (xy 343.460981 -251.111154) (xy 343.441033 -251.064334)
			(xy 343.428854 -251.01492) (xy 343.424759 -250.964192) (xy 343.106502 -250.964192) (xy 343.106007 -250.988799)
			(xy 343.098112 -251.037376) (xy 343.082528 -251.084057) (xy 343.059657 -251.127634) (xy 343.030092 -251.166978)
			(xy 342.994599 -251.20107) (xy 342.954096 -251.229026) (xy 342.909634 -251.250124) (xy 342.862363 -251.263816)
			(xy 342.813508 -251.269748) (xy 342.764333 -251.267767) (xy 342.716114 -251.257923) (xy 342.670098 -251.240471)
			(xy 342.627477 -251.215864) (xy 342.589356 -251.184739) (xy 342.556721 -251.147902) (xy 342.530418 -251.106306)
			(xy 342.511127 -251.06103) (xy 342.49935 -251.013246) (xy 342.49539 -250.964192) (xy 342.166448 -250.964192)
			(xy 342.165953 -250.988799) (xy 342.158058 -251.037376) (xy 342.142474 -251.084057) (xy 342.119603 -251.127634)
			(xy 342.090038 -251.166978) (xy 342.054545 -251.20107) (xy 342.014042 -251.229026) (xy 341.96958 -251.250124)
			(xy 341.922309 -251.263816) (xy 341.873454 -251.269748) (xy 341.824279 -251.267767) (xy 341.77606 -251.257923)
			(xy 341.730044 -251.240471) (xy 341.687423 -251.215864) (xy 341.649302 -251.184739) (xy 341.616667 -251.147902)
			(xy 341.590364 -251.106306) (xy 341.571073 -251.06103) (xy 341.559296 -251.013246) (xy 341.555336 -250.964192)
			(xy 341.225787 -250.964192) (xy 341.226237 -250.986202) (xy 341.222076 -251.014738) (xy 341.22233 -251.014738)
			(xy 341.219125 -251.032156) (xy 341.209188 -251.06615) (xy 341.202518 -251.082556) (xy 341.198454 -251.092208)
			(xy 341.198454 -251.37872) (xy 341.199093 -251.390133) (xy 341.209005 -251.410696) (xy 341.217504 -251.418344)
			(xy 341.287862 -251.474478) (xy 341.30996 -251.479558) (xy 341.321644 -251.476764) (xy 341.33874 -251.473064)
			(xy 341.373496 -251.469112) (xy 341.390986 -251.46889) (xy 341.416245 -251.469382) (xy 341.466073 -251.477694)
			(xy 341.513854 -251.494096) (xy 341.558283 -251.518138) (xy 341.598149 -251.549165) (xy 341.632364 -251.586331)
			(xy 341.659995 -251.628622) (xy 341.680289 -251.674884) (xy 341.69269 -251.723855) (xy 341.696862 -251.774198)
			(xy 342.014805 -251.774198) (xy 342.0189 -251.72347) (xy 342.031079 -251.674056) (xy 342.051027 -251.627236)
			(xy 342.078228 -251.584222) (xy 342.111976 -251.546128) (xy 342.151398 -251.513941) (xy 342.195472 -251.488495)
			(xy 342.243058 -251.470448) (xy 342.292922 -251.460268) (xy 342.343774 -251.458219) (xy 342.394295 -251.464353)
			(xy 342.443179 -251.478513) (xy 342.489158 -251.50033) (xy 342.531042 -251.52924) (xy 342.567746 -251.564495)
			(xy 342.598319 -251.605181) (xy 342.62197 -251.650244) (xy 342.638086 -251.698518) (xy 342.64625 -251.748752)
			(xy 342.646762 -251.774198) (xy 342.96529 -251.774198) (xy 342.96925 -251.725144) (xy 342.981027 -251.67736)
			(xy 343.000318 -251.632084) (xy 343.026621 -251.590488) (xy 343.059256 -251.553651) (xy 343.097377 -251.522526)
			(xy 343.139998 -251.497919) (xy 343.186014 -251.480467) (xy 343.234233 -251.470623) (xy 343.283408 -251.468642)
			(xy 343.332263 -251.474574) (xy 343.379534 -251.488266) (xy 343.423996 -251.509364) (xy 343.464499 -251.53732)
			(xy 343.499992 -251.571412) (xy 343.529557 -251.610756) (xy 343.552428 -251.654333) (xy 343.568012 -251.701014)
			(xy 343.575907 -251.749591) (xy 343.576402 -251.774198) (xy 343.905344 -251.774198) (xy 343.909304 -251.725144)
			(xy 343.921081 -251.67736) (xy 343.940372 -251.632084) (xy 343.966675 -251.590488) (xy 343.99931 -251.553651)
			(xy 344.037431 -251.522526) (xy 344.080052 -251.497919) (xy 344.126068 -251.480467) (xy 344.174287 -251.470623)
			(xy 344.223462 -251.468642) (xy 344.272317 -251.474574) (xy 344.319588 -251.488266) (xy 344.36405 -251.509364)
			(xy 344.404553 -251.53732) (xy 344.440046 -251.571412) (xy 344.469611 -251.610756) (xy 344.492482 -251.654333)
			(xy 344.508066 -251.701014) (xy 344.515961 -251.749591) (xy 344.516456 -251.774198) (xy 345.785198 -251.774198)
			(xy 345.789158 -251.725144) (xy 345.800935 -251.67736) (xy 345.820226 -251.632084) (xy 345.846529 -251.590488)
			(xy 345.879164 -251.553651) (xy 345.917285 -251.522526) (xy 345.959906 -251.497919) (xy 346.005922 -251.480467)
			(xy 346.054141 -251.470623) (xy 346.103316 -251.468642) (xy 346.152171 -251.474574) (xy 346.199442 -251.488266)
			(xy 346.243904 -251.509364) (xy 346.284407 -251.53732) (xy 346.3199 -251.571412) (xy 346.349465 -251.610756)
			(xy 346.372336 -251.654333) (xy 346.38792 -251.701014) (xy 346.395815 -251.749591) (xy 346.39631 -251.774198)
			(xy 347.665306 -251.774198) (xy 347.669266 -251.725144) (xy 347.681043 -251.67736) (xy 347.700334 -251.632084)
			(xy 347.726637 -251.590488) (xy 347.759272 -251.553651) (xy 347.797393 -251.522526) (xy 347.840014 -251.497919)
			(xy 347.88603 -251.480467) (xy 347.934249 -251.470623) (xy 347.983424 -251.468642) (xy 348.032279 -251.474574)
			(xy 348.07955 -251.488266) (xy 348.124012 -251.509364) (xy 348.164515 -251.53732) (xy 348.200008 -251.571412)
			(xy 348.229573 -251.610756) (xy 348.252444 -251.654333) (xy 348.268028 -251.701014) (xy 348.275923 -251.749591)
			(xy 348.276418 -251.774198) (xy 348.275923 -251.798805) (xy 348.268028 -251.847382) (xy 348.252444 -251.894063)
			(xy 348.229573 -251.93764) (xy 348.200008 -251.976984) (xy 348.164515 -252.011076) (xy 348.124012 -252.039032)
			(xy 348.07955 -252.06013) (xy 348.032279 -252.073822) (xy 347.983424 -252.079754) (xy 347.934249 -252.077773)
			(xy 347.88603 -252.067929) (xy 347.840014 -252.050477) (xy 347.797393 -252.02587) (xy 347.759272 -251.994745)
			(xy 347.726637 -251.957908) (xy 347.700334 -251.916312) (xy 347.681043 -251.871036) (xy 347.669266 -251.823252)
			(xy 347.665306 -251.774198) (xy 346.39631 -251.774198) (xy 346.395815 -251.798805) (xy 346.38792 -251.847382)
			(xy 346.372336 -251.894063) (xy 346.349465 -251.93764) (xy 346.3199 -251.976984) (xy 346.284407 -252.011076)
			(xy 346.243904 -252.039032) (xy 346.199442 -252.06013) (xy 346.152171 -252.073822) (xy 346.103316 -252.079754)
			(xy 346.054141 -252.077773) (xy 346.005922 -252.067929) (xy 345.959906 -252.050477) (xy 345.917285 -252.02587)
			(xy 345.879164 -251.994745) (xy 345.846529 -251.957908) (xy 345.820226 -251.916312) (xy 345.800935 -251.871036)
			(xy 345.789158 -251.823252) (xy 345.785198 -251.774198) (xy 344.516456 -251.774198) (xy 344.515961 -251.798805)
			(xy 344.508066 -251.847382) (xy 344.492482 -251.894063) (xy 344.469611 -251.93764) (xy 344.440046 -251.976984)
			(xy 344.404553 -252.011076) (xy 344.36405 -252.039032) (xy 344.319588 -252.06013) (xy 344.272317 -252.073822)
			(xy 344.223462 -252.079754) (xy 344.174287 -252.077773) (xy 344.126068 -252.067929) (xy 344.080052 -252.050477)
			(xy 344.037431 -252.02587) (xy 343.99931 -251.994745) (xy 343.966675 -251.957908) (xy 343.940372 -251.916312)
			(xy 343.921081 -251.871036) (xy 343.909304 -251.823252) (xy 343.905344 -251.774198) (xy 343.576402 -251.774198)
			(xy 343.575907 -251.798805) (xy 343.568012 -251.847382) (xy 343.552428 -251.894063) (xy 343.529557 -251.93764)
			(xy 343.499992 -251.976984) (xy 343.464499 -252.011076) (xy 343.423996 -252.039032) (xy 343.379534 -252.06013)
			(xy 343.332263 -252.073822) (xy 343.283408 -252.079754) (xy 343.234233 -252.077773) (xy 343.186014 -252.067929)
			(xy 343.139998 -252.050477) (xy 343.097377 -252.02587) (xy 343.059256 -251.994745) (xy 343.026621 -251.957908)
			(xy 343.000318 -251.916312) (xy 342.981027 -251.871036) (xy 342.96925 -251.823252) (xy 342.96529 -251.774198)
			(xy 342.646762 -251.774198) (xy 342.64625 -251.799644) (xy 342.638086 -251.849878) (xy 342.62197 -251.898152)
			(xy 342.598319 -251.943215) (xy 342.567746 -251.983901) (xy 342.531042 -252.019156) (xy 342.489158 -252.048066)
			(xy 342.443179 -252.069883) (xy 342.394295 -252.084043) (xy 342.343774 -252.090177) (xy 342.292922 -252.088128)
			(xy 342.243058 -252.077948) (xy 342.195472 -252.059901) (xy 342.151398 -252.034455) (xy 342.111976 -252.002268)
			(xy 342.078228 -251.964174) (xy 342.051027 -251.92116) (xy 342.031079 -251.87434) (xy 342.0189 -251.824926)
			(xy 342.014805 -251.774198) (xy 341.696862 -251.774198) (xy 341.696862 -251.7742) (xy 341.69269 -251.824545)
			(xy 341.680289 -251.873516) (xy 341.659995 -251.919778) (xy 341.632364 -251.962069) (xy 341.598149 -251.999235)
			(xy 341.558283 -252.030262) (xy 341.513854 -252.054304) (xy 341.466073 -252.070706) (xy 341.416245 -252.079018)
			(xy 341.390986 -252.079506) (xy 341.373495 -252.079295) (xy 341.338736 -252.075351) (xy 341.321644 -252.071632)
			(xy 341.30996 -252.068838) (xy 341.287862 -252.073918) (xy 341.217504 -252.130052) (xy 341.208989 -252.137684)
			(xy 341.199088 -252.15826) (xy 341.198454 -252.169676) (xy 341.198454 -252.455934) (xy 341.202518 -252.465332)
			(xy 341.213078 -252.492166) (xy 341.225056 -252.548567) (xy 341.225783 -252.584204) (xy 341.544905 -252.584204)
			(xy 341.549 -252.533476) (xy 341.561179 -252.484062) (xy 341.581127 -252.437242) (xy 341.608328 -252.394228)
			(xy 341.642076 -252.356134) (xy 341.681498 -252.323947) (xy 341.725572 -252.298501) (xy 341.773158 -252.280454)
			(xy 341.823022 -252.270274) (xy 341.873874 -252.268225) (xy 341.924395 -252.274359) (xy 341.973279 -252.288519)
			(xy 342.019258 -252.310336) (xy 342.061142 -252.339246) (xy 342.097846 -252.374501) (xy 342.128419 -252.415187)
			(xy 342.15207 -252.46025) (xy 342.168186 -252.508524) (xy 342.17635 -252.558758) (xy 342.176862 -252.584204)
			(xy 342.49539 -252.584204) (xy 342.49935 -252.53515) (xy 342.511127 -252.487366) (xy 342.530418 -252.44209)
			(xy 342.556721 -252.400494) (xy 342.589356 -252.363657) (xy 342.627477 -252.332532) (xy 342.670098 -252.307925)
			(xy 342.716114 -252.290473) (xy 342.764333 -252.280629) (xy 342.813508 -252.278648) (xy 342.862363 -252.28458)
			(xy 342.909634 -252.298272) (xy 342.954096 -252.31937) (xy 342.994599 -252.347326) (xy 343.030092 -252.381418)
			(xy 343.059657 -252.420762) (xy 343.082528 -252.464339) (xy 343.098112 -252.51102) (xy 343.106007 -252.559597)
			(xy 343.106502 -252.584204) (xy 343.424759 -252.584204) (xy 343.428854 -252.533476) (xy 343.441033 -252.484062)
			(xy 343.460981 -252.437242) (xy 343.488182 -252.394228) (xy 343.52193 -252.356134) (xy 343.561352 -252.323947)
			(xy 343.605426 -252.298501) (xy 343.653012 -252.280454) (xy 343.702876 -252.270274) (xy 343.753728 -252.268225)
			(xy 343.804249 -252.274359) (xy 343.853133 -252.288519) (xy 343.899112 -252.310336) (xy 343.940996 -252.339246)
			(xy 343.9777 -252.374501) (xy 344.008273 -252.415187) (xy 344.031924 -252.46025) (xy 344.04804 -252.508524)
			(xy 344.056204 -252.558758) (xy 344.056716 -252.584204) (xy 345.315298 -252.584204) (xy 345.319258 -252.53515)
			(xy 345.331035 -252.487366) (xy 345.350326 -252.44209) (xy 345.376629 -252.400494) (xy 345.409264 -252.363657)
			(xy 345.447385 -252.332532) (xy 345.490006 -252.307925) (xy 345.536022 -252.290473) (xy 345.584241 -252.280629)
			(xy 345.633416 -252.278648) (xy 345.682271 -252.28458) (xy 345.729542 -252.298272) (xy 345.774004 -252.31937)
			(xy 345.814507 -252.347326) (xy 345.85 -252.381418) (xy 345.879565 -252.420762) (xy 345.902436 -252.464339)
			(xy 345.91802 -252.51102) (xy 345.925915 -252.559597) (xy 345.92641 -252.584204) (xy 347.195406 -252.584204)
			(xy 347.199366 -252.53515) (xy 347.211143 -252.487366) (xy 347.230434 -252.44209) (xy 347.256737 -252.400494)
			(xy 347.289372 -252.363657) (xy 347.327493 -252.332532) (xy 347.370114 -252.307925) (xy 347.41613 -252.290473)
			(xy 347.464349 -252.280629) (xy 347.513524 -252.278648) (xy 347.562379 -252.28458) (xy 347.60965 -252.298272)
			(xy 347.654112 -252.31937) (xy 347.694615 -252.347326) (xy 347.730108 -252.381418) (xy 347.759673 -252.420762)
			(xy 347.782544 -252.464339) (xy 347.798128 -252.51102) (xy 347.806023 -252.559597) (xy 347.806518 -252.584204)
			(xy 347.806023 -252.608811) (xy 347.798128 -252.657388) (xy 347.782544 -252.704069) (xy 347.759673 -252.747646)
			(xy 347.730108 -252.78699) (xy 347.694615 -252.821082) (xy 347.654112 -252.849038) (xy 347.60965 -252.870136)
			(xy 347.562379 -252.883828) (xy 347.513524 -252.88976) (xy 347.464349 -252.887779) (xy 347.41613 -252.877935)
			(xy 347.370114 -252.860483) (xy 347.327493 -252.835876) (xy 347.289372 -252.804751) (xy 347.256737 -252.767914)
			(xy 347.230434 -252.726318) (xy 347.211143 -252.681042) (xy 347.199366 -252.633258) (xy 347.195406 -252.584204)
			(xy 345.92641 -252.584204) (xy 345.925915 -252.608811) (xy 345.91802 -252.657388) (xy 345.902436 -252.704069)
			(xy 345.879565 -252.747646) (xy 345.85 -252.78699) (xy 345.814507 -252.821082) (xy 345.774004 -252.849038)
			(xy 345.729542 -252.870136) (xy 345.682271 -252.883828) (xy 345.633416 -252.88976) (xy 345.584241 -252.887779)
			(xy 345.536022 -252.877935) (xy 345.490006 -252.860483) (xy 345.447385 -252.835876) (xy 345.409264 -252.804751)
			(xy 345.376629 -252.767914) (xy 345.350326 -252.726318) (xy 345.331035 -252.681042) (xy 345.319258 -252.633258)
			(xy 345.315298 -252.584204) (xy 344.056716 -252.584204) (xy 344.056204 -252.60965) (xy 344.04804 -252.659884)
			(xy 344.031924 -252.708158) (xy 344.008273 -252.753221) (xy 343.9777 -252.793907) (xy 343.940996 -252.829162)
			(xy 343.899112 -252.858072) (xy 343.853133 -252.879889) (xy 343.804249 -252.894049) (xy 343.753728 -252.900183)
			(xy 343.702876 -252.898134) (xy 343.653012 -252.887954) (xy 343.605426 -252.869907) (xy 343.561352 -252.844461)
			(xy 343.52193 -252.812274) (xy 343.488182 -252.77418) (xy 343.460981 -252.731166) (xy 343.441033 -252.684346)
			(xy 343.428854 -252.634932) (xy 343.424759 -252.584204) (xy 343.106502 -252.584204) (xy 343.106007 -252.608811)
			(xy 343.098112 -252.657388) (xy 343.082528 -252.704069) (xy 343.059657 -252.747646) (xy 343.030092 -252.78699)
			(xy 342.994599 -252.821082) (xy 342.954096 -252.849038) (xy 342.909634 -252.870136) (xy 342.862363 -252.883828)
			(xy 342.813508 -252.88976) (xy 342.764333 -252.887779) (xy 342.716114 -252.877935) (xy 342.670098 -252.860483)
			(xy 342.627477 -252.835876) (xy 342.589356 -252.804751) (xy 342.556721 -252.767914) (xy 342.530418 -252.726318)
			(xy 342.511127 -252.681042) (xy 342.49935 -252.633258) (xy 342.49539 -252.584204) (xy 342.176862 -252.584204)
			(xy 342.17635 -252.60965) (xy 342.168186 -252.659884) (xy 342.15207 -252.708158) (xy 342.128419 -252.753221)
			(xy 342.097846 -252.793907) (xy 342.061142 -252.829162) (xy 342.019258 -252.858072) (xy 341.973279 -252.879889)
			(xy 341.924395 -252.894049) (xy 341.873874 -252.900183) (xy 341.823022 -252.898134) (xy 341.773158 -252.887954)
			(xy 341.725572 -252.869907) (xy 341.681498 -252.844461) (xy 341.642076 -252.812274) (xy 341.608328 -252.77418)
			(xy 341.581127 -252.731166) (xy 341.561179 -252.684346) (xy 341.549 -252.634932) (xy 341.544905 -252.584204)
			(xy 341.225783 -252.584204) (xy 341.226232 -252.606213) (xy 341.222076 -252.63475) (xy 341.22233 -252.63475)
			(xy 341.21913 -252.652169) (xy 341.209202 -252.686167) (xy 341.202518 -252.702568) (xy 341.198454 -252.71222)
			(xy 341.198454 -252.998732) (xy 341.198971 -253.010178) (xy 341.208881 -253.030813) (xy 341.217504 -253.038356)
			(xy 341.287862 -253.09449) (xy 341.30996 -253.09957) (xy 341.321644 -253.096776) (xy 341.33874 -253.093076)
			(xy 341.373496 -253.089123) (xy 341.390986 -253.088902) (xy 341.416244 -253.089394) (xy 341.46607 -253.097706)
			(xy 341.513849 -253.114107) (xy 341.558277 -253.138148) (xy 341.598141 -253.169174) (xy 341.632355 -253.206338)
			(xy 341.659985 -253.248628) (xy 341.680277 -253.294888) (xy 341.692678 -253.343857) (xy 341.69685 -253.3942)
			(xy 341.696849 -253.39421) (xy 342.014805 -253.39421) (xy 342.0189 -253.343482) (xy 342.031079 -253.294068)
			(xy 342.051027 -253.247248) (xy 342.078228 -253.204234) (xy 342.111976 -253.16614) (xy 342.151398 -253.133953)
			(xy 342.195472 -253.108507) (xy 342.243058 -253.09046) (xy 342.292922 -253.08028) (xy 342.343774 -253.078231)
			(xy 342.394295 -253.084365) (xy 342.443179 -253.098525) (xy 342.489158 -253.120342) (xy 342.531042 -253.149252)
			(xy 342.567746 -253.184507) (xy 342.598319 -253.225193) (xy 342.62197 -253.270256) (xy 342.638086 -253.31853)
			(xy 342.64625 -253.368764) (xy 342.646762 -253.39421) (xy 342.954859 -253.39421) (xy 342.958954 -253.343482)
			(xy 342.971133 -253.294068) (xy 342.991081 -253.247248) (xy 343.018282 -253.204234) (xy 343.05203 -253.16614)
			(xy 343.091452 -253.133953) (xy 343.135526 -253.108507) (xy 343.183112 -253.09046) (xy 343.232976 -253.08028)
			(xy 343.283828 -253.078231) (xy 343.334349 -253.084365) (xy 343.383233 -253.098525) (xy 343.429212 -253.120342)
			(xy 343.471096 -253.149252) (xy 343.5078 -253.184507) (xy 343.538373 -253.225193) (xy 343.562024 -253.270256)
			(xy 343.57814 -253.31853) (xy 343.586304 -253.368764) (xy 343.586816 -253.39421) (xy 343.905344 -253.39421)
			(xy 343.909304 -253.345156) (xy 343.921081 -253.297372) (xy 343.940372 -253.252096) (xy 343.966675 -253.2105)
			(xy 343.99931 -253.173663) (xy 344.037431 -253.142538) (xy 344.080052 -253.117931) (xy 344.126068 -253.100479)
			(xy 344.174287 -253.090635) (xy 344.223462 -253.088654) (xy 344.272317 -253.094586) (xy 344.319588 -253.108278)
			(xy 344.36405 -253.129376) (xy 344.404553 -253.157332) (xy 344.440046 -253.191424) (xy 344.469611 -253.230768)
			(xy 344.492482 -253.274345) (xy 344.508066 -253.321026) (xy 344.515961 -253.369603) (xy 344.516456 -253.39421)
			(xy 345.785198 -253.39421) (xy 345.789158 -253.345156) (xy 345.800935 -253.297372) (xy 345.820226 -253.252096)
			(xy 345.846529 -253.2105) (xy 345.879164 -253.173663) (xy 345.917285 -253.142538) (xy 345.959906 -253.117931)
			(xy 346.005922 -253.100479) (xy 346.054141 -253.090635) (xy 346.103316 -253.088654) (xy 346.152171 -253.094586)
			(xy 346.199442 -253.108278) (xy 346.243904 -253.129376) (xy 346.284407 -253.157332) (xy 346.3199 -253.191424)
			(xy 346.349465 -253.230768) (xy 346.372336 -253.274345) (xy 346.38792 -253.321026) (xy 346.395815 -253.369603)
			(xy 346.39631 -253.39421) (xy 347.665306 -253.39421) (xy 347.669266 -253.345156) (xy 347.681043 -253.297372)
			(xy 347.700334 -253.252096) (xy 347.726637 -253.2105) (xy 347.759272 -253.173663) (xy 347.797393 -253.142538)
			(xy 347.840014 -253.117931) (xy 347.88603 -253.100479) (xy 347.934249 -253.090635) (xy 347.983424 -253.088654)
			(xy 348.032279 -253.094586) (xy 348.07955 -253.108278) (xy 348.124012 -253.129376) (xy 348.164515 -253.157332)
			(xy 348.200008 -253.191424) (xy 348.229573 -253.230768) (xy 348.252444 -253.274345) (xy 348.268028 -253.321026)
			(xy 348.275923 -253.369603) (xy 348.276418 -253.39421) (xy 348.275923 -253.418817) (xy 348.268028 -253.467394)
			(xy 348.252444 -253.514075) (xy 348.229573 -253.557652) (xy 348.200008 -253.596996) (xy 348.164515 -253.631088)
			(xy 348.124012 -253.659044) (xy 348.07955 -253.680142) (xy 348.032279 -253.693834) (xy 347.983424 -253.699766)
			(xy 347.934249 -253.697785) (xy 347.88603 -253.687941) (xy 347.840014 -253.670489) (xy 347.797393 -253.645882)
			(xy 347.759272 -253.614757) (xy 347.726637 -253.57792) (xy 347.700334 -253.536324) (xy 347.681043 -253.491048)
			(xy 347.669266 -253.443264) (xy 347.665306 -253.39421) (xy 346.39631 -253.39421) (xy 346.395815 -253.418817)
			(xy 346.38792 -253.467394) (xy 346.372336 -253.514075) (xy 346.349465 -253.557652) (xy 346.3199 -253.596996)
			(xy 346.284407 -253.631088) (xy 346.243904 -253.659044) (xy 346.199442 -253.680142) (xy 346.152171 -253.693834)
			(xy 346.103316 -253.699766) (xy 346.054141 -253.697785) (xy 346.005922 -253.687941) (xy 345.959906 -253.670489)
			(xy 345.917285 -253.645882) (xy 345.879164 -253.614757) (xy 345.846529 -253.57792) (xy 345.820226 -253.536324)
			(xy 345.800935 -253.491048) (xy 345.789158 -253.443264) (xy 345.785198 -253.39421) (xy 344.516456 -253.39421)
			(xy 344.515961 -253.418817) (xy 344.508066 -253.467394) (xy 344.492482 -253.514075) (xy 344.469611 -253.557652)
			(xy 344.440046 -253.596996) (xy 344.404553 -253.631088) (xy 344.36405 -253.659044) (xy 344.319588 -253.680142)
			(xy 344.272317 -253.693834) (xy 344.223462 -253.699766) (xy 344.174287 -253.697785) (xy 344.126068 -253.687941)
			(xy 344.080052 -253.670489) (xy 344.037431 -253.645882) (xy 343.99931 -253.614757) (xy 343.966675 -253.57792)
			(xy 343.940372 -253.536324) (xy 343.921081 -253.491048) (xy 343.909304 -253.443264) (xy 343.905344 -253.39421)
			(xy 343.586816 -253.39421) (xy 343.586304 -253.419656) (xy 343.57814 -253.46989) (xy 343.562024 -253.518164)
			(xy 343.538373 -253.563227) (xy 343.5078 -253.603913) (xy 343.471096 -253.639168) (xy 343.429212 -253.668078)
			(xy 343.383233 -253.689895) (xy 343.334349 -253.704055) (xy 343.283828 -253.710189) (xy 343.232976 -253.70814)
			(xy 343.183112 -253.69796) (xy 343.135526 -253.679913) (xy 343.091452 -253.654467) (xy 343.05203 -253.62228)
			(xy 343.018282 -253.584186) (xy 342.991081 -253.541172) (xy 342.971133 -253.494352) (xy 342.958954 -253.444938)
			(xy 342.954859 -253.39421) (xy 342.646762 -253.39421) (xy 342.64625 -253.419656) (xy 342.638086 -253.46989)
			(xy 342.62197 -253.518164) (xy 342.598319 -253.563227) (xy 342.567746 -253.603913) (xy 342.531042 -253.639168)
			(xy 342.489158 -253.668078) (xy 342.443179 -253.689895) (xy 342.394295 -253.704055) (xy 342.343774 -253.710189)
			(xy 342.292922 -253.70814) (xy 342.243058 -253.69796) (xy 342.195472 -253.679913) (xy 342.151398 -253.654467)
			(xy 342.111976 -253.62228) (xy 342.078228 -253.584186) (xy 342.051027 -253.541172) (xy 342.031079 -253.494352)
			(xy 342.0189 -253.444938) (xy 342.014805 -253.39421) (xy 341.696849 -253.39421) (xy 341.692678 -253.444543)
			(xy 341.680277 -253.493512) (xy 341.659985 -253.539772) (xy 341.632355 -253.582062) (xy 341.598141 -253.619226)
			(xy 341.558277 -253.650252) (xy 341.513849 -253.674293) (xy 341.46607 -253.690694) (xy 341.416244 -253.699006)
			(xy 341.390986 -253.699518) (xy 341.373495 -253.699307) (xy 341.338736 -253.695363) (xy 341.321644 -253.691644)
			(xy 341.30996 -253.68885) (xy 341.287862 -253.69393) (xy 341.217504 -253.750064) (xy 341.208991 -253.757697)
			(xy 341.199095 -253.778273) (xy 341.198454 -253.789688) (xy 341.198454 -254.075946) (xy 341.202518 -254.085344)
			(xy 341.213077 -254.112178) (xy 341.225052 -254.168579) (xy 341.225778 -254.204216) (xy 341.544905 -254.204216)
			(xy 341.549 -254.153488) (xy 341.561179 -254.104074) (xy 341.581127 -254.057254) (xy 341.608328 -254.01424)
			(xy 341.642076 -253.976146) (xy 341.681498 -253.943959) (xy 341.725572 -253.918513) (xy 341.773158 -253.900466)
			(xy 341.823022 -253.890286) (xy 341.873874 -253.888237) (xy 341.924395 -253.894371) (xy 341.973279 -253.908531)
			(xy 342.019258 -253.930348) (xy 342.061142 -253.959258) (xy 342.097846 -253.994513) (xy 342.128419 -254.035199)
			(xy 342.15207 -254.080262) (xy 342.168186 -254.128536) (xy 342.17635 -254.17877) (xy 342.176862 -254.204216)
			(xy 342.49539 -254.204216) (xy 342.49935 -254.155162) (xy 342.511127 -254.107378) (xy 342.530418 -254.062102)
			(xy 342.556721 -254.020506) (xy 342.589356 -253.983669) (xy 342.627477 -253.952544) (xy 342.670098 -253.927937)
			(xy 342.716114 -253.910485) (xy 342.764333 -253.900641) (xy 342.813508 -253.89866) (xy 342.862363 -253.904592)
			(xy 342.909634 -253.918284) (xy 342.954096 -253.939382) (xy 342.994599 -253.967338) (xy 343.030092 -254.00143)
			(xy 343.059657 -254.040774) (xy 343.082528 -254.084351) (xy 343.098112 -254.131032) (xy 343.106007 -254.179609)
			(xy 343.106502 -254.204216) (xy 343.424759 -254.204216) (xy 343.428854 -254.153488) (xy 343.441033 -254.104074)
			(xy 343.460981 -254.057254) (xy 343.488182 -254.01424) (xy 343.52193 -253.976146) (xy 343.561352 -253.943959)
			(xy 343.605426 -253.918513) (xy 343.653012 -253.900466) (xy 343.702876 -253.890286) (xy 343.753728 -253.888237)
			(xy 343.804249 -253.894371) (xy 343.853133 -253.908531) (xy 343.899112 -253.930348) (xy 343.940996 -253.959258)
			(xy 343.9777 -253.994513) (xy 344.008273 -254.035199) (xy 344.031924 -254.080262) (xy 344.04804 -254.128536)
			(xy 344.056204 -254.17877) (xy 344.056716 -254.204216) (xy 345.315298 -254.204216) (xy 345.319258 -254.155162)
			(xy 345.331035 -254.107378) (xy 345.350326 -254.062102) (xy 345.376629 -254.020506) (xy 345.409264 -253.983669)
			(xy 345.447385 -253.952544) (xy 345.490006 -253.927937) (xy 345.536022 -253.910485) (xy 345.584241 -253.900641)
			(xy 345.633416 -253.89866) (xy 345.682271 -253.904592) (xy 345.729542 -253.918284) (xy 345.774004 -253.939382)
			(xy 345.814507 -253.967338) (xy 345.85 -254.00143) (xy 345.879565 -254.040774) (xy 345.902436 -254.084351)
			(xy 345.91802 -254.131032) (xy 345.925915 -254.179609) (xy 345.92641 -254.204216) (xy 347.195406 -254.204216)
			(xy 347.199366 -254.155162) (xy 347.211143 -254.107378) (xy 347.230434 -254.062102) (xy 347.256737 -254.020506)
			(xy 347.289372 -253.983669) (xy 347.327493 -253.952544) (xy 347.370114 -253.927937) (xy 347.41613 -253.910485)
			(xy 347.464349 -253.900641) (xy 347.513524 -253.89866) (xy 347.562379 -253.904592) (xy 347.60965 -253.918284)
			(xy 347.654112 -253.939382) (xy 347.694615 -253.967338) (xy 347.730108 -254.00143) (xy 347.759673 -254.040774)
			(xy 347.782544 -254.084351) (xy 347.798128 -254.131032) (xy 347.806023 -254.179609) (xy 347.806518 -254.204216)
			(xy 347.806023 -254.228823) (xy 347.798128 -254.2774) (xy 347.782544 -254.324081) (xy 347.759673 -254.367658)
			(xy 347.730108 -254.407002) (xy 347.694615 -254.441094) (xy 347.654112 -254.46905) (xy 347.60965 -254.490148)
			(xy 347.562379 -254.50384) (xy 347.513524 -254.509772) (xy 347.464349 -254.507791) (xy 347.41613 -254.497947)
			(xy 347.370114 -254.480495) (xy 347.327493 -254.455888) (xy 347.289372 -254.424763) (xy 347.256737 -254.387926)
			(xy 347.230434 -254.34633) (xy 347.211143 -254.301054) (xy 347.199366 -254.25327) (xy 347.195406 -254.204216)
			(xy 345.92641 -254.204216) (xy 345.925915 -254.228823) (xy 345.91802 -254.2774) (xy 345.902436 -254.324081)
			(xy 345.879565 -254.367658) (xy 345.85 -254.407002) (xy 345.814507 -254.441094) (xy 345.774004 -254.46905)
			(xy 345.729542 -254.490148) (xy 345.682271 -254.50384) (xy 345.633416 -254.509772) (xy 345.584241 -254.507791)
			(xy 345.536022 -254.497947) (xy 345.490006 -254.480495) (xy 345.447385 -254.455888) (xy 345.409264 -254.424763)
			(xy 345.376629 -254.387926) (xy 345.350326 -254.34633) (xy 345.331035 -254.301054) (xy 345.319258 -254.25327)
			(xy 345.315298 -254.204216) (xy 344.056716 -254.204216) (xy 344.056204 -254.229662) (xy 344.04804 -254.279896)
			(xy 344.031924 -254.32817) (xy 344.008273 -254.373233) (xy 343.9777 -254.413919) (xy 343.940996 -254.449174)
			(xy 343.899112 -254.478084) (xy 343.853133 -254.499901) (xy 343.804249 -254.514061) (xy 343.753728 -254.520195)
			(xy 343.702876 -254.518146) (xy 343.653012 -254.507966) (xy 343.605426 -254.489919) (xy 343.561352 -254.464473)
			(xy 343.52193 -254.432286) (xy 343.488182 -254.394192) (xy 343.460981 -254.351178) (xy 343.441033 -254.304358)
			(xy 343.428854 -254.254944) (xy 343.424759 -254.204216) (xy 343.106502 -254.204216) (xy 343.106007 -254.228823)
			(xy 343.098112 -254.2774) (xy 343.082528 -254.324081) (xy 343.059657 -254.367658) (xy 343.030092 -254.407002)
			(xy 342.994599 -254.441094) (xy 342.954096 -254.46905) (xy 342.909634 -254.490148) (xy 342.862363 -254.50384)
			(xy 342.813508 -254.509772) (xy 342.764333 -254.507791) (xy 342.716114 -254.497947) (xy 342.670098 -254.480495)
			(xy 342.627477 -254.455888) (xy 342.589356 -254.424763) (xy 342.556721 -254.387926) (xy 342.530418 -254.34633)
			(xy 342.511127 -254.301054) (xy 342.49935 -254.25327) (xy 342.49539 -254.204216) (xy 342.176862 -254.204216)
			(xy 342.17635 -254.229662) (xy 342.168186 -254.279896) (xy 342.15207 -254.32817) (xy 342.128419 -254.373233)
			(xy 342.097846 -254.413919) (xy 342.061142 -254.449174) (xy 342.019258 -254.478084) (xy 341.973279 -254.499901)
			(xy 341.924395 -254.514061) (xy 341.873874 -254.520195) (xy 341.823022 -254.518146) (xy 341.773158 -254.507966)
			(xy 341.725572 -254.489919) (xy 341.681498 -254.464473) (xy 341.642076 -254.432286) (xy 341.608328 -254.394192)
			(xy 341.581127 -254.351178) (xy 341.561179 -254.304358) (xy 341.549 -254.254944) (xy 341.544905 -254.204216)
			(xy 341.225778 -254.204216) (xy 341.226226 -254.226225) (xy 341.222076 -254.254762) (xy 341.22233 -254.254762)
			(xy 341.219129 -254.272181) (xy 341.2092 -254.306179) (xy 341.202518 -254.32258) (xy 341.198454 -254.332232)
			(xy 341.198454 -254.618744) (xy 341.198973 -254.630189) (xy 341.208886 -254.650819) (xy 341.217504 -254.658368)
			(xy 341.287862 -254.714502) (xy 341.30996 -254.719582) (xy 341.321644 -254.716788) (xy 341.33874 -254.713088)
			(xy 341.373496 -254.709137) (xy 341.390986 -254.708914) (xy 341.416243 -254.709405) (xy 341.466067 -254.717718)
			(xy 341.513844 -254.734118) (xy 341.55827 -254.758158) (xy 341.598133 -254.789183) (xy 341.632346 -254.826346)
			(xy 341.659974 -254.868633) (xy 341.680266 -254.914892) (xy 341.692667 -254.963859) (xy 341.696838 -255.0142)
			(xy 341.696836 -255.014222) (xy 342.014805 -255.014222) (xy 342.0189 -254.963494) (xy 342.031079 -254.91408)
			(xy 342.051027 -254.86726) (xy 342.078228 -254.824246) (xy 342.111976 -254.786152) (xy 342.151398 -254.753965)
			(xy 342.195472 -254.728519) (xy 342.243058 -254.710472) (xy 342.292922 -254.700292) (xy 342.343774 -254.698243)
			(xy 342.394295 -254.704377) (xy 342.443179 -254.718537) (xy 342.489158 -254.740354) (xy 342.531042 -254.769264)
			(xy 342.567746 -254.804519) (xy 342.598319 -254.845205) (xy 342.62197 -254.890268) (xy 342.638086 -254.938542)
			(xy 342.64625 -254.988776) (xy 342.646762 -255.014222) (xy 342.954859 -255.014222) (xy 342.958954 -254.963494)
			(xy 342.971133 -254.91408) (xy 342.991081 -254.86726) (xy 343.018282 -254.824246) (xy 343.05203 -254.786152)
			(xy 343.091452 -254.753965) (xy 343.135526 -254.728519) (xy 343.183112 -254.710472) (xy 343.232976 -254.700292)
			(xy 343.283828 -254.698243) (xy 343.334349 -254.704377) (xy 343.383233 -254.718537) (xy 343.429212 -254.740354)
			(xy 343.471096 -254.769264) (xy 343.5078 -254.804519) (xy 343.538373 -254.845205) (xy 343.562024 -254.890268)
			(xy 343.57814 -254.938542) (xy 343.586304 -254.988776) (xy 343.586816 -255.014222) (xy 343.905344 -255.014222)
			(xy 343.909304 -254.965168) (xy 343.921081 -254.917384) (xy 343.940372 -254.872108) (xy 343.966675 -254.830512)
			(xy 343.99931 -254.793675) (xy 344.037431 -254.76255) (xy 344.080052 -254.737943) (xy 344.126068 -254.720491)
			(xy 344.174287 -254.710647) (xy 344.223462 -254.708666) (xy 344.272317 -254.714598) (xy 344.319588 -254.72829)
			(xy 344.36405 -254.749388) (xy 344.404553 -254.777344) (xy 344.440046 -254.811436) (xy 344.469611 -254.85078)
			(xy 344.492482 -254.894357) (xy 344.508066 -254.941038) (xy 344.515961 -254.989615) (xy 344.516456 -255.014222)
			(xy 345.785198 -255.014222) (xy 345.789158 -254.965168) (xy 345.800935 -254.917384) (xy 345.820226 -254.872108)
			(xy 345.846529 -254.830512) (xy 345.879164 -254.793675) (xy 345.917285 -254.76255) (xy 345.959906 -254.737943)
			(xy 346.005922 -254.720491) (xy 346.054141 -254.710647) (xy 346.103316 -254.708666) (xy 346.152171 -254.714598)
			(xy 346.199442 -254.72829) (xy 346.243904 -254.749388) (xy 346.284407 -254.777344) (xy 346.3199 -254.811436)
			(xy 346.349465 -254.85078) (xy 346.372336 -254.894357) (xy 346.38792 -254.941038) (xy 346.395815 -254.989615)
			(xy 346.39631 -255.014222) (xy 347.665306 -255.014222) (xy 347.669266 -254.965168) (xy 347.681043 -254.917384)
			(xy 347.700334 -254.872108) (xy 347.726637 -254.830512) (xy 347.759272 -254.793675) (xy 347.797393 -254.76255)
			(xy 347.840014 -254.737943) (xy 347.88603 -254.720491) (xy 347.934249 -254.710647) (xy 347.983424 -254.708666)
			(xy 348.032279 -254.714598) (xy 348.07955 -254.72829) (xy 348.124012 -254.749388) (xy 348.164515 -254.777344)
			(xy 348.200008 -254.811436) (xy 348.229573 -254.85078) (xy 348.252444 -254.894357) (xy 348.268028 -254.941038)
			(xy 348.275923 -254.989615) (xy 348.276418 -255.014222) (xy 348.275923 -255.038829) (xy 348.268028 -255.087406)
			(xy 348.252444 -255.134087) (xy 348.229573 -255.177664) (xy 348.200008 -255.217008) (xy 348.164515 -255.2511)
			(xy 348.124012 -255.279056) (xy 348.07955 -255.300154) (xy 348.032279 -255.313846) (xy 347.983424 -255.319778)
			(xy 347.934249 -255.317797) (xy 347.88603 -255.307953) (xy 347.840014 -255.290501) (xy 347.797393 -255.265894)
			(xy 347.759272 -255.234769) (xy 347.726637 -255.197932) (xy 347.700334 -255.156336) (xy 347.681043 -255.11106)
			(xy 347.669266 -255.063276) (xy 347.665306 -255.014222) (xy 346.39631 -255.014222) (xy 346.395815 -255.038829)
			(xy 346.38792 -255.087406) (xy 346.372336 -255.134087) (xy 346.349465 -255.177664) (xy 346.3199 -255.217008)
			(xy 346.284407 -255.2511) (xy 346.243904 -255.279056) (xy 346.199442 -255.300154) (xy 346.152171 -255.313846)
			(xy 346.103316 -255.319778) (xy 346.054141 -255.317797) (xy 346.005922 -255.307953) (xy 345.959906 -255.290501)
			(xy 345.917285 -255.265894) (xy 345.879164 -255.234769) (xy 345.846529 -255.197932) (xy 345.820226 -255.156336)
			(xy 345.800935 -255.11106) (xy 345.789158 -255.063276) (xy 345.785198 -255.014222) (xy 344.516456 -255.014222)
			(xy 344.515961 -255.038829) (xy 344.508066 -255.087406) (xy 344.492482 -255.134087) (xy 344.469611 -255.177664)
			(xy 344.440046 -255.217008) (xy 344.404553 -255.2511) (xy 344.36405 -255.279056) (xy 344.319588 -255.300154)
			(xy 344.272317 -255.313846) (xy 344.223462 -255.319778) (xy 344.174287 -255.317797) (xy 344.126068 -255.307953)
			(xy 344.080052 -255.290501) (xy 344.037431 -255.265894) (xy 343.99931 -255.234769) (xy 343.966675 -255.197932)
			(xy 343.940372 -255.156336) (xy 343.921081 -255.11106) (xy 343.909304 -255.063276) (xy 343.905344 -255.014222)
			(xy 343.586816 -255.014222) (xy 343.586304 -255.039668) (xy 343.57814 -255.089902) (xy 343.562024 -255.138176)
			(xy 343.538373 -255.183239) (xy 343.5078 -255.223925) (xy 343.471096 -255.25918) (xy 343.429212 -255.28809)
			(xy 343.383233 -255.309907) (xy 343.334349 -255.324067) (xy 343.283828 -255.330201) (xy 343.232976 -255.328152)
			(xy 343.183112 -255.317972) (xy 343.135526 -255.299925) (xy 343.091452 -255.274479) (xy 343.05203 -255.242292)
			(xy 343.018282 -255.204198) (xy 342.991081 -255.161184) (xy 342.971133 -255.114364) (xy 342.958954 -255.06495)
			(xy 342.954859 -255.014222) (xy 342.646762 -255.014222) (xy 342.64625 -255.039668) (xy 342.638086 -255.089902)
			(xy 342.62197 -255.138176) (xy 342.598319 -255.183239) (xy 342.567746 -255.223925) (xy 342.531042 -255.25918)
			(xy 342.489158 -255.28809) (xy 342.443179 -255.309907) (xy 342.394295 -255.324067) (xy 342.343774 -255.330201)
			(xy 342.292922 -255.328152) (xy 342.243058 -255.317972) (xy 342.195472 -255.299925) (xy 342.151398 -255.274479)
			(xy 342.111976 -255.242292) (xy 342.078228 -255.204198) (xy 342.051027 -255.161184) (xy 342.031079 -255.114364)
			(xy 342.0189 -255.06495) (xy 342.014805 -255.014222) (xy 341.696836 -255.014222) (xy 341.692667 -255.064541)
			(xy 341.680266 -255.113508) (xy 341.659974 -255.159767) (xy 341.632346 -255.202054) (xy 341.598133 -255.239217)
			(xy 341.55827 -255.270242) (xy 341.513844 -255.294282) (xy 341.466067 -255.310682) (xy 341.416243 -255.318995)
			(xy 341.390986 -255.31953) (xy 341.373495 -255.319319) (xy 341.338736 -255.315375) (xy 341.321644 -255.311656)
			(xy 341.30996 -255.308862) (xy 341.287862 -255.313942) (xy 341.217504 -255.370076) (xy 341.208993 -255.377709)
			(xy 341.199101 -255.398286) (xy 341.198454 -255.4097) (xy 341.198454 -255.695958) (xy 341.202518 -255.705356)
			(xy 341.207679 -255.718154) (xy 341.215949 -255.744483) (xy 341.219028 -255.757934) (xy 341.221447 -255.769304)
			(xy 341.224755 -255.792316) (xy 341.225632 -255.803908) (xy 341.226394 -255.813306) (xy 341.23376 -255.829816)
			(xy 341.488268 -256.084324) (xy 341.495667 -256.091168) (xy 341.514266 -256.098889) (xy 341.524336 -256.09931)
		)
		(stroke
			(width 0)
			(type solid)
		)
		(fill yes)
		(layer "In4.Cu")
		(net "PVDD18_S5_P0")
	)
	(gr_poly
		(pts
			(xy 335.489296 -401.160488) (xy 335.499366 -401.160065) (xy 335.517971 -401.152351) (xy 335.525364 -401.145502)
			(xy 335.95945 -400.711416) (xy 335.966289 -400.704016) (xy 335.974001 -400.685417) (xy 335.974436 -400.675348)
			(xy 335.974436 -398.919446) (xy 335.974001 -398.909382) (xy 335.966266 -398.890797) (xy 335.95945 -398.883378)
			(xy 335.930748 -398.85493) (xy 335.91373 -398.847564) (xy 335.904078 -398.847056) (xy 335.879631 -398.845406)
			(xy 335.831691 -398.835293) (xy 335.785981 -398.817656) (xy 335.743672 -398.792947) (xy 335.705852 -398.7618)
			(xy 335.673489 -398.725015) (xy 335.647414 -398.683534) (xy 335.628296 -398.638423) (xy 335.616625 -398.590838)
			(xy 335.612702 -398.542) (xy 335.616625 -398.493162) (xy 335.628296 -398.445577) (xy 335.647414 -398.400466)
			(xy 335.673489 -398.358986) (xy 335.705851 -398.3222) (xy 335.743672 -398.291054) (xy 335.785981 -398.266345)
			(xy 335.831691 -398.248707) (xy 335.879631 -398.238594) (xy 335.904078 -398.236948) (xy 335.91373 -398.23644)
			(xy 335.930748 -398.229074) (xy 335.959196 -398.20088) (xy 335.96614 -398.193453) (xy 335.973991 -398.174717)
			(xy 335.974436 -398.164558) (xy 335.974436 -397.028924) (xy 335.956402 -397.003016) (xy 335.941162 -396.997428)
			(xy 335.919436 -396.989013) (xy 335.878623 -396.966545) (xy 335.841698 -396.938136) (xy 335.80952 -396.904444)
			(xy 335.782836 -396.866253) (xy 335.762267 -396.824451) (xy 335.74829 -396.780008) (xy 335.74123 -396.733957)
			(xy 335.740756 -396.710662) (xy 335.741255 -396.685264) (xy 335.749654 -396.635166) (xy 335.76623 -396.58715)
			(xy 335.790526 -396.54254) (xy 335.821871 -396.502568) (xy 335.840324 -396.48511) (xy 335.848183 -396.477335)
			(xy 335.856898 -396.457046) (xy 335.857088 -396.445994) (xy 335.854548 -396.35811) (xy 335.844896 -396.338552)
			(xy 335.83626 -396.33144) (xy 335.817701 -396.315636) (xy 335.784978 -396.279508) (xy 335.757908 -396.238971)
			(xy 335.737078 -396.194901) (xy 335.722938 -396.148253) (xy 335.715793 -396.100034) (xy 335.715356 -396.075662)
			(xy 335.715795 -396.051546) (xy 335.722799 -396.003825) (xy 335.736655 -395.957626) (xy 335.757069 -395.913926)
			(xy 335.769966 -395.893544) (xy 335.775808 -395.884908) (xy 335.779364 -395.864588) (xy 335.758282 -395.772132)
			(xy 335.74609 -395.755622) (xy 335.736946 -395.750288) (xy 335.71617 -395.737413) (xy 335.678306 -395.706507)
			(xy 335.645406 -395.670363) (xy 335.618185 -395.629769) (xy 335.597239 -395.585609) (xy 335.583023 -395.538846)
			(xy 335.575846 -395.4905) (xy 335.575402 -395.466062) (xy 335.575963 -395.438779) (xy 335.584924 -395.384955)
			(xy 335.602596 -395.333331) (xy 335.628501 -395.285307) (xy 335.661936 -395.242185) (xy 335.681574 -395.223238)
			(xy 335.687877 -395.217063) (xy 335.696078 -395.201453) (xy 335.697576 -395.192758) (xy 335.698084 -395.185646)
			(xy 335.698084 -395.111478) (xy 335.697576 -395.104366) (xy 335.695976 -395.095704) (xy 335.687804 -395.080112)
			(xy 335.681574 -395.073886) (xy 335.661917 -395.054954) (xy 335.628471 -395.011834) (xy 335.60256 -394.963808)
			(xy 335.584887 -394.912178) (xy 335.575932 -394.858347) (xy 335.575402 -394.831062) (xy 335.575402 -394.830808)
			(xy 335.575848 -394.807179) (xy 335.582613 -394.760406) (xy 335.595951 -394.715068) (xy 335.605374 -394.693394)
			(xy 335.609226 -394.684056) (xy 335.610014 -394.663887) (xy 335.606898 -394.654278) (xy 335.581752 -394.586968)
			(xy 335.577879 -394.57773) (xy 335.564266 -394.563056) (xy 335.555336 -394.55852) (xy 335.555082 -394.55852)
			(xy 335.530711 -394.546828) (xy 335.485823 -394.51672) (xy 335.446432 -394.47971) (xy 335.413586 -394.436785)
			(xy 335.388161 -394.389088) (xy 335.370835 -394.33789) (xy 335.362069 -394.284555) (xy 335.361534 -394.25753)
			(xy 335.362015 -394.23154) (xy 335.370143 -394.180201) (xy 335.386203 -394.130765) (xy 335.4098 -394.08445)
			(xy 335.440352 -394.042398) (xy 335.477108 -394.005644) (xy 335.519161 -393.975093) (xy 335.565476 -393.951498)
			(xy 335.614912 -393.93544) (xy 335.666252 -393.927314) (xy 335.692242 -393.926822) (xy 335.71601 -393.927236)
			(xy 335.763055 -393.934045) (xy 335.808642 -393.947515) (xy 335.830418 -393.957048) (xy 335.842102 -393.962382)
			(xy 335.86801 -393.960604) (xy 335.951068 -393.907518) (xy 335.958028 -393.902663) (xy 335.968521 -393.889338)
			(xy 335.974112 -393.873325) (xy 335.974436 -393.864846) (xy 335.974436 -393.679426) (xy 335.974725 -393.671081)
			(xy 335.980039 -393.655263) (xy 335.98485 -393.648438) (xy 335.98866 -393.643866) (xy 335.993232 -393.633452)
			(xy 335.994756 -393.626086) (xy 336.000285 -393.601532) (xy 336.017769 -393.554337) (xy 336.042192 -393.510332)
			(xy 336.072994 -393.470529) (xy 336.109464 -393.435846) (xy 336.150763 -393.407081) (xy 336.195939 -393.384897)
			(xy 336.243952 -393.369806) (xy 336.293696 -393.362153) (xy 336.31886 -393.361672) (xy 336.342677 -393.362085)
			(xy 336.389819 -393.368915) (xy 336.435492 -393.382439) (xy 336.478752 -393.402378) (xy 336.498946 -393.415012)
			(xy 336.505226 -393.418807) (xy 336.519297 -393.422942) (xy 336.526632 -393.42314) (xy 336.901028 -393.42314)
			(xy 336.911257 -393.42266) (xy 336.93009 -393.414662) (xy 336.944335 -393.399975) (xy 336.948526 -393.390628)
			(xy 336.982562 -393.301728) (xy 336.985739 -393.292069) (xy 336.985023 -393.271765) (xy 336.976527 -393.253309)
			(xy 336.969354 -393.246102) (xy 336.9691 -393.245848) (xy 336.948785 -393.226883) (xy 336.914175 -393.183405)
			(xy 336.887323 -393.134751) (xy 336.868983 -393.082293) (xy 336.859671 -393.027508) (xy 336.859118 -392.999722)
			(xy 336.859628 -392.973735) (xy 336.867758 -392.9224) (xy 336.883819 -392.87297) (xy 336.907415 -392.82666)
			(xy 336.937965 -392.784612) (xy 336.974716 -392.747861) (xy 337.016764 -392.717311) (xy 337.063074 -392.693715)
			(xy 337.112504 -392.677654) (xy 337.163839 -392.669524) (xy 337.215813 -392.669524) (xy 337.267148 -392.677654)
			(xy 337.316578 -392.693715) (xy 337.362888 -392.717311) (xy 337.404936 -392.747861) (xy 337.441687 -392.784612)
			(xy 337.472237 -392.82666) (xy 337.495833 -392.87297) (xy 337.511894 -392.9224) (xy 337.520024 -392.973735)
			(xy 337.520534 -392.999722) (xy 337.520089 -393.024618) (xy 337.512637 -393.073849) (xy 337.497889 -393.121407)
			(xy 337.476179 -393.166216) (xy 337.447996 -393.207265) (xy 337.413979 -393.243625) (xy 337.374896 -393.274475)
			(xy 337.33163 -393.299118) (xy 337.285158 -393.316997) (xy 337.260946 -393.32281) (xy 337.24342 -393.32662)
			(xy 337.221068 -393.354306) (xy 337.221068 -393.37234) (xy 337.221562 -393.382345) (xy 337.229228 -393.400828)
			(xy 337.243378 -393.414977) (xy 337.261863 -393.422639) (xy 337.271868 -393.42314) (xy 337.318604 -393.42314)
			(xy 337.332574 -393.419076) (xy 337.33867 -393.415012) (xy 337.361803 -393.400653) (xy 337.411704 -393.378885)
			(xy 337.464497 -393.365585) (xy 337.518756 -393.361112) (xy 337.573015 -393.365585) (xy 337.625808 -393.378885)
			(xy 337.675709 -393.400653) (xy 337.698842 -393.415012) (xy 337.705122 -393.418807) (xy 337.719193 -393.422943)
			(xy 337.726528 -393.42314) (xy 338.101178 -393.42314) (xy 338.111413 -393.422669) (xy 338.130262 -393.414682)
			(xy 338.144522 -393.399995) (xy 338.148676 -393.390628) (xy 338.182712 -393.301728) (xy 338.18589 -393.29207)
			(xy 338.185174 -393.271766) (xy 338.176672 -393.253315) (xy 338.169504 -393.246102) (xy 338.16925 -393.245848)
			(xy 338.148932 -393.226885) (xy 338.114318 -393.183408) (xy 338.087461 -393.134755) (xy 338.069118 -393.082296)
			(xy 338.059805 -393.027508) (xy 338.059268 -392.999722) (xy 338.059778 -392.973735) (xy 338.067908 -392.9224)
			(xy 338.083969 -392.87297) (xy 338.107565 -392.82666) (xy 338.138115 -392.784612) (xy 338.174866 -392.747861)
			(xy 338.216914 -392.717311) (xy 338.263224 -392.693715) (xy 338.312654 -392.677654) (xy 338.363989 -392.669524)
			(xy 338.415963 -392.669524) (xy 338.467298 -392.677654) (xy 338.516728 -392.693715) (xy 338.563038 -392.717311)
			(xy 338.605086 -392.747861) (xy 338.641837 -392.784612) (xy 338.672387 -392.82666) (xy 338.695983 -392.87297)
			(xy 338.712044 -392.9224) (xy 338.720174 -392.973735) (xy 338.720684 -392.999722) (xy 338.720239 -393.024619)
			(xy 338.712788 -393.073852) (xy 338.69804 -393.121412) (xy 338.676331 -393.166225) (xy 338.648151 -393.207277)
			(xy 338.614135 -393.243642) (xy 338.575053 -393.274497) (xy 338.531788 -393.299146) (xy 338.485317 -393.317031)
			(xy 338.461096 -393.32281) (xy 338.44357 -393.32662) (xy 338.421218 -393.354306) (xy 338.421218 -393.37234)
			(xy 338.421713 -393.382341) (xy 338.42938 -393.400816) (xy 338.443533 -393.414952) (xy 338.462016 -393.422598)
			(xy 338.472018 -393.42314) (xy 338.518754 -393.42314) (xy 338.532724 -393.419076) (xy 338.53882 -393.415012)
			(xy 338.561953 -393.400653) (xy 338.611854 -393.378885) (xy 338.664647 -393.365585) (xy 338.718906 -393.361112)
			(xy 338.773165 -393.365585) (xy 338.825958 -393.378885) (xy 338.875859 -393.400653) (xy 338.898992 -393.415012)
			(xy 338.905273 -393.418801) (xy 338.919345 -393.422923) (xy 338.926678 -393.42314) (xy 339.301074 -393.42314)
			(xy 339.311309 -393.42267) (xy 339.330159 -393.414683) (xy 339.344421 -393.399996) (xy 339.348572 -393.390628)
			(xy 339.382608 -393.301728) (xy 339.385786 -393.29207) (xy 339.38507 -393.271766) (xy 339.376568 -393.253315)
			(xy 339.3694 -393.246102) (xy 339.369146 -393.245848) (xy 339.348828 -393.226885) (xy 339.314214 -393.183407)
			(xy 339.287358 -393.134755) (xy 339.269015 -393.082296) (xy 339.259702 -393.027508) (xy 339.259164 -392.999722)
			(xy 339.259674 -392.973735) (xy 339.267804 -392.9224) (xy 339.283865 -392.87297) (xy 339.307461 -392.82666)
			(xy 339.338011 -392.784612) (xy 339.374762 -392.747861) (xy 339.41681 -392.717311) (xy 339.46312 -392.693715)
			(xy 339.51255 -392.677654) (xy 339.563885 -392.669524) (xy 339.615859 -392.669524) (xy 339.667194 -392.677654)
			(xy 339.716624 -392.693715) (xy 339.762934 -392.717311) (xy 339.804982 -392.747861) (xy 339.841733 -392.784612)
			(xy 339.872283 -392.82666) (xy 339.895879 -392.87297) (xy 339.91194 -392.9224) (xy 339.92007 -392.973735)
			(xy 339.92058 -392.999722) (xy 339.920135 -393.024619) (xy 339.912684 -393.073852) (xy 339.897936 -393.121412)
			(xy 339.876227 -393.166224) (xy 339.848046 -393.207276) (xy 339.814031 -393.24364) (xy 339.774949 -393.274495)
			(xy 339.731683 -393.299144) (xy 339.685212 -393.317029) (xy 339.660992 -393.32281) (xy 339.643466 -393.32662)
			(xy 339.621114 -393.354306) (xy 339.621114 -393.37234) (xy 339.621609 -393.382341) (xy 339.629276 -393.400817)
			(xy 339.643428 -393.414954) (xy 339.661912 -393.422602) (xy 339.671914 -393.42314) (xy 339.71865 -393.42314)
			(xy 339.73262 -393.419076) (xy 339.738716 -393.415012) (xy 339.761849 -393.400653) (xy 339.81175 -393.378885)
			(xy 339.864543 -393.365585) (xy 339.918802 -393.361112) (xy 339.973061 -393.365585) (xy 340.025854 -393.378885)
			(xy 340.075755 -393.400653) (xy 340.098888 -393.415012) (xy 340.105169 -393.418801) (xy 340.119241 -393.422924)
			(xy 340.126574 -393.42314) (xy 340.501224 -393.42314) (xy 340.511454 -393.422661) (xy 340.530288 -393.414664)
			(xy 340.544534 -393.399976) (xy 340.548722 -393.390628) (xy 340.582758 -393.301728) (xy 340.585934 -393.292069)
			(xy 340.585219 -393.271765) (xy 340.576723 -393.25331) (xy 340.56955 -393.246102) (xy 340.569296 -393.245848)
			(xy 340.548981 -393.226883) (xy 340.514372 -393.183404) (xy 340.48752 -393.134751) (xy 340.46918 -393.082293)
			(xy 340.459868 -393.027507) (xy 340.459314 -392.999722) (xy 340.459824 -392.973735) (xy 340.467954 -392.9224)
			(xy 340.484015 -392.87297) (xy 340.507611 -392.82666) (xy 340.538161 -392.784612) (xy 340.574912 -392.747861)
			(xy 340.61696 -392.717311) (xy 340.66327 -392.693715) (xy 340.7127 -392.677654) (xy 340.764035 -392.669524)
			(xy 340.816009 -392.669524) (xy 340.867344 -392.677654) (xy 340.916774 -392.693715) (xy 340.963084 -392.717311)
			(xy 341.005132 -392.747861) (xy 341.041883 -392.784612) (xy 341.072433 -392.82666) (xy 341.096029 -392.87297)
			(xy 341.11209 -392.9224) (xy 341.12022 -392.973735) (xy 341.12073 -392.999722) (xy 341.120285 -393.024618)
			(xy 341.112833 -393.073849) (xy 341.098085 -393.121406) (xy 341.076374 -393.166216) (xy 341.048192 -393.207264)
			(xy 341.014175 -393.243624) (xy 340.975091 -393.274474) (xy 340.931825 -393.299116) (xy 340.885354 -393.316994)
			(xy 340.861142 -393.32281) (xy 340.843616 -393.32662) (xy 340.821264 -393.354306) (xy 340.821264 -393.37234)
			(xy 340.821758 -393.382345) (xy 340.829424 -393.400829) (xy 340.843574 -393.414978) (xy 340.862059 -393.422642)
			(xy 340.872064 -393.42314) (xy 340.918546 -393.42314) (xy 340.932516 -393.419076) (xy 340.938612 -393.415012)
			(xy 340.961745 -393.400653) (xy 341.011646 -393.378885) (xy 341.064439 -393.365585) (xy 341.118698 -393.361112)
			(xy 341.172957 -393.365585) (xy 341.22575 -393.378885) (xy 341.275651 -393.400653) (xy 341.298784 -393.415012)
			(xy 341.305065 -393.418802) (xy 341.319137 -393.422926) (xy 341.32647 -393.42314) (xy 341.70112 -393.42314)
			(xy 341.71135 -393.422662) (xy 341.730185 -393.414665) (xy 341.744433 -393.399978) (xy 341.748618 -393.390628)
			(xy 341.782654 -393.301728) (xy 341.785831 -393.292069) (xy 341.785115 -393.271765) (xy 341.776618 -393.25331)
			(xy 341.769446 -393.246102) (xy 341.769192 -393.245848) (xy 341.748877 -393.226883) (xy 341.714269 -393.183404)
			(xy 341.687417 -393.134751) (xy 341.669077 -393.082293) (xy 341.659766 -393.027507) (xy 341.65921 -392.999722)
			(xy 341.65972 -392.973735) (xy 341.66785 -392.9224) (xy 341.683911 -392.87297) (xy 341.707507 -392.82666)
			(xy 341.738057 -392.784612) (xy 341.774808 -392.747861) (xy 341.816856 -392.717311) (xy 341.863166 -392.693715)
			(xy 341.912596 -392.677654) (xy 341.963931 -392.669524) (xy 342.015905 -392.669524) (xy 342.06724 -392.677654)
			(xy 342.11667 -392.693715) (xy 342.16298 -392.717311) (xy 342.205028 -392.747861) (xy 342.241779 -392.784612)
			(xy 342.272329 -392.82666) (xy 342.295925 -392.87297) (xy 342.311986 -392.9224) (xy 342.320116 -392.973735)
			(xy 342.320626 -392.999722) (xy 342.320181 -393.024618) (xy 342.312729 -393.073849) (xy 342.297981 -393.121406)
			(xy 342.27627 -393.166215) (xy 342.248088 -393.207263) (xy 342.21407 -393.243623) (xy 342.174987 -393.274472)
			(xy 342.13172 -393.299114) (xy 342.085249 -393.316991) (xy 342.061038 -393.32281) (xy 342.043512 -393.32662)
			(xy 342.02116 -393.354306) (xy 342.02116 -393.37234) (xy 342.021654 -393.382345) (xy 342.02932 -393.40083)
			(xy 342.04347 -393.41498) (xy 342.061955 -393.422646) (xy 342.07196 -393.42314) (xy 342.118696 -393.42314)
			(xy 342.132666 -393.419076) (xy 342.138762 -393.415012) (xy 342.161895 -393.400653) (xy 342.211796 -393.378885)
			(xy 342.264589 -393.365585) (xy 342.318848 -393.361112) (xy 342.373107 -393.365585) (xy 342.4259 -393.378885)
			(xy 342.475801 -393.400653) (xy 342.498934 -393.415012) (xy 342.505214 -393.418808) (xy 342.519285 -393.422946)
			(xy 342.52662 -393.42314) (xy 342.901016 -393.42314) (xy 342.911247 -393.422662) (xy 342.930083 -393.414667)
			(xy 342.944332 -393.39998) (xy 342.948514 -393.390628) (xy 342.98255 -393.301728) (xy 342.985727 -393.292069)
			(xy 342.985011 -393.271765) (xy 342.976514 -393.25331) (xy 342.969342 -393.246102) (xy 342.969088 -393.245848)
			(xy 342.948773 -393.226883) (xy 342.914165 -393.183404) (xy 342.887314 -393.134751) (xy 342.868974 -393.082293)
			(xy 342.859663 -393.027507) (xy 342.859106 -392.999722) (xy 342.859616 -392.973735) (xy 342.867746 -392.9224)
			(xy 342.883807 -392.87297) (xy 342.907403 -392.82666) (xy 342.937953 -392.784612) (xy 342.974704 -392.747861)
			(xy 343.016752 -392.717311) (xy 343.063062 -392.693715) (xy 343.112492 -392.677654) (xy 343.163827 -392.669524)
			(xy 343.215801 -392.669524) (xy 343.267136 -392.677654) (xy 343.316566 -392.693715) (xy 343.362876 -392.717311)
			(xy 343.404924 -392.747861) (xy 343.441675 -392.784612) (xy 343.472225 -392.82666) (xy 343.495821 -392.87297)
			(xy 343.511882 -392.9224) (xy 343.520012 -392.973735) (xy 343.520522 -392.999722) (xy 343.520077 -393.024618)
			(xy 343.512625 -393.073848) (xy 343.497877 -393.121405) (xy 343.476166 -393.166214) (xy 343.447983 -393.207262)
			(xy 343.413966 -393.243621) (xy 343.374882 -393.27447) (xy 343.331616 -393.299112) (xy 343.285144 -393.316989)
			(xy 343.260934 -393.32281) (xy 343.243408 -393.32662) (xy 343.221056 -393.354306) (xy 343.221056 -393.37234)
			(xy 343.22155 -393.382346) (xy 343.229215 -393.400831) (xy 343.243365 -393.414982) (xy 343.26185 -393.422649)
			(xy 343.271856 -393.42314) (xy 343.318592 -393.42314) (xy 343.332562 -393.419076) (xy 343.338658 -393.415012)
			(xy 343.361791 -393.400653) (xy 343.411692 -393.378885) (xy 343.464485 -393.365585) (xy 343.518744 -393.361112)
			(xy 343.573003 -393.365585) (xy 343.625796 -393.378885) (xy 343.675697 -393.400653) (xy 343.69883 -393.415012)
			(xy 343.70511 -393.418809) (xy 343.719181 -393.422948) (xy 343.726516 -393.42314) (xy 344.101166 -393.42314)
			(xy 344.111402 -393.422671) (xy 344.130255 -393.414686) (xy 344.144519 -393.4) (xy 344.148664 -393.390628)
			(xy 344.1827 -393.301728) (xy 344.185879 -393.29207) (xy 344.185163 -393.271767) (xy 344.176659 -393.253316)
			(xy 344.169492 -393.246102) (xy 344.169238 -393.245848) (xy 344.148921 -393.226884) (xy 344.114308 -393.183407)
			(xy 344.087452 -393.134754) (xy 344.069109 -393.082295) (xy 344.059797 -393.027508) (xy 344.059256 -392.999722)
			(xy 344.059766 -392.973735) (xy 344.067896 -392.9224) (xy 344.083957 -392.87297) (xy 344.107553 -392.82666)
			(xy 344.138103 -392.784612) (xy 344.174854 -392.747861) (xy 344.216902 -392.717311) (xy 344.263212 -392.693715)
			(xy 344.312642 -392.677654) (xy 344.363977 -392.669524) (xy 344.415951 -392.669524) (xy 344.467286 -392.677654)
			(xy 344.516716 -392.693715) (xy 344.563026 -392.717311) (xy 344.605074 -392.747861) (xy 344.641825 -392.784612)
			(xy 344.672375 -392.82666) (xy 344.695971 -392.87297) (xy 344.712032 -392.9224) (xy 344.720162 -392.973735)
			(xy 344.720672 -392.999722) (xy 344.720227 -393.024619) (xy 344.712775 -393.073852) (xy 344.698028 -393.121411)
			(xy 344.676319 -393.166223) (xy 344.648138 -393.207274) (xy 344.614122 -393.243638) (xy 344.575039 -393.274492)
			(xy 344.531774 -393.299139) (xy 344.485303 -393.317023) (xy 344.461084 -393.32281) (xy 344.443558 -393.32662)
			(xy 344.421206 -393.354306) (xy 344.421206 -393.37234) (xy 344.421701 -393.382342) (xy 344.429368 -393.400819)
			(xy 344.44352 -393.414958) (xy 344.462004 -393.422608) (xy 344.472006 -393.42314) (xy 344.518742 -393.42314)
			(xy 344.532712 -393.419076) (xy 344.538808 -393.415012) (xy 344.561941 -393.400653) (xy 344.611842 -393.378885)
			(xy 344.664635 -393.365585) (xy 344.718894 -393.361112) (xy 344.773153 -393.365585) (xy 344.825946 -393.378885)
			(xy 344.875847 -393.400653) (xy 344.89898 -393.415012) (xy 344.905261 -393.418802) (xy 344.919332 -393.422928)
			(xy 344.926666 -393.42314) (xy 345.301062 -393.42314) (xy 345.311299 -393.422672) (xy 345.330152 -393.414688)
			(xy 345.344418 -393.400001) (xy 345.34856 -393.390628) (xy 345.382596 -393.301728) (xy 345.385775 -393.29207)
			(xy 345.385059 -393.271767) (xy 345.376555 -393.253316) (xy 345.369388 -393.246102) (xy 345.369134 -393.245848)
			(xy 345.348817 -393.226884) (xy 345.314204 -393.183407) (xy 345.287349 -393.134754) (xy 345.269006 -393.082295)
			(xy 345.259694 -393.027508) (xy 345.259152 -392.999722) (xy 345.259662 -392.973735) (xy 345.267792 -392.9224)
			(xy 345.283853 -392.87297) (xy 345.307449 -392.82666) (xy 345.337999 -392.784612) (xy 345.37475 -392.747861)
			(xy 345.416798 -392.717311) (xy 345.463108 -392.693715) (xy 345.512538 -392.677654) (xy 345.563873 -392.669524)
			(xy 345.615847 -392.669524) (xy 345.667182 -392.677654) (xy 345.716612 -392.693715) (xy 345.762922 -392.717311)
			(xy 345.80497 -392.747861) (xy 345.841721 -392.784612) (xy 345.872271 -392.82666) (xy 345.895867 -392.87297)
			(xy 345.911928 -392.9224) (xy 345.920058 -392.973735) (xy 345.920568 -392.999722) (xy 345.920123 -393.024619)
			(xy 345.912671 -393.073851) (xy 345.897924 -393.121411) (xy 345.876214 -393.166222) (xy 345.848033 -393.207273)
			(xy 345.814017 -393.243636) (xy 345.774935 -393.27449) (xy 345.731669 -393.299137) (xy 345.685198 -393.31702)
			(xy 345.66098 -393.32281) (xy 345.643454 -393.32662) (xy 345.621102 -393.354306) (xy 345.621102 -393.37234)
			(xy 345.621597 -393.382342) (xy 345.629264 -393.40082) (xy 345.643415 -393.41496) (xy 345.661899 -393.422611)
			(xy 345.671902 -393.42314) (xy 345.718638 -393.42314) (xy 345.732608 -393.419076) (xy 345.738704 -393.415012)
			(xy 345.761837 -393.400653) (xy 345.811738 -393.378885) (xy 345.864531 -393.365585) (xy 345.91879 -393.361112)
			(xy 345.973049 -393.365585) (xy 346.025842 -393.378885) (xy 346.075743 -393.400653) (xy 346.098876 -393.415012)
			(xy 346.105157 -393.418803) (xy 346.119228 -393.422929) (xy 346.126562 -393.42314) (xy 346.501212 -393.42314)
			(xy 346.511443 -393.422663) (xy 346.530281 -393.414669) (xy 346.544531 -393.399981) (xy 346.54871 -393.390628)
			(xy 346.582746 -393.301728) (xy 346.585923 -393.292069) (xy 346.585207 -393.271765) (xy 346.57671 -393.253311)
			(xy 346.569538 -393.246102) (xy 346.569284 -393.245848) (xy 346.54897 -393.226883) (xy 346.514362 -393.183404)
			(xy 346.487511 -393.13475) (xy 346.469171 -393.082293) (xy 346.45986 -393.027507) (xy 346.459302 -392.999722)
			(xy 346.459812 -392.973735) (xy 346.467942 -392.9224) (xy 346.484003 -392.87297) (xy 346.507599 -392.82666)
			(xy 346.538149 -392.784612) (xy 346.5749 -392.747861) (xy 346.616948 -392.717311) (xy 346.663258 -392.693715)
			(xy 346.712688 -392.677654) (xy 346.764023 -392.669524) (xy 346.815997 -392.669524) (xy 346.867332 -392.677654)
			(xy 346.916762 -392.693715) (xy 346.963072 -392.717311) (xy 347.00512 -392.747861) (xy 347.041871 -392.784612)
			(xy 347.072421 -392.82666) (xy 347.096017 -392.87297) (xy 347.112078 -392.9224) (xy 347.120208 -392.973735)
			(xy 347.120718 -392.999722) (xy 347.120274 -393.02462) (xy 347.112822 -393.073855) (xy 347.098076 -393.121417)
			(xy 347.076368 -393.166231) (xy 347.048188 -393.207286) (xy 347.014173 -393.243653) (xy 346.975092 -393.274512)
			(xy 346.931828 -393.299165) (xy 346.885357 -393.317055) (xy 346.86113 -393.32281) (xy 346.843604 -393.32662)
			(xy 346.821252 -393.354306) (xy 346.821252 -393.37234) (xy 346.821746 -393.382346) (xy 346.829411 -393.400832)
			(xy 346.843561 -393.414984) (xy 346.862046 -393.422652) (xy 346.872052 -393.42314) (xy 346.918534 -393.42314)
			(xy 346.932504 -393.419076) (xy 346.9386 -393.415012) (xy 346.961733 -393.400653) (xy 347.011634 -393.378885)
			(xy 347.064427 -393.365585) (xy 347.118686 -393.361112) (xy 347.172945 -393.365585) (xy 347.225738 -393.378885)
			(xy 347.275639 -393.400653) (xy 347.298772 -393.415012) (xy 347.305053 -393.418803) (xy 347.319124 -393.422931)
			(xy 347.326458 -393.42314) (xy 347.701108 -393.42314) (xy 347.711339 -393.422664) (xy 347.730179 -393.41467)
			(xy 347.74443 -393.399983) (xy 347.748606 -393.390628) (xy 347.782642 -393.301728) (xy 347.785819 -393.292069)
			(xy 347.785103 -393.271765) (xy 347.776605 -393.253311) (xy 347.769434 -393.246102) (xy 347.76918 -393.245848)
			(xy 347.748866 -393.226883) (xy 347.714259 -393.183403) (xy 347.687408 -393.13475) (xy 347.669069 -393.082292)
			(xy 347.659758 -393.027507) (xy 347.659198 -392.999722) (xy 347.659708 -392.973735) (xy 347.667838 -392.9224)
			(xy 347.683899 -392.87297) (xy 347.707495 -392.82666) (xy 347.738045 -392.784612) (xy 347.774796 -392.747861)
			(xy 347.816844 -392.717311) (xy 347.863154 -392.693715) (xy 347.912584 -392.677654) (xy 347.963919 -392.669524)
			(xy 348.015893 -392.669524) (xy 348.067228 -392.677654) (xy 348.116658 -392.693715) (xy 348.162968 -392.717311)
			(xy 348.205016 -392.747861) (xy 348.241767 -392.784612) (xy 348.272317 -392.82666) (xy 348.295913 -392.87297)
			(xy 348.311974 -392.9224) (xy 348.320104 -392.973735) (xy 348.320614 -392.999722) (xy 348.32017 -393.02462)
			(xy 348.312718 -393.073854) (xy 348.297972 -393.121416) (xy 348.276263 -393.16623) (xy 348.248084 -393.207285)
			(xy 348.214069 -393.243652) (xy 348.174988 -393.274511) (xy 348.131723 -393.299163) (xy 348.085252 -393.317053)
			(xy 348.061026 -393.32281) (xy 348.0435 -393.32662) (xy 348.021148 -393.354306) (xy 348.021148 -393.37234)
			(xy 348.021575 -393.382352) (xy 348.029254 -393.400847) (xy 348.043426 -393.414995) (xy 348.061935 -393.422642)
			(xy 348.071948 -393.42314) (xy 348.118684 -393.42314) (xy 348.132654 -393.419076) (xy 348.13875 -393.415012)
			(xy 348.161883 -393.400653) (xy 348.211784 -393.378885) (xy 348.264577 -393.365585) (xy 348.318836 -393.361112)
			(xy 348.373095 -393.365585) (xy 348.425888 -393.378885) (xy 348.475789 -393.400653) (xy 348.498922 -393.415012)
			(xy 348.505201 -393.41881) (xy 348.519273 -393.422951) (xy 348.526608 -393.42314) (xy 348.901004 -393.42314)
			(xy 348.911236 -393.422665) (xy 348.930076 -393.414672) (xy 348.944329 -393.399984) (xy 348.948502 -393.390628)
			(xy 348.982538 -393.301728) (xy 348.985715 -393.292069) (xy 348.984999 -393.271765) (xy 348.976501 -393.253312)
			(xy 348.96933 -393.246102) (xy 348.969076 -393.245848) (xy 348.948757 -393.226886) (xy 348.91414 -393.183409)
			(xy 348.887281 -393.134757) (xy 348.868936 -393.082297) (xy 348.859622 -393.027509) (xy 348.859094 -392.999722)
			(xy 348.859604 -392.973735) (xy 348.867734 -392.9224) (xy 348.883795 -392.87297) (xy 348.907391 -392.82666)
			(xy 348.937941 -392.784612) (xy 348.974692 -392.747861) (xy 349.01674 -392.717311) (xy 349.06305 -392.693715)
			(xy 349.11248 -392.677654) (xy 349.163815 -392.669524) (xy 349.215789 -392.669524) (xy 349.267124 -392.677654)
			(xy 349.316554 -392.693715) (xy 349.362864 -392.717311) (xy 349.404912 -392.747861) (xy 349.441663 -392.784612)
			(xy 349.472213 -392.82666) (xy 349.495809 -392.87297) (xy 349.51187 -392.9224) (xy 349.52 -392.973735)
			(xy 349.52051 -392.999722) (xy 349.520066 -393.02462) (xy 349.512614 -393.073854) (xy 349.497868 -393.121416)
			(xy 349.476159 -393.16623) (xy 349.447979 -393.207284) (xy 349.413964 -393.243651) (xy 349.374883 -393.274509)
			(xy 349.331618 -393.299161) (xy 349.285148 -393.31705) (xy 349.260922 -393.32281) (xy 349.243396 -393.32662)
			(xy 349.221044 -393.354306) (xy 349.221044 -393.37234) (xy 349.221471 -393.382353) (xy 349.22915 -393.400848)
			(xy 349.243322 -393.414997) (xy 349.26183 -393.422645) (xy 349.271844 -393.42314) (xy 349.31858 -393.42314)
			(xy 349.33255 -393.419076) (xy 349.338646 -393.415012) (xy 349.361779 -393.400653) (xy 349.41168 -393.378885)
			(xy 349.464473 -393.365585) (xy 349.518732 -393.361112) (xy 349.572991 -393.365585) (xy 349.625784 -393.378885)
			(xy 349.675685 -393.400653) (xy 349.698818 -393.415012) (xy 349.705097 -393.41881) (xy 349.719169 -393.422953)
			(xy 349.726504 -393.42314) (xy 350.101154 -393.42314) (xy 350.111392 -393.422673) (xy 350.130248 -393.414691)
			(xy 350.144516 -393.400004) (xy 350.148652 -393.390628) (xy 350.182688 -393.301728) (xy 350.185867 -393.29207)
			(xy 350.185151 -393.271767) (xy 350.176646 -393.253317) (xy 350.16948 -393.246102) (xy 350.169226 -393.245848)
			(xy 350.148909 -393.226884) (xy 350.114297 -393.183406) (xy 350.087443 -393.134753) (xy 350.069101 -393.082295)
			(xy 350.059789 -393.027508) (xy 350.059244 -392.999722) (xy 350.059754 -392.973735) (xy 350.067884 -392.9224)
			(xy 350.083945 -392.87297) (xy 350.107541 -392.82666) (xy 350.138091 -392.784612) (xy 350.174842 -392.747861)
			(xy 350.21689 -392.717311) (xy 350.2632 -392.693715) (xy 350.31263 -392.677654) (xy 350.363965 -392.669524)
			(xy 350.415939 -392.669524) (xy 350.467274 -392.677654) (xy 350.516704 -392.693715) (xy 350.563014 -392.717311)
			(xy 350.605062 -392.747861) (xy 350.641813 -392.784612) (xy 350.672363 -392.82666) (xy 350.695959 -392.87297)
			(xy 350.71202 -392.9224) (xy 350.72015 -392.973735) (xy 350.72066 -392.999722) (xy 350.720215 -393.024619)
			(xy 350.712763 -393.073851) (xy 350.698016 -393.12141) (xy 350.676306 -393.166221) (xy 350.648125 -393.207271)
			(xy 350.614108 -393.243634) (xy 350.575026 -393.274487) (xy 350.53176 -393.299133) (xy 350.485289 -393.317015)
			(xy 350.461072 -393.32281) (xy 350.443546 -393.32662) (xy 350.421194 -393.354306) (xy 350.421194 -393.37234)
			(xy 350.421689 -393.382343) (xy 350.429355 -393.400822) (xy 350.443507 -393.414964) (xy 350.461991 -393.422618)
			(xy 350.471994 -393.42314) (xy 350.51873 -393.42314) (xy 350.5327 -393.419076) (xy 350.538796 -393.415012)
			(xy 350.561929 -393.400653) (xy 350.61183 -393.378885) (xy 350.664623 -393.365585) (xy 350.718882 -393.361112)
			(xy 350.773141 -393.365585) (xy 350.825934 -393.378885) (xy 350.875835 -393.400653) (xy 350.898968 -393.415012)
			(xy 350.905249 -393.418804) (xy 350.91932 -393.422933) (xy 350.926654 -393.42314) (xy 351.30105 -393.42314)
			(xy 351.311288 -393.422674) (xy 351.330146 -393.414693) (xy 351.344415 -393.400006) (xy 351.348548 -393.390628)
			(xy 351.382584 -393.301728) (xy 351.385764 -393.29207) (xy 351.385047 -393.271767) (xy 351.376542 -393.253317)
			(xy 351.369376 -393.246102) (xy 351.369122 -393.245848) (xy 351.348805 -393.226884) (xy 351.314194 -393.183406)
			(xy 351.28734 -393.134753) (xy 351.268998 -393.082295) (xy 351.259686 -393.027508) (xy 351.25914 -392.999722)
			(xy 351.25965 -392.973735) (xy 351.26778 -392.9224) (xy 351.283841 -392.87297) (xy 351.307437 -392.82666)
			(xy 351.337987 -392.784612) (xy 351.374738 -392.747861) (xy 351.416786 -392.717311) (xy 351.463096 -392.693715)
			(xy 351.512526 -392.677654) (xy 351.563861 -392.669524) (xy 351.615835 -392.669524) (xy 351.66717 -392.677654)
			(xy 351.7166 -392.693715) (xy 351.76291 -392.717311) (xy 351.804958 -392.747861) (xy 351.841709 -392.784612)
			(xy 351.872259 -392.82666) (xy 351.895855 -392.87297) (xy 351.911916 -392.9224) (xy 351.920046 -392.973735)
			(xy 351.920556 -392.999722) (xy 351.920111 -393.024619) (xy 351.912659 -393.073851) (xy 351.897912 -393.121409)
			(xy 351.876202 -393.16622) (xy 351.84802 -393.20727) (xy 351.814004 -393.243632) (xy 351.774921 -393.274485)
			(xy 351.731655 -393.29913) (xy 351.685184 -393.317012) (xy 351.660968 -393.32281) (xy 351.643442 -393.32662)
			(xy 351.62109 -393.354306) (xy 351.62109 -393.37234) (xy 351.621585 -393.382343) (xy 351.629251 -393.400823)
			(xy 351.643402 -393.414966) (xy 351.661887 -393.422621) (xy 351.67189 -393.42314) (xy 351.718626 -393.42314)
			(xy 351.732596 -393.419076) (xy 351.738692 -393.415012) (xy 351.761825 -393.400653) (xy 351.811726 -393.378885)
			(xy 351.864519 -393.365585) (xy 351.918778 -393.361112) (xy 351.973037 -393.365585) (xy 352.02583 -393.378885)
			(xy 352.075731 -393.400653) (xy 352.098864 -393.415012) (xy 352.105145 -393.418804) (xy 352.119216 -393.422934)
			(xy 352.12655 -393.42314) (xy 352.5012 -393.42314) (xy 352.511432 -393.422665) (xy 352.530274 -393.414673)
			(xy 352.544528 -393.399986) (xy 352.548698 -393.390628) (xy 352.582734 -393.301728) (xy 352.585912 -393.292069)
			(xy 352.585196 -393.271766) (xy 352.576697 -393.253312) (xy 352.569526 -393.246102) (xy 352.569272 -393.245848)
			(xy 352.548953 -393.226885) (xy 352.514336 -393.183409) (xy 352.487478 -393.134756) (xy 352.469133 -393.082297)
			(xy 352.459819 -393.027509) (xy 352.45929 -392.999722) (xy 352.4598 -392.973735) (xy 352.46793 -392.9224)
			(xy 352.483991 -392.87297) (xy 352.507587 -392.82666) (xy 352.538137 -392.784612) (xy 352.574888 -392.747861)
			(xy 352.616936 -392.717311) (xy 352.663246 -392.693715) (xy 352.712676 -392.677654) (xy 352.764011 -392.669524)
			(xy 352.815985 -392.669524) (xy 352.86732 -392.677654) (xy 352.91675 -392.693715) (xy 352.96306 -392.717311)
			(xy 353.005108 -392.747861) (xy 353.041859 -392.784612) (xy 353.072409 -392.82666) (xy 353.096005 -392.87297)
			(xy 353.112066 -392.9224) (xy 353.120196 -392.973735) (xy 353.120706 -392.999722) (xy 353.120262 -393.02462)
			(xy 353.11281 -393.073854) (xy 353.098064 -393.121415) (xy 353.076355 -393.166229) (xy 353.048175 -393.207283)
			(xy 353.01416 -393.243649) (xy 352.975079 -393.274507) (xy 352.931814 -393.299159) (xy 352.885343 -393.317047)
			(xy 352.861118 -393.32281) (xy 352.843592 -393.32662) (xy 352.82124 -393.354306) (xy 352.82124 -393.37234)
			(xy 352.821736 -393.382339) (xy 352.829404 -393.40081) (xy 352.843557 -393.414941) (xy 352.86204 -393.42258)
			(xy 352.87204 -393.42314) (xy 352.918776 -393.42314) (xy 352.932746 -393.419076) (xy 352.938842 -393.415012)
			(xy 352.961975 -393.400653) (xy 353.011876 -393.378885) (xy 353.064669 -393.365585) (xy 353.118928 -393.361112)
			(xy 353.173187 -393.365585) (xy 353.22598 -393.378885) (xy 353.275881 -393.400653) (xy 353.299014 -393.415012)
			(xy 353.305293 -393.418811) (xy 353.319364 -393.422955) (xy 353.3267 -393.42314) (xy 353.701096 -393.42314)
			(xy 353.711329 -393.422666) (xy 353.730172 -393.414675) (xy 353.744427 -393.399988) (xy 353.748594 -393.390628)
			(xy 353.78263 -393.301728) (xy 353.785808 -393.29207) (xy 353.785092 -393.271766) (xy 353.776592 -393.253312)
			(xy 353.769422 -393.246102) (xy 353.769168 -393.245848) (xy 353.748849 -393.226885) (xy 353.714233 -393.183409)
			(xy 353.687375 -393.134756) (xy 353.66903 -393.082297) (xy 353.659717 -393.027509) (xy 353.659186 -392.999722)
			(xy 353.659696 -392.973735) (xy 353.667826 -392.9224) (xy 353.683887 -392.87297) (xy 353.707483 -392.82666)
			(xy 353.738033 -392.784612) (xy 353.774784 -392.747861) (xy 353.816832 -392.717311) (xy 353.863142 -392.693715)
			(xy 353.912572 -392.677654) (xy 353.963907 -392.669524) (xy 354.015881 -392.669524) (xy 354.067216 -392.677654)
			(xy 354.116646 -392.693715) (xy 354.162956 -392.717311) (xy 354.205004 -392.747861) (xy 354.241755 -392.784612)
			(xy 354.272305 -392.82666) (xy 354.295901 -392.87297) (xy 354.311962 -392.9224) (xy 354.320092 -392.973735)
			(xy 354.320602 -392.999722) (xy 354.320157 -393.024619) (xy 354.312706 -393.073854) (xy 354.297959 -393.121415)
			(xy 354.27625 -393.166228) (xy 354.24807 -393.207282) (xy 354.214055 -393.243648) (xy 354.174974 -393.274505)
			(xy 354.131709 -393.299156) (xy 354.085238 -393.317044) (xy 354.061014 -393.32281) (xy 354.043488 -393.32662)
			(xy 354.021136 -393.354306) (xy 354.021136 -393.37234) (xy 354.021631 -393.38234) (xy 354.029299 -393.400812)
			(xy 354.043452 -393.414943) (xy 354.061935 -393.422584) (xy 354.071936 -393.42314) (xy 354.118672 -393.42314)
			(xy 354.132642 -393.419076) (xy 354.138738 -393.415012) (xy 354.158939 -393.40239) (xy 354.202198 -393.382449)
			(xy 354.247868 -393.368918) (xy 354.295008 -393.362076) (xy 354.318824 -393.361672) (xy 354.344838 -393.362151)
			(xy 354.396227 -393.370288) (xy 354.445707 -393.386374) (xy 354.492057 -393.41001) (xy 354.534132 -393.440614)
			(xy 354.570896 -393.47743) (xy 354.601439 -393.51955) (xy 354.625009 -393.565934) (xy 354.641023 -393.615437)
			(xy 354.645468 -393.641072) (xy 354.646992 -393.65047) (xy 354.689664 -393.724384) (xy 354.69449 -393.72921)
			(xy 355.063806 -394.098526) (xy 355.070648 -394.105926) (xy 355.078372 -394.124524) (xy 355.078792 -394.134594)
			(xy 355.078792 -394.429742) (xy 355.078792 -394.431774) (xy 355.079376 -394.439918) (xy 355.085074 -394.45521)
			(xy 355.089968 -394.461746) (xy 355.092762 -394.464794) (xy 355.11359 -394.486638) (xy 355.114098 -394.487146)
			(xy 355.120541 -394.493259) (xy 355.13654 -394.500944) (xy 355.14534 -394.502132) (xy 355.170716 -394.505237)
			(xy 355.220152 -394.518261) (xy 355.266995 -394.538737) (xy 355.310129 -394.566177) (xy 355.348527 -394.599928)
			(xy 355.381274 -394.639185) (xy 355.40759 -394.683014) (xy 355.426848 -394.73037) (xy 355.43859 -394.780126)
			(xy 355.442536 -394.831096) (xy 355.438591 -394.882066) (xy 355.426851 -394.931822) (xy 355.407594 -394.979179)
			(xy 355.381278 -395.023009) (xy 355.348532 -395.062267) (xy 355.310135 -395.096018) (xy 355.267002 -395.12346)
			(xy 355.22016 -395.143937) (xy 355.170724 -395.156962) (xy 355.14534 -395.159992) (xy 355.136562 -395.16126)
			(xy 355.120582 -395.168926) (xy 355.114098 -395.174978) (xy 355.11359 -395.175486) (xy 355.092762 -395.19733)
			(xy 355.089968 -395.200378) (xy 355.085111 -395.206934) (xy 355.079416 -395.222215) (xy 355.078792 -395.23035)
			(xy 355.078792 -396.671292) (xy 356.023672 -396.671292) (xy 356.024182 -396.645305) (xy 356.032312 -396.59397)
			(xy 356.048373 -396.54454) (xy 356.071969 -396.49823) (xy 356.102519 -396.456182) (xy 356.13927 -396.419431)
			(xy 356.181318 -396.388881) (xy 356.227628 -396.365285) (xy 356.277058 -396.349224) (xy 356.328393 -396.341094)
			(xy 356.380367 -396.341094) (xy 356.431702 -396.349224) (xy 356.481132 -396.365285) (xy 356.527442 -396.388881)
			(xy 356.56949 -396.419431) (xy 356.606241 -396.456182) (xy 356.636791 -396.49823) (xy 356.660387 -396.54454)
			(xy 356.676448 -396.59397) (xy 356.684578 -396.645305) (xy 356.685088 -396.671292) (xy 356.684573 -396.698915)
			(xy 356.675387 -396.753392) (xy 356.657284 -396.805589) (xy 356.630767 -396.854056) (xy 356.596572 -396.897448)
			(xy 356.555648 -396.934561) (xy 356.532688 -396.94993) (xy 356.521258 -396.957296) (xy 356.508812 -396.980664)
			(xy 356.512368 -397.094964) (xy 356.526084 -397.11757) (xy 356.538022 -397.124174) (xy 356.559725 -397.136797)
			(xy 356.599385 -397.16758) (xy 356.633933 -397.204006) (xy 356.662574 -397.24524) (xy 356.684649 -397.29033)
			(xy 356.69965 -397.338241) (xy 356.707233 -397.38787) (xy 356.707694 -397.412972) (xy 356.707234 -397.43738)
			(xy 356.700049 -397.485664) (xy 356.685845 -397.532368) (xy 356.664932 -397.576477) (xy 356.637762 -397.617034)
			(xy 356.604927 -397.653157) (xy 356.56714 -397.684061) (xy 356.546404 -397.696944) (xy 356.539098 -397.701735)
			(xy 356.528001 -397.715212) (xy 356.522119 -397.731649) (xy 356.521766 -397.740378) (xy 356.521766 -397.828008)
			(xy 356.522189 -397.836663) (xy 356.528007 -397.852967) (xy 356.538937 -397.86639) (xy 356.54615 -397.871188)
			(xy 356.54615 -397.871442) (xy 356.546658 -397.871442) (xy 356.567329 -397.884356) (xy 356.605013 -397.915265)
			(xy 356.637754 -397.95137) (xy 356.664841 -397.991888) (xy 356.685688 -398.035943) (xy 356.699844 -398.082581)
			(xy 356.707003 -398.130791) (xy 356.70744 -398.15516) (xy 356.70693 -398.181147) (xy 356.6988 -398.232482)
			(xy 356.682739 -398.281912) (xy 356.659143 -398.328222) (xy 356.628593 -398.37027) (xy 356.591842 -398.407021)
			(xy 356.549794 -398.437571) (xy 356.503484 -398.461167) (xy 356.454054 -398.477228) (xy 356.402719 -398.485358)
			(xy 356.350745 -398.485358) (xy 356.29941 -398.477228) (xy 356.24998 -398.461167) (xy 356.20367 -398.437571)
			(xy 356.161622 -398.407021) (xy 356.124871 -398.37027) (xy 356.094321 -398.328222) (xy 356.070725 -398.281912)
			(xy 356.054664 -398.232482) (xy 356.046534 -398.181147) (xy 356.046024 -398.15516) (xy 356.046422 -398.13075)
			(xy 356.053617 -398.082462) (xy 356.067831 -398.035757) (xy 356.088755 -397.991647) (xy 356.115934 -397.951091)
			(xy 356.148778 -397.91497) (xy 356.186574 -397.884069) (xy 356.207314 -397.871188) (xy 356.214655 -397.866443)
			(xy 356.225744 -397.852945) (xy 356.23161 -397.83649) (xy 356.231952 -397.827754) (xy 356.231952 -397.740124)
			(xy 356.231613 -397.731461) (xy 356.225763 -397.71515) (xy 356.214797 -397.701732) (xy 356.207568 -397.696944)
			(xy 356.207568 -397.69669) (xy 356.20706 -397.69669) (xy 356.186362 -397.683816) (xy 356.148677 -397.652901)
			(xy 356.115938 -397.61679) (xy 356.088853 -397.576265) (xy 356.068011 -397.532203) (xy 356.053861 -397.485559)
			(xy 356.04671 -397.437344) (xy 356.046278 -397.412972) (xy 356.046857 -397.385352) (xy 356.056032 -397.330878)
			(xy 356.074123 -397.278684) (xy 356.100628 -397.230217) (xy 356.134811 -397.186823) (xy 356.175723 -397.149705)
			(xy 356.198678 -397.134334) (xy 356.210108 -397.126968) (xy 356.222554 -397.1036) (xy 356.218998 -396.9893)
			(xy 356.205282 -396.966694) (xy 356.193344 -396.96009) (xy 356.171662 -396.947435) (xy 356.132004 -396.916656)
			(xy 356.097456 -396.880233) (xy 356.068814 -396.839006) (xy 356.046735 -396.793921) (xy 356.031728 -396.746016)
			(xy 356.024138 -396.696392) (xy 356.023672 -396.671292) (xy 355.078792 -396.671292) (xy 355.078792 -397.06804)
			(xy 355.079222 -397.078107) (xy 355.086946 -397.096702) (xy 355.093778 -397.104108) (xy 355.6254 -397.63573)
			(xy 355.632242 -397.64313) (xy 355.639965 -397.661728) (xy 355.640386 -397.671798) (xy 355.640386 -399.341086)
			(xy 355.640824 -399.35115) (xy 355.648559 -399.369733) (xy 355.655372 -399.377154) (xy 356.031546 -399.753328)
			(xy 356.038943 -399.760175) (xy 356.057543 -399.767904) (xy 356.067614 -399.768314) (xy 356.431596 -399.768314)
			(xy 356.441667 -399.767892) (xy 356.460274 -399.76018) (xy 356.467664 -399.753328) (xy 357.017828 -399.203164)
			(xy 357.024677 -399.195767) (xy 357.032409 -399.177168) (xy 357.032814 -399.167096) (xy 357.032814 -397.577564)
			(xy 357.032351 -397.567688) (xy 357.024905 -397.549393) (xy 357.018336 -397.542004) (xy 356.999767 -397.522455)
			(xy 356.967754 -397.479071) (xy 356.942168 -397.431611) (xy 356.923518 -397.381023) (xy 356.912176 -397.328312)
			(xy 356.908367 -397.27453) (xy 356.912167 -397.220747) (xy 356.923501 -397.168035) (xy 356.942143 -397.117443)
			(xy 356.967722 -397.06998) (xy 356.999728 -397.02659) (xy 357.018336 -397.00708) (xy 357.024925 -396.999701)
			(xy 357.03239 -396.981402) (xy 357.032814 -396.97152) (xy 357.032814 -395.23289) (xy 357.0097 -395.20495)
			(xy 356.991666 -395.201394) (xy 356.965892 -395.195964) (xy 356.916041 -395.178953) (xy 356.869005 -395.155245)
			(xy 356.825679 -395.125289) (xy 356.786887 -395.089657) (xy 356.753367 -395.049027) (xy 356.725756 -395.00417)
			(xy 356.704581 -394.95594) (xy 356.690244 -394.905256) (xy 356.683017 -394.853081) (xy 356.682548 -394.826744)
			(xy 356.682548 -394.826236) (xy 356.682814 -394.806272) (xy 356.687018 -394.766567) (xy 356.69093 -394.746988)
			(xy 356.693724 -394.733526) (xy 356.685088 -394.707364) (xy 356.607618 -394.6398) (xy 356.602363 -394.635485)
			(xy 356.590133 -394.629556) (xy 356.583488 -394.628116) (xy 356.576791 -394.627029) (xy 356.563268 -394.628046)
			(xy 356.556818 -394.630148) (xy 356.525486 -394.640758) (xy 356.460349 -394.65225) (xy 356.427278 -394.653008)
			(xy 356.400028 -394.652521) (xy 356.346082 -394.644762) (xy 356.29379 -394.629405) (xy 356.244216 -394.606762)
			(xy 356.198368 -394.577295) (xy 356.157181 -394.541604) (xy 356.121491 -394.500414) (xy 356.092027 -394.454565)
			(xy 356.069388 -394.404989) (xy 356.054034 -394.352696) (xy 356.046278 -394.29875) (xy 356.04577 -394.2715)
			(xy 356.046209 -394.245518) (xy 356.053264 -394.194034) (xy 356.067243 -394.143985) (xy 356.087888 -394.096297)
			(xy 356.114815 -394.051854) (xy 356.147527 -394.011477) (xy 356.166166 -393.99337) (xy 356.17531 -393.984734)
			(xy 356.183438 -393.961366) (xy 356.167436 -393.85367) (xy 356.152958 -393.833604) (xy 356.141528 -393.828016)
			(xy 356.118152 -393.815933) (xy 356.075227 -393.785501) (xy 356.037661 -393.748656) (xy 356.006403 -393.706328)
			(xy 355.98224 -393.659586) (xy 355.965783 -393.609607) (xy 355.957445 -393.557653) (xy 355.95687 -393.531344)
			(xy 355.95687 -393.53109) (xy 355.957314 -393.506217) (xy 355.964759 -393.457032) (xy 355.979496 -393.40952)
			(xy 356.00119 -393.364754) (xy 356.029352 -393.323747) (xy 356.046024 -393.305284) (xy 356.052374 -393.298426)
			(xy 356.059486 -393.281154) (xy 356.061772 -393.195048) (xy 356.055676 -393.177522) (xy 356.04958 -393.17041)
			(xy 356.034836 -393.152406) (xy 356.010015 -393.113043) (xy 355.990956 -393.07059) (xy 355.978035 -393.025884)
			(xy 355.971507 -392.97981) (xy 355.971094 -392.956542) (xy 355.971574 -392.930551) (xy 355.9797 -392.879207)
			(xy 355.995759 -392.829767) (xy 356.019354 -392.783448) (xy 356.049906 -392.741391) (xy 356.086661 -392.704632)
			(xy 356.128714 -392.674075) (xy 356.17503 -392.650474) (xy 356.224468 -392.634409) (xy 356.275811 -392.626277)
			(xy 356.301802 -392.625834) (xy 356.302056 -392.625834) (xy 356.325558 -392.626226) (xy 356.372091 -392.632851)
			(xy 356.394766 -392.639042) (xy 356.408228 -392.643106) (xy 356.43439 -392.636502) (xy 356.517448 -392.555222)
			(xy 356.524814 -392.528806) (xy 356.521258 -392.515598) (xy 356.515327 -392.491651) (xy 356.508954 -392.442729)
			(xy 356.508558 -392.418062) (xy 356.509046 -392.390812) (xy 356.516807 -392.336866) (xy 356.532165 -392.284574)
			(xy 356.554808 -392.234999) (xy 356.584275 -392.189151) (xy 356.619966 -392.147963) (xy 356.661155 -392.112272)
			(xy 356.707003 -392.082806) (xy 356.756578 -392.060164) (xy 356.80887 -392.044806) (xy 356.862816 -392.037046)
			(xy 356.890066 -392.036554) (xy 356.922578 -392.037824) (xy 356.933246 -392.03884) (xy 356.953566 -392.031982)
			(xy 357.016304 -391.97407) (xy 357.023741 -391.966574) (xy 357.032258 -391.947278) (xy 357.032814 -391.936732)
			(xy 357.032814 -391.754614) (xy 357.032376 -391.74455) (xy 357.024641 -391.725967) (xy 357.017828 -391.718546)
			(xy 356.003606 -390.704324) (xy 355.996494 -390.696958) (xy 355.977698 -390.689338) (xy 333.9465 -390.689338)
			(xy 333.936431 -390.689762) (xy 333.91783 -390.697481) (xy 333.910432 -390.704324) (xy 333.557372 -391.057384)
			(xy 333.550006 -391.064496) (xy 333.542386 -391.083292) (xy 333.542386 -391.316543) (xy 334.66583 -391.316543)
			(xy 334.66583 -391.264569) (xy 334.67396 -391.213234) (xy 334.690021 -391.163804) (xy 334.713617 -391.117494)
			(xy 334.744167 -391.075446) (xy 334.780918 -391.038695) (xy 334.822966 -391.008145) (xy 334.869276 -390.984549)
			(xy 334.918706 -390.968488) (xy 334.970041 -390.960358) (xy 335.022015 -390.960358) (xy 335.07335 -390.968488)
			(xy 335.12278 -390.984549) (xy 335.16909 -391.008145) (xy 335.211138 -391.038695) (xy 335.247889 -391.075446)
			(xy 335.278439 -391.117494) (xy 335.302035 -391.163804) (xy 335.318096 -391.213234) (xy 335.325648 -391.260917)
			(xy 336.013808 -391.260917) (xy 336.013808 -391.208943) (xy 336.021938 -391.157608) (xy 336.037999 -391.108178)
			(xy 336.061595 -391.061868) (xy 336.092145 -391.01982) (xy 336.128896 -390.983069) (xy 336.170944 -390.952519)
			(xy 336.217254 -390.928923) (xy 336.266684 -390.912862) (xy 336.318019 -390.904732) (xy 336.369993 -390.904732)
			(xy 336.421328 -390.912862) (xy 336.470758 -390.928923) (xy 336.517068 -390.952519) (xy 336.559116 -390.983069)
			(xy 336.595867 -391.01982) (xy 336.626417 -391.061868) (xy 336.650013 -391.108178) (xy 336.666074 -391.157608)
			(xy 336.674204 -391.208943) (xy 336.674714 -391.23493) (xy 336.674204 -391.260917) (xy 337.213958 -391.260917)
			(xy 337.213958 -391.208943) (xy 337.222088 -391.157608) (xy 337.238149 -391.108178) (xy 337.261745 -391.061868)
			(xy 337.292295 -391.01982) (xy 337.329046 -390.983069) (xy 337.371094 -390.952519) (xy 337.417404 -390.928923)
			(xy 337.466834 -390.912862) (xy 337.518169 -390.904732) (xy 337.570143 -390.904732) (xy 337.621478 -390.912862)
			(xy 337.670908 -390.928923) (xy 337.717218 -390.952519) (xy 337.759266 -390.983069) (xy 337.796017 -391.01982)
			(xy 337.826567 -391.061868) (xy 337.850163 -391.108178) (xy 337.866224 -391.157608) (xy 337.874354 -391.208943)
			(xy 337.874864 -391.23493) (xy 337.874354 -391.260917) (xy 338.413854 -391.260917) (xy 338.413854 -391.208943)
			(xy 338.421984 -391.157608) (xy 338.438045 -391.108178) (xy 338.461641 -391.061868) (xy 338.492191 -391.01982)
			(xy 338.528942 -390.983069) (xy 338.57099 -390.952519) (xy 338.6173 -390.928923) (xy 338.66673 -390.912862)
			(xy 338.718065 -390.904732) (xy 338.770039 -390.904732) (xy 338.821374 -390.912862) (xy 338.870804 -390.928923)
			(xy 338.917114 -390.952519) (xy 338.959162 -390.983069) (xy 338.995913 -391.01982) (xy 339.026463 -391.061868)
			(xy 339.050059 -391.108178) (xy 339.06612 -391.157608) (xy 339.07425 -391.208943) (xy 339.07476 -391.23493)
			(xy 339.07425 -391.260917) (xy 339.61375 -391.260917) (xy 339.61375 -391.208943) (xy 339.62188 -391.157608)
			(xy 339.637941 -391.108178) (xy 339.661537 -391.061868) (xy 339.692087 -391.01982) (xy 339.728838 -390.983069)
			(xy 339.770886 -390.952519) (xy 339.817196 -390.928923) (xy 339.866626 -390.912862) (xy 339.917961 -390.904732)
			(xy 339.969935 -390.904732) (xy 340.02127 -390.912862) (xy 340.0707 -390.928923) (xy 340.11701 -390.952519)
			(xy 340.159058 -390.983069) (xy 340.195809 -391.01982) (xy 340.226359 -391.061868) (xy 340.249955 -391.108178)
			(xy 340.266016 -391.157608) (xy 340.274146 -391.208943) (xy 340.274656 -391.23493) (xy 340.274146 -391.260917)
			(xy 340.8139 -391.260917) (xy 340.8139 -391.208943) (xy 340.82203 -391.157608) (xy 340.838091 -391.108178)
			(xy 340.861687 -391.061868) (xy 340.892237 -391.01982) (xy 340.928988 -390.983069) (xy 340.971036 -390.952519)
			(xy 341.017346 -390.928923) (xy 341.066776 -390.912862) (xy 341.118111 -390.904732) (xy 341.170085 -390.904732)
			(xy 341.22142 -390.912862) (xy 341.27085 -390.928923) (xy 341.31716 -390.952519) (xy 341.359208 -390.983069)
			(xy 341.395959 -391.01982) (xy 341.426509 -391.061868) (xy 341.450105 -391.108178) (xy 341.466166 -391.157608)
			(xy 341.474296 -391.208943) (xy 341.474806 -391.23493) (xy 341.474296 -391.260917) (xy 342.013796 -391.260917)
			(xy 342.013796 -391.208943) (xy 342.021926 -391.157608) (xy 342.037987 -391.108178) (xy 342.061583 -391.061868)
			(xy 342.092133 -391.01982) (xy 342.128884 -390.983069) (xy 342.170932 -390.952519) (xy 342.217242 -390.928923)
			(xy 342.266672 -390.912862) (xy 342.318007 -390.904732) (xy 342.369981 -390.904732) (xy 342.421316 -390.912862)
			(xy 342.470746 -390.928923) (xy 342.517056 -390.952519) (xy 342.559104 -390.983069) (xy 342.595855 -391.01982)
			(xy 342.626405 -391.061868) (xy 342.650001 -391.108178) (xy 342.666062 -391.157608) (xy 342.674192 -391.208943)
			(xy 342.674702 -391.23493) (xy 342.674192 -391.260917) (xy 343.213946 -391.260917) (xy 343.213946 -391.208943)
			(xy 343.222076 -391.157608) (xy 343.238137 -391.108178) (xy 343.261733 -391.061868) (xy 343.292283 -391.01982)
			(xy 343.329034 -390.983069) (xy 343.371082 -390.952519) (xy 343.417392 -390.928923) (xy 343.466822 -390.912862)
			(xy 343.518157 -390.904732) (xy 343.570131 -390.904732) (xy 343.621466 -390.912862) (xy 343.670896 -390.928923)
			(xy 343.717206 -390.952519) (xy 343.759254 -390.983069) (xy 343.796005 -391.01982) (xy 343.826555 -391.061868)
			(xy 343.850151 -391.108178) (xy 343.866212 -391.157608) (xy 343.874342 -391.208943) (xy 343.874852 -391.23493)
			(xy 343.874342 -391.260917) (xy 344.413842 -391.260917) (xy 344.413842 -391.208943) (xy 344.421972 -391.157608)
			(xy 344.438033 -391.108178) (xy 344.461629 -391.061868) (xy 344.492179 -391.01982) (xy 344.52893 -390.983069)
			(xy 344.570978 -390.952519) (xy 344.617288 -390.928923) (xy 344.666718 -390.912862) (xy 344.718053 -390.904732)
			(xy 344.770027 -390.904732) (xy 344.821362 -390.912862) (xy 344.870792 -390.928923) (xy 344.917102 -390.952519)
			(xy 344.95915 -390.983069) (xy 344.995901 -391.01982) (xy 345.026451 -391.061868) (xy 345.050047 -391.108178)
			(xy 345.066108 -391.157608) (xy 345.074238 -391.208943) (xy 345.074748 -391.23493) (xy 345.074238 -391.260917)
			(xy 345.613738 -391.260917) (xy 345.613738 -391.208943) (xy 345.621868 -391.157608) (xy 345.637929 -391.108178)
			(xy 345.661525 -391.061868) (xy 345.692075 -391.01982) (xy 345.728826 -390.983069) (xy 345.770874 -390.952519)
			(xy 345.817184 -390.928923) (xy 345.866614 -390.912862) (xy 345.917949 -390.904732) (xy 345.969923 -390.904732)
			(xy 346.021258 -390.912862) (xy 346.070688 -390.928923) (xy 346.116998 -390.952519) (xy 346.159046 -390.983069)
			(xy 346.195797 -391.01982) (xy 346.226347 -391.061868) (xy 346.249943 -391.108178) (xy 346.266004 -391.157608)
			(xy 346.274134 -391.208943) (xy 346.274644 -391.23493) (xy 346.274134 -391.260917) (xy 346.813888 -391.260917)
			(xy 346.813888 -391.208943) (xy 346.822018 -391.157608) (xy 346.838079 -391.108178) (xy 346.861675 -391.061868)
			(xy 346.892225 -391.01982) (xy 346.928976 -390.983069) (xy 346.971024 -390.952519) (xy 347.017334 -390.928923)
			(xy 347.066764 -390.912862) (xy 347.118099 -390.904732) (xy 347.170073 -390.904732) (xy 347.221408 -390.912862)
			(xy 347.270838 -390.928923) (xy 347.317148 -390.952519) (xy 347.359196 -390.983069) (xy 347.395947 -391.01982)
			(xy 347.426497 -391.061868) (xy 347.450093 -391.108178) (xy 347.466154 -391.157608) (xy 347.474284 -391.208943)
			(xy 347.474794 -391.23493) (xy 347.474284 -391.260917) (xy 348.013784 -391.260917) (xy 348.013784 -391.208943)
			(xy 348.021914 -391.157608) (xy 348.037975 -391.108178) (xy 348.061571 -391.061868) (xy 348.092121 -391.01982)
			(xy 348.128872 -390.983069) (xy 348.17092 -390.952519) (xy 348.21723 -390.928923) (xy 348.26666 -390.912862)
			(xy 348.317995 -390.904732) (xy 348.369969 -390.904732) (xy 348.421304 -390.912862) (xy 348.470734 -390.928923)
			(xy 348.517044 -390.952519) (xy 348.559092 -390.983069) (xy 348.595843 -391.01982) (xy 348.626393 -391.061868)
			(xy 348.649989 -391.108178) (xy 348.66605 -391.157608) (xy 348.67418 -391.208943) (xy 348.67469 -391.23493)
			(xy 348.67418 -391.260917) (xy 349.213934 -391.260917) (xy 349.213934 -391.208943) (xy 349.222064 -391.157608)
			(xy 349.238125 -391.108178) (xy 349.261721 -391.061868) (xy 349.292271 -391.01982) (xy 349.329022 -390.983069)
			(xy 349.37107 -390.952519) (xy 349.41738 -390.928923) (xy 349.46681 -390.912862) (xy 349.518145 -390.904732)
			(xy 349.570119 -390.904732) (xy 349.621454 -390.912862) (xy 349.670884 -390.928923) (xy 349.717194 -390.952519)
			(xy 349.759242 -390.983069) (xy 349.795993 -391.01982) (xy 349.826543 -391.061868) (xy 349.850139 -391.108178)
			(xy 349.8662 -391.157608) (xy 349.87433 -391.208943) (xy 349.87484 -391.23493) (xy 349.87433 -391.260917)
			(xy 350.41383 -391.260917) (xy 350.41383 -391.208943) (xy 350.42196 -391.157608) (xy 350.438021 -391.108178)
			(xy 350.461617 -391.061868) (xy 350.492167 -391.01982) (xy 350.528918 -390.983069) (xy 350.570966 -390.952519)
			(xy 350.617276 -390.928923) (xy 350.666706 -390.912862) (xy 350.718041 -390.904732) (xy 350.770015 -390.904732)
			(xy 350.82135 -390.912862) (xy 350.87078 -390.928923) (xy 350.91709 -390.952519) (xy 350.959138 -390.983069)
			(xy 350.995889 -391.01982) (xy 351.026439 -391.061868) (xy 351.050035 -391.108178) (xy 351.066096 -391.157608)
			(xy 351.074226 -391.208943) (xy 351.074736 -391.23493) (xy 351.074226 -391.260917) (xy 351.613726 -391.260917)
			(xy 351.613726 -391.208943) (xy 351.621856 -391.157608) (xy 351.637917 -391.108178) (xy 351.661513 -391.061868)
			(xy 351.692063 -391.01982) (xy 351.728814 -390.983069) (xy 351.770862 -390.952519) (xy 351.817172 -390.928923)
			(xy 351.866602 -390.912862) (xy 351.917937 -390.904732) (xy 351.969911 -390.904732) (xy 352.021246 -390.912862)
			(xy 352.070676 -390.928923) (xy 352.116986 -390.952519) (xy 352.159034 -390.983069) (xy 352.195785 -391.01982)
			(xy 352.226335 -391.061868) (xy 352.249931 -391.108178) (xy 352.265992 -391.157608) (xy 352.274122 -391.208943)
			(xy 352.274632 -391.23493) (xy 352.274122 -391.260917) (xy 352.813876 -391.260917) (xy 352.813876 -391.208943)
			(xy 352.822006 -391.157608) (xy 352.838067 -391.108178) (xy 352.861663 -391.061868) (xy 352.892213 -391.01982)
			(xy 352.928964 -390.983069) (xy 352.971012 -390.952519) (xy 353.017322 -390.928923) (xy 353.066752 -390.912862)
			(xy 353.118087 -390.904732) (xy 353.170061 -390.904732) (xy 353.221396 -390.912862) (xy 353.270826 -390.928923)
			(xy 353.317136 -390.952519) (xy 353.359184 -390.983069) (xy 353.395935 -391.01982) (xy 353.426485 -391.061868)
			(xy 353.450081 -391.108178) (xy 353.466142 -391.157608) (xy 353.474272 -391.208943) (xy 353.474782 -391.23493)
			(xy 353.474272 -391.260917) (xy 354.013772 -391.260917) (xy 354.013772 -391.208943) (xy 354.021902 -391.157608)
			(xy 354.037963 -391.108178) (xy 354.061559 -391.061868) (xy 354.092109 -391.01982) (xy 354.12886 -390.983069)
			(xy 354.170908 -390.952519) (xy 354.217218 -390.928923) (xy 354.266648 -390.912862) (xy 354.317983 -390.904732)
			(xy 354.369957 -390.904732) (xy 354.421292 -390.912862) (xy 354.470722 -390.928923) (xy 354.517032 -390.952519)
			(xy 354.55908 -390.983069) (xy 354.595831 -391.01982) (xy 354.626381 -391.061868) (xy 354.649977 -391.108178)
			(xy 354.666038 -391.157608) (xy 354.674168 -391.208943) (xy 354.674678 -391.23493) (xy 354.674168 -391.260917)
			(xy 354.666038 -391.312252) (xy 354.649977 -391.361682) (xy 354.626381 -391.407992) (xy 354.595831 -391.45004)
			(xy 354.55908 -391.486791) (xy 354.517032 -391.517341) (xy 354.470722 -391.540937) (xy 354.421292 -391.556998)
			(xy 354.369957 -391.565128) (xy 354.317983 -391.565128) (xy 354.266648 -391.556998) (xy 354.217218 -391.540937)
			(xy 354.170908 -391.517341) (xy 354.12886 -391.486791) (xy 354.092109 -391.45004) (xy 354.061559 -391.407992)
			(xy 354.037963 -391.361682) (xy 354.021902 -391.312252) (xy 354.013772 -391.260917) (xy 353.474272 -391.260917)
			(xy 353.466142 -391.312252) (xy 353.450081 -391.361682) (xy 353.426485 -391.407992) (xy 353.395935 -391.45004)
			(xy 353.359184 -391.486791) (xy 353.317136 -391.517341) (xy 353.270826 -391.540937) (xy 353.221396 -391.556998)
			(xy 353.170061 -391.565128) (xy 353.118087 -391.565128) (xy 353.066752 -391.556998) (xy 353.017322 -391.540937)
			(xy 352.971012 -391.517341) (xy 352.928964 -391.486791) (xy 352.892213 -391.45004) (xy 352.861663 -391.407992)
			(xy 352.838067 -391.361682) (xy 352.822006 -391.312252) (xy 352.813876 -391.260917) (xy 352.274122 -391.260917)
			(xy 352.265992 -391.312252) (xy 352.249931 -391.361682) (xy 352.226335 -391.407992) (xy 352.195785 -391.45004)
			(xy 352.159034 -391.486791) (xy 352.116986 -391.517341) (xy 352.070676 -391.540937) (xy 352.021246 -391.556998)
			(xy 351.969911 -391.565128) (xy 351.917937 -391.565128) (xy 351.866602 -391.556998) (xy 351.817172 -391.540937)
			(xy 351.770862 -391.517341) (xy 351.728814 -391.486791) (xy 351.692063 -391.45004) (xy 351.661513 -391.407992)
			(xy 351.637917 -391.361682) (xy 351.621856 -391.312252) (xy 351.613726 -391.260917) (xy 351.074226 -391.260917)
			(xy 351.066096 -391.312252) (xy 351.050035 -391.361682) (xy 351.026439 -391.407992) (xy 350.995889 -391.45004)
			(xy 350.959138 -391.486791) (xy 350.91709 -391.517341) (xy 350.87078 -391.540937) (xy 350.82135 -391.556998)
			(xy 350.770015 -391.565128) (xy 350.718041 -391.565128) (xy 350.666706 -391.556998) (xy 350.617276 -391.540937)
			(xy 350.570966 -391.517341) (xy 350.528918 -391.486791) (xy 350.492167 -391.45004) (xy 350.461617 -391.407992)
			(xy 350.438021 -391.361682) (xy 350.42196 -391.312252) (xy 350.41383 -391.260917) (xy 349.87433 -391.260917)
			(xy 349.8662 -391.312252) (xy 349.850139 -391.361682) (xy 349.826543 -391.407992) (xy 349.795993 -391.45004)
			(xy 349.759242 -391.486791) (xy 349.717194 -391.517341) (xy 349.670884 -391.540937) (xy 349.621454 -391.556998)
			(xy 349.570119 -391.565128) (xy 349.518145 -391.565128) (xy 349.46681 -391.556998) (xy 349.41738 -391.540937)
			(xy 349.37107 -391.517341) (xy 349.329022 -391.486791) (xy 349.292271 -391.45004) (xy 349.261721 -391.407992)
			(xy 349.238125 -391.361682) (xy 349.222064 -391.312252) (xy 349.213934 -391.260917) (xy 348.67418 -391.260917)
			(xy 348.66605 -391.312252) (xy 348.649989 -391.361682) (xy 348.626393 -391.407992) (xy 348.595843 -391.45004)
			(xy 348.559092 -391.486791) (xy 348.517044 -391.517341) (xy 348.470734 -391.540937) (xy 348.421304 -391.556998)
			(xy 348.369969 -391.565128) (xy 348.317995 -391.565128) (xy 348.26666 -391.556998) (xy 348.21723 -391.540937)
			(xy 348.17092 -391.517341) (xy 348.128872 -391.486791) (xy 348.092121 -391.45004) (xy 348.061571 -391.407992)
			(xy 348.037975 -391.361682) (xy 348.021914 -391.312252) (xy 348.013784 -391.260917) (xy 347.474284 -391.260917)
			(xy 347.466154 -391.312252) (xy 347.450093 -391.361682) (xy 347.426497 -391.407992) (xy 347.395947 -391.45004)
			(xy 347.359196 -391.486791) (xy 347.317148 -391.517341) (xy 347.270838 -391.540937) (xy 347.221408 -391.556998)
			(xy 347.170073 -391.565128) (xy 347.118099 -391.565128) (xy 347.066764 -391.556998) (xy 347.017334 -391.540937)
			(xy 346.971024 -391.517341) (xy 346.928976 -391.486791) (xy 346.892225 -391.45004) (xy 346.861675 -391.407992)
			(xy 346.838079 -391.361682) (xy 346.822018 -391.312252) (xy 346.813888 -391.260917) (xy 346.274134 -391.260917)
			(xy 346.266004 -391.312252) (xy 346.249943 -391.361682) (xy 346.226347 -391.407992) (xy 346.195797 -391.45004)
			(xy 346.159046 -391.486791) (xy 346.116998 -391.517341) (xy 346.070688 -391.540937) (xy 346.021258 -391.556998)
			(xy 345.969923 -391.565128) (xy 345.917949 -391.565128) (xy 345.866614 -391.556998) (xy 345.817184 -391.540937)
			(xy 345.770874 -391.517341) (xy 345.728826 -391.486791) (xy 345.692075 -391.45004) (xy 345.661525 -391.407992)
			(xy 345.637929 -391.361682) (xy 345.621868 -391.312252) (xy 345.613738 -391.260917) (xy 345.074238 -391.260917)
			(xy 345.066108 -391.312252) (xy 345.050047 -391.361682) (xy 345.026451 -391.407992) (xy 344.995901 -391.45004)
			(xy 344.95915 -391.486791) (xy 344.917102 -391.517341) (xy 344.870792 -391.540937) (xy 344.821362 -391.556998)
			(xy 344.770027 -391.565128) (xy 344.718053 -391.565128) (xy 344.666718 -391.556998) (xy 344.617288 -391.540937)
			(xy 344.570978 -391.517341) (xy 344.52893 -391.486791) (xy 344.492179 -391.45004) (xy 344.461629 -391.407992)
			(xy 344.438033 -391.361682) (xy 344.421972 -391.312252) (xy 344.413842 -391.260917) (xy 343.874342 -391.260917)
			(xy 343.866212 -391.312252) (xy 343.850151 -391.361682) (xy 343.826555 -391.407992) (xy 343.796005 -391.45004)
			(xy 343.759254 -391.486791) (xy 343.717206 -391.517341) (xy 343.670896 -391.540937) (xy 343.621466 -391.556998)
			(xy 343.570131 -391.565128) (xy 343.518157 -391.565128) (xy 343.466822 -391.556998) (xy 343.417392 -391.540937)
			(xy 343.371082 -391.517341) (xy 343.329034 -391.486791) (xy 343.292283 -391.45004) (xy 343.261733 -391.407992)
			(xy 343.238137 -391.361682) (xy 343.222076 -391.312252) (xy 343.213946 -391.260917) (xy 342.674192 -391.260917)
			(xy 342.666062 -391.312252) (xy 342.650001 -391.361682) (xy 342.626405 -391.407992) (xy 342.595855 -391.45004)
			(xy 342.559104 -391.486791) (xy 342.517056 -391.517341) (xy 342.470746 -391.540937) (xy 342.421316 -391.556998)
			(xy 342.369981 -391.565128) (xy 342.318007 -391.565128) (xy 342.266672 -391.556998) (xy 342.217242 -391.540937)
			(xy 342.170932 -391.517341) (xy 342.128884 -391.486791) (xy 342.092133 -391.45004) (xy 342.061583 -391.407992)
			(xy 342.037987 -391.361682) (xy 342.021926 -391.312252) (xy 342.013796 -391.260917) (xy 341.474296 -391.260917)
			(xy 341.466166 -391.312252) (xy 341.450105 -391.361682) (xy 341.426509 -391.407992) (xy 341.395959 -391.45004)
			(xy 341.359208 -391.486791) (xy 341.31716 -391.517341) (xy 341.27085 -391.540937) (xy 341.22142 -391.556998)
			(xy 341.170085 -391.565128) (xy 341.118111 -391.565128) (xy 341.066776 -391.556998) (xy 341.017346 -391.540937)
			(xy 340.971036 -391.517341) (xy 340.928988 -391.486791) (xy 340.892237 -391.45004) (xy 340.861687 -391.407992)
			(xy 340.838091 -391.361682) (xy 340.82203 -391.312252) (xy 340.8139 -391.260917) (xy 340.274146 -391.260917)
			(xy 340.266016 -391.312252) (xy 340.249955 -391.361682) (xy 340.226359 -391.407992) (xy 340.195809 -391.45004)
			(xy 340.159058 -391.486791) (xy 340.11701 -391.517341) (xy 340.0707 -391.540937) (xy 340.02127 -391.556998)
			(xy 339.969935 -391.565128) (xy 339.917961 -391.565128) (xy 339.866626 -391.556998) (xy 339.817196 -391.540937)
			(xy 339.770886 -391.517341) (xy 339.728838 -391.486791) (xy 339.692087 -391.45004) (xy 339.661537 -391.407992)
			(xy 339.637941 -391.361682) (xy 339.62188 -391.312252) (xy 339.61375 -391.260917) (xy 339.07425 -391.260917)
			(xy 339.06612 -391.312252) (xy 339.050059 -391.361682) (xy 339.026463 -391.407992) (xy 338.995913 -391.45004)
			(xy 338.959162 -391.486791) (xy 338.917114 -391.517341) (xy 338.870804 -391.540937) (xy 338.821374 -391.556998)
			(xy 338.770039 -391.565128) (xy 338.718065 -391.565128) (xy 338.66673 -391.556998) (xy 338.6173 -391.540937)
			(xy 338.57099 -391.517341) (xy 338.528942 -391.486791) (xy 338.492191 -391.45004) (xy 338.461641 -391.407992)
			(xy 338.438045 -391.361682) (xy 338.421984 -391.312252) (xy 338.413854 -391.260917) (xy 337.874354 -391.260917)
			(xy 337.866224 -391.312252) (xy 337.850163 -391.361682) (xy 337.826567 -391.407992) (xy 337.796017 -391.45004)
			(xy 337.759266 -391.486791) (xy 337.717218 -391.517341) (xy 337.670908 -391.540937) (xy 337.621478 -391.556998)
			(xy 337.570143 -391.565128) (xy 337.518169 -391.565128) (xy 337.466834 -391.556998) (xy 337.417404 -391.540937)
			(xy 337.371094 -391.517341) (xy 337.329046 -391.486791) (xy 337.292295 -391.45004) (xy 337.261745 -391.407992)
			(xy 337.238149 -391.361682) (xy 337.222088 -391.312252) (xy 337.213958 -391.260917) (xy 336.674204 -391.260917)
			(xy 336.666074 -391.312252) (xy 336.650013 -391.361682) (xy 336.626417 -391.407992) (xy 336.595867 -391.45004)
			(xy 336.559116 -391.486791) (xy 336.517068 -391.517341) (xy 336.470758 -391.540937) (xy 336.421328 -391.556998)
			(xy 336.369993 -391.565128) (xy 336.318019 -391.565128) (xy 336.266684 -391.556998) (xy 336.217254 -391.540937)
			(xy 336.170944 -391.517341) (xy 336.128896 -391.486791) (xy 336.092145 -391.45004) (xy 336.061595 -391.407992)
			(xy 336.037999 -391.361682) (xy 336.021938 -391.312252) (xy 336.013808 -391.260917) (xy 335.325648 -391.260917)
			(xy 335.326226 -391.264569) (xy 335.326736 -391.290556) (xy 335.326226 -391.316543) (xy 335.318096 -391.367878)
			(xy 335.302035 -391.417308) (xy 335.278439 -391.463618) (xy 335.247889 -391.505666) (xy 335.211138 -391.542417)
			(xy 335.16909 -391.572967) (xy 335.12278 -391.596563) (xy 335.07335 -391.612624) (xy 335.022015 -391.620754)
			(xy 334.970041 -391.620754) (xy 334.918706 -391.612624) (xy 334.869276 -391.596563) (xy 334.822966 -391.572967)
			(xy 334.780918 -391.542417) (xy 334.744167 -391.505666) (xy 334.713617 -391.463618) (xy 334.690021 -391.417308)
			(xy 334.67396 -391.367878) (xy 334.66583 -391.316543) (xy 333.542386 -391.316543) (xy 333.542386 -392.413998)
			(xy 333.543001 -392.426714) (xy 333.554985 -392.449138) (xy 333.565246 -392.45667) (xy 333.572358 -392.46048)
			(xy 333.670148 -392.504676) (xy 333.699358 -392.500358) (xy 333.710788 -392.490452) (xy 333.728956 -392.475116)
			(xy 333.768859 -392.449268) (xy 333.812051 -392.429396) (xy 333.857643 -392.41591) (xy 333.904694 -392.409088)
			(xy 333.928466 -392.408664) (xy 333.92872 -392.408664) (xy 333.954708 -392.409175) (xy 334.006045 -392.417309)
			(xy 334.055477 -392.433373) (xy 334.101787 -392.456972) (xy 334.143836 -392.487525) (xy 334.180588 -392.524279)
			(xy 334.211139 -392.56633) (xy 334.234735 -392.612642) (xy 334.250796 -392.662075) (xy 334.258926 -392.713412)
			(xy 334.258926 -392.765388) (xy 334.250796 -392.816725) (xy 334.234735 -392.866158) (xy 334.211139 -392.91247)
			(xy 334.180588 -392.954521) (xy 334.143836 -392.991275) (xy 334.101787 -393.021828) (xy 334.094171 -393.025709)
			(xy 335.659732 -393.025709) (xy 335.659732 -392.973735) (xy 335.667862 -392.9224) (xy 335.683923 -392.87297)
			(xy 335.707519 -392.82666) (xy 335.738069 -392.784612) (xy 335.77482 -392.747861) (xy 335.816868 -392.717311)
			(xy 335.863178 -392.693715) (xy 335.912608 -392.677654) (xy 335.963943 -392.669524) (xy 336.015917 -392.669524)
			(xy 336.067252 -392.677654) (xy 336.116682 -392.693715) (xy 336.162992 -392.717311) (xy 336.20504 -392.747861)
			(xy 336.241791 -392.784612) (xy 336.272341 -392.82666) (xy 336.295937 -392.87297) (xy 336.311998 -392.9224)
			(xy 336.320128 -392.973735) (xy 336.320638 -392.999722) (xy 336.320128 -393.025709) (xy 336.311998 -393.077044)
			(xy 336.295937 -393.126474) (xy 336.272341 -393.172784) (xy 336.241791 -393.214832) (xy 336.20504 -393.251583)
			(xy 336.162992 -393.282133) (xy 336.116682 -393.305729) (xy 336.067252 -393.32179) (xy 336.015917 -393.32992)
			(xy 335.963943 -393.32992) (xy 335.912608 -393.32179) (xy 335.863178 -393.305729) (xy 335.816868 -393.282133)
			(xy 335.77482 -393.251583) (xy 335.738069 -393.214832) (xy 335.707519 -393.172784) (xy 335.683923 -393.126474)
			(xy 335.667862 -393.077044) (xy 335.659732 -393.025709) (xy 334.094171 -393.025709) (xy 334.055477 -393.045427)
			(xy 334.006045 -393.061491) (xy 333.954708 -393.069625) (xy 333.92872 -393.07008) (xy 333.928466 -393.07008)
			(xy 333.904692 -393.069672) (xy 333.857633 -393.062867) (xy 333.812035 -393.049388) (xy 333.768839 -393.029513)
			(xy 333.728937 -393.003653) (xy 333.710788 -392.988292) (xy 333.699358 -392.978386) (xy 333.670148 -392.974068)
			(xy 333.572358 -393.018264) (xy 333.565246 -393.022074) (xy 333.555017 -393.029639) (xy 333.543021 -393.052038)
			(xy 333.542386 -393.064746) (xy 333.542386 -393.630658) (xy 333.564484 -393.658344) (xy 333.581756 -393.662408)
			(xy 333.607135 -393.668781) (xy 333.655627 -393.688438) (xy 333.700419 -393.715484) (xy 333.740394 -393.749245)
			(xy 333.774556 -393.788878) (xy 333.802052 -393.833395) (xy 333.822197 -393.881686) (xy 333.834488 -393.932547)
			(xy 333.838619 -393.984708) (xy 333.834486 -394.036868) (xy 333.822192 -394.087728) (xy 333.802045 -394.136018)
			(xy 333.774547 -394.180534) (xy 333.740383 -394.220166) (xy 333.700406 -394.253925) (xy 333.655613 -394.280969)
			(xy 333.60712 -394.300624) (xy 333.581756 -394.30706) (xy 333.564484 -394.311124) (xy 333.542386 -394.33881)
			(xy 333.542386 -394.44041) (xy 333.542843 -394.449919) (xy 333.549752 -394.467641) (xy 333.555848 -394.474954)
			(xy 333.60233 -394.5255) (xy 333.609112 -394.532267) (xy 333.626346 -394.5406) (xy 333.635858 -394.541756)
			(xy 333.660393 -394.544198) (xy 333.7084 -394.555427) (xy 333.754208 -394.57366) (xy 333.7968 -394.598494)
			(xy 333.835232 -394.629378) (xy 333.868651 -394.665626) (xy 333.896317 -394.706436) (xy 333.917616 -394.750901)
			(xy 333.932076 -394.798036) (xy 333.939376 -394.846796) (xy 333.939896 -394.871448) (xy 333.939342 -394.898734)
			(xy 333.930396 -394.952569) (xy 333.912738 -395.004206) (xy 333.886847 -395.052245) (xy 333.870554 -395.07414)
			(xy 333.8703 -395.074394) (xy 333.869792 -395.075156) (xy 333.864828 -395.082393) (xy 333.859643 -395.099146)
			(xy 333.859632 -395.107922) (xy 333.862172 -395.173454) (xy 333.862498 -395.177968) (xy 333.864547 -395.186782)
			(xy 333.866236 -395.19098) (xy 333.869538 -395.198854) (xy 333.875634 -395.205712) (xy 333.875888 -395.205966)
			(xy 333.892221 -395.224365) (xy 333.919818 -395.265092) (xy 333.941071 -395.309461) (xy 333.955509 -395.356491)
			(xy 333.962814 -395.405142) (xy 333.963264 -395.42974) (xy 333.962785 -395.455298) (xy 333.954918 -395.505806)
			(xy 333.939376 -395.554503) (xy 333.916529 -395.60023) (xy 333.886921 -395.641899) (xy 333.851258 -395.678519)
			(xy 333.810386 -395.709219) (xy 333.765279 -395.733267) (xy 333.717011 -395.750092) (xy 333.666729 -395.759293)
			(xy 333.641192 -395.760448) (xy 333.631286 -395.760702) (xy 333.613252 -395.768576) (xy 333.556864 -395.826488)
			(xy 333.550285 -395.83387) (xy 333.542845 -395.85217) (xy 333.542386 -395.862048) (xy 333.542386 -396.245842)
			(xy 333.54285 -396.255717) (xy 333.550298 -396.274011) (xy 333.556864 -396.281402) (xy 333.613252 -396.339314)
			(xy 333.631286 -396.347188) (xy 333.641192 -396.347442) (xy 333.666734 -396.348582) (xy 333.71703 -396.357758)
			(xy 333.765315 -396.374564) (xy 333.810439 -396.3986) (xy 333.851328 -396.429292) (xy 333.887007 -396.46591)
			(xy 333.916626 -396.507582) (xy 333.939481 -396.553316) (xy 333.955027 -396.602021) (xy 333.962893 -396.652538)
			(xy 333.962893 -396.703664) (xy 333.955026 -396.754182) (xy 333.93948 -396.802887) (xy 333.916625 -396.84862)
			(xy 333.887005 -396.890292) (xy 333.851326 -396.92691) (xy 333.810437 -396.957602) (xy 333.765313 -396.981637)
			(xy 333.717027 -396.998442) (xy 333.666731 -397.007618) (xy 333.641192 -397.008858) (xy 333.631286 -397.009112)
			(xy 333.613252 -397.016986) (xy 333.556864 -397.074898) (xy 333.550287 -397.082281) (xy 333.54285 -397.10058)
			(xy 333.542386 -397.110458) (xy 333.542386 -398.017492) (xy 333.542822 -398.027188) (xy 333.550011 -398.045199)
			(xy 333.556356 -398.052544) (xy 333.61122 -398.110456) (xy 333.628746 -398.118584) (xy 333.638652 -398.119092)
			(xy 333.663682 -398.120911) (xy 333.712808 -398.131161) (xy 333.759821 -398.148715) (xy 333.803642 -398.173171)
			(xy 333.843264 -398.203968) (xy 333.877779 -398.240398) (xy 333.906392 -398.281625) (xy 333.928448 -398.326701)
			(xy 333.943441 -398.374593) (xy 333.951024 -398.4242) (xy 333.95158 -398.449292) (xy 333.951187 -398.472526)
			(xy 333.944685 -398.518536) (xy 333.931807 -398.563184) (xy 333.912808 -398.60559) (xy 333.88806 -398.64492)
			(xy 333.873348 -398.662906) (xy 333.867506 -398.669764) (xy 333.861156 -398.686782) (xy 333.861156 -398.770602)
			(xy 333.867506 -398.78762) (xy 333.873348 -398.794478) (xy 333.888054 -398.812469) (xy 333.912805 -398.851795)
			(xy 333.931805 -398.8942) (xy 333.944679 -398.938848) (xy 333.951174 -398.984858) (xy 333.95158 -399.008092)
			(xy 333.951115 -399.033189) (xy 333.94353 -399.082806) (xy 333.928534 -399.130707) (xy 333.906471 -399.175791)
			(xy 333.877848 -399.217023) (xy 333.843322 -399.253456) (xy 333.803687 -399.284252) (xy 333.759853 -399.308705)
			(xy 333.712826 -399.326252) (xy 333.663688 -399.336491) (xy 333.638652 -399.338292) (xy 333.628746 -399.3388)
			(xy 333.61122 -399.346928) (xy 333.556356 -399.40484) (xy 333.549975 -399.412162) (xy 333.542796 -399.430188)
			(xy 333.542386 -399.439892) (xy 333.542386 -400.183937) (xy 334.692246 -400.183937) (xy 334.692246 -400.131963)
			(xy 334.700376 -400.080628) (xy 334.716437 -400.031198) (xy 334.740033 -399.984888) (xy 334.770583 -399.94284)
			(xy 334.807334 -399.906089) (xy 334.849382 -399.875539) (xy 334.895692 -399.851943) (xy 334.945122 -399.835882)
			(xy 334.996457 -399.827752) (xy 335.048431 -399.827752) (xy 335.099766 -399.835882) (xy 335.149196 -399.851943)
			(xy 335.195506 -399.875539) (xy 335.237554 -399.906089) (xy 335.274305 -399.94284) (xy 335.304855 -399.984888)
			(xy 335.328451 -400.031198) (xy 335.344512 -400.080628) (xy 335.352642 -400.131963) (xy 335.353152 -400.15795)
			(xy 335.352642 -400.183937) (xy 335.344512 -400.235272) (xy 335.328451 -400.284702) (xy 335.304855 -400.331012)
			(xy 335.274305 -400.37306) (xy 335.237554 -400.409811) (xy 335.195506 -400.440361) (xy 335.149196 -400.463957)
			(xy 335.099766 -400.480018) (xy 335.048431 -400.488148) (xy 334.996457 -400.488148) (xy 334.945122 -400.480018)
			(xy 334.895692 -400.463957) (xy 334.849382 -400.440361) (xy 334.807334 -400.409811) (xy 334.770583 -400.37306)
			(xy 334.740033 -400.331012) (xy 334.716437 -400.284702) (xy 334.700376 -400.235272) (xy 334.692246 -400.183937)
			(xy 333.542386 -400.183937) (xy 333.542386 -400.360642) (xy 333.542816 -400.370709) (xy 333.55054 -400.389304)
			(xy 333.557372 -400.39671) (xy 334.306164 -401.145502) (xy 334.313566 -401.152338) (xy 334.332164 -401.160049)
			(xy 334.342232 -401.160488)
		)
		(stroke
			(width 0)
			(type solid)
		)
		(fill yes)
		(layer "In4.Cu")
		(net "NCF_CPU0_P1_GND")
	)
	(gr_poly
		(pts
			(xy 465.017612 -82.026506) (xy 465.025132 -82.024908) (xy 465.038825 -82.017936) (xy 465.044536 -82.01279)
			(xy 469.73109 -77.326236) (xy 469.737927 -77.318834) (xy 469.74564 -77.300236) (xy 469.746076 -77.290168)
			(xy 469.746076 -44.657264) (xy 469.745646 -44.647197) (xy 469.737919 -44.628604) (xy 469.73109 -44.621196)
			(xy 468.734394 -43.6245) (xy 468.727282 -43.617134) (xy 468.708486 -43.609514) (xy 459.74762 -43.609514)
			(xy 459.741524 -43.609768) (xy 459.73702 -43.610404) (xy 459.728329 -43.613085) (xy 459.724252 -43.615102)
			(xy 459.705202 -43.624754) (xy 459.696058 -43.63085) (xy 459.691994 -43.634152) (xy 459.688438 -43.63847)
			(xy 459.688184 -43.638724) (xy 459.68666 -43.640756) (xy 459.668436 -43.662458) (xy 459.62667 -43.700757)
			(xy 459.579699 -43.732459) (xy 459.528557 -43.756866) (xy 459.474367 -43.773442) (xy 459.418322 -43.781822)
			(xy 459.361654 -43.781822) (xy 459.305609 -43.773442) (xy 459.251419 -43.756866) (xy 459.200277 -43.732459)
			(xy 459.153306 -43.700757) (xy 459.11154 -43.662458) (xy 459.093316 -43.640756) (xy 459.091792 -43.638724)
			(xy 459.091538 -43.63847) (xy 459.087982 -43.634152) (xy 459.083918 -43.63085) (xy 459.074774 -43.624754)
			(xy 459.055724 -43.615102) (xy 459.05164 -43.6131) (xy 459.042954 -43.610409) (xy 459.038452 -43.609768)
			(xy 459.03261 -43.609514) (xy 442.587888 -43.609514) (xy 442.577819 -43.60994) (xy 442.559219 -43.617659)
			(xy 442.55182 -43.6245) (xy 441.665106 -44.511214) (xy 461.600294 -44.511214) (xy 461.604365 -44.455592)
			(xy 461.616491 -44.401155) (xy 461.636414 -44.349064) (xy 461.66371 -44.300429) (xy 461.697796 -44.256286)
			(xy 461.737945 -44.217577) (xy 461.783303 -44.185126) (xy 461.832903 -44.159625) (xy 461.885687 -44.141618)
			(xy 461.94053 -44.131488) (xy 461.996264 -44.129451) (xy 462.051701 -44.135551) (xy 462.105658 -44.149657)
			(xy 462.156987 -44.171469) (xy 462.204593 -44.200523) (xy 462.247461 -44.236198) (xy 462.284678 -44.277735)
			(xy 462.315451 -44.324248) (xy 462.339123 -44.374745) (xy 462.355191 -44.428152) (xy 462.363311 -44.483328)
			(xy 462.36382 -44.511214) (xy 462.363311 -44.5391) (xy 462.355191 -44.594276) (xy 462.339123 -44.647683)
			(xy 462.315451 -44.69818) (xy 462.284678 -44.744693) (xy 462.247461 -44.78623) (xy 462.204593 -44.821905)
			(xy 462.156987 -44.850959) (xy 462.105658 -44.872771) (xy 462.051701 -44.886877) (xy 461.996264 -44.892977)
			(xy 461.94053 -44.89094) (xy 461.885687 -44.88081) (xy 461.832903 -44.862803) (xy 461.783303 -44.837302)
			(xy 461.737945 -44.804851) (xy 461.697796 -44.766142) (xy 461.66371 -44.721999) (xy 461.636414 -44.673364)
			(xy 461.616491 -44.621273) (xy 461.604365 -44.566836) (xy 461.600294 -44.511214) (xy 441.665106 -44.511214)
			(xy 441.477146 -44.699174) (xy 441.469746 -44.706015) (xy 441.451147 -44.713733) (xy 441.441078 -44.71416)
			(xy 434.864002 -44.71416) (xy 434.853933 -44.714584) (xy 434.835334 -44.722305) (xy 434.827934 -44.729146)
			(xy 430.143666 -49.413414) (xy 430.1363 -49.420526) (xy 430.12868 -49.439322) (xy 430.12868 -50.489796)
			(xy 431.237386 -50.489796) (xy 431.237386 -50.4051) (xy 431.245437 -50.320786) (xy 431.261466 -50.23762)
			(xy 431.285327 -50.156353) (xy 431.316806 -50.077723) (xy 431.355617 -50.002442) (xy 431.401407 -49.93119)
			(xy 431.453763 -49.864614) (xy 431.512211 -49.803316) (xy 431.576221 -49.747851) (xy 431.645213 -49.698722)
			(xy 431.718563 -49.656373) (xy 431.795606 -49.621189) (xy 431.875645 -49.593487) (xy 431.957954 -49.573519)
			(xy 432.041789 -49.561466) (xy 432.12639 -49.557436) (xy 432.210991 -49.561466) (xy 432.294826 -49.573519)
			(xy 432.377135 -49.593487) (xy 432.457174 -49.621189) (xy 432.534217 -49.656373) (xy 432.607567 -49.698722)
			(xy 432.676559 -49.747851) (xy 432.740569 -49.803316) (xy 432.799017 -49.864614) (xy 432.851373 -49.93119)
			(xy 432.897163 -50.002442) (xy 432.935974 -50.077723) (xy 432.967453 -50.156353) (xy 432.991314 -50.23762)
			(xy 433.007343 -50.320786) (xy 433.015394 -50.4051) (xy 433.015898 -50.447448) (xy 433.015394 -50.489796)
			(xy 438.952636 -50.489796) (xy 438.952636 -50.4051) (xy 438.960687 -50.320786) (xy 438.976716 -50.23762)
			(xy 439.000577 -50.156353) (xy 439.032056 -50.077723) (xy 439.070867 -50.002442) (xy 439.116657 -49.93119)
			(xy 439.169013 -49.864614) (xy 439.227461 -49.803316) (xy 439.291471 -49.747851) (xy 439.360463 -49.698722)
			(xy 439.433813 -49.656373) (xy 439.510856 -49.621189) (xy 439.590895 -49.593487) (xy 439.673204 -49.573519)
			(xy 439.757039 -49.561466) (xy 439.84164 -49.557436) (xy 439.926241 -49.561466) (xy 440.010076 -49.573519)
			(xy 440.092385 -49.593487) (xy 440.172424 -49.621189) (xy 440.249467 -49.656373) (xy 440.322817 -49.698722)
			(xy 440.391809 -49.747851) (xy 440.455819 -49.803316) (xy 440.514267 -49.864614) (xy 440.566623 -49.93119)
			(xy 440.612413 -50.002442) (xy 440.651224 -50.077723) (xy 440.682703 -50.156353) (xy 440.706564 -50.23762)
			(xy 440.722593 -50.320786) (xy 440.730644 -50.4051) (xy 440.731148 -50.447448) (xy 440.730644 -50.489796)
			(xy 440.722593 -50.57411) (xy 440.706564 -50.657276) (xy 440.682703 -50.738543) (xy 440.651224 -50.817173)
			(xy 440.612413 -50.892454) (xy 440.566623 -50.963706) (xy 440.514267 -51.030282) (xy 440.455819 -51.09158)
			(xy 440.391809 -51.147045) (xy 440.322817 -51.196174) (xy 440.249467 -51.238523) (xy 440.172424 -51.273707)
			(xy 440.092385 -51.301409) (xy 440.010076 -51.321377) (xy 439.926241 -51.33343) (xy 439.84164 -51.337461)
			(xy 439.757039 -51.33343) (xy 439.673204 -51.321377) (xy 439.590895 -51.301409) (xy 439.510856 -51.273707)
			(xy 439.433813 -51.238523) (xy 439.360463 -51.196174) (xy 439.291471 -51.147045) (xy 439.227461 -51.09158)
			(xy 439.169013 -51.030282) (xy 439.116657 -50.963706) (xy 439.070867 -50.892454) (xy 439.032056 -50.817173)
			(xy 439.000577 -50.738543) (xy 438.976716 -50.657276) (xy 438.960687 -50.57411) (xy 438.952636 -50.489796)
			(xy 433.015394 -50.489796) (xy 433.007343 -50.57411) (xy 432.991314 -50.657276) (xy 432.967453 -50.738543)
			(xy 432.935974 -50.817173) (xy 432.897163 -50.892454) (xy 432.851373 -50.963706) (xy 432.799017 -51.030282)
			(xy 432.740569 -51.09158) (xy 432.676559 -51.147045) (xy 432.607567 -51.196174) (xy 432.534217 -51.238523)
			(xy 432.457174 -51.273707) (xy 432.377135 -51.301409) (xy 432.294826 -51.321377) (xy 432.210991 -51.33343)
			(xy 432.12639 -51.337461) (xy 432.041789 -51.33343) (xy 431.957954 -51.321377) (xy 431.875645 -51.301409)
			(xy 431.795606 -51.273707) (xy 431.718563 -51.238523) (xy 431.645213 -51.196174) (xy 431.576221 -51.147045)
			(xy 431.512211 -51.09158) (xy 431.453763 -51.030282) (xy 431.401407 -50.963706) (xy 431.355617 -50.892454)
			(xy 431.316806 -50.817173) (xy 431.285327 -50.738543) (xy 431.261466 -50.657276) (xy 431.245437 -50.57411)
			(xy 431.237386 -50.489796) (xy 430.12868 -50.489796) (xy 430.12868 -52.989918) (xy 431.237386 -52.989918)
			(xy 431.237386 -52.905222) (xy 431.245437 -52.820908) (xy 431.261466 -52.737742) (xy 431.285327 -52.656475)
			(xy 431.316806 -52.577845) (xy 431.355617 -52.502564) (xy 431.401407 -52.431312) (xy 431.453763 -52.364736)
			(xy 431.512211 -52.303438) (xy 431.576221 -52.247973) (xy 431.645213 -52.198844) (xy 431.718563 -52.156495)
			(xy 431.795606 -52.121311) (xy 431.875645 -52.093609) (xy 431.957954 -52.073641) (xy 432.041789 -52.061588)
			(xy 432.12639 -52.057558) (xy 432.210991 -52.061588) (xy 432.294826 -52.073641) (xy 432.377135 -52.093609)
			(xy 432.457174 -52.121311) (xy 432.534217 -52.156495) (xy 432.607567 -52.198844) (xy 432.676559 -52.247973)
			(xy 432.740569 -52.303438) (xy 432.799017 -52.364736) (xy 432.851373 -52.431312) (xy 432.897163 -52.502564)
			(xy 432.935974 -52.577845) (xy 432.967453 -52.656475) (xy 432.991314 -52.737742) (xy 433.007343 -52.820908)
			(xy 433.015394 -52.905222) (xy 433.015898 -52.94757) (xy 433.015394 -52.989918) (xy 438.952636 -52.989918)
			(xy 438.952636 -52.905222) (xy 438.960687 -52.820908) (xy 438.976716 -52.737742) (xy 439.000577 -52.656475)
			(xy 439.032056 -52.577845) (xy 439.070867 -52.502564) (xy 439.116657 -52.431312) (xy 439.169013 -52.364736)
			(xy 439.227461 -52.303438) (xy 439.291471 -52.247973) (xy 439.360463 -52.198844) (xy 439.433813 -52.156495)
			(xy 439.510856 -52.121311) (xy 439.590895 -52.093609) (xy 439.673204 -52.073641) (xy 439.757039 -52.061588)
			(xy 439.84164 -52.057558) (xy 439.926241 -52.061588) (xy 440.010076 -52.073641) (xy 440.092385 -52.093609)
			(xy 440.172424 -52.121311) (xy 440.249467 -52.156495) (xy 440.322817 -52.198844) (xy 440.391809 -52.247973)
			(xy 440.455819 -52.303438) (xy 440.514267 -52.364736) (xy 440.566623 -52.431312) (xy 440.612413 -52.502564)
			(xy 440.651224 -52.577845) (xy 440.682703 -52.656475) (xy 440.706564 -52.737742) (xy 440.722593 -52.820908)
			(xy 440.730644 -52.905222) (xy 440.731148 -52.94757) (xy 440.730644 -52.989918) (xy 440.722593 -53.074232)
			(xy 440.706564 -53.157398) (xy 440.682703 -53.238665) (xy 440.651224 -53.317295) (xy 440.612413 -53.392576)
			(xy 440.566623 -53.463828) (xy 440.514267 -53.530404) (xy 440.455819 -53.591702) (xy 440.391809 -53.647167)
			(xy 440.322817 -53.696296) (xy 440.249467 -53.738645) (xy 440.172424 -53.773829) (xy 440.092385 -53.801531)
			(xy 440.010076 -53.821499) (xy 439.926241 -53.833552) (xy 439.84164 -53.837583) (xy 439.757039 -53.833552)
			(xy 439.673204 -53.821499) (xy 439.590895 -53.801531) (xy 439.510856 -53.773829) (xy 439.433813 -53.738645)
			(xy 439.360463 -53.696296) (xy 439.291471 -53.647167) (xy 439.227461 -53.591702) (xy 439.169013 -53.530404)
			(xy 439.116657 -53.463828) (xy 439.070867 -53.392576) (xy 439.032056 -53.317295) (xy 439.000577 -53.238665)
			(xy 438.976716 -53.157398) (xy 438.960687 -53.074232) (xy 438.952636 -52.989918) (xy 433.015394 -52.989918)
			(xy 433.007343 -53.074232) (xy 432.991314 -53.157398) (xy 432.967453 -53.238665) (xy 432.935974 -53.317295)
			(xy 432.897163 -53.392576) (xy 432.851373 -53.463828) (xy 432.799017 -53.530404) (xy 432.740569 -53.591702)
			(xy 432.676559 -53.647167) (xy 432.607567 -53.696296) (xy 432.534217 -53.738645) (xy 432.457174 -53.773829)
			(xy 432.377135 -53.801531) (xy 432.294826 -53.821499) (xy 432.210991 -53.833552) (xy 432.12639 -53.837583)
			(xy 432.041789 -53.833552) (xy 431.957954 -53.821499) (xy 431.875645 -53.801531) (xy 431.795606 -53.773829)
			(xy 431.718563 -53.738645) (xy 431.645213 -53.696296) (xy 431.576221 -53.647167) (xy 431.512211 -53.591702)
			(xy 431.453763 -53.530404) (xy 431.401407 -53.463828) (xy 431.355617 -53.392576) (xy 431.316806 -53.317295)
			(xy 431.285327 -53.238665) (xy 431.261466 -53.157398) (xy 431.245437 -53.074232) (xy 431.237386 -52.989918)
			(xy 430.12868 -52.989918) (xy 430.12868 -53.250338) (xy 430.129109 -53.260406) (xy 430.136831 -53.279002)
			(xy 430.143666 -53.286406) (xy 440.307222 -63.449962) (xy 440.314067 -63.45736) (xy 440.321791 -63.475959)
			(xy 440.322208 -63.48603) (xy 440.322208 -74.241914) (xy 440.322517 -74.250401) (xy 440.328071 -74.266438)
			(xy 440.338591 -74.279756) (xy 440.345576 -74.284586) (xy 440.359915 -74.294041) (xy 440.387006 -74.315156)
			(xy 440.399678 -74.32675) (xy 440.407075 -74.333107) (xy 440.425236 -74.340172) (xy 440.434984 -74.340466)
			(xy 440.515248 -74.339704) (xy 440.533536 -74.33183) (xy 440.540648 -74.324718) (xy 440.567064 -74.300588)
			(xy 440.571382 -74.297032) (xy 440.577732 -74.288904) (xy 440.58967 -74.265028) (xy 440.592047 -74.259749)
			(xy 440.594613 -74.248463) (xy 440.59475 -74.242676) (xy 440.59475 -74.18578) (xy 440.594622 -74.179991)
			(xy 440.592055 -74.168704) (xy 440.58967 -74.163428) (xy 440.580526 -74.14514) (xy 440.57862 -74.141438)
			(xy 440.573772 -74.134668) (xy 440.570874 -74.131678) (xy 440.56681 -74.127614) (xy 440.565032 -74.12609)
			(xy 440.544003 -74.107852) (xy 440.506936 -74.066328) (xy 440.476289 -74.019862) (xy 440.452712 -73.96944)
			(xy 440.436705 -73.916129) (xy 440.428606 -73.861059) (xy 440.428126 -73.833228) (xy 440.428587 -73.805975)
			(xy 440.436341 -73.752023) (xy 440.451695 -73.699723) (xy 440.474337 -73.650142) (xy 440.503804 -73.604288)
			(xy 440.539499 -73.563094) (xy 440.580692 -73.527401) (xy 440.626547 -73.497934) (xy 440.676129 -73.475293)
			(xy 440.728428 -73.45994) (xy 440.782381 -73.452187) (xy 440.809634 -73.45172) (xy 440.810142 -73.45172)
			(xy 440.835733 -73.45215) (xy 440.886452 -73.459029) (xy 440.935794 -73.472632) (xy 440.982873 -73.492714)
			(xy 441.026842 -73.518913) (xy 441.047124 -73.534524) (xy 441.053982 -73.540112) (xy 441.06973 -73.5457)
			(xy 441.10021 -73.5457) (xy 441.105713 -73.545826) (xy 441.116471 -73.548139) (xy 441.121546 -73.550272)
			(xy 441.135516 -73.556876) (xy 441.144503 -73.560566) (xy 441.163887 -73.561574) (xy 441.182248 -73.555276)
			(xy 441.189872 -73.549256) (xy 441.19546 -73.54443) (xy 441.215746 -73.52752) (xy 441.260109 -73.498869)
			(xy 441.308001 -73.476612) (xy 441.358506 -73.461176) (xy 441.410657 -73.452855) (xy 441.463458 -73.45181)
			(xy 441.515898 -73.458059) (xy 441.566974 -73.471484) (xy 441.61571 -73.491827) (xy 441.661173 -73.5187)
			(xy 441.682124 -73.534778) (xy 441.688982 -73.540112) (xy 441.70473 -73.5457) (xy 441.73521 -73.5457)
			(xy 441.740713 -73.545826) (xy 441.751471 -73.548139) (xy 441.756546 -73.550272) (xy 441.770516 -73.556876)
			(xy 441.779503 -73.560566) (xy 441.798887 -73.561574) (xy 441.817248 -73.555276) (xy 441.824872 -73.549256)
			(xy 441.83046 -73.54443) (xy 441.850746 -73.52752) (xy 441.895109 -73.498869) (xy 441.943001 -73.476612)
			(xy 441.993506 -73.461176) (xy 442.045657 -73.452855) (xy 442.098458 -73.45181) (xy 442.150898 -73.458059)
			(xy 442.201974 -73.471484) (xy 442.25071 -73.491827) (xy 442.296173 -73.5187) (xy 442.317124 -73.534778)
			(xy 442.323982 -73.540112) (xy 442.33973 -73.5457) (xy 442.37021 -73.5457) (xy 442.375713 -73.545826)
			(xy 442.386471 -73.548139) (xy 442.391546 -73.550272) (xy 442.405516 -73.556876) (xy 442.414503 -73.560566)
			(xy 442.433887 -73.561574) (xy 442.452248 -73.555276) (xy 442.459872 -73.549256) (xy 442.46546 -73.54443)
			(xy 442.486338 -73.527039) (xy 442.532089 -73.497726) (xy 442.581537 -73.475203) (xy 442.633681 -73.459926)
			(xy 442.687466 -73.452205) (xy 442.714634 -73.45172) (xy 442.74476 -73.452284) (xy 442.804264 -73.461747)
			(xy 442.86154 -73.480449) (xy 442.915162 -73.507924) (xy 442.963798 -73.543489) (xy 442.985398 -73.564496)
			(xy 442.992796 -73.571343) (xy 443.011394 -73.579079) (xy 443.021466 -73.579482) (xy 443.093602 -73.579482)
			(xy 443.103672 -73.579058) (xy 443.122274 -73.571341) (xy 443.12967 -73.564496) (xy 443.151296 -73.54352)
			(xy 443.199932 -73.507969) (xy 443.25355 -73.4805) (xy 443.310817 -73.461796) (xy 443.370312 -73.452321)
			(xy 443.400434 -73.45172) (xy 443.429998 -73.452314) (xy 443.488411 -73.461503) (xy 443.544711 -73.479578)
			(xy 443.571376 -73.49236) (xy 443.582298 -73.496424) (xy 443.588902 -73.497948) (xy 443.617096 -73.497948)
			(xy 443.621232 -73.497915) (xy 443.629403 -73.496639) (xy 443.633352 -73.495408) (xy 443.643512 -73.490582)
			(xy 443.707774 -73.451974) (xy 443.715047 -73.447157) (xy 443.726083 -73.433661) (xy 443.73198 -73.417255)
			(xy 443.732412 -73.40854) (xy 443.732412 -73.251822) (xy 443.731975 -73.241758) (xy 443.724242 -73.223173)
			(xy 443.717426 -73.215754) (xy 443.330076 -72.828404) (xy 443.32398 -72.822054) (xy 443.308994 -72.807068)
			(xy 443.253622 -72.751442) (xy 443.246818 -72.744095) (xy 443.239103 -72.725632) (xy 443.238636 -72.715628)
			(xy 443.238636 -52.469542) (xy 443.239167 -52.459552) (xy 443.246874 -52.441112) (xy 443.253622 -52.433728)
			(xy 445.63792 -50.04943) (xy 445.645265 -50.042619) (xy 445.663728 -50.034889) (xy 445.673734 -50.034444)
			(xy 446.69964 -50.034444) (xy 446.709706 -50.034012) (xy 446.728294 -50.026281) (xy 446.735708 -50.019458)
			(xy 451.02272 -45.732446) (xy 451.02653 -45.697394) (xy 451.017132 -45.682154) (xy 451.003231 -45.659235)
			(xy 450.981296 -45.610327) (xy 450.96643 -45.558829) (xy 450.958926 -45.505755) (xy 450.958458 -45.478954)
			(xy 450.958944 -45.451685) (xy 450.966706 -45.397701) (xy 450.982071 -45.345371) (xy 451.004728 -45.295761)
			(xy 451.034214 -45.24988) (xy 451.069929 -45.208663) (xy 451.111146 -45.172948) (xy 451.157027 -45.143462)
			(xy 451.206637 -45.120805) (xy 451.258967 -45.10544) (xy 451.312951 -45.097678) (xy 451.367489 -45.097678)
			(xy 451.421473 -45.10544) (xy 451.473803 -45.120805) (xy 451.523413 -45.143462) (xy 451.569294 -45.172948)
			(xy 451.610511 -45.208663) (xy 451.646226 -45.24988) (xy 451.675712 -45.295761) (xy 451.698369 -45.345371)
			(xy 451.713734 -45.397701) (xy 451.721496 -45.451685) (xy 451.721982 -45.478954) (xy 451.721516 -45.506315)
			(xy 451.713711 -45.560477) (xy 451.711016 -45.569632) (xy 451.973694 -45.569632) (xy 451.977767 -45.513973)
			(xy 451.989902 -45.4595) (xy 452.009838 -45.407374) (xy 452.037152 -45.358706) (xy 452.07126 -45.314534)
			(xy 452.111437 -45.275799) (xy 452.156825 -45.243327) (xy 452.206457 -45.217809) (xy 452.259277 -45.19979)
			(xy 452.314156 -45.189653) (xy 452.369927 -45.187615) (xy 452.425401 -45.193718) (xy 452.479394 -45.207834)
			(xy 452.530757 -45.229661) (xy 452.536363 -45.233082) (xy 455.152758 -45.233082) (xy 455.156829 -45.17746)
			(xy 455.168955 -45.123023) (xy 455.188878 -45.070932) (xy 455.216174 -45.022297) (xy 455.25026 -44.978154)
			(xy 455.290409 -44.939445) (xy 455.335767 -44.906994) (xy 455.385367 -44.881493) (xy 455.438151 -44.863486)
			(xy 455.492994 -44.853356) (xy 455.548728 -44.851319) (xy 455.604165 -44.857419) (xy 455.658122 -44.871525)
			(xy 455.709451 -44.893337) (xy 455.757057 -44.922391) (xy 455.799925 -44.958066) (xy 455.837142 -44.999603)
			(xy 455.8481 -45.016166) (xy 456.958954 -45.016166) (xy 456.959393 -44.988895) (xy 456.96716 -44.934909)
			(xy 456.98253 -44.882578) (xy 457.005191 -44.832966) (xy 457.034682 -44.787085) (xy 457.070402 -44.745867)
			(xy 457.111625 -44.710152) (xy 457.15751 -44.680667) (xy 457.207124 -44.658013) (xy 457.259458 -44.642649)
			(xy 457.313445 -44.634889) (xy 457.340716 -44.634404) (xy 457.367369 -44.634903) (xy 457.420157 -44.642328)
			(xy 457.4714 -44.657017) (xy 457.520104 -44.678684) (xy 457.565325 -44.706911) (xy 457.606184 -44.741148)
			(xy 457.641888 -44.780731) (xy 457.6572 -44.802552) (xy 457.678056 -44.824179) (xy 457.713387 -44.872771)
			(xy 457.740677 -44.926294) (xy 457.759252 -44.98343) (xy 457.768655 -45.042768) (xy 457.769214 -45.072808)
			(xy 457.769105 -45.085804) (xy 457.767325 -45.111735) (xy 457.765658 -45.124624) (xy 457.767201 -45.137012)
			(xy 457.768853 -45.161925) (xy 457.76896 -45.174408) (xy 457.768552 -45.201663) (xy 457.760793 -45.255619)
			(xy 457.745433 -45.30792) (xy 457.722786 -45.357504) (xy 457.693313 -45.403359) (xy 457.657613 -45.444553)
			(xy 457.616414 -45.480247) (xy 457.570555 -45.509713) (xy 457.520968 -45.532353) (xy 457.468664 -45.547705)
			(xy 457.414707 -45.555456) (xy 457.387452 -45.555916) (xy 457.358822 -45.555468) (xy 457.302207 -45.54689)
			(xy 457.24751 -45.52995) (xy 457.195958 -45.505027) (xy 457.148708 -45.472681) (xy 457.106822 -45.433639)
			(xy 457.07124 -45.388776) (xy 457.04276 -45.339101) (xy 457.022022 -45.285727) (xy 457.009492 -45.229855)
			(xy 457.00696 -45.201332) (xy 456.991919 -45.172804) (xy 456.970532 -45.111969) (xy 456.959653 -45.048408)
			(xy 456.958954 -45.016166) (xy 455.8481 -45.016166) (xy 455.867915 -45.046116) (xy 455.891587 -45.096613)
			(xy 455.907655 -45.15002) (xy 455.915775 -45.205196) (xy 455.916284 -45.233082) (xy 455.915775 -45.260968)
			(xy 455.907655 -45.316144) (xy 455.891587 -45.369551) (xy 455.867915 -45.420048) (xy 455.837142 -45.466561)
			(xy 455.799925 -45.508098) (xy 455.757057 -45.543773) (xy 455.709451 -45.572827) (xy 455.658122 -45.594639)
			(xy 455.604165 -45.608745) (xy 455.548728 -45.614845) (xy 455.492994 -45.612808) (xy 455.438151 -45.602678)
			(xy 455.385367 -45.584671) (xy 455.335767 -45.55917) (xy 455.290409 -45.526719) (xy 455.25026 -45.48801)
			(xy 455.216174 -45.443867) (xy 455.188878 -45.395232) (xy 455.168955 -45.343141) (xy 455.156829 -45.288704)
			(xy 455.152758 -45.233082) (xy 452.536363 -45.233082) (xy 452.578395 -45.258734) (xy 452.621291 -45.294433)
			(xy 452.658533 -45.335997) (xy 452.689327 -45.382541) (xy 452.713015 -45.433072) (xy 452.729093 -45.486514)
			(xy 452.737219 -45.541728) (xy 452.737728 -45.569632) (xy 452.737219 -45.597536) (xy 452.729093 -45.65275)
			(xy 452.713015 -45.706192) (xy 452.689327 -45.756723) (xy 452.658533 -45.803267) (xy 452.621291 -45.844831)
			(xy 452.582365 -45.877226) (xy 461.205832 -45.877226) (xy 461.209903 -45.821604) (xy 461.222029 -45.767167)
			(xy 461.241952 -45.715076) (xy 461.269248 -45.666441) (xy 461.303334 -45.622298) (xy 461.343483 -45.583589)
			(xy 461.388841 -45.551138) (xy 461.438441 -45.525637) (xy 461.491225 -45.50763) (xy 461.546068 -45.4975)
			(xy 461.601802 -45.495463) (xy 461.657239 -45.501563) (xy 461.711196 -45.515669) (xy 461.762525 -45.537481)
			(xy 461.810131 -45.566535) (xy 461.852999 -45.60221) (xy 461.890216 -45.643747) (xy 461.920989 -45.69026)
			(xy 461.944661 -45.740757) (xy 461.960729 -45.794164) (xy 461.968849 -45.84934) (xy 461.969358 -45.877226)
			(xy 461.968849 -45.905112) (xy 461.960729 -45.960288) (xy 461.944661 -46.013695) (xy 461.920989 -46.064192)
			(xy 461.890216 -46.110705) (xy 461.852999 -46.152242) (xy 461.810131 -46.187917) (xy 461.762525 -46.216971)
			(xy 461.711196 -46.238783) (xy 461.657239 -46.252889) (xy 461.601802 -46.258989) (xy 461.546068 -46.256952)
			(xy 461.491225 -46.246822) (xy 461.438441 -46.228815) (xy 461.388841 -46.203314) (xy 461.343483 -46.170863)
			(xy 461.303334 -46.132154) (xy 461.269248 -46.088011) (xy 461.241952 -46.039376) (xy 461.222029 -45.987285)
			(xy 461.209903 -45.932848) (xy 461.205832 -45.877226) (xy 452.582365 -45.877226) (xy 452.578395 -45.88053)
			(xy 452.530757 -45.909603) (xy 452.479394 -45.93143) (xy 452.425401 -45.945546) (xy 452.369927 -45.951649)
			(xy 452.314156 -45.949611) (xy 452.259277 -45.939474) (xy 452.206457 -45.921455) (xy 452.156825 -45.895937)
			(xy 452.111437 -45.863465) (xy 452.07126 -45.82473) (xy 452.037152 -45.780558) (xy 452.009838 -45.73189)
			(xy 451.989902 -45.679764) (xy 451.977767 -45.625291) (xy 451.973694 -45.569632) (xy 451.711016 -45.569632)
			(xy 451.698256 -45.612971) (xy 451.675466 -45.662722) (xy 451.661022 -45.685964) (xy 451.652894 -45.713396)
			(xy 451.652894 -45.965618) (xy 451.652353 -45.975604) (xy 451.644634 -45.994031) (xy 451.637908 -46.001432)
			(xy 450.381878 -47.257462) (xy 452.986138 -47.257462) (xy 452.990211 -47.201803) (xy 453.002346 -47.14733)
			(xy 453.022282 -47.095204) (xy 453.049596 -47.046536) (xy 453.083704 -47.002364) (xy 453.123881 -46.963629)
			(xy 453.169269 -46.931157) (xy 453.218901 -46.905639) (xy 453.271721 -46.88762) (xy 453.3266 -46.877483)
			(xy 453.382371 -46.875445) (xy 453.437845 -46.881548) (xy 453.491838 -46.895664) (xy 453.543201 -46.917491)
			(xy 453.590839 -46.946564) (xy 453.633735 -46.982263) (xy 453.670977 -47.023827) (xy 453.701771 -47.070371)
			(xy 453.725459 -47.120902) (xy 453.741537 -47.174344) (xy 453.749663 -47.229558) (xy 453.750172 -47.257462)
			(xy 453.749663 -47.285366) (xy 453.741537 -47.34058) (xy 453.725459 -47.394022) (xy 453.701771 -47.444553)
			(xy 453.68103 -47.475902) (xy 457.470762 -47.475902) (xy 457.474833 -47.42028) (xy 457.486959 -47.365843)
			(xy 457.506882 -47.313752) (xy 457.534178 -47.265117) (xy 457.568264 -47.220974) (xy 457.608413 -47.182265)
			(xy 457.653771 -47.149814) (xy 457.703371 -47.124313) (xy 457.756155 -47.106306) (xy 457.810998 -47.096176)
			(xy 457.866732 -47.094139) (xy 457.922169 -47.100239) (xy 457.976126 -47.114345) (xy 458.027455 -47.136157)
			(xy 458.075061 -47.165211) (xy 458.117929 -47.200886) (xy 458.155146 -47.242423) (xy 458.185919 -47.288936)
			(xy 458.209591 -47.339433) (xy 458.225659 -47.39284) (xy 458.233779 -47.448016) (xy 458.23407 -47.463964)
			(xy 458.461362 -47.463964) (xy 458.465433 -47.408342) (xy 458.477559 -47.353905) (xy 458.497482 -47.301814)
			(xy 458.524778 -47.253179) (xy 458.558864 -47.209036) (xy 458.599013 -47.170327) (xy 458.644371 -47.137876)
			(xy 458.693971 -47.112375) (xy 458.746755 -47.094368) (xy 458.801598 -47.084238) (xy 458.857332 -47.082201)
			(xy 458.912769 -47.088301) (xy 458.966726 -47.102407) (xy 459.018055 -47.124219) (xy 459.065661 -47.153273)
			(xy 459.108529 -47.188948) (xy 459.145746 -47.230485) (xy 459.176519 -47.276998) (xy 459.200191 -47.327495)
			(xy 459.216259 -47.380902) (xy 459.224379 -47.436078) (xy 459.224888 -47.463964) (xy 459.224379 -47.49185)
			(xy 459.216259 -47.547026) (xy 459.200191 -47.600433) (xy 459.176519 -47.65093) (xy 459.145746 -47.697443)
			(xy 459.108529 -47.73898) (xy 459.065661 -47.774655) (xy 459.018055 -47.803709) (xy 458.966726 -47.825521)
			(xy 458.912769 -47.839627) (xy 458.857332 -47.845727) (xy 458.801598 -47.84369) (xy 458.746755 -47.83356)
			(xy 458.693971 -47.815553) (xy 458.644371 -47.790052) (xy 458.599013 -47.757601) (xy 458.558864 -47.718892)
			(xy 458.524778 -47.674749) (xy 458.497482 -47.626114) (xy 458.477559 -47.574023) (xy 458.465433 -47.519586)
			(xy 458.461362 -47.463964) (xy 458.23407 -47.463964) (xy 458.234288 -47.475902) (xy 458.233779 -47.503788)
			(xy 458.225659 -47.558964) (xy 458.209591 -47.612371) (xy 458.185919 -47.662868) (xy 458.155146 -47.709381)
			(xy 458.117929 -47.750918) (xy 458.075061 -47.786593) (xy 458.027455 -47.815647) (xy 457.976126 -47.837459)
			(xy 457.922169 -47.851565) (xy 457.866732 -47.857665) (xy 457.810998 -47.855628) (xy 457.756155 -47.845498)
			(xy 457.703371 -47.827491) (xy 457.653771 -47.80199) (xy 457.608413 -47.769539) (xy 457.568264 -47.73083)
			(xy 457.534178 -47.686687) (xy 457.506882 -47.638052) (xy 457.486959 -47.585961) (xy 457.474833 -47.531524)
			(xy 457.470762 -47.475902) (xy 453.68103 -47.475902) (xy 453.670977 -47.491097) (xy 453.633735 -47.532661)
			(xy 453.590839 -47.56836) (xy 453.543201 -47.597433) (xy 453.491838 -47.61926) (xy 453.437845 -47.633376)
			(xy 453.382371 -47.639479) (xy 453.3266 -47.637441) (xy 453.271721 -47.627304) (xy 453.218901 -47.609285)
			(xy 453.169269 -47.583767) (xy 453.123881 -47.551295) (xy 453.083704 -47.51256) (xy 453.049596 -47.468388)
			(xy 453.022282 -47.41972) (xy 453.002346 -47.367594) (xy 452.990211 -47.313121) (xy 452.986138 -47.257462)
			(xy 450.381878 -47.257462) (xy 448.305571 -49.333769) (xy 449.466704 -49.333769) (xy 449.466704 -49.279231)
			(xy 449.474466 -49.225247) (xy 449.48983 -49.172917) (xy 449.512486 -49.123306) (xy 449.54197 -49.077424)
			(xy 449.577684 -49.036205) (xy 449.6189 -49.000488) (xy 449.66478 -48.971) (xy 449.714389 -48.948341)
			(xy 449.766717 -48.932972) (xy 449.820701 -48.925207) (xy 449.84797 -48.924718) (xy 449.875712 -48.925254)
			(xy 449.930608 -48.933312) (xy 449.983759 -48.949235) (xy 450.034044 -48.972686) (xy 450.080403 -49.003171)
			(xy 450.101462 -49.021238) (xy 450.108574 -49.027334) (xy 450.11721 -49.030636) (xy 450.121561 -49.032168)
			(xy 450.130633 -49.033834) (xy 450.135244 -49.033938) (xy 450.2023 -49.033938) (xy 450.206913 -49.033853)
			(xy 450.215987 -49.032183) (xy 450.220334 -49.030636) (xy 450.22897 -49.027334) (xy 450.236082 -49.021238)
			(xy 450.25712 -49.003146) (xy 450.303487 -48.972666) (xy 450.353777 -48.949218) (xy 450.406931 -48.933295)
			(xy 450.46183 -48.925232) (xy 450.489574 -48.924718) (xy 450.516845 -48.92522) (xy 450.570832 -48.932978)
			(xy 450.623165 -48.948342) (xy 450.672779 -48.970997) (xy 450.718663 -49.000482) (xy 450.759884 -49.036197)
			(xy 450.763429 -49.040288) (xy 453.089262 -49.040288) (xy 453.093333 -48.984666) (xy 453.105459 -48.930229)
			(xy 453.125382 -48.878138) (xy 453.152678 -48.829503) (xy 453.186764 -48.78536) (xy 453.226913 -48.746651)
			(xy 453.272271 -48.7142) (xy 453.321871 -48.688699) (xy 453.374655 -48.670692) (xy 453.429498 -48.660562)
			(xy 453.485232 -48.658525) (xy 453.540669 -48.664625) (xy 453.594626 -48.678731) (xy 453.645955 -48.700543)
			(xy 453.693561 -48.729597) (xy 453.736429 -48.765272) (xy 453.773646 -48.806809) (xy 453.804419 -48.853322)
			(xy 453.828091 -48.903819) (xy 453.844159 -48.957226) (xy 453.852279 -49.012402) (xy 453.852788 -49.040288)
			(xy 453.852279 -49.068174) (xy 453.844159 -49.12335) (xy 453.828091 -49.176757) (xy 453.804419 -49.227254)
			(xy 453.773646 -49.273767) (xy 453.736429 -49.315304) (xy 453.693561 -49.350979) (xy 453.645955 -49.380033)
			(xy 453.594626 -49.401845) (xy 453.540669 -49.415951) (xy 453.485232 -49.422051) (xy 453.429498 -49.420014)
			(xy 453.374655 -49.409884) (xy 453.321871 -49.391877) (xy 453.272271 -49.366376) (xy 453.226913 -49.333925)
			(xy 453.186764 -49.295216) (xy 453.152678 -49.251073) (xy 453.125382 -49.202438) (xy 453.105459 -49.150347)
			(xy 453.093333 -49.09591) (xy 453.089262 -49.040288) (xy 450.763429 -49.040288) (xy 450.795603 -49.077416)
			(xy 450.825091 -49.123299) (xy 450.847749 -49.172911) (xy 450.863116 -49.225243) (xy 450.870878 -49.279229)
			(xy 450.870878 -49.333771) (xy 450.863116 -49.387757) (xy 450.847749 -49.440089) (xy 450.841603 -49.453546)
			(xy 460.176878 -49.453546) (xy 460.180949 -49.397924) (xy 460.193075 -49.343487) (xy 460.212998 -49.291396)
			(xy 460.240294 -49.242761) (xy 460.27438 -49.198618) (xy 460.314529 -49.159909) (xy 460.359887 -49.127458)
			(xy 460.409487 -49.101957) (xy 460.462271 -49.08395) (xy 460.517114 -49.07382) (xy 460.572848 -49.071783)
			(xy 460.628285 -49.077883) (xy 460.682242 -49.091989) (xy 460.733571 -49.113801) (xy 460.781177 -49.142855)
			(xy 460.824045 -49.17853) (xy 460.861262 -49.220067) (xy 460.892035 -49.26658) (xy 460.915707 -49.317077)
			(xy 460.931775 -49.370484) (xy 460.939895 -49.42566) (xy 460.940404 -49.453546) (xy 460.939895 -49.481432)
			(xy 460.931775 -49.536608) (xy 460.915707 -49.590015) (xy 460.892035 -49.640512) (xy 460.861262 -49.687025)
			(xy 460.824045 -49.728562) (xy 460.781177 -49.764237) (xy 460.733571 -49.793291) (xy 460.682242 -49.815103)
			(xy 460.628285 -49.829209) (xy 460.572848 -49.835309) (xy 460.517114 -49.833272) (xy 460.462271 -49.823142)
			(xy 460.409487 -49.805135) (xy 460.359887 -49.779634) (xy 460.314529 -49.747183) (xy 460.27438 -49.708474)
			(xy 460.240294 -49.664331) (xy 460.212998 -49.615696) (xy 460.193075 -49.563605) (xy 460.180949 -49.509168)
			(xy 460.176878 -49.453546) (xy 450.841603 -49.453546) (xy 450.825091 -49.489701) (xy 450.795603 -49.535584)
			(xy 450.759884 -49.576803) (xy 450.718663 -49.612518) (xy 450.672779 -49.642003) (xy 450.623165 -49.664658)
			(xy 450.570832 -49.680022) (xy 450.516845 -49.68778) (xy 450.489574 -49.688242) (xy 450.461831 -49.687725)
			(xy 450.406935 -49.679659) (xy 450.353785 -49.663731) (xy 450.3035 -49.640277) (xy 450.257141 -49.609789)
			(xy 450.236082 -49.591722) (xy 450.22897 -49.585626) (xy 450.220334 -49.582324) (xy 450.215987 -49.580781)
			(xy 450.206912 -49.579122) (xy 450.2023 -49.579022) (xy 450.135244 -49.579022) (xy 450.130632 -49.579121)
			(xy 450.121558 -49.580781) (xy 450.11721 -49.582324) (xy 450.108574 -49.585626) (xy 450.101462 -49.591722)
			(xy 450.080401 -49.609787) (xy 450.034041 -49.640272) (xy 449.983757 -49.663726) (xy 449.930607 -49.679656)
			(xy 449.875712 -49.687725) (xy 449.84797 -49.688242) (xy 449.820701 -49.687793) (xy 449.766717 -49.680028)
			(xy 449.714389 -49.664659) (xy 449.66478 -49.642) (xy 449.6189 -49.612512) (xy 449.577684 -49.576795)
			(xy 449.54197 -49.535576) (xy 449.512486 -49.489694) (xy 449.48983 -49.440083) (xy 449.474466 -49.387753)
			(xy 449.466704 -49.333769) (xy 448.305571 -49.333769) (xy 447.322448 -50.316892) (xy 459.681578 -50.316892)
			(xy 459.685649 -50.26127) (xy 459.697775 -50.206833) (xy 459.717698 -50.154742) (xy 459.744994 -50.106107)
			(xy 459.77908 -50.061964) (xy 459.819229 -50.023255) (xy 459.864587 -49.990804) (xy 459.914187 -49.965303)
			(xy 459.966971 -49.947296) (xy 460.021814 -49.937166) (xy 460.077548 -49.935129) (xy 460.132985 -49.941229)
			(xy 460.186942 -49.955335) (xy 460.238271 -49.977147) (xy 460.285877 -50.006201) (xy 460.328745 -50.041876)
			(xy 460.365962 -50.083413) (xy 460.396735 -50.129926) (xy 460.420407 -50.180423) (xy 460.436475 -50.23383)
			(xy 460.444595 -50.289006) (xy 460.445104 -50.316892) (xy 460.444595 -50.344778) (xy 460.436475 -50.399954)
			(xy 460.420407 -50.453361) (xy 460.396735 -50.503858) (xy 460.365962 -50.550371) (xy 460.328745 -50.591908)
			(xy 460.285877 -50.627583) (xy 460.238271 -50.656637) (xy 460.186942 -50.678449) (xy 460.132985 -50.692555)
			(xy 460.077548 -50.698655) (xy 460.021814 -50.696618) (xy 459.966971 -50.686488) (xy 459.914187 -50.668481)
			(xy 459.864587 -50.64298) (xy 459.819229 -50.610529) (xy 459.77908 -50.57182) (xy 459.744994 -50.527677)
			(xy 459.717698 -50.479042) (xy 459.697775 -50.426951) (xy 459.685649 -50.372514) (xy 459.681578 -50.316892)
			(xy 447.322448 -50.316892) (xy 446.994534 -50.644806) (xy 446.987185 -50.651606) (xy 446.968722 -50.659313)
			(xy 446.95872 -50.659792) (xy 445.932814 -50.659792) (xy 445.922751 -50.66023) (xy 445.904168 -50.667966)
			(xy 445.896746 -50.674778) (xy 445.169452 -51.402072) (xy 445.516704 -51.402072) (xy 445.516704 -51.347528)
			(xy 445.524466 -51.29354) (xy 445.539833 -51.241207) (xy 445.562492 -51.191593) (xy 445.591981 -51.145709)
			(xy 445.6277 -51.104488) (xy 445.668921 -51.068771) (xy 445.714807 -51.039284) (xy 445.764422 -51.016627)
			(xy 445.816756 -51.001263) (xy 445.870744 -50.993502) (xy 445.898016 -50.99304) (xy 445.925751 -50.993505)
			(xy 445.980638 -51.001524) (xy 446.033785 -51.017406) (xy 446.084073 -51.040815) (xy 446.130442 -51.071259)
			(xy 446.151508 -51.089306) (xy 446.162877 -51.098716) (xy 446.189628 -51.11115) (xy 446.218818 -51.115414)
			(xy 446.248008 -51.11115) (xy 446.274759 -51.098716) (xy 446.286128 -51.089306) (xy 446.30722 -51.071294)
			(xy 446.353589 -51.040864) (xy 446.403872 -51.01746) (xy 446.457011 -51.001574) (xy 446.511889 -50.993541)
			(xy 446.53962 -50.99304) (xy 446.566889 -50.993524) (xy 446.62087 -51.001288) (xy 446.673198 -51.016655)
			(xy 446.722806 -51.039312) (xy 446.768684 -51.068799) (xy 446.8099 -51.104514) (xy 446.845613 -51.145732)
			(xy 446.875097 -51.191612) (xy 446.897752 -51.241221) (xy 446.913116 -51.293549) (xy 446.920878 -51.347531)
			(xy 446.920878 -51.402069) (xy 446.918578 -51.418067) (xy 447.310028 -51.418067) (xy 447.310028 -51.363533)
			(xy 447.317789 -51.309554) (xy 447.333152 -51.257228) (xy 447.355804 -51.207622) (xy 447.385286 -51.161743)
			(xy 447.420996 -51.120527) (xy 447.462208 -51.084812) (xy 447.508083 -51.055326) (xy 447.557687 -51.032667)
			(xy 447.610011 -51.017298) (xy 447.663989 -51.009531) (xy 447.691256 -51.009042) (xy 447.71899 -51.009542)
			(xy 447.773875 -51.017553) (xy 447.827022 -51.033426) (xy 447.877311 -51.056828) (xy 447.923681 -51.087265)
			(xy 447.944748 -51.105308) (xy 447.956117 -51.114718) (xy 447.982868 -51.127152) (xy 448.012058 -51.131416)
			(xy 448.041248 -51.127152) (xy 448.067999 -51.114718) (xy 448.079368 -51.105308) (xy 448.100445 -51.087278)
			(xy 448.146818 -51.05685) (xy 448.197105 -51.03345) (xy 448.250247 -51.017569) (xy 448.305128 -51.009541)
			(xy 448.33286 -51.009042) (xy 448.360133 -51.009495) (xy 448.414125 -51.017252) (xy 448.466463 -51.032615)
			(xy 448.516082 -51.055271) (xy 448.524949 -51.060969) (xy 449.047604 -51.060969) (xy 449.047604 -51.006431)
			(xy 449.055366 -50.952447) (xy 449.07073 -50.900117) (xy 449.093386 -50.850506) (xy 449.12287 -50.804624)
			(xy 449.158584 -50.763405) (xy 449.1998 -50.727688) (xy 449.24568 -50.6982) (xy 449.295289 -50.675541)
			(xy 449.347617 -50.660172) (xy 449.401601 -50.652407) (xy 449.42887 -50.651918) (xy 449.456612 -50.652454)
			(xy 449.511508 -50.660512) (xy 449.564659 -50.676435) (xy 449.614944 -50.699886) (xy 449.661303 -50.730371)
			(xy 449.682362 -50.748438) (xy 449.689474 -50.754534) (xy 449.69811 -50.757836) (xy 449.702461 -50.759368)
			(xy 449.711533 -50.761034) (xy 449.716144 -50.761138) (xy 449.7832 -50.761138) (xy 449.787813 -50.761053)
			(xy 449.796887 -50.759383) (xy 449.801234 -50.757836) (xy 449.80987 -50.754534) (xy 449.816982 -50.748438)
			(xy 449.83802 -50.730346) (xy 449.884387 -50.699866) (xy 449.934677 -50.676418) (xy 449.987831 -50.660495)
			(xy 450.04273 -50.652432) (xy 450.070474 -50.651918) (xy 450.096761 -50.652352) (xy 450.148839 -50.659552)
			(xy 450.199436 -50.673834) (xy 450.247593 -50.694926) (xy 450.292398 -50.72243) (xy 450.333003 -50.755825)
			(xy 450.351144 -50.774854) (xy 450.351398 -50.775108) (xy 450.358625 -50.78209) (xy 450.376939 -50.79032)
			(xy 450.386958 -50.79111) (xy 450.469 -50.793396) (xy 450.48805 -50.78603) (xy 450.495416 -50.778918)
			(xy 450.516888 -50.759138) (xy 450.564683 -50.72562) (xy 450.617025 -50.699772) (xy 450.672693 -50.682196)
			(xy 450.730388 -50.673302) (xy 450.759576 -50.672746) (xy 450.787318 -50.673271) (xy 450.842215 -50.681331)
			(xy 450.895366 -50.697256) (xy 450.945651 -50.72071) (xy 450.99201 -50.751198) (xy 451.013068 -50.769266)
			(xy 451.02018 -50.775362) (xy 451.028816 -50.778664) (xy 451.033168 -50.780194) (xy 451.042239 -50.781862)
			(xy 451.04685 -50.781966) (xy 451.113906 -50.781966) (xy 451.118518 -50.781855) (xy 451.127592 -50.780203)
			(xy 451.13194 -50.778664) (xy 451.140576 -50.775362) (xy 451.147688 -50.769266) (xy 451.168728 -50.751176)
			(xy 451.215094 -50.720695) (xy 451.265384 -50.697246) (xy 451.318537 -50.681322) (xy 451.373436 -50.673259)
			(xy 451.40118 -50.672746) (xy 451.428453 -50.673192) (xy 451.482443 -50.680952) (xy 451.534779 -50.696317)
			(xy 451.584396 -50.718974) (xy 451.630283 -50.748462) (xy 451.671506 -50.78418) (xy 451.707226 -50.825401)
			(xy 451.736717 -50.871287) (xy 451.759376 -50.920902) (xy 451.774744 -50.973238) (xy 451.782506 -51.027228)
			(xy 451.782506 -51.081772) (xy 451.774744 -51.135762) (xy 451.759376 -51.188098) (xy 451.736717 -51.237713)
			(xy 451.707226 -51.283599) (xy 451.671506 -51.32482) (xy 451.630283 -51.360538) (xy 451.584396 -51.390026)
			(xy 451.534779 -51.412683) (xy 451.482443 -51.428048) (xy 451.428453 -51.435808) (xy 451.40118 -51.43627)
			(xy 451.373437 -51.435767) (xy 451.318539 -51.427701) (xy 451.265388 -51.411771) (xy 451.215103 -51.388312)
			(xy 451.168746 -51.35782) (xy 451.147688 -51.33975) (xy 451.140576 -51.333654) (xy 451.13194 -51.330352)
			(xy 451.127593 -51.328807) (xy 451.118518 -51.327149) (xy 451.113906 -51.32705) (xy 451.04685 -51.32705)
			(xy 451.042238 -51.327149) (xy 451.033164 -51.328809) (xy 451.028816 -51.330352) (xy 451.02018 -51.333654)
			(xy 451.013068 -51.33975) (xy 450.992009 -51.357817) (xy 450.945648 -51.3883) (xy 450.895363 -51.411754)
			(xy 450.842214 -51.427683) (xy 450.787318 -51.435753) (xy 450.759576 -51.43627) (xy 450.733288 -51.435874)
			(xy 450.681208 -51.428666) (xy 450.63061 -51.414377) (xy 450.582453 -51.393278) (xy 450.537649 -51.365767)
			(xy 450.497046 -51.332366) (xy 450.478906 -51.313334) (xy 450.478652 -51.31308) (xy 450.471408 -51.306117)
			(xy 450.453107 -51.297877) (xy 450.443092 -51.297078) (xy 450.36105 -51.294792) (xy 450.342 -51.302158)
			(xy 450.334634 -51.30927) (xy 450.313181 -51.329072) (xy 450.265381 -51.362587) (xy 450.213034 -51.388431)
			(xy 450.157362 -51.406002) (xy 450.099664 -51.414889) (xy 450.070474 -51.415442) (xy 450.042731 -51.414925)
			(xy 449.987835 -51.406859) (xy 449.934685 -51.390931) (xy 449.8844 -51.367477) (xy 449.838041 -51.336989)
			(xy 449.816982 -51.318922) (xy 449.80987 -51.312826) (xy 449.801234 -51.309524) (xy 449.796887 -51.307981)
			(xy 449.787812 -51.306322) (xy 449.7832 -51.306222) (xy 449.716144 -51.306222) (xy 449.711532 -51.306321)
			(xy 449.702458 -51.307981) (xy 449.69811 -51.309524) (xy 449.689474 -51.312826) (xy 449.682362 -51.318922)
			(xy 449.661301 -51.336987) (xy 449.614941 -51.367472) (xy 449.564657 -51.390926) (xy 449.511507 -51.406856)
			(xy 449.456612 -51.414925) (xy 449.42887 -51.415442) (xy 449.401601 -51.414993) (xy 449.347617 -51.407228)
			(xy 449.295289 -51.391859) (xy 449.24568 -51.3692) (xy 449.1998 -51.339712) (xy 449.158584 -51.303995)
			(xy 449.12287 -51.262776) (xy 449.093386 -51.216894) (xy 449.07073 -51.167283) (xy 449.055366 -51.114953)
			(xy 449.047604 -51.060969) (xy 448.524949 -51.060969) (xy 448.561971 -51.084758) (xy 448.603196 -51.120476)
			(xy 448.638918 -51.161697) (xy 448.66841 -51.207583) (xy 448.691071 -51.2572) (xy 448.706439 -51.309536)
			(xy 448.714202 -51.363527) (xy 448.714202 -51.418073) (xy 448.706439 -51.472064) (xy 448.691071 -51.5244)
			(xy 448.66841 -51.574017) (xy 448.638918 -51.619903) (xy 448.603196 -51.661124) (xy 448.561971 -51.696842)
			(xy 448.516082 -51.726329) (xy 448.466463 -51.748985) (xy 448.414125 -51.764348) (xy 448.360133 -51.772105)
			(xy 448.33286 -51.772566) (xy 448.305127 -51.772055) (xy 448.250242 -51.764046) (xy 448.197095 -51.748175)
			(xy 448.146806 -51.724776) (xy 448.100436 -51.694342) (xy 448.079368 -51.6763) (xy 448.067999 -51.66689)
			(xy 448.041248 -51.654456) (xy 448.012058 -51.650192) (xy 447.982868 -51.654456) (xy 447.956117 -51.66689)
			(xy 447.944748 -51.6763) (xy 447.923666 -51.694324) (xy 447.877294 -51.724752) (xy 447.827009 -51.748154)
			(xy 447.773867 -51.764036) (xy 447.718988 -51.772066) (xy 447.691256 -51.772566) (xy 447.663989 -51.772069)
			(xy 447.610011 -51.764302) (xy 447.557687 -51.748933) (xy 447.508083 -51.726274) (xy 447.462208 -51.696788)
			(xy 447.420996 -51.661073) (xy 447.385286 -51.619857) (xy 447.355804 -51.573978) (xy 447.333152 -51.524372)
			(xy 447.317789 -51.472046) (xy 447.310028 -51.418067) (xy 446.918578 -51.418067) (xy 446.913116 -51.456051)
			(xy 446.897752 -51.508379) (xy 446.875097 -51.557988) (xy 446.845613 -51.603868) (xy 446.8099 -51.645086)
			(xy 446.768684 -51.680801) (xy 446.722806 -51.710288) (xy 446.673198 -51.732945) (xy 446.62087 -51.748312)
			(xy 446.566889 -51.756076) (xy 446.53962 -51.756564) (xy 446.511886 -51.756077) (xy 446.457 -51.748063)
			(xy 446.403853 -51.732186) (xy 446.353565 -51.708782) (xy 446.307195 -51.678342) (xy 446.286128 -51.660298)
			(xy 446.274759 -51.650888) (xy 446.248008 -51.638454) (xy 446.218818 -51.63419) (xy 446.189628 -51.638454)
			(xy 446.162877 -51.650888) (xy 446.151508 -51.660298) (xy 446.130441 -51.678341) (xy 446.084065 -51.708766)
			(xy 446.033776 -51.732164) (xy 445.980631 -51.748042) (xy 445.925749 -51.756067) (xy 445.898016 -51.756564)
			(xy 445.870744 -51.756098) (xy 445.816756 -51.748337) (xy 445.764422 -51.732973) (xy 445.714807 -51.710316)
			(xy 445.668921 -51.680829) (xy 445.6277 -51.645112) (xy 445.591981 -51.603891) (xy 445.562492 -51.558007)
			(xy 445.539833 -51.508393) (xy 445.524466 -51.45606) (xy 445.516704 -51.402072) (xy 445.169452 -51.402072)
			(xy 443.87897 -52.692554) (xy 443.872124 -52.699952) (xy 443.864398 -52.718551) (xy 443.863984 -52.728622)
			(xy 443.863984 -52.845716) (xy 443.867794 -52.858924) (xy 443.871604 -52.86502) (xy 443.875006 -52.871018)
			(xy 443.878731 -52.88429) (xy 443.87897 -52.891182) (xy 443.87897 -53.055266) (xy 460.930242 -53.055266)
			(xy 460.934313 -52.999644) (xy 460.946439 -52.945207) (xy 460.966362 -52.893116) (xy 460.993658 -52.844481)
			(xy 461.027744 -52.800338) (xy 461.067893 -52.761629) (xy 461.113251 -52.729178) (xy 461.162851 -52.703677)
			(xy 461.215635 -52.68567) (xy 461.270478 -52.67554) (xy 461.326212 -52.673503) (xy 461.381649 -52.679603)
			(xy 461.435606 -52.693709) (xy 461.486935 -52.715521) (xy 461.534541 -52.744575) (xy 461.577409 -52.78025)
			(xy 461.614626 -52.821787) (xy 461.645399 -52.8683) (xy 461.669071 -52.918797) (xy 461.685139 -52.972204)
			(xy 461.693259 -53.02738) (xy 461.693768 -53.055266) (xy 461.693259 -53.083152) (xy 461.685139 -53.138328)
			(xy 461.669071 -53.191735) (xy 461.645399 -53.242232) (xy 461.614626 -53.288745) (xy 461.577409 -53.330282)
			(xy 461.534541 -53.365957) (xy 461.486935 -53.395011) (xy 461.435606 -53.416823) (xy 461.381649 -53.430929)
			(xy 461.326212 -53.437029) (xy 461.270478 -53.434992) (xy 461.215635 -53.424862) (xy 461.162851 -53.406855)
			(xy 461.113251 -53.381354) (xy 461.067893 -53.348903) (xy 461.027744 -53.310194) (xy 460.993658 -53.266051)
			(xy 460.966362 -53.217416) (xy 460.946439 -53.165325) (xy 460.934313 -53.110888) (xy 460.930242 -53.055266)
			(xy 443.87897 -53.055266) (xy 443.87897 -53.739288) (xy 443.878859 -53.744385) (xy 443.876814 -53.754372)
			(xy 443.874906 -53.7591) (xy 443.868048 -53.775102) (xy 443.866177 -53.779841) (xy 443.864129 -53.789821)
			(xy 443.863984 -53.794914) (xy 443.863984 -68.527676) (xy 444.63208 -68.527676) (xy 444.632623 -68.49876)
			(xy 444.641342 -68.441588) (xy 444.658594 -68.386389) (xy 444.68398 -68.334426) (xy 444.716921 -68.286892)
			(xy 444.756661 -68.244876) (xy 444.779146 -68.226686) (xy 444.787957 -68.219083) (xy 444.798137 -68.198179)
			(xy 444.798704 -68.186554) (xy 444.798704 -68.106798) (xy 444.79815 -68.095168) (xy 444.787972 -68.074258)
			(xy 444.779146 -68.066666) (xy 444.756635 -68.048508) (xy 444.716904 -68.00648) (xy 444.68397 -67.958937)
			(xy 444.658587 -67.90697) (xy 444.641336 -67.851767) (xy 444.632612 -67.794594) (xy 444.63208 -67.765676)
			(xy 444.632555 -67.738425) (xy 444.640315 -67.684477) (xy 444.655672 -67.632183) (xy 444.678316 -67.582607)
			(xy 444.707783 -67.536757) (xy 444.743476 -67.495567) (xy 444.784666 -67.459876) (xy 444.830517 -67.43041)
			(xy 444.880094 -67.407768) (xy 444.932389 -67.392412) (xy 444.986337 -67.384655) (xy 445.013588 -67.384168)
			(xy 445.042506 -67.384669) (xy 445.099679 -67.393398) (xy 445.154879 -67.410658) (xy 445.206842 -67.436052)
			(xy 445.254375 -67.469) (xy 445.29639 -67.508746) (xy 445.314578 -67.531234) (xy 445.322199 -67.540027)
			(xy 445.343089 -67.550217) (xy 445.35471 -67.550792) (xy 445.434466 -67.550792) (xy 445.446094 -67.550222)
			(xy 445.467004 -67.540055) (xy 445.474598 -67.531234) (xy 445.491351 -67.510451) (xy 445.529705 -67.473321)
			(xy 445.572859 -67.441899) (xy 445.619973 -67.4168) (xy 445.670125 -67.398514) (xy 445.722336 -67.387397)
			(xy 445.775588 -67.383667) (xy 445.82884 -67.387397) (xy 445.881051 -67.398514) (xy 445.931203 -67.4168)
			(xy 445.978317 -67.441899) (xy 446.021471 -67.473321) (xy 446.059825 -67.510451) (xy 446.076578 -67.531234)
			(xy 446.084199 -67.540027) (xy 446.105089 -67.550217) (xy 446.11671 -67.550792) (xy 446.196466 -67.550792)
			(xy 446.208094 -67.550222) (xy 446.229004 -67.540055) (xy 446.236598 -67.531234) (xy 446.254799 -67.508759)
			(xy 446.296815 -67.469021) (xy 446.344348 -67.43608) (xy 446.396308 -67.41069) (xy 446.451504 -67.393433)
			(xy 446.508672 -67.384703) (xy 446.537588 -67.384168) (xy 446.564838 -67.384689) (xy 446.618783 -67.392444)
			(xy 446.671076 -67.407796) (xy 446.720651 -67.430434) (xy 446.7665 -67.459897) (xy 446.80769 -67.495584)
			(xy 446.843382 -67.536771) (xy 446.872849 -67.582617) (xy 446.895491 -67.632191) (xy 446.910849 -67.684482)
			(xy 446.918608 -67.738426) (xy 446.919096 -67.765676) (xy 446.918562 -67.794592) (xy 446.909836 -67.851763)
			(xy 446.892582 -67.906961) (xy 446.867193 -67.958923) (xy 446.834252 -68.006458) (xy 446.794514 -68.048475)
			(xy 446.77203 -68.066666) (xy 446.763237 -68.074286) (xy 446.753048 -68.095177) (xy 446.752472 -68.106798)
			(xy 446.752472 -68.186554) (xy 446.752969 -68.198192) (xy 446.763185 -68.219103) (xy 446.77203 -68.226686)
			(xy 446.794513 -68.244877) (xy 446.834247 -68.286898) (xy 446.867185 -68.334433) (xy 446.892573 -68.386394)
			(xy 446.90983 -68.441591) (xy 446.917662 -68.492878) (xy 447.058034 -68.492878) (xy 447.058596 -68.463963)
			(xy 447.067314 -68.406793) (xy 447.084562 -68.351594) (xy 447.109946 -68.299632) (xy 447.142883 -68.252097)
			(xy 447.182617 -68.210079) (xy 447.2051 -68.191888) (xy 447.213903 -68.184276) (xy 447.224089 -68.163379)
			(xy 447.224658 -68.151756) (xy 447.224658 -68.072) (xy 447.224119 -68.060368) (xy 447.213932 -68.039457)
			(xy 447.2051 -68.031868) (xy 447.182601 -68.013695) (xy 447.142867 -67.971672) (xy 447.10993 -67.924133)
			(xy 447.084544 -67.872168) (xy 447.067291 -67.816967) (xy 447.058567 -67.759795) (xy 447.058034 -67.730878)
			(xy 447.058435 -67.703623) (xy 447.066196 -67.649667) (xy 447.081557 -67.597366) (xy 447.104205 -67.547783)
			(xy 447.133679 -67.501927) (xy 447.169379 -67.460734) (xy 447.210579 -67.425041) (xy 447.256439 -67.395574)
			(xy 447.306026 -67.372934) (xy 447.35833 -67.357582) (xy 447.412287 -67.34983) (xy 447.439542 -67.34937)
			(xy 447.468459 -67.349904) (xy 447.52563 -67.358626) (xy 447.58083 -67.375879) (xy 447.632792 -67.401268)
			(xy 447.680326 -67.43421) (xy 447.722342 -67.473951) (xy 447.740532 -67.496436) (xy 447.748129 -67.505254)
			(xy 447.769038 -67.51543) (xy 447.780664 -67.515994) (xy 447.86042 -67.515994) (xy 447.872052 -67.515454)
			(xy 447.892961 -67.505266) (xy 447.900552 -67.496436) (xy 447.917305 -67.475653) (xy 447.955659 -67.438523)
			(xy 447.998813 -67.407101) (xy 448.045927 -67.382002) (xy 448.096079 -67.363716) (xy 448.14829 -67.352599)
			(xy 448.201542 -67.348869) (xy 448.254794 -67.352599) (xy 448.307005 -67.363716) (xy 448.357157 -67.382002)
			(xy 448.404271 -67.407101) (xy 448.447425 -67.438523) (xy 448.485779 -67.475653) (xy 448.502532 -67.496436)
			(xy 448.510129 -67.505254) (xy 448.531038 -67.51543) (xy 448.542664 -67.515994) (xy 448.62242 -67.515994)
			(xy 448.634052 -67.515454) (xy 448.654961 -67.505266) (xy 448.662552 -67.496436) (xy 448.680779 -67.473983)
			(xy 448.72279 -67.434244) (xy 448.770317 -67.401301) (xy 448.822272 -67.375907) (xy 448.877463 -67.358644)
			(xy 448.934628 -67.349908) (xy 448.963542 -67.34937) (xy 448.990793 -67.349839) (xy 449.04474 -67.3576)
			(xy 449.097034 -67.37296) (xy 449.14661 -67.395604) (xy 449.192459 -67.425073) (xy 449.233648 -67.460766)
			(xy 449.269339 -67.501957) (xy 449.298806 -67.547807) (xy 449.321447 -67.597385) (xy 449.336804 -67.649679)
			(xy 449.344563 -67.703627) (xy 449.34505 -67.730878) (xy 449.344535 -67.759795) (xy 449.335808 -67.816967)
			(xy 449.318551 -67.872167) (xy 449.293158 -67.924129) (xy 449.260213 -67.971663) (xy 449.220471 -68.013679)
			(xy 449.197984 -68.031868) (xy 449.189198 -68.039496) (xy 449.179003 -68.060381) (xy 449.178426 -68.072)
			(xy 449.178426 -68.151756) (xy 449.178938 -68.163392) (xy 449.189145 -68.184301) (xy 449.197984 -68.191888)
			(xy 449.220458 -68.21009) (xy 449.260195 -68.252107) (xy 449.293135 -68.299639) (xy 449.318526 -68.351599)
			(xy 449.335784 -68.406794) (xy 449.344514 -68.463963) (xy 449.34505 -68.492878) (xy 449.344501 -68.520127)
			(xy 449.336749 -68.57407) (xy 449.321399 -68.626361) (xy 449.298763 -68.675935) (xy 449.269303 -68.721784)
			(xy 449.233618 -68.762973) (xy 449.192435 -68.798665) (xy 449.146591 -68.828133) (xy 449.097021 -68.850776)
			(xy 449.044733 -68.866135) (xy 448.990791 -68.873897) (xy 448.963542 -68.874386) (xy 448.934626 -68.873843)
			(xy 448.877456 -68.86512) (xy 448.822257 -68.847867) (xy 448.770295 -68.82248) (xy 448.722761 -68.789541)
			(xy 448.680743 -68.749804) (xy 448.662552 -68.72732) (xy 448.65497 -68.718488) (xy 448.63405 -68.708321)
			(xy 448.62242 -68.707762) (xy 448.542664 -68.707762) (xy 448.531028 -68.708273) (xy 448.510118 -68.71848)
			(xy 448.502532 -68.72732) (xy 448.485779 -68.748103) (xy 448.447425 -68.785233) (xy 448.404271 -68.816655)
			(xy 448.357157 -68.841754) (xy 448.307005 -68.86004) (xy 448.254794 -68.871157) (xy 448.201542 -68.874887)
			(xy 448.14829 -68.871157) (xy 448.096079 -68.86004) (xy 448.045927 -68.841754) (xy 447.998813 -68.816655)
			(xy 447.955659 -68.785233) (xy 447.917305 -68.748103) (xy 447.900552 -68.72732) (xy 447.89297 -68.718488)
			(xy 447.87205 -68.708321) (xy 447.86042 -68.707762) (xy 447.780664 -68.707762) (xy 447.769028 -68.708273)
			(xy 447.748118 -68.71848) (xy 447.740532 -68.72732) (xy 447.722328 -68.749792) (xy 447.68031 -68.789527)
			(xy 447.632778 -68.822467) (xy 447.580819 -68.847857) (xy 447.525624 -68.865116) (xy 447.468457 -68.873849)
			(xy 447.439542 -68.874386) (xy 447.412289 -68.873906) (xy 447.358338 -68.866154) (xy 447.306039 -68.850802)
			(xy 447.256457 -68.828163) (xy 447.210603 -68.798697) (xy 447.169409 -68.763005) (xy 447.133715 -68.721813)
			(xy 447.104247 -68.67596) (xy 447.081605 -68.62638) (xy 447.066251 -68.574082) (xy 447.058496 -68.520131)
			(xy 447.058034 -68.492878) (xy 446.917662 -68.492878) (xy 446.91856 -68.49876) (xy 446.919096 -68.527676)
			(xy 446.918622 -68.554929) (xy 446.910868 -68.60888) (xy 446.895515 -68.661178) (xy 446.872874 -68.710759)
			(xy 446.843408 -68.756613) (xy 446.807715 -68.797806) (xy 446.766523 -68.8335) (xy 446.72067 -68.862968)
			(xy 446.67109 -68.885611) (xy 446.618792 -68.900966) (xy 446.564841 -68.908721) (xy 446.537588 -68.909184)
			(xy 446.508673 -68.908609) (xy 446.451504 -68.899892) (xy 446.396306 -68.882646) (xy 446.344344 -68.857265)
			(xy 446.296809 -68.824331) (xy 446.25479 -68.784599) (xy 446.236598 -68.762118) (xy 446.228996 -68.753306)
			(xy 446.208091 -68.743128) (xy 446.196466 -68.74256) (xy 446.11671 -68.74256) (xy 446.105077 -68.743098)
			(xy 446.084167 -68.753286) (xy 446.076578 -68.762118) (xy 446.059825 -68.782901) (xy 446.021471 -68.820031)
			(xy 445.978317 -68.851453) (xy 445.931203 -68.876552) (xy 445.881051 -68.894838) (xy 445.82884 -68.905955)
			(xy 445.775588 -68.909685) (xy 445.722336 -68.905955) (xy 445.670125 -68.894838) (xy 445.619973 -68.876552)
			(xy 445.572859 -68.851453) (xy 445.529705 -68.820031) (xy 445.491351 -68.782901) (xy 445.474598 -68.762118)
			(xy 445.466996 -68.753306) (xy 445.446091 -68.743128) (xy 445.434466 -68.74256) (xy 445.35471 -68.74256)
			(xy 445.343077 -68.743098) (xy 445.322167 -68.753286) (xy 445.314578 -68.762118) (xy 445.296404 -68.784616)
			(xy 445.25438 -68.824349) (xy 445.206842 -68.857286) (xy 445.154877 -68.882672) (xy 445.099677 -68.899925)
			(xy 445.042505 -68.908651) (xy 445.013588 -68.909184) (xy 444.986334 -68.908756) (xy 444.93238 -68.900997)
			(xy 444.88008 -68.885638) (xy 444.830498 -68.862993) (xy 444.784644 -68.833521) (xy 444.743451 -68.797824)
			(xy 444.707757 -68.756627) (xy 444.67829 -68.71077) (xy 444.655649 -68.661186) (xy 444.640295 -68.608885)
			(xy 444.632541 -68.55493) (xy 444.63208 -68.527676) (xy 443.863984 -68.527676) (xy 443.863984 -69.003164)
			(xy 450.629274 -69.003164) (xy 450.629764 -68.975996) (xy 450.637482 -68.922211) (xy 450.652757 -68.870066)
			(xy 450.675279 -68.820618) (xy 450.704592 -68.774867) (xy 450.721984 -68.75399) (xy 450.72681 -68.748402)
			(xy 450.732806 -68.74076) (xy 450.739116 -68.72241) (xy 450.738116 -68.703031) (xy 450.73443 -68.694046)
			(xy 450.727826 -68.680076) (xy 450.725676 -68.675008) (xy 450.723373 -68.664244) (xy 450.723254 -68.65874)
			(xy 450.723254 -68.62826) (xy 450.717666 -68.612512) (xy 450.712332 -68.605654) (xy 450.69628 -68.584683)
			(xy 450.669402 -68.539225) (xy 450.649054 -68.490493) (xy 450.635625 -68.439419) (xy 450.629371 -68.386981)
			(xy 450.630414 -68.334181) (xy 450.638732 -68.282031) (xy 450.654167 -68.231527) (xy 450.676423 -68.183637)
			(xy 450.705074 -68.139275) (xy 450.721984 -68.11899) (xy 450.72681 -68.113402) (xy 450.732806 -68.10576)
			(xy 450.739116 -68.08741) (xy 450.738116 -68.068031) (xy 450.73443 -68.059046) (xy 450.727826 -68.045076)
			(xy 450.725676 -68.040008) (xy 450.723373 -68.029244) (xy 450.723254 -68.02374) (xy 450.723254 -67.99326)
			(xy 450.717666 -67.977512) (xy 450.712332 -67.970654) (xy 450.69628 -67.949683) (xy 450.669402 -67.904225)
			(xy 450.649054 -67.855493) (xy 450.635625 -67.804419) (xy 450.629371 -67.751981) (xy 450.630414 -67.699181)
			(xy 450.638732 -67.647031) (xy 450.654167 -67.596527) (xy 450.676423 -67.548637) (xy 450.705074 -67.504275)
			(xy 450.721984 -67.48399) (xy 450.72681 -67.478402) (xy 450.732806 -67.47076) (xy 450.739116 -67.45241)
			(xy 450.738116 -67.433031) (xy 450.73443 -67.424046) (xy 450.727826 -67.410076) (xy 450.725676 -67.405008)
			(xy 450.723373 -67.394244) (xy 450.723254 -67.38874) (xy 450.723254 -67.35826) (xy 450.717666 -67.342512)
			(xy 450.712332 -67.335654) (xy 450.69628 -67.314683) (xy 450.669402 -67.269225) (xy 450.649054 -67.220493)
			(xy 450.635625 -67.169419) (xy 450.629371 -67.116981) (xy 450.630414 -67.064181) (xy 450.638732 -67.012031)
			(xy 450.654167 -66.961527) (xy 450.676423 -66.913637) (xy 450.705074 -66.869275) (xy 450.721984 -66.84899)
			(xy 450.72681 -66.843402) (xy 450.732806 -66.83576) (xy 450.739116 -66.81741) (xy 450.738116 -66.798031)
			(xy 450.73443 -66.789046) (xy 450.727826 -66.775076) (xy 450.725676 -66.770008) (xy 450.723373 -66.759244)
			(xy 450.723254 -66.75374) (xy 450.723254 -66.72326) (xy 450.717666 -66.707512) (xy 450.712078 -66.700654)
			(xy 450.696459 -66.680314) (xy 450.670215 -66.636256) (xy 450.650113 -66.589077) (xy 450.636518 -66.539629)
			(xy 450.629675 -66.488806) (xy 450.629274 -66.463164) (xy 450.629744 -66.435913) (xy 450.637505 -66.381965)
			(xy 450.652864 -66.329671) (xy 450.675508 -66.280095) (xy 450.704976 -66.234246) (xy 450.740669 -66.193057)
			(xy 450.78186 -66.157366) (xy 450.827711 -66.127899) (xy 450.877288 -66.105258) (xy 450.929583 -66.089901)
			(xy 450.983531 -66.082143) (xy 451.010782 -66.081656) (xy 451.036902 -66.082041) (xy 451.088653 -66.08917)
			(xy 451.138943 -66.10331) (xy 451.186826 -66.124195) (xy 451.231402 -66.151433) (xy 451.271834 -66.184513)
			(xy 451.307362 -66.222811) (xy 451.322694 -66.243962) (xy 451.325234 -66.247518) (xy 451.332854 -66.255138)
			(xy 451.34022 -66.262504) (xy 451.359016 -66.270124) (xy 451.465696 -66.269108) (xy 451.48754 -66.25717)
			(xy 451.494652 -66.246248) (xy 451.509819 -66.223831) (xy 451.545524 -66.183154) (xy 451.586616 -66.147929)
			(xy 451.632272 -66.118861) (xy 451.681577 -66.096533) (xy 451.733541 -66.081394) (xy 451.787122 -66.073747)
			(xy 451.814184 -66.073274) (xy 451.841434 -66.073793) (xy 451.89538 -66.081547) (xy 451.947673 -66.096899)
			(xy 451.997248 -66.119537) (xy 452.043098 -66.149) (xy 452.084288 -66.184688) (xy 452.11998 -66.225875)
			(xy 452.149447 -66.271722) (xy 452.172089 -66.321296) (xy 452.187446 -66.373587) (xy 452.195204 -66.427532)
			(xy 452.195692 -66.454782) (xy 452.195237 -66.481951) (xy 452.187512 -66.535738) (xy 452.172229 -66.587884)
			(xy 452.149699 -66.637331) (xy 452.120378 -66.68308) (xy 452.102982 -66.703956) (xy 452.098156 -66.709544)
			(xy 452.092124 -66.71716) (xy 452.085828 -66.735525) (xy 452.086842 -66.754913) (xy 452.090536 -66.7639)
			(xy 452.09714 -66.77787) (xy 452.099278 -66.782943) (xy 452.101588 -66.793703) (xy 452.101712 -66.799206)
			(xy 452.101712 -66.829686) (xy 452.1073 -66.845434) (xy 452.112634 -66.852292) (xy 452.128727 -66.873232)
			(xy 452.155598 -66.918697) (xy 452.17594 -66.967435) (xy 452.189363 -67.018513) (xy 452.19561 -67.070954)
			(xy 452.194563 -67.123756) (xy 452.186241 -67.175908) (xy 452.170803 -67.226413) (xy 452.148545 -67.274306)
			(xy 452.119892 -67.31867) (xy 452.102982 -67.338956) (xy 452.098156 -67.344544) (xy 452.092124 -67.35216)
			(xy 452.085828 -67.370525) (xy 452.086842 -67.389913) (xy 452.090536 -67.3989) (xy 452.09714 -67.41287)
			(xy 452.099278 -67.417943) (xy 452.101588 -67.428703) (xy 452.101712 -67.434206) (xy 452.101712 -67.464686)
			(xy 452.1073 -67.480434) (xy 452.112634 -67.487292) (xy 452.128727 -67.508232) (xy 452.155598 -67.553697)
			(xy 452.17594 -67.602435) (xy 452.189363 -67.653513) (xy 452.19561 -67.705954) (xy 452.194563 -67.758756)
			(xy 452.186241 -67.810908) (xy 452.170803 -67.861413) (xy 452.148545 -67.909306) (xy 452.119892 -67.95367)
			(xy 452.102982 -67.973956) (xy 452.098156 -67.979544) (xy 452.092124 -67.98716) (xy 452.085828 -68.005525)
			(xy 452.086842 -68.024913) (xy 452.090536 -68.0339) (xy 452.09714 -68.04787) (xy 452.099278 -68.052943)
			(xy 452.101588 -68.063703) (xy 452.101712 -68.069206) (xy 452.101712 -68.099686) (xy 452.1073 -68.115434)
			(xy 452.112634 -68.122292) (xy 452.128727 -68.143232) (xy 452.155598 -68.188697) (xy 452.17594 -68.237435)
			(xy 452.189363 -68.288513) (xy 452.19561 -68.340954) (xy 452.194563 -68.393756) (xy 452.186241 -68.445908)
			(xy 452.170803 -68.496413) (xy 452.148545 -68.544306) (xy 452.119892 -68.58867) (xy 452.102982 -68.608956)
			(xy 452.098156 -68.614544) (xy 452.092124 -68.62216) (xy 452.085828 -68.640525) (xy 452.086842 -68.659913)
			(xy 452.090536 -68.6689) (xy 452.09714 -68.68287) (xy 452.099278 -68.687943) (xy 452.101588 -68.698703)
			(xy 452.101712 -68.704206) (xy 452.101712 -68.734686) (xy 452.1073 -68.750434) (xy 452.112888 -68.757292)
			(xy 452.128523 -68.77762) (xy 452.154766 -68.821681) (xy 452.174865 -68.868863) (xy 452.188456 -68.918313)
			(xy 452.195294 -68.96914) (xy 452.195692 -68.994782) (xy 452.728076 -68.994782) (xy 452.728576 -68.967614)
			(xy 452.736291 -68.91383) (xy 452.751564 -68.861685) (xy 452.774084 -68.812237) (xy 452.803395 -68.766486)
			(xy 452.820786 -68.745608) (xy 452.825612 -68.74002) (xy 452.831594 -68.732368) (xy 452.837908 -68.714024)
			(xy 452.836915 -68.694649) (xy 452.833232 -68.685664) (xy 452.826628 -68.671694) (xy 452.824483 -68.666624)
			(xy 452.822177 -68.655862) (xy 452.822056 -68.650358) (xy 452.822056 -68.619878) (xy 452.816468 -68.60413)
			(xy 452.811134 -68.597272) (xy 452.795001 -68.57636) (xy 452.768127 -68.530892) (xy 452.747784 -68.482149)
			(xy 452.734362 -68.431067) (xy 452.728116 -68.37862) (xy 452.729168 -68.325814) (xy 452.737496 -68.273658)
			(xy 452.752941 -68.22315) (xy 452.775208 -68.175256) (xy 452.803871 -68.130893) (xy 452.820786 -68.110608)
			(xy 452.825612 -68.10502) (xy 452.831594 -68.097368) (xy 452.837908 -68.079024) (xy 452.836915 -68.059649)
			(xy 452.833232 -68.050664) (xy 452.826628 -68.036694) (xy 452.824483 -68.031624) (xy 452.822177 -68.020862)
			(xy 452.822056 -68.015358) (xy 452.822056 -67.984878) (xy 452.816468 -67.96913) (xy 452.81088 -67.962272)
			(xy 452.79527 -67.941926) (xy 452.769024 -67.897869) (xy 452.748921 -67.850692) (xy 452.735324 -67.801246)
			(xy 452.728478 -67.750423) (xy 452.728076 -67.724782) (xy 452.728562 -67.697531) (xy 452.736318 -67.643583)
			(xy 452.751673 -67.591288) (xy 452.774315 -67.541711) (xy 452.803781 -67.495861) (xy 452.839472 -67.45467)
			(xy 452.880663 -67.418979) (xy 452.926513 -67.389513) (xy 452.97609 -67.366871) (xy 453.028385 -67.351516)
			(xy 453.082333 -67.34376) (xy 453.136835 -67.34376) (xy 453.190783 -67.351516) (xy 453.243078 -67.366871)
			(xy 453.292655 -67.389513) (xy 453.338505 -67.418979) (xy 453.379696 -67.45467) (xy 453.415387 -67.495861)
			(xy 453.444853 -67.541711) (xy 453.467495 -67.591288) (xy 453.48285 -67.643583) (xy 453.490606 -67.697531)
			(xy 453.491092 -67.724782) (xy 453.490637 -67.751951) (xy 453.482912 -67.805738) (xy 453.467629 -67.857884)
			(xy 453.445099 -67.907331) (xy 453.415778 -67.95308) (xy 453.398382 -67.973956) (xy 453.393556 -67.979544)
			(xy 453.387524 -67.98716) (xy 453.381228 -68.005525) (xy 453.382242 -68.024913) (xy 453.385936 -68.0339)
			(xy 453.39254 -68.04787) (xy 453.394678 -68.052943) (xy 453.396988 -68.063703) (xy 453.397112 -68.069206)
			(xy 453.397112 -68.099686) (xy 453.4027 -68.115434) (xy 453.408034 -68.122292) (xy 453.424127 -68.143232)
			(xy 453.450998 -68.188697) (xy 453.47134 -68.237435) (xy 453.484763 -68.288513) (xy 453.49101 -68.340954)
			(xy 453.489963 -68.393756) (xy 453.481641 -68.445908) (xy 453.466203 -68.496413) (xy 453.443945 -68.544306)
			(xy 453.415292 -68.58867) (xy 453.398382 -68.608956) (xy 453.393556 -68.614544) (xy 453.387524 -68.62216)
			(xy 453.381228 -68.640525) (xy 453.382242 -68.659913) (xy 453.385936 -68.6689) (xy 453.39254 -68.68287)
			(xy 453.394678 -68.687943) (xy 453.396988 -68.698703) (xy 453.397112 -68.704206) (xy 453.397112 -68.734686)
			(xy 453.4027 -68.750434) (xy 453.408288 -68.757292) (xy 453.423923 -68.77762) (xy 453.450166 -68.821681)
			(xy 453.470265 -68.868863) (xy 453.483856 -68.918313) (xy 453.490694 -68.96914) (xy 453.491092 -68.994782)
			(xy 458.747876 -68.994782) (xy 458.748376 -68.967614) (xy 458.756091 -68.91383) (xy 458.771364 -68.861685)
			(xy 458.793884 -68.812237) (xy 458.823195 -68.766486) (xy 458.840586 -68.745608) (xy 458.845412 -68.74002)
			(xy 458.851394 -68.732368) (xy 458.857708 -68.714024) (xy 458.856715 -68.694649) (xy 458.853032 -68.685664)
			(xy 458.846428 -68.671694) (xy 458.844283 -68.666624) (xy 458.841977 -68.655862) (xy 458.841856 -68.650358)
			(xy 458.841856 -68.619878) (xy 458.836268 -68.60413) (xy 458.830934 -68.597272) (xy 458.814801 -68.57636)
			(xy 458.787927 -68.530892) (xy 458.767584 -68.482149) (xy 458.754162 -68.431067) (xy 458.747916 -68.37862)
			(xy 458.748968 -68.325814) (xy 458.757296 -68.273658) (xy 458.772741 -68.22315) (xy 458.795008 -68.175256)
			(xy 458.823671 -68.130893) (xy 458.840586 -68.110608) (xy 458.845412 -68.10502) (xy 458.851394 -68.097368)
			(xy 458.857708 -68.079024) (xy 458.856715 -68.059649) (xy 458.853032 -68.050664) (xy 458.846428 -68.036694)
			(xy 458.844283 -68.031624) (xy 458.841977 -68.020862) (xy 458.841856 -68.015358) (xy 458.841856 -67.984878)
			(xy 458.836268 -67.96913) (xy 458.830934 -67.962272) (xy 458.814801 -67.94136) (xy 458.787927 -67.895892)
			(xy 458.767584 -67.847149) (xy 458.754162 -67.796067) (xy 458.747916 -67.74362) (xy 458.748968 -67.690814)
			(xy 458.757296 -67.638658) (xy 458.772741 -67.58815) (xy 458.795008 -67.540256) (xy 458.823671 -67.495893)
			(xy 458.840586 -67.475608) (xy 458.845412 -67.47002) (xy 458.851394 -67.462368) (xy 458.857708 -67.444024)
			(xy 458.856715 -67.424649) (xy 458.853032 -67.415664) (xy 458.846428 -67.401694) (xy 458.844283 -67.396624)
			(xy 458.841977 -67.385862) (xy 458.841856 -67.380358) (xy 458.841856 -67.349878) (xy 458.836268 -67.33413)
			(xy 458.83068 -67.327272) (xy 458.81507 -67.306926) (xy 458.788824 -67.262869) (xy 458.768721 -67.215692)
			(xy 458.755124 -67.166246) (xy 458.748278 -67.115423) (xy 458.747876 -67.089782) (xy 458.748362 -67.062531)
			(xy 458.756118 -67.008583) (xy 458.771473 -66.956288) (xy 458.794115 -66.906711) (xy 458.823581 -66.860861)
			(xy 458.859272 -66.81967) (xy 458.900463 -66.783979) (xy 458.946313 -66.754513) (xy 458.99589 -66.731871)
			(xy 459.048185 -66.716516) (xy 459.102133 -66.70876) (xy 459.156635 -66.70876) (xy 459.210583 -66.716516)
			(xy 459.262878 -66.731871) (xy 459.312455 -66.754513) (xy 459.358305 -66.783979) (xy 459.399496 -66.81967)
			(xy 459.435187 -66.860861) (xy 459.464653 -66.906711) (xy 459.487295 -66.956288) (xy 459.50265 -67.008583)
			(xy 459.510406 -67.062531) (xy 459.510892 -67.089782) (xy 459.510437 -67.116951) (xy 459.502712 -67.170738)
			(xy 459.487429 -67.222884) (xy 459.464899 -67.272331) (xy 459.435578 -67.31808) (xy 459.418182 -67.338956)
			(xy 459.413356 -67.344544) (xy 459.407324 -67.35216) (xy 459.401028 -67.370525) (xy 459.402042 -67.389913)
			(xy 459.405736 -67.3989) (xy 459.41234 -67.41287) (xy 459.414478 -67.417943) (xy 459.416788 -67.428703)
			(xy 459.416912 -67.434206) (xy 459.416912 -67.464686) (xy 459.4225 -67.480434) (xy 459.427834 -67.487292)
			(xy 459.443927 -67.508232) (xy 459.470798 -67.553697) (xy 459.49114 -67.602435) (xy 459.504563 -67.653513)
			(xy 459.51081 -67.705954) (xy 459.509763 -67.758756) (xy 459.501441 -67.810908) (xy 459.486003 -67.861413)
			(xy 459.463745 -67.909306) (xy 459.435092 -67.95367) (xy 459.418182 -67.973956) (xy 459.413356 -67.979544)
			(xy 459.407324 -67.98716) (xy 459.401028 -68.005525) (xy 459.402042 -68.024913) (xy 459.405736 -68.0339)
			(xy 459.41234 -68.04787) (xy 459.414478 -68.052943) (xy 459.416788 -68.063703) (xy 459.416912 -68.069206)
			(xy 459.416912 -68.099686) (xy 459.4225 -68.115434) (xy 459.427834 -68.122292) (xy 459.443927 -68.143232)
			(xy 459.470798 -68.188697) (xy 459.49114 -68.237435) (xy 459.504563 -68.288513) (xy 459.51081 -68.340954)
			(xy 459.509763 -68.393756) (xy 459.501441 -68.445908) (xy 459.486003 -68.496413) (xy 459.463745 -68.544306)
			(xy 459.435092 -68.58867) (xy 459.418182 -68.608956) (xy 459.413356 -68.614544) (xy 459.407324 -68.62216)
			(xy 459.401028 -68.640525) (xy 459.402042 -68.659913) (xy 459.405736 -68.6689) (xy 459.41234 -68.68287)
			(xy 459.414478 -68.687943) (xy 459.416788 -68.698703) (xy 459.416912 -68.704206) (xy 459.416912 -68.734686)
			(xy 459.4225 -68.750434) (xy 459.428088 -68.757292) (xy 459.443723 -68.77762) (xy 459.469966 -68.821681)
			(xy 459.490065 -68.868863) (xy 459.503656 -68.918313) (xy 459.510494 -68.96914) (xy 459.510892 -68.994782)
			(xy 459.510406 -69.022033) (xy 459.50265 -69.075981) (xy 459.487295 -69.128276) (xy 459.464653 -69.177853)
			(xy 459.435187 -69.223703) (xy 459.399496 -69.264894) (xy 459.358305 -69.300585) (xy 459.312455 -69.330051)
			(xy 459.262878 -69.352693) (xy 459.210583 -69.368048) (xy 459.156635 -69.375804) (xy 459.102133 -69.375804)
			(xy 459.048185 -69.368048) (xy 458.99589 -69.352693) (xy 458.946313 -69.330051) (xy 458.900463 -69.300585)
			(xy 458.859272 -69.264894) (xy 458.823581 -69.223703) (xy 458.794115 -69.177853) (xy 458.771473 -69.128276)
			(xy 458.756118 -69.075981) (xy 458.748362 -69.022033) (xy 458.747876 -68.994782) (xy 453.491092 -68.994782)
			(xy 453.490606 -69.022033) (xy 453.48285 -69.075981) (xy 453.467495 -69.128276) (xy 453.444853 -69.177853)
			(xy 453.415387 -69.223703) (xy 453.379696 -69.264894) (xy 453.338505 -69.300585) (xy 453.292655 -69.330051)
			(xy 453.243078 -69.352693) (xy 453.190783 -69.368048) (xy 453.136835 -69.375804) (xy 453.082333 -69.375804)
			(xy 453.028385 -69.368048) (xy 452.97609 -69.352693) (xy 452.926513 -69.330051) (xy 452.880663 -69.300585)
			(xy 452.839472 -69.264894) (xy 452.803781 -69.223703) (xy 452.774315 -69.177853) (xy 452.751673 -69.128276)
			(xy 452.736318 -69.075981) (xy 452.728562 -69.022033) (xy 452.728076 -68.994782) (xy 452.195692 -68.994782)
			(xy 452.195228 -69.022035) (xy 452.187473 -69.075987) (xy 452.172118 -69.128286) (xy 452.149477 -69.177867)
			(xy 452.120009 -69.223721) (xy 452.084315 -69.264914) (xy 452.043122 -69.300608) (xy 451.997269 -69.330076)
			(xy 451.947688 -69.352718) (xy 451.895389 -69.368073) (xy 451.841437 -69.375828) (xy 451.814184 -69.37629)
			(xy 451.788066 -69.375836) (xy 451.736319 -69.368717) (xy 451.686032 -69.354587) (xy 451.63815 -69.333713)
			(xy 451.593573 -69.306486) (xy 451.553138 -69.273418) (xy 451.517606 -69.23513) (xy 451.502272 -69.213984)
			(xy 451.499732 -69.210428) (xy 451.492112 -69.202808) (xy 451.484746 -69.195442) (xy 451.46595 -69.187822)
			(xy 451.35927 -69.188838) (xy 451.337426 -69.200776) (xy 451.330314 -69.211698) (xy 451.315087 -69.234072)
			(xy 451.279394 -69.274752) (xy 451.238313 -69.309983) (xy 451.192667 -69.339057) (xy 451.143372 -69.361391)
			(xy 451.091416 -69.376538) (xy 451.037841 -69.384194) (xy 451.010782 -69.384672) (xy 450.983527 -69.384262)
			(xy 450.929572 -69.376501) (xy 450.877271 -69.361141) (xy 450.827689 -69.338494) (xy 450.781834 -69.309021)
			(xy 450.74064 -69.273321) (xy 450.704947 -69.232123) (xy 450.67548 -69.186264) (xy 450.65284 -69.136678)
			(xy 450.637487 -69.084375) (xy 450.629734 -69.030419) (xy 450.629274 -69.003164) (xy 443.863984 -69.003164)
			(xy 443.863984 -69.722746) (xy 454.449178 -69.722746) (xy 454.453249 -69.667124) (xy 454.465375 -69.612687)
			(xy 454.485298 -69.560596) (xy 454.512594 -69.511961) (xy 454.54668 -69.467818) (xy 454.586829 -69.429109)
			(xy 454.632187 -69.396658) (xy 454.681787 -69.371157) (xy 454.734571 -69.35315) (xy 454.789414 -69.34302)
			(xy 454.845148 -69.340983) (xy 454.900585 -69.347083) (xy 454.954542 -69.361189) (xy 455.005871 -69.383001)
			(xy 455.053477 -69.412055) (xy 455.096345 -69.44773) (xy 455.133562 -69.489267) (xy 455.164335 -69.53578)
			(xy 455.188007 -69.586277) (xy 455.204075 -69.639684) (xy 455.212195 -69.69486) (xy 455.212704 -69.722746)
			(xy 455.338178 -69.722746) (xy 455.342249 -69.667124) (xy 455.354375 -69.612687) (xy 455.374298 -69.560596)
			(xy 455.401594 -69.511961) (xy 455.43568 -69.467818) (xy 455.475829 -69.429109) (xy 455.521187 -69.396658)
			(xy 455.570787 -69.371157) (xy 455.623571 -69.35315) (xy 455.678414 -69.34302) (xy 455.734148 -69.340983)
			(xy 455.789585 -69.347083) (xy 455.843542 -69.361189) (xy 455.894871 -69.383001) (xy 455.942477 -69.412055)
			(xy 455.985345 -69.44773) (xy 456.022562 -69.489267) (xy 456.053335 -69.53578) (xy 456.077007 -69.586277)
			(xy 456.093075 -69.639684) (xy 456.101195 -69.69486) (xy 456.101704 -69.722746) (xy 456.227178 -69.722746)
			(xy 456.231249 -69.667124) (xy 456.243375 -69.612687) (xy 456.263298 -69.560596) (xy 456.290594 -69.511961)
			(xy 456.32468 -69.467818) (xy 456.364829 -69.429109) (xy 456.410187 -69.396658) (xy 456.459787 -69.371157)
			(xy 456.512571 -69.35315) (xy 456.567414 -69.34302) (xy 456.623148 -69.340983) (xy 456.678585 -69.347083)
			(xy 456.732542 -69.361189) (xy 456.783871 -69.383001) (xy 456.831477 -69.412055) (xy 456.874345 -69.44773)
			(xy 456.911562 -69.489267) (xy 456.942335 -69.53578) (xy 456.966007 -69.586277) (xy 456.982075 -69.639684)
			(xy 456.990195 -69.69486) (xy 456.990704 -69.722746) (xy 457.116178 -69.722746) (xy 457.120249 -69.667124)
			(xy 457.132375 -69.612687) (xy 457.152298 -69.560596) (xy 457.179594 -69.511961) (xy 457.21368 -69.467818)
			(xy 457.253829 -69.429109) (xy 457.299187 -69.396658) (xy 457.348787 -69.371157) (xy 457.401571 -69.35315)
			(xy 457.456414 -69.34302) (xy 457.512148 -69.340983) (xy 457.567585 -69.347083) (xy 457.621542 -69.361189)
			(xy 457.672871 -69.383001) (xy 457.720477 -69.412055) (xy 457.763345 -69.44773) (xy 457.800562 -69.489267)
			(xy 457.831335 -69.53578) (xy 457.855007 -69.586277) (xy 457.871075 -69.639684) (xy 457.879195 -69.69486)
			(xy 457.879704 -69.722746) (xy 457.879195 -69.750632) (xy 457.871075 -69.805808) (xy 457.855007 -69.859215)
			(xy 457.831335 -69.909712) (xy 457.800562 -69.956225) (xy 457.763345 -69.997762) (xy 457.720477 -70.033437)
			(xy 457.672871 -70.062491) (xy 457.621542 -70.084303) (xy 457.567585 -70.098409) (xy 457.512148 -70.104509)
			(xy 457.456414 -70.102472) (xy 457.401571 -70.092342) (xy 457.348787 -70.074335) (xy 457.299187 -70.048834)
			(xy 457.253829 -70.016383) (xy 457.21368 -69.977674) (xy 457.179594 -69.933531) (xy 457.152298 -69.884896)
			(xy 457.132375 -69.832805) (xy 457.120249 -69.778368) (xy 457.116178 -69.722746) (xy 456.990704 -69.722746)
			(xy 456.990195 -69.750632) (xy 456.982075 -69.805808) (xy 456.966007 -69.859215) (xy 456.942335 -69.909712)
			(xy 456.911562 -69.956225) (xy 456.874345 -69.997762) (xy 456.831477 -70.033437) (xy 456.783871 -70.062491)
			(xy 456.732542 -70.084303) (xy 456.678585 -70.098409) (xy 456.623148 -70.104509) (xy 456.567414 -70.102472)
			(xy 456.512571 -70.092342) (xy 456.459787 -70.074335) (xy 456.410187 -70.048834) (xy 456.364829 -70.016383)
			(xy 456.32468 -69.977674) (xy 456.290594 -69.933531) (xy 456.263298 -69.884896) (xy 456.243375 -69.832805)
			(xy 456.231249 -69.778368) (xy 456.227178 -69.722746) (xy 456.101704 -69.722746) (xy 456.101195 -69.750632)
			(xy 456.093075 -69.805808) (xy 456.077007 -69.859215) (xy 456.053335 -69.909712) (xy 456.022562 -69.956225)
			(xy 455.985345 -69.997762) (xy 455.942477 -70.033437) (xy 455.894871 -70.062491) (xy 455.843542 -70.084303)
			(xy 455.789585 -70.098409) (xy 455.734148 -70.104509) (xy 455.678414 -70.102472) (xy 455.623571 -70.092342)
			(xy 455.570787 -70.074335) (xy 455.521187 -70.048834) (xy 455.475829 -70.016383) (xy 455.43568 -69.977674)
			(xy 455.401594 -69.933531) (xy 455.374298 -69.884896) (xy 455.354375 -69.832805) (xy 455.342249 -69.778368)
			(xy 455.338178 -69.722746) (xy 455.212704 -69.722746) (xy 455.212195 -69.750632) (xy 455.204075 -69.805808)
			(xy 455.188007 -69.859215) (xy 455.164335 -69.909712) (xy 455.133562 -69.956225) (xy 455.096345 -69.997762)
			(xy 455.053477 -70.033437) (xy 455.005871 -70.062491) (xy 454.954542 -70.084303) (xy 454.900585 -70.098409)
			(xy 454.845148 -70.104509) (xy 454.789414 -70.102472) (xy 454.734571 -70.092342) (xy 454.681787 -70.074335)
			(xy 454.632187 -70.048834) (xy 454.586829 -70.016383) (xy 454.54668 -69.977674) (xy 454.512594 -69.933531)
			(xy 454.485298 -69.884896) (xy 454.465375 -69.832805) (xy 454.453249 -69.778368) (xy 454.449178 -69.722746)
			(xy 443.863984 -69.722746) (xy 443.863984 -71.592186) (xy 444.82258 -71.592186) (xy 444.82313 -71.56327)
			(xy 444.831848 -71.506099) (xy 444.849098 -71.450899) (xy 444.874483 -71.398937) (xy 444.907423 -71.351402)
			(xy 444.947162 -71.309386) (xy 444.969646 -71.291196) (xy 444.978453 -71.283589) (xy 444.988635 -71.262688)
			(xy 444.989204 -71.251064) (xy 444.989204 -71.171308) (xy 444.988645 -71.159679) (xy 444.97847 -71.138769)
			(xy 444.969646 -71.131176) (xy 444.94714 -71.113012) (xy 444.907408 -71.070985) (xy 444.874474 -71.023444)
			(xy 444.84909 -70.971478) (xy 444.831838 -70.916276) (xy 444.823113 -70.859103) (xy 444.82258 -70.830186)
			(xy 444.823065 -70.802935) (xy 444.830823 -70.748988) (xy 444.846179 -70.696694) (xy 444.868821 -70.647117)
			(xy 444.898288 -70.601268) (xy 444.933979 -70.560078) (xy 444.975169 -70.524386) (xy 445.021019 -70.49492)
			(xy 445.070596 -70.472278) (xy 445.12289 -70.456922) (xy 445.176837 -70.449165) (xy 445.204088 -70.448678)
			(xy 445.233006 -70.449175) (xy 445.29018 -70.457904) (xy 445.34538 -70.475165) (xy 445.397342 -70.50056)
			(xy 445.444876 -70.533509) (xy 445.48689 -70.573256) (xy 445.505078 -70.595744) (xy 445.512697 -70.604538)
			(xy 445.533589 -70.614727) (xy 445.54521 -70.615302) (xy 445.624966 -70.615302) (xy 445.636594 -70.614728)
			(xy 445.657503 -70.604564) (xy 445.665098 -70.595744) (xy 445.681851 -70.574961) (xy 445.720205 -70.537831)
			(xy 445.763359 -70.506409) (xy 445.810473 -70.48131) (xy 445.860625 -70.463024) (xy 445.912836 -70.451907)
			(xy 445.966088 -70.448177) (xy 446.01934 -70.451907) (xy 446.071551 -70.463024) (xy 446.121703 -70.48131)
			(xy 446.168817 -70.506409) (xy 446.211971 -70.537831) (xy 446.250325 -70.574961) (xy 446.267078 -70.595744)
			(xy 446.274697 -70.604538) (xy 446.295589 -70.614727) (xy 446.30721 -70.615302) (xy 446.386966 -70.615302)
			(xy 446.398594 -70.614728) (xy 446.419503 -70.604564) (xy 446.427098 -70.595744) (xy 446.443851 -70.574961)
			(xy 446.482205 -70.537831) (xy 446.525359 -70.506409) (xy 446.572473 -70.48131) (xy 446.622625 -70.463024)
			(xy 446.674836 -70.451907) (xy 446.728088 -70.448177) (xy 446.78134 -70.451907) (xy 446.833551 -70.463024)
			(xy 446.883703 -70.48131) (xy 446.930817 -70.506409) (xy 446.973971 -70.537831) (xy 447.012325 -70.574961)
			(xy 447.029078 -70.595744) (xy 447.036697 -70.604538) (xy 447.057589 -70.614727) (xy 447.06921 -70.615302)
			(xy 447.148966 -70.615302) (xy 447.160594 -70.614728) (xy 447.181503 -70.604564) (xy 447.189098 -70.595744)
			(xy 447.207301 -70.573271) (xy 447.249317 -70.533533) (xy 447.296849 -70.500591) (xy 447.348808 -70.475201)
			(xy 447.404004 -70.457943) (xy 447.461173 -70.449213) (xy 447.490088 -70.448678) (xy 447.517338 -70.449189)
			(xy 447.571284 -70.456944) (xy 447.623578 -70.472297) (xy 447.673154 -70.494935) (xy 447.719004 -70.524399)
			(xy 447.760194 -70.560088) (xy 447.795885 -70.601276) (xy 447.825352 -70.647123) (xy 447.847994 -70.696698)
			(xy 447.863351 -70.74899) (xy 447.871109 -70.802936) (xy 447.871596 -70.830186) (xy 447.871069 -70.859103)
			(xy 447.862342 -70.916273) (xy 447.845086 -70.971472) (xy 447.819696 -71.023434) (xy 447.786754 -71.070968)
			(xy 447.747015 -71.112985) (xy 447.72453 -71.131176) (xy 447.715732 -71.138791) (xy 447.705546 -71.159686)
			(xy 447.704972 -71.171308) (xy 447.704972 -71.251064) (xy 447.705463 -71.262703) (xy 447.715683 -71.283613)
			(xy 447.72453 -71.291196) (xy 447.747018 -71.309382) (xy 447.786751 -71.351403) (xy 447.819689 -71.39894)
			(xy 447.845076 -71.450902) (xy 447.862332 -71.5061) (xy 447.871061 -71.56327) (xy 447.871596 -71.592186)
			(xy 447.871132 -71.619439) (xy 447.863376 -71.673391) (xy 447.848021 -71.725689) (xy 447.82538 -71.77527)
			(xy 447.795912 -71.821124) (xy 447.760218 -71.862317) (xy 447.719025 -71.898011) (xy 447.673172 -71.927479)
			(xy 447.623591 -71.950121) (xy 447.571293 -71.965476) (xy 447.517341 -71.973231) (xy 447.490088 -71.973694)
			(xy 447.461173 -71.973115) (xy 447.404005 -71.964399) (xy 447.348807 -71.947153) (xy 447.296845 -71.921773)
			(xy 447.24931 -71.88884) (xy 447.20729 -71.849109) (xy 447.189098 -71.826628) (xy 447.181494 -71.817818)
			(xy 447.16059 -71.807639) (xy 447.148966 -71.80707) (xy 447.06921 -71.80707) (xy 447.057577 -71.807605)
			(xy 447.036666 -71.817794) (xy 447.029078 -71.826628) (xy 447.012325 -71.847411) (xy 446.973971 -71.884541)
			(xy 446.930817 -71.915963) (xy 446.883703 -71.941062) (xy 446.833551 -71.959348) (xy 446.78134 -71.970465)
			(xy 446.728088 -71.974195) (xy 446.674836 -71.970465) (xy 446.622625 -71.959348) (xy 446.572473 -71.941062)
			(xy 446.525359 -71.915963) (xy 446.482205 -71.884541) (xy 446.443851 -71.847411) (xy 446.427098 -71.826628)
			(xy 446.419494 -71.817818) (xy 446.39859 -71.807639) (xy 446.386966 -71.80707) (xy 446.30721 -71.80707)
			(xy 446.295577 -71.807605) (xy 446.274666 -71.817794) (xy 446.267078 -71.826628) (xy 446.250325 -71.847411)
			(xy 446.211971 -71.884541) (xy 446.168817 -71.915963) (xy 446.121703 -71.941062) (xy 446.071551 -71.959348)
			(xy 446.01934 -71.970465) (xy 445.966088 -71.974195) (xy 445.912836 -71.970465) (xy 445.860625 -71.959348)
			(xy 445.810473 -71.941062) (xy 445.763359 -71.915963) (xy 445.720205 -71.884541) (xy 445.681851 -71.847411)
			(xy 445.665098 -71.826628) (xy 445.657494 -71.817818) (xy 445.63659 -71.807639) (xy 445.624966 -71.80707)
			(xy 445.54521 -71.80707) (xy 445.533577 -71.807605) (xy 445.512666 -71.817794) (xy 445.505078 -71.826628)
			(xy 445.486906 -71.849128) (xy 445.444882 -71.888861) (xy 445.397343 -71.921797) (xy 445.345378 -71.947182)
			(xy 445.290177 -71.964435) (xy 445.233005 -71.973161) (xy 445.204088 -71.973694) (xy 445.176834 -71.973256)
			(xy 445.122882 -71.965497) (xy 445.070582 -71.950139) (xy 445.021001 -71.927494) (xy 444.975147 -71.898023)
			(xy 444.933954 -71.862327) (xy 444.898261 -71.821132) (xy 444.868793 -71.775276) (xy 444.846152 -71.725693)
			(xy 444.830797 -71.673393) (xy 444.823042 -71.61944) (xy 444.82258 -71.592186) (xy 443.863984 -71.592186)
			(xy 443.863984 -72.415584) (xy 448.803264 -72.415584) (xy 448.803264 -72.330888) (xy 448.811315 -72.246574)
			(xy 448.827344 -72.163408) (xy 448.851205 -72.082141) (xy 448.882684 -72.003511) (xy 448.921495 -71.92823)
			(xy 448.967285 -71.856978) (xy 449.019641 -71.790402) (xy 449.078089 -71.729104) (xy 449.142099 -71.673639)
			(xy 449.211091 -71.62451) (xy 449.284441 -71.582161) (xy 449.361484 -71.546977) (xy 449.441523 -71.519275)
			(xy 449.523832 -71.499307) (xy 449.607667 -71.487254) (xy 449.692268 -71.483224) (xy 449.776869 -71.487254)
			(xy 449.860704 -71.499307) (xy 449.943013 -71.519275) (xy 450.023052 -71.546977) (xy 450.100095 -71.582161)
			(xy 450.173445 -71.62451) (xy 450.242437 -71.673639) (xy 450.306447 -71.729104) (xy 450.364895 -71.790402)
			(xy 450.417251 -71.856978) (xy 450.463041 -71.92823) (xy 450.501852 -72.003511) (xy 450.533331 -72.082141)
			(xy 450.557192 -72.163408) (xy 450.573221 -72.246574) (xy 450.581272 -72.330888) (xy 450.581776 -72.373236)
			(xy 450.581272 -72.415584) (xy 456.311504 -72.415584) (xy 456.311504 -72.330888) (xy 456.319555 -72.246574)
			(xy 456.335584 -72.163408) (xy 456.359445 -72.082141) (xy 456.390924 -72.003511) (xy 456.429735 -71.92823)
			(xy 456.475525 -71.856978) (xy 456.527881 -71.790402) (xy 456.586329 -71.729104) (xy 456.650339 -71.673639)
			(xy 456.719331 -71.62451) (xy 456.792681 -71.582161) (xy 456.869724 -71.546977) (xy 456.949763 -71.519275)
			(xy 457.032072 -71.499307) (xy 457.115907 -71.487254) (xy 457.200508 -71.483224) (xy 457.285109 -71.487254)
			(xy 457.368944 -71.499307) (xy 457.451253 -71.519275) (xy 457.531292 -71.546977) (xy 457.608335 -71.582161)
			(xy 457.681685 -71.62451) (xy 457.750677 -71.673639) (xy 457.814687 -71.729104) (xy 457.873135 -71.790402)
			(xy 457.925491 -71.856978) (xy 457.971281 -71.92823) (xy 458.010092 -72.003511) (xy 458.041571 -72.082141)
			(xy 458.065432 -72.163408) (xy 458.081461 -72.246574) (xy 458.089512 -72.330888) (xy 458.090016 -72.373236)
			(xy 458.089512 -72.415584) (xy 458.081461 -72.499898) (xy 458.065432 -72.583064) (xy 458.041571 -72.664331)
			(xy 458.010092 -72.742961) (xy 457.971281 -72.818242) (xy 457.925491 -72.889494) (xy 457.873135 -72.95607)
			(xy 457.814687 -73.017368) (xy 457.750677 -73.072833) (xy 457.681685 -73.121962) (xy 457.608335 -73.164311)
			(xy 457.531292 -73.199495) (xy 457.451253 -73.227197) (xy 457.368944 -73.247165) (xy 457.285109 -73.259218)
			(xy 457.200508 -73.263249) (xy 457.115907 -73.259218) (xy 457.032072 -73.247165) (xy 456.949763 -73.227197)
			(xy 456.869724 -73.199495) (xy 456.792681 -73.164311) (xy 456.719331 -73.121962) (xy 456.650339 -73.072833)
			(xy 456.586329 -73.017368) (xy 456.527881 -72.95607) (xy 456.475525 -72.889494) (xy 456.429735 -72.818242)
			(xy 456.390924 -72.742961) (xy 456.359445 -72.664331) (xy 456.335584 -72.583064) (xy 456.319555 -72.499898)
			(xy 456.311504 -72.415584) (xy 450.581272 -72.415584) (xy 450.573221 -72.499898) (xy 450.557192 -72.583064)
			(xy 450.533331 -72.664331) (xy 450.501852 -72.742961) (xy 450.463041 -72.818242) (xy 450.417251 -72.889494)
			(xy 450.364895 -72.95607) (xy 450.306447 -73.017368) (xy 450.242437 -73.072833) (xy 450.173445 -73.121962)
			(xy 450.100095 -73.164311) (xy 450.023052 -73.199495) (xy 449.943013 -73.227197) (xy 449.860704 -73.247165)
			(xy 449.776869 -73.259218) (xy 449.692268 -73.263249) (xy 449.607667 -73.259218) (xy 449.523832 -73.247165)
			(xy 449.441523 -73.227197) (xy 449.361484 -73.199495) (xy 449.284441 -73.164311) (xy 449.211091 -73.121962)
			(xy 449.142099 -73.072833) (xy 449.078089 -73.017368) (xy 449.019641 -72.95607) (xy 448.967285 -72.889494)
			(xy 448.921495 -72.818242) (xy 448.882684 -72.742961) (xy 448.851205 -72.664331) (xy 448.827344 -72.583064)
			(xy 448.811315 -72.499898) (xy 448.803264 -72.415584) (xy 443.863984 -72.415584) (xy 443.863984 -72.456548)
			(xy 443.864415 -72.466615) (xy 443.87214 -72.485208) (xy 443.87897 -72.492616) (xy 444.266574 -72.879966)
			(xy 444.272924 -72.88657) (xy 444.28791 -72.901556) (xy 444.343028 -72.956928) (xy 444.349842 -72.964271)
			(xy 444.357576 -72.982735) (xy 444.358014 -72.992742) (xy 444.358014 -73.091548) (xy 444.358268 -73.1012)
			(xy 444.358268 -74.520044) (xy 444.46139 -74.520044) (xy 444.465461 -74.464422) (xy 444.477587 -74.409985)
			(xy 444.49751 -74.357894) (xy 444.524806 -74.309259) (xy 444.558892 -74.265116) (xy 444.599041 -74.226407)
			(xy 444.644399 -74.193956) (xy 444.693999 -74.168455) (xy 444.746783 -74.150448) (xy 444.801626 -74.140318)
			(xy 444.85736 -74.138281) (xy 444.912797 -74.144381) (xy 444.966754 -74.158487) (xy 445.018083 -74.180299)
			(xy 445.065689 -74.209353) (xy 445.108557 -74.245028) (xy 445.145774 -74.286565) (xy 445.176547 -74.333078)
			(xy 445.200219 -74.383575) (xy 445.216287 -74.436982) (xy 445.224407 -74.492158) (xy 445.224916 -74.520044)
			(xy 445.224407 -74.54793) (xy 445.216287 -74.603106) (xy 445.200219 -74.656513) (xy 445.176547 -74.70701)
			(xy 445.145774 -74.753523) (xy 445.108557 -74.79506) (xy 445.065689 -74.830735) (xy 445.018083 -74.859789)
			(xy 444.966754 -74.881601) (xy 444.912797 -74.895707) (xy 444.85736 -74.901807) (xy 444.801626 -74.89977)
			(xy 444.746783 -74.88964) (xy 444.693999 -74.871633) (xy 444.644399 -74.846132) (xy 444.599041 -74.813681)
			(xy 444.558892 -74.774972) (xy 444.524806 -74.730829) (xy 444.49751 -74.682194) (xy 444.477587 -74.630103)
			(xy 444.465461 -74.575666) (xy 444.46139 -74.520044) (xy 444.358268 -74.520044) (xy 444.358268 -74.915706)
			(xy 448.803264 -74.915706) (xy 448.803264 -74.83101) (xy 448.811315 -74.746696) (xy 448.827344 -74.66353)
			(xy 448.851205 -74.582263) (xy 448.882684 -74.503633) (xy 448.921495 -74.428352) (xy 448.967285 -74.3571)
			(xy 449.019641 -74.290524) (xy 449.078089 -74.229226) (xy 449.142099 -74.173761) (xy 449.211091 -74.124632)
			(xy 449.284441 -74.082283) (xy 449.361484 -74.047099) (xy 449.441523 -74.019397) (xy 449.523832 -73.999429)
			(xy 449.607667 -73.987376) (xy 449.692268 -73.983346) (xy 449.776869 -73.987376) (xy 449.860704 -73.999429)
			(xy 449.943013 -74.019397) (xy 450.023052 -74.047099) (xy 450.100095 -74.082283) (xy 450.173445 -74.124632)
			(xy 450.242437 -74.173761) (xy 450.306447 -74.229226) (xy 450.364895 -74.290524) (xy 450.417251 -74.3571)
			(xy 450.463041 -74.428352) (xy 450.501852 -74.503633) (xy 450.533331 -74.582263) (xy 450.557192 -74.66353)
			(xy 450.573221 -74.746696) (xy 450.581272 -74.83101) (xy 450.581776 -74.873358) (xy 450.581272 -74.915706)
			(xy 456.311504 -74.915706) (xy 456.311504 -74.83101) (xy 456.319555 -74.746696) (xy 456.335584 -74.66353)
			(xy 456.359445 -74.582263) (xy 456.390924 -74.503633) (xy 456.429735 -74.428352) (xy 456.475525 -74.3571)
			(xy 456.527881 -74.290524) (xy 456.586329 -74.229226) (xy 456.650339 -74.173761) (xy 456.719331 -74.124632)
			(xy 456.792681 -74.082283) (xy 456.869724 -74.047099) (xy 456.949763 -74.019397) (xy 457.032072 -73.999429)
			(xy 457.115907 -73.987376) (xy 457.200508 -73.983346) (xy 457.285109 -73.987376) (xy 457.368944 -73.999429)
			(xy 457.451253 -74.019397) (xy 457.531292 -74.047099) (xy 457.608335 -74.082283) (xy 457.681685 -74.124632)
			(xy 457.750677 -74.173761) (xy 457.814687 -74.229226) (xy 457.873135 -74.290524) (xy 457.925491 -74.3571)
			(xy 457.971281 -74.428352) (xy 458.010092 -74.503633) (xy 458.041571 -74.582263) (xy 458.065432 -74.66353)
			(xy 458.081461 -74.746696) (xy 458.089512 -74.83101) (xy 458.090016 -74.873358) (xy 458.089512 -74.915706)
			(xy 458.081461 -75.00002) (xy 458.065432 -75.083186) (xy 458.041571 -75.164453) (xy 458.010092 -75.243083)
			(xy 457.971281 -75.318364) (xy 457.925491 -75.389616) (xy 457.873135 -75.456192) (xy 457.814687 -75.51749)
			(xy 457.750677 -75.572955) (xy 457.681685 -75.622084) (xy 457.608335 -75.664433) (xy 457.531292 -75.699617)
			(xy 457.451253 -75.727319) (xy 457.368944 -75.747287) (xy 457.285109 -75.75934) (xy 457.200508 -75.763371)
			(xy 457.115907 -75.75934) (xy 457.032072 -75.747287) (xy 456.949763 -75.727319) (xy 456.869724 -75.699617)
			(xy 456.792681 -75.664433) (xy 456.719331 -75.622084) (xy 456.650339 -75.572955) (xy 456.586329 -75.51749)
			(xy 456.527881 -75.456192) (xy 456.475525 -75.389616) (xy 456.429735 -75.318364) (xy 456.390924 -75.243083)
			(xy 456.359445 -75.164453) (xy 456.335584 -75.083186) (xy 456.319555 -75.00002) (xy 456.311504 -74.915706)
			(xy 450.581272 -74.915706) (xy 450.573221 -75.00002) (xy 450.557192 -75.083186) (xy 450.533331 -75.164453)
			(xy 450.501852 -75.243083) (xy 450.463041 -75.318364) (xy 450.417251 -75.389616) (xy 450.364895 -75.456192)
			(xy 450.306447 -75.51749) (xy 450.242437 -75.572955) (xy 450.173445 -75.622084) (xy 450.100095 -75.664433)
			(xy 450.023052 -75.699617) (xy 449.943013 -75.727319) (xy 449.860704 -75.747287) (xy 449.776869 -75.75934)
			(xy 449.692268 -75.763371) (xy 449.607667 -75.75934) (xy 449.523832 -75.747287) (xy 449.441523 -75.727319)
			(xy 449.361484 -75.699617) (xy 449.284441 -75.664433) (xy 449.211091 -75.622084) (xy 449.142099 -75.572955)
			(xy 449.078089 -75.51749) (xy 449.019641 -75.456192) (xy 448.967285 -75.389616) (xy 448.921495 -75.318364)
			(xy 448.882684 -75.243083) (xy 448.851205 -75.164453) (xy 448.827344 -75.083186) (xy 448.811315 -75.00002)
			(xy 448.803264 -74.915706) (xy 444.358268 -74.915706) (xy 444.358268 -76.339446) (xy 444.358014 -76.349098)
			(xy 444.358014 -76.447904) (xy 444.357476 -76.457891) (xy 444.349763 -76.476324) (xy 444.343028 -76.483718)
			(xy 444.28791 -76.53909) (xy 444.272924 -76.554076) (xy 444.266574 -76.56068) (xy 442.905642 -77.921358)
			(xy 442.898276 -77.92847) (xy 442.890656 -77.947266) (xy 442.890656 -81.976468) (xy 442.891138 -81.986483)
			(xy 442.89879 -82.004993) (xy 442.912943 -82.019167) (xy 442.931442 -82.026847) (xy 442.941456 -82.027268)
			(xy 465.008976 -82.027268)
		)
		(stroke
			(width 0)
			(type solid)
		)
		(fill yes)
		(layer "In4.Cu")
		(net "GND")
	)
	(gr_poly
		(pts
			(xy 376.127772 -267.93063) (xy 376.138989 -267.929866) (xy 376.159142 -267.919965) (xy 376.166634 -267.91158)
			(xy 376.171714 -267.903706) (xy 376.212862 -267.826998) (xy 376.216826 -267.818741) (xy 376.219209 -267.800593)
			(xy 376.215065 -267.782765) (xy 376.210322 -267.774928) (xy 376.210322 -267.774674) (xy 376.198303 -267.755831)
			(xy 376.179313 -267.715374) (xy 376.166426 -267.67258) (xy 376.15992 -267.628364) (xy 376.159522 -267.606018)
			(xy 376.159522 -267.59916) (xy 376.160496 -267.575524) (xy 376.168839 -267.528961) (xy 376.184265 -267.484243)
			(xy 376.206404 -267.44244) (xy 376.234727 -267.404552) (xy 376.268556 -267.371487) (xy 376.30708 -267.344037)
			(xy 376.349378 -267.322858) (xy 376.394437 -267.308457) (xy 376.441178 -267.30118) (xy 376.46483 -267.30071)
			(xy 376.488492 -267.301157) (xy 376.53525 -267.308462) (xy 376.580321 -267.322892) (xy 376.622626 -267.344103)
			(xy 376.661153 -267.371586) (xy 376.694979 -267.404683) (xy 376.723295 -267.442601) (xy 376.745423 -267.484435)
			(xy 376.760832 -267.52918) (xy 376.769154 -267.575768) (xy 376.770138 -267.599414) (xy 376.770138 -267.606018)
			(xy 376.769747 -267.628364) (xy 376.763232 -267.672579) (xy 376.750343 -267.715372) (xy 376.731355 -267.75583)
			(xy 376.719338 -267.774674) (xy 376.719338 -267.774928) (xy 376.714565 -267.782754) (xy 376.710398 -267.800592)
			(xy 376.712795 -267.818752) (xy 376.716798 -267.826998) (xy 376.757946 -267.903706) (xy 376.763026 -267.91158)
			(xy 376.770504 -267.919981) (xy 376.790668 -267.929883) (xy 376.801888 -267.93063) (xy 377.067064 -267.93063)
			(xy 377.067826 -267.93063) (xy 377.079809 -267.929725) (xy 377.101002 -267.918459) (xy 377.108466 -267.90904)
			(xy 377.111768 -267.903706) (xy 377.15444 -267.824712) (xy 377.152662 -267.796518) (xy 377.144534 -267.78458)
			(xy 377.131472 -267.764764) (xy 377.110821 -267.722033) (xy 377.096823 -267.676685) (xy 377.089796 -267.629749)
			(xy 377.089416 -267.606018) (xy 377.089902 -267.581228) (xy 377.097658 -267.53226) (xy 377.112979 -267.485107)
			(xy 377.135488 -267.440932) (xy 377.16463 -267.400821) (xy 377.199687 -267.365764) (xy 377.239798 -267.336622)
			(xy 377.283973 -267.314113) (xy 377.331126 -267.298792) (xy 377.380094 -267.291036) (xy 377.429674 -267.291036)
			(xy 377.478642 -267.298792) (xy 377.525795 -267.314113) (xy 377.56997 -267.336622) (xy 377.610081 -267.365764)
			(xy 377.645138 -267.400821) (xy 377.67428 -267.440932) (xy 377.696789 -267.485107) (xy 377.71211 -267.53226)
			(xy 377.719866 -267.581228) (xy 377.720352 -267.606018) (xy 377.719934 -267.629743) (xy 377.712862 -267.676663)
			(xy 377.698864 -267.722001) (xy 377.678253 -267.764741) (xy 377.665234 -267.78458) (xy 377.657106 -267.796264)
			(xy 377.655582 -267.824458) (xy 377.698 -267.903706) (xy 377.70181 -267.910056) (xy 377.709272 -267.919164)
			(xy 377.730192 -267.929906) (xy 377.741942 -267.93063) (xy 378.007118 -267.93063) (xy 378.00788 -267.93063)
			(xy 378.019106 -267.929884) (xy 378.039289 -267.920006) (xy 378.046742 -267.91158) (xy 378.051822 -267.903706)
			(xy 378.09297 -267.826998) (xy 378.096934 -267.818741) (xy 378.099316 -267.800593) (xy 378.095173 -267.782765)
			(xy 378.09043 -267.774928) (xy 378.09043 -267.774674) (xy 378.078411 -267.755831) (xy 378.05942 -267.715375)
			(xy 378.046533 -267.67258) (xy 378.040026 -267.628364) (xy 378.03963 -267.606018) (xy 378.03963 -267.599414)
			(xy 378.040586 -267.575765) (xy 378.048898 -267.529173) (xy 378.064302 -267.484422) (xy 378.086429 -267.442584)
			(xy 378.114748 -267.404664) (xy 378.14858 -267.371568) (xy 378.187115 -267.344092) (xy 378.22943 -267.322892)
			(xy 378.27451 -267.308477) (xy 378.321274 -267.301194) (xy 378.344938 -267.30071) (xy 378.370458 -267.30122)
			(xy 378.420788 -267.309701) (xy 378.469006 -267.326435) (xy 378.513768 -267.350958) (xy 378.553827 -267.382586)
			(xy 378.588066 -267.420436) (xy 378.615532 -267.463455) (xy 378.635458 -267.510444) (xy 378.641864 -267.535152)
			(xy 378.645166 -267.548868) (xy 378.663962 -267.568426) (xy 378.760482 -267.595858) (xy 378.770388 -267.597636)
			(xy 378.780358 -267.597913) (xy 378.799316 -267.591781) (xy 378.807218 -267.585698) (xy 378.810266 -267.582904)
			(xy 378.833126 -267.560044) (xy 378.839846 -267.552808) (xy 378.847459 -267.534604) (xy 378.847858 -267.524738)
			(xy 378.847858 -267.17117) (xy 378.847415 -267.161382) (xy 378.840105 -267.14322) (xy 378.833634 -267.135864)
			(xy 378.81941 -267.121132) (xy 378.816362 -267.118166) (xy 378.809468 -267.113187) (xy 378.805694 -267.111226)
			(xy 378.783342 -267.099796) (xy 378.77496 -267.09878) (xy 378.750787 -267.095114) (xy 378.703952 -267.081096)
			(xy 378.659948 -267.059795) (xy 378.6199 -267.031755) (xy 378.58483 -266.997694) (xy 378.555634 -266.95848)
			(xy 378.533059 -266.915116) (xy 378.51768 -266.86871) (xy 378.509892 -266.820446) (xy 378.509891 -266.771557)
			(xy 378.51768 -266.723293) (xy 378.533058 -266.676886) (xy 378.555633 -266.633522) (xy 378.584828 -266.594308)
			(xy 378.619897 -266.560247) (xy 378.659945 -266.532207) (xy 378.703949 -266.510906) (xy 378.750784 -266.496887)
			(xy 378.77496 -266.493244) (xy 378.783342 -266.492228) (xy 378.805694 -266.480798) (xy 378.809471 -266.478843)
			(xy 378.816364 -266.47386) (xy 378.81941 -266.470892) (xy 378.833634 -266.45616) (xy 378.840118 -266.448809)
			(xy 378.847437 -266.430646) (xy 378.847858 -266.420854) (xy 378.847858 -266.344146) (xy 378.842778 -266.328652)
			(xy 378.837698 -266.322048) (xy 378.81647 -266.292887) (xy 378.780888 -266.230144) (xy 378.75367 -266.163346)
			(xy 378.73527 -266.093602) (xy 378.725993 -266.022071) (xy 378.72543 -265.986006) (xy 378.726015 -265.9492)
			(xy 378.735671 -265.876224) (xy 378.754818 -265.805145) (xy 378.783124 -265.737193) (xy 378.801122 -265.705082)
			(xy 378.841 -265.636502) (xy 378.844145 -265.630625) (xy 378.847627 -265.617763) (xy 378.847858 -265.611102)
			(xy 378.847858 -265.551158) (xy 378.847412 -265.541371) (xy 378.8401 -265.523212) (xy 378.833634 -265.515852)
			(xy 378.81941 -265.50112) (xy 378.816365 -265.49815) (xy 378.809474 -265.493163) (xy 378.805694 -265.491214)
			(xy 378.783342 -265.479784) (xy 378.77496 -265.478768) (xy 378.750789 -265.475101) (xy 378.703955 -265.461083)
			(xy 378.659953 -265.439783) (xy 378.619906 -265.411745) (xy 378.584838 -265.377685) (xy 378.555644 -265.338472)
			(xy 378.53307 -265.29511) (xy 378.517692 -265.248705) (xy 378.509904 -265.200443) (xy 378.509904 -265.151557)
			(xy 378.517692 -265.103295) (xy 378.53307 -265.05689) (xy 378.555644 -265.013528) (xy 378.584838 -264.974315)
			(xy 378.619906 -264.940255) (xy 378.659953 -264.912217) (xy 378.703955 -264.890917) (xy 378.750789 -264.876899)
			(xy 378.77496 -264.873232) (xy 378.783342 -264.872216) (xy 378.805694 -264.860786) (xy 378.809474 -264.858834)
			(xy 378.816372 -264.853858) (xy 378.81941 -264.85088) (xy 378.833634 -264.836148) (xy 378.840116 -264.828797)
			(xy 378.84743 -264.810634) (xy 378.847858 -264.800842) (xy 378.847858 -264.724134) (xy 378.842778 -264.70864)
			(xy 378.837698 -264.702036) (xy 378.815583 -264.671487) (xy 378.778878 -264.605603) (xy 378.764546 -264.570718)
			(xy 378.759466 -264.557764) (xy 378.737876 -264.540746) (xy 378.624084 -264.52576) (xy 378.598684 -264.536682)
			(xy 378.590302 -264.547604) (xy 378.575798 -264.566432) (xy 378.541943 -264.599783) (xy 378.503329 -264.627486)
			(xy 378.460889 -264.648873) (xy 378.415649 -264.663426) (xy 378.3687 -264.670794) (xy 378.344938 -264.671302)
			(xy 378.319679 -264.670812) (xy 378.269848 -264.662503) (xy 378.222066 -264.646104) (xy 378.177634 -264.622064)
			(xy 378.137765 -264.591038) (xy 378.103548 -264.553872) (xy 378.075915 -264.511581) (xy 378.055621 -264.465318)
			(xy 378.043218 -264.416346) (xy 378.039046 -264.366) (xy 378.043218 -264.315654) (xy 378.055621 -264.266682)
			(xy 378.075915 -264.220419) (xy 378.103548 -264.178128) (xy 378.137765 -264.140962) (xy 378.177634 -264.109936)
			(xy 378.222066 -264.085896) (xy 378.269848 -264.069497) (xy 378.319679 -264.061188) (xy 378.344938 -264.060686)
			(xy 378.368698 -264.061162) (xy 378.415638 -264.068565) (xy 378.460869 -264.083139) (xy 378.503301 -264.104535)
			(xy 378.541912 -264.132236) (xy 378.575774 -264.165576) (xy 378.590302 -264.184384) (xy 378.598684 -264.195306)
			(xy 378.624084 -264.206228) (xy 378.737876 -264.191242) (xy 378.759466 -264.174224) (xy 378.764546 -264.16127)
			(xy 378.772418 -264.141635) (xy 378.790723 -264.103492) (xy 378.801122 -264.08507) (xy 378.841 -264.01649)
			(xy 378.844144 -264.010613) (xy 378.847622 -263.997751) (xy 378.847858 -263.99109) (xy 378.847858 -263.525254)
			(xy 378.847425 -263.515188) (xy 378.839694 -263.4966) (xy 378.832872 -263.489186) (xy 378.696982 -263.353296)
			(xy 378.68987 -263.34593) (xy 378.671074 -263.33831) (xy 378.26315 -263.33831) (xy 378.251211 -263.33895)
			(xy 378.229875 -263.349672) (xy 378.222256 -263.358884) (xy 378.175012 -263.422638) (xy 378.171202 -263.446768)
			(xy 378.175012 -263.458706) (xy 378.182142 -263.482392) (xy 378.189803 -263.531257) (xy 378.190252 -263.555988)
			(xy 378.189766 -263.580778) (xy 378.18201 -263.629746) (xy 378.166689 -263.676899) (xy 378.14418 -263.721074)
			(xy 378.115038 -263.761185) (xy 378.079981 -263.796242) (xy 378.03987 -263.825384) (xy 377.995695 -263.847893)
			(xy 377.948542 -263.863214) (xy 377.899574 -263.87097) (xy 377.849994 -263.87097) (xy 377.801026 -263.863214)
			(xy 377.753873 -263.847893) (xy 377.709698 -263.825384) (xy 377.669587 -263.796242) (xy 377.63453 -263.761185)
			(xy 377.605388 -263.721074) (xy 377.582879 -263.676899) (xy 377.567558 -263.629746) (xy 377.559802 -263.580778)
			(xy 377.559316 -263.555988) (xy 377.559732 -263.531254) (xy 377.56739 -263.482383) (xy 377.574556 -263.458706)
			(xy 377.578366 -263.446768) (xy 377.574556 -263.422638) (xy 377.527312 -263.358884) (xy 377.519701 -263.349658)
			(xy 377.498363 -263.338928) (xy 377.486418 -263.33831) (xy 377.323096 -263.33831) (xy 377.311163 -263.338962)
			(xy 377.289846 -263.349696) (xy 377.282202 -263.358884) (xy 377.234958 -263.422892) (xy 377.228372 -263.432824)
			(xy 377.224271 -263.456269) (xy 377.227084 -263.46785) (xy 377.227084 -263.468104) (xy 377.233098 -263.489512)
			(xy 377.2396 -263.533501) (xy 377.240038 -263.555734) (xy 377.240038 -263.55929) (xy 377.239259 -263.584366)
			(xy 377.230524 -263.633767) (xy 377.21383 -263.681074) (xy 377.189628 -263.725016) (xy 377.158568 -263.764411)
			(xy 377.121485 -263.798199) (xy 377.079378 -263.82547) (xy 377.03338 -263.84549) (xy 376.984728 -263.857723)
			(xy 376.93473 -263.861837) (xy 376.884732 -263.857723) (xy 376.83608 -263.84549) (xy 376.790082 -263.82547)
			(xy 376.747975 -263.798199) (xy 376.710892 -263.764411) (xy 376.679832 -263.725016) (xy 376.65563 -263.681074)
			(xy 376.638936 -263.633767) (xy 376.630201 -263.584366) (xy 376.629422 -263.55929) (xy 376.629422 -263.555734)
			(xy 376.629822 -263.533498) (xy 376.636328 -263.489505) (xy 376.642376 -263.468104) (xy 376.642376 -263.46785)
			(xy 376.645236 -263.456269) (xy 376.641142 -263.432801) (xy 376.634502 -263.422892) (xy 376.587258 -263.358884)
			(xy 376.57965 -263.349651) (xy 376.558312 -263.338901) (xy 376.546364 -263.33831) (xy 376.383296 -263.33831)
			(xy 376.371363 -263.338962) (xy 376.350046 -263.349696) (xy 376.342402 -263.358884) (xy 376.295158 -263.422638)
			(xy 376.291348 -263.446768) (xy 376.295158 -263.458706) (xy 376.302388 -263.482374) (xy 376.31017 -263.531245)
			(xy 376.310652 -263.555988) (xy 376.310165 -263.580798) (xy 376.302403 -263.629806) (xy 376.28707 -263.676996)
			(xy 376.264543 -263.721207) (xy 376.235378 -263.76135) (xy 376.200292 -263.796436) (xy 376.160149 -263.825601)
			(xy 376.115938 -263.848128) (xy 376.068748 -263.863461) (xy 376.01974 -263.871223) (xy 375.97012 -263.871223)
			(xy 375.921112 -263.863461) (xy 375.873922 -263.848128) (xy 375.829711 -263.825601) (xy 375.789568 -263.796436)
			(xy 375.754482 -263.76135) (xy 375.725317 -263.721207) (xy 375.70279 -263.676996) (xy 375.687457 -263.629806)
			(xy 375.679695 -263.580798) (xy 375.679208 -263.555988) (xy 375.679732 -263.531249) (xy 375.687516 -263.482385)
			(xy 375.694702 -263.458706) (xy 375.698512 -263.446768) (xy 375.694702 -263.422638) (xy 375.647458 -263.358884)
			(xy 375.63985 -263.349651) (xy 375.618512 -263.338901) (xy 375.606564 -263.33831) (xy 375.443242 -263.33831)
			(xy 375.431304 -263.338952) (xy 375.409971 -263.349675) (xy 375.402348 -263.358884) (xy 375.355104 -263.422892)
			(xy 375.348523 -263.432825) (xy 375.344427 -263.456268) (xy 375.34723 -263.46785) (xy 375.34723 -263.468104)
			(xy 375.353245 -263.489512) (xy 375.359748 -263.533501) (xy 375.360184 -263.555734) (xy 375.360184 -263.55929)
			(xy 375.359405 -263.584366) (xy 375.35067 -263.633767) (xy 375.333976 -263.681074) (xy 375.309774 -263.725016)
			(xy 375.278714 -263.764411) (xy 375.241631 -263.798199) (xy 375.199524 -263.82547) (xy 375.153526 -263.84549)
			(xy 375.104874 -263.857723) (xy 375.054876 -263.861837) (xy 375.004878 -263.857723) (xy 374.956226 -263.84549)
			(xy 374.910228 -263.82547) (xy 374.868121 -263.798199) (xy 374.831038 -263.764411) (xy 374.799978 -263.725016)
			(xy 374.775776 -263.681074) (xy 374.759082 -263.633767) (xy 374.750347 -263.584366) (xy 374.749568 -263.55929)
			(xy 374.749568 -263.555734) (xy 374.749968 -263.533498) (xy 374.756475 -263.489505) (xy 374.762522 -263.468104)
			(xy 374.762522 -263.46785) (xy 374.765384 -263.456269) (xy 374.761285 -263.432802) (xy 374.754648 -263.422892)
			(xy 374.707404 -263.358884) (xy 374.699792 -263.34966) (xy 374.678454 -263.338932) (xy 374.66651 -263.33831)
			(xy 373.563134 -263.33831) (xy 373.551197 -263.338954) (xy 373.529866 -263.349679) (xy 373.52224 -263.358884)
			(xy 373.474996 -263.422892) (xy 373.468416 -263.432825) (xy 373.46432 -263.456268) (xy 373.467122 -263.46785)
			(xy 373.467122 -263.468104) (xy 373.473137 -263.489512) (xy 373.47964 -263.533501) (xy 373.480076 -263.555734)
			(xy 373.480076 -263.55929) (xy 373.479297 -263.584366) (xy 373.470562 -263.633767) (xy 373.453868 -263.681074)
			(xy 373.429666 -263.725016) (xy 373.398606 -263.764411) (xy 373.361523 -263.798199) (xy 373.319416 -263.82547)
			(xy 373.273418 -263.84549) (xy 373.224766 -263.857723) (xy 373.174768 -263.861837) (xy 373.12477 -263.857723)
			(xy 373.076118 -263.84549) (xy 373.03012 -263.82547) (xy 372.988013 -263.798199) (xy 372.95093 -263.764411)
			(xy 372.91987 -263.725016) (xy 372.895668 -263.681074) (xy 372.878974 -263.633767) (xy 372.870239 -263.584366)
			(xy 372.86946 -263.55929) (xy 372.86946 -263.555734) (xy 372.86986 -263.533498) (xy 372.876366 -263.489505)
			(xy 372.882414 -263.468104) (xy 372.882414 -263.46785) (xy 372.885276 -263.45627) (xy 372.881177 -263.432803)
			(xy 372.87454 -263.422892) (xy 372.827296 -263.358884) (xy 372.819684 -263.349661) (xy 372.798345 -263.338937)
			(xy 372.786402 -263.33831) (xy 372.051326 -263.33831) (xy 372.041489 -263.337774) (xy 372.023327 -263.330187)
			(xy 372.01602 -263.323578) (xy 371.755924 -263.063482) (xy 371.752891 -263.060499) (xy 371.74599 -263.055524)
			(xy 371.742208 -263.053576) (xy 371.734334 -263.049766) (xy 371.725952 -263.04875) (xy 371.701109 -263.045048)
			(xy 371.653012 -263.030587) (xy 371.607932 -263.008447) (xy 371.567084 -262.979227) (xy 371.531571 -262.943713)
			(xy 371.50235 -262.902864) (xy 371.480211 -262.857783) (xy 371.465751 -262.809686) (xy 371.462046 -262.784844)
			(xy 371.46103 -262.776462) (xy 371.45722 -262.768588) (xy 371.455237 -262.764828) (xy 371.450256 -262.757941)
			(xy 371.447314 -262.754872) (xy 371.156738 -262.464296) (xy 371.149626 -262.45693) (xy 371.13083 -262.44931)
			(xy 371.082316 -262.44931) (xy 371.072293 -262.449727) (xy 371.053773 -262.457394) (xy 371.039598 -262.471568)
			(xy 371.031928 -262.490087) (xy 371.031516 -262.50011) (xy 371.031516 -262.510016) (xy 371.038628 -262.52805)
			(xy 371.045486 -262.535162) (xy 371.061263 -262.552297) (xy 371.087961 -262.59046) (xy 371.108548 -262.632239)
			(xy 371.122545 -262.676661) (xy 371.129627 -262.722694) (xy 371.130068 -262.745982) (xy 371.129623 -262.769975)
			(xy 371.122118 -262.81737) (xy 371.107291 -262.863008) (xy 371.085506 -262.905763) (xy 371.0573 -262.944584)
			(xy 371.023368 -262.978514) (xy 370.984545 -263.006717) (xy 370.941787 -263.028499) (xy 370.896149 -263.043324)
			(xy 370.848753 -263.050825) (xy 370.82476 -263.05129) (xy 370.80106 -263.050839) (xy 370.75423 -263.04351)
			(xy 370.709096 -263.029033) (xy 370.66674 -263.007756) (xy 370.628179 -262.98019) (xy 370.594341 -262.946998)
			(xy 370.566038 -262.908976) (xy 370.543949 -262.867038) (xy 370.528605 -262.82219) (xy 370.520375 -262.77551)
			(xy 370.519452 -262.751824) (xy 370.519452 -262.747252) (xy 370.519858 -262.721345) (xy 370.528401 -262.670246)
			(xy 370.545473 -262.62133) (xy 370.557552 -262.598408) (xy 370.564156 -262.58647) (xy 370.563648 -262.559546)
			(xy 370.51361 -262.474456) (xy 370.508857 -262.466963) (xy 370.495227 -262.455617) (xy 370.478537 -262.449622)
			(xy 370.469668 -262.44931) (xy 370.239798 -262.44931) (xy 370.230949 -262.4497) (xy 370.214308 -262.455727)
			(xy 370.200692 -262.467034) (xy 370.195856 -262.474456) (xy 370.145818 -262.559546) (xy 370.14531 -262.58647)
			(xy 370.151914 -262.598408) (xy 370.163949 -262.621347) (xy 370.180979 -262.670265) (xy 370.189535 -262.721352)
			(xy 370.190014 -262.747252) (xy 370.190014 -262.751824) (xy 370.189041 -262.776763) (xy 370.179985 -262.82584)
			(xy 370.16307 -262.872792) (xy 370.138744 -262.916369) (xy 370.107657 -262.95541) (xy 370.070635 -262.988876)
			(xy 370.028664 -263.015877) (xy 369.982861 -263.035693) (xy 369.934446 -263.047798) (xy 369.884706 -263.051869)
			(xy 369.834966 -263.047798) (xy 369.786551 -263.035693) (xy 369.740748 -263.015877) (xy 369.698777 -262.988876)
			(xy 369.661755 -262.95541) (xy 369.630668 -262.916369) (xy 369.606342 -262.872792) (xy 369.589427 -262.82584)
			(xy 369.580371 -262.776763) (xy 369.579398 -262.751824) (xy 369.579398 -262.747252) (xy 369.579804 -262.721345)
			(xy 369.588346 -262.670245) (xy 369.605414 -262.621328) (xy 369.617498 -262.598408) (xy 369.624102 -262.58647)
			(xy 369.623594 -262.559546) (xy 369.573556 -262.474456) (xy 369.568805 -262.466958) (xy 369.555177 -262.455599)
			(xy 369.538485 -262.44959) (xy 369.529614 -262.44931) (xy 367.606326 -262.44931) (xy 367.596489 -262.448774)
			(xy 367.578327 -262.441187) (xy 367.57102 -262.434578) (xy 366.965738 -261.829296) (xy 366.958626 -261.82193)
			(xy 366.93983 -261.81431) (xy 365.736378 -261.81431) (xy 365.733584 -261.81431) (xy 365.721299 -261.815568)
			(xy 365.700116 -261.828211) (xy 365.693198 -261.83844) (xy 365.690912 -261.84225) (xy 365.651288 -261.921244)
			(xy 365.647381 -261.929846) (xy 365.64559 -261.948641) (xy 365.650756 -261.9668) (xy 365.656114 -261.974584)
			(xy 365.656114 -261.974838) (xy 365.672123 -261.99722) (xy 365.697557 -262.046013) (xy 365.714885 -262.098238)
			(xy 365.723664 -262.152558) (xy 365.724186 -262.18007) (xy 365.724186 -262.187436) (xy 365.723114 -262.214043)
			(xy 365.713771 -262.266464) (xy 365.696451 -262.316815) (xy 365.671567 -262.36389) (xy 365.639718 -262.406562)
			(xy 365.601665 -262.443807) (xy 365.55832 -262.474735) (xy 365.510722 -262.498602) (xy 365.460011 -262.514839)
			(xy 365.407402 -262.523056) (xy 365.354154 -262.523056) (xy 365.301545 -262.514839) (xy 365.250834 -262.498602)
			(xy 365.203236 -262.474735) (xy 365.159891 -262.443807) (xy 365.121838 -262.406562) (xy 365.089989 -262.36389)
			(xy 365.065105 -262.316815) (xy 365.047785 -262.266464) (xy 365.038442 -262.214043) (xy 365.03737 -262.187436)
			(xy 365.03737 -262.18007) (xy 365.037916 -262.152559) (xy 365.046693 -262.098243) (xy 365.064018 -262.04602)
			(xy 365.089448 -261.997228) (xy 365.105442 -261.974838) (xy 365.105442 -261.974584) (xy 365.11074 -261.96678)
			(xy 365.115838 -261.948637) (xy 365.114074 -261.929875) (xy 365.110268 -261.921244) (xy 365.070644 -261.84225)
			(xy 365.068358 -261.83844) (xy 365.061279 -261.828377) (xy 365.040188 -261.81578) (xy 365.027972 -261.81431)
			(xy 364.891828 -261.81431) (xy 364.88199 -261.813774) (xy 364.863829 -261.806188) (xy 364.856522 -261.799578)
			(xy 364.56874 -261.511796) (xy 364.560563 -261.504387) (xy 364.53989 -261.496733) (xy 364.528862 -261.497064)
			(xy 364.453678 -261.502906) (xy 364.442707 -261.504395) (xy 364.423474 -261.515315) (xy 364.416594 -261.523988)
			(xy 364.400318 -261.545611) (xy 364.362109 -261.583937) (xy 364.318367 -261.615803) (xy 364.270173 -261.640422)
			(xy 364.218716 -261.657187) (xy 364.165269 -261.665683) (xy 364.13821 -261.666228) (xy 364.137956 -261.666228)
			(xy 364.110973 -261.665695) (xy 364.057671 -261.657247) (xy 364.006347 -261.640566) (xy 363.958263 -261.616062)
			(xy 363.914605 -261.584339) (xy 363.876446 -261.546177) (xy 363.844725 -261.502516) (xy 363.820225 -261.454431)
			(xy 363.803547 -261.403106) (xy 363.795103 -261.349803) (xy 363.794548 -261.32282) (xy 363.795059 -261.296142)
			(xy 363.803323 -261.24343) (xy 363.819639 -261.192629) (xy 363.843615 -261.144963) (xy 363.874673 -261.101578)
			(xy 363.912068 -261.063518) (xy 363.954898 -261.031699) (xy 364.002134 -261.006886) (xy 364.052638 -260.989677)
			(xy 364.105197 -260.980485) (xy 364.13186 -260.979412) (xy 364.138718 -260.979412) (xy 364.169303 -260.980129)
			(xy 364.229495 -260.991038) (xy 364.286814 -261.012404) (xy 364.31347 -261.027418) (xy 364.325154 -261.03453)
			(xy 364.352586 -261.034784) (xy 364.4392 -260.985508) (xy 364.44301 -260.983222) (xy 364.45251 -260.975885)
			(xy 364.463914 -260.954802) (xy 364.464854 -260.942836) (xy 364.464854 -260.21665) (xy 364.464463 -260.207518)
			(xy 364.458034 -260.190422) (xy 364.446013 -260.17667) (xy 364.438184 -260.171946) (xy 364.361476 -260.130544)
			(xy 364.353366 -260.12663) (xy 364.335535 -260.124187) (xy 364.31796 -260.128058) (xy 364.310168 -260.132576)
			(xy 364.30966 -260.13283) (xy 364.309406 -260.13283) (xy 364.288416 -260.145978) (xy 364.243458 -260.166762)
			(xy 364.195982 -260.180877) (xy 364.146972 -260.188031) (xy 364.122208 -260.188456) (xy 364.115604 -260.188456)
			(xy 364.089212 -260.187465) (xy 364.037189 -260.178379) (xy 363.987169 -260.161436) (xy 363.940333 -260.137035)
			(xy 363.897784 -260.105752) (xy 363.860526 -260.068323) (xy 363.829437 -260.025632) (xy 363.805251 -259.978685)
			(xy 363.788536 -259.928588) (xy 363.779688 -259.876524) (xy 363.7788 -259.850128) (xy 363.7788 -259.847842)
			(xy 363.7788 -259.845048) (xy 363.779287 -259.819564) (xy 363.786857 -259.76916) (xy 363.80178 -259.720424)
			(xy 363.812328 -259.69722) (xy 363.817916 -259.685282) (xy 363.816392 -259.659374) (xy 363.764576 -259.577332)
			(xy 363.762798 -259.574792) (xy 363.755234 -259.565452) (xy 363.7339 -259.554454) (xy 363.721904 -259.55371)
			(xy 361.922822 -259.55371) (xy 361.922568 -259.55371) (xy 361.910567 -259.554431) (xy 361.889234 -259.565442)
			(xy 361.881674 -259.574792) (xy 361.879896 -259.577332) (xy 361.82808 -259.659374) (xy 361.826556 -259.685282)
			(xy 361.832144 -259.69722) (xy 361.842721 -259.720414) (xy 361.857663 -259.769149) (xy 361.865222 -259.819561)
			(xy 361.865672 -259.845048) (xy 361.865672 -259.850128) (xy 361.864767 -259.876852) (xy 361.8557 -259.929547)
			(xy 361.838577 -259.9802) (xy 361.813811 -260.027587) (xy 361.782 -260.070563) (xy 361.743913 -260.108091)
			(xy 361.70047 -260.139263) (xy 361.652722 -260.163326) (xy 361.601821 -260.179698) (xy 361.548998 -260.187984)
			(xy 361.49553 -260.187984) (xy 361.442707 -260.179698) (xy 361.391806 -260.163326) (xy 361.344058 -260.139263)
			(xy 361.300615 -260.108091) (xy 361.262528 -260.070563) (xy 361.230717 -260.027587) (xy 361.205951 -259.9802)
			(xy 361.188828 -259.929547) (xy 361.179761 -259.876852) (xy 361.178856 -259.850128) (xy 361.178856 -259.847842)
			(xy 361.178856 -259.845048) (xy 361.179343 -259.819564) (xy 361.186912 -259.769159) (xy 361.201833 -259.720423)
			(xy 361.212384 -259.69722) (xy 361.217972 -259.685282) (xy 361.216448 -259.659374) (xy 361.164632 -259.577332)
			(xy 361.162854 -259.574792) (xy 361.155287 -259.565459) (xy 361.133952 -259.55448) (xy 361.12196 -259.55371)
			(xy 360.396028 -259.55371) (xy 360.38619 -259.553174) (xy 360.368029 -259.545588) (xy 360.360722 -259.538978)
			(xy 359.74147 -258.919726) (xy 359.734293 -258.913129) (xy 359.716397 -258.905444) (xy 359.706672 -258.90474)
			(xy 359.69702 -258.905502) (xy 359.60558 -258.920996) (xy 359.585768 -258.935728) (xy 359.580434 -258.94665)
			(xy 359.567893 -258.970935) (xy 359.536297 -259.01553) (xy 359.498037 -259.054559) (xy 359.454079 -259.087035)
			(xy 359.405532 -259.112139) (xy 359.353622 -259.129238) (xy 359.299659 -259.137899) (xy 359.272332 -259.13842)
			(xy 359.245548 -259.137909) (xy 359.192628 -259.129596) (xy 359.141641 -259.113168) (xy 359.093824 -259.089021)
			(xy 359.050335 -259.057743) (xy 359.012231 -259.020092) (xy 358.980435 -258.976981) (xy 358.955718 -258.929455)
			(xy 358.938681 -258.878669) (xy 358.929736 -258.825852) (xy 358.928924 -258.799076) (xy 358.928924 -258.794758)
			(xy 358.929583 -258.763776) (xy 358.940698 -258.702818) (xy 358.951022 -258.6736) (xy 358.955594 -258.661916)
			(xy 358.952546 -258.637278) (xy 358.899206 -258.559808) (xy 358.891681 -258.549911) (xy 358.869713 -258.53833)
			(xy 358.857296 -258.53771) (xy 357.187246 -258.53771) (xy 357.174823 -258.538318) (xy 357.152838 -258.54989)
			(xy 357.145336 -258.559808) (xy 357.091996 -258.637278) (xy 357.088948 -258.661916) (xy 357.09352 -258.6736)
			(xy 357.103739 -258.702649) (xy 357.114856 -258.763211) (xy 357.115618 -258.793996) (xy 357.115618 -258.799076)
			(xy 357.114787 -258.825849) (xy 357.105842 -258.878659) (xy 357.088804 -258.929439) (xy 357.064088 -258.976957)
			(xy 357.032293 -259.020061) (xy 356.99419 -259.057705) (xy 356.950703 -259.088975) (xy 356.902889 -259.113112)
			(xy 356.851906 -259.129532) (xy 356.798991 -259.137836) (xy 356.77221 -259.13842) (xy 356.767892 -259.13842)
			(xy 356.757926 -259.138896) (xy 356.739488 -259.146471) (xy 356.732078 -259.153152) (xy 356.68204 -259.202936)
			(xy 356.67522 -259.2102) (xy 356.667483 -259.228542) (xy 356.667054 -259.238496) (xy 356.667054 -259.401056)
			(xy 356.667489 -259.41112) (xy 356.675224 -259.429705) (xy 356.68204 -259.437124) (xy 356.732078 -259.486908)
			(xy 356.739487 -259.493595) (xy 356.757923 -259.501183) (xy 356.767892 -259.50164) (xy 356.77221 -259.50164)
			(xy 356.797905 -259.502121) (xy 356.84872 -259.509781) (xy 356.897827 -259.52493) (xy 356.944127 -259.547228)
			(xy 356.986586 -259.576177) (xy 357.024257 -259.611132) (xy 357.056297 -259.65131) (xy 357.081992 -259.695815)
			(xy 357.100766 -259.743653) (xy 357.112201 -259.793754) (xy 357.116042 -259.845) (xy 357.116038 -259.845048)
			(xy 358.928419 -259.845048) (xy 358.932449 -259.79255) (xy 358.944446 -259.741282) (xy 358.964129 -259.692447)
			(xy 358.991035 -259.647188) (xy 359.024535 -259.606567) (xy 359.063843 -259.571536) (xy 359.108038 -259.542916)
			(xy 359.156083 -259.521377) (xy 359.206854 -259.507425) (xy 359.259159 -259.501387) (xy 359.311773 -259.503404)
			(xy 359.363463 -259.513428) (xy 359.413016 -259.531226) (xy 359.459272 -259.556379) (xy 359.501146 -259.588298)
			(xy 359.537658 -259.626236) (xy 359.56795 -259.669302) (xy 359.591313 -259.716487) (xy 359.607199 -259.766686)
			(xy 359.615236 -259.818722) (xy 359.61574 -259.845048) (xy 359.615236 -259.871374) (xy 359.607199 -259.92341)
			(xy 359.591313 -259.973609) (xy 359.56795 -260.020794) (xy 359.537658 -260.06386) (xy 359.501146 -260.101798)
			(xy 359.459272 -260.133717) (xy 359.413016 -260.15887) (xy 359.363463 -260.176668) (xy 359.311773 -260.186692)
			(xy 359.259159 -260.188709) (xy 359.206854 -260.182671) (xy 359.156083 -260.168719) (xy 359.108038 -260.14718)
			(xy 359.063843 -260.11856) (xy 359.024535 -260.083529) (xy 358.991035 -260.042908) (xy 358.964129 -259.997649)
			(xy 358.944446 -259.948814) (xy 358.932449 -259.897546) (xy 358.928419 -259.845048) (xy 357.116038 -259.845048)
			(xy 357.112201 -259.896246) (xy 357.100766 -259.946347) (xy 357.081992 -259.994185) (xy 357.056297 -260.03869)
			(xy 357.024257 -260.078868) (xy 356.986586 -260.113823) (xy 356.944127 -260.142772) (xy 356.897827 -260.16507)
			(xy 356.84872 -260.180219) (xy 356.797905 -260.187879) (xy 356.77221 -260.188456) (xy 356.767892 -260.188456)
			(xy 356.757924 -260.188931) (xy 356.739481 -260.196499) (xy 356.732078 -260.203188) (xy 356.68204 -260.252972)
			(xy 356.675225 -260.260238) (xy 356.667501 -260.27858) (xy 356.667054 -260.288532) (xy 356.667054 -260.986524)
			(xy 356.681786 -261.010654) (xy 356.69474 -261.017258) (xy 356.718452 -261.030011) (xy 356.761932 -261.061759)
			(xy 356.799926 -261.099902) (xy 356.831501 -261.143508) (xy 356.855884 -261.191507) (xy 356.872479 -261.242723)
			(xy 356.880877 -261.295901) (xy 356.88143 -261.32282) (xy 357.144069 -261.32282) (xy 357.148099 -261.270322)
			(xy 357.160096 -261.219054) (xy 357.179779 -261.170219) (xy 357.206685 -261.12496) (xy 357.240185 -261.084339)
			(xy 357.279493 -261.049308) (xy 357.323688 -261.020688) (xy 357.371733 -260.999149) (xy 357.422504 -260.985197)
			(xy 357.474809 -260.979159) (xy 357.527423 -260.981176) (xy 357.579113 -260.9912) (xy 357.628666 -261.008998)
			(xy 357.674922 -261.034151) (xy 357.716796 -261.06607) (xy 357.753308 -261.104008) (xy 357.7836 -261.147074)
			(xy 357.806963 -261.194259) (xy 357.822849 -261.244458) (xy 357.830886 -261.296494) (xy 357.83139 -261.32282)
			(xy 358.094029 -261.32282) (xy 358.098059 -261.270322) (xy 358.110056 -261.219054) (xy 358.129739 -261.170219)
			(xy 358.156645 -261.12496) (xy 358.190145 -261.084339) (xy 358.229453 -261.049308) (xy 358.273648 -261.020688)
			(xy 358.321693 -260.999149) (xy 358.372464 -260.985197) (xy 358.424769 -260.979159) (xy 358.477383 -260.981176)
			(xy 358.529073 -260.9912) (xy 358.578626 -261.008998) (xy 358.624882 -261.034151) (xy 358.666756 -261.06607)
			(xy 358.703268 -261.104008) (xy 358.73356 -261.147074) (xy 358.756923 -261.194259) (xy 358.772809 -261.244458)
			(xy 358.780846 -261.296494) (xy 358.78135 -261.32282) (xy 359.043989 -261.32282) (xy 359.048019 -261.270322)
			(xy 359.060016 -261.219054) (xy 359.079699 -261.170219) (xy 359.106605 -261.12496) (xy 359.140105 -261.084339)
			(xy 359.179413 -261.049308) (xy 359.223608 -261.020688) (xy 359.271653 -260.999149) (xy 359.322424 -260.985197)
			(xy 359.374729 -260.979159) (xy 359.427343 -260.981176) (xy 359.479033 -260.9912) (xy 359.528586 -261.008998)
			(xy 359.574842 -261.034151) (xy 359.616716 -261.06607) (xy 359.653228 -261.104008) (xy 359.68352 -261.147074)
			(xy 359.706883 -261.194259) (xy 359.722769 -261.244458) (xy 359.730806 -261.296494) (xy 359.73131 -261.32282)
			(xy 359.993949 -261.32282) (xy 359.997979 -261.270322) (xy 360.009976 -261.219054) (xy 360.029659 -261.170219)
			(xy 360.056565 -261.12496) (xy 360.090065 -261.084339) (xy 360.129373 -261.049308) (xy 360.173568 -261.020688)
			(xy 360.221613 -260.999149) (xy 360.272384 -260.985197) (xy 360.324689 -260.979159) (xy 360.377303 -260.981176)
			(xy 360.428993 -260.9912) (xy 360.478546 -261.008998) (xy 360.524802 -261.034151) (xy 360.566676 -261.06607)
			(xy 360.603188 -261.104008) (xy 360.63348 -261.147074) (xy 360.656843 -261.194259) (xy 360.672729 -261.244458)
			(xy 360.680766 -261.296494) (xy 360.68127 -261.32282) (xy 360.944163 -261.32282) (xy 360.948193 -261.270322)
			(xy 360.96019 -261.219054) (xy 360.979873 -261.170219) (xy 361.006779 -261.12496) (xy 361.040279 -261.084339)
			(xy 361.079587 -261.049308) (xy 361.123782 -261.020688) (xy 361.171827 -260.999149) (xy 361.222598 -260.985197)
			(xy 361.274903 -260.979159) (xy 361.327517 -260.981176) (xy 361.379207 -260.9912) (xy 361.42876 -261.008998)
			(xy 361.475016 -261.034151) (xy 361.51689 -261.06607) (xy 361.553402 -261.104008) (xy 361.583694 -261.147074)
			(xy 361.607057 -261.194259) (xy 361.622943 -261.244458) (xy 361.63098 -261.296494) (xy 361.631484 -261.32282)
			(xy 361.894123 -261.32282) (xy 361.898153 -261.270322) (xy 361.91015 -261.219054) (xy 361.929833 -261.170219)
			(xy 361.956739 -261.12496) (xy 361.990239 -261.084339) (xy 362.029547 -261.049308) (xy 362.073742 -261.020688)
			(xy 362.121787 -260.999149) (xy 362.172558 -260.985197) (xy 362.224863 -260.979159) (xy 362.277477 -260.981176)
			(xy 362.329167 -260.9912) (xy 362.37872 -261.008998) (xy 362.424976 -261.034151) (xy 362.46685 -261.06607)
			(xy 362.503362 -261.104008) (xy 362.533654 -261.147074) (xy 362.557017 -261.194259) (xy 362.572903 -261.244458)
			(xy 362.58094 -261.296494) (xy 362.581444 -261.32282) (xy 362.844083 -261.32282) (xy 362.848113 -261.270322)
			(xy 362.86011 -261.219054) (xy 362.879793 -261.170219) (xy 362.906699 -261.12496) (xy 362.940199 -261.084339)
			(xy 362.979507 -261.049308) (xy 363.023702 -261.020688) (xy 363.071747 -260.999149) (xy 363.122518 -260.985197)
			(xy 363.174823 -260.979159) (xy 363.227437 -260.981176) (xy 363.279127 -260.9912) (xy 363.32868 -261.008998)
			(xy 363.374936 -261.034151) (xy 363.41681 -261.06607) (xy 363.453322 -261.104008) (xy 363.483614 -261.147074)
			(xy 363.506977 -261.194259) (xy 363.522863 -261.244458) (xy 363.5309 -261.296494) (xy 363.531404 -261.32282)
			(xy 363.5309 -261.349146) (xy 363.522863 -261.401182) (xy 363.506977 -261.451381) (xy 363.483614 -261.498566)
			(xy 363.453322 -261.541632) (xy 363.41681 -261.57957) (xy 363.374936 -261.611489) (xy 363.32868 -261.636642)
			(xy 363.279127 -261.65444) (xy 363.227437 -261.664464) (xy 363.174823 -261.666481) (xy 363.122518 -261.660443)
			(xy 363.071747 -261.646491) (xy 363.023702 -261.624952) (xy 362.979507 -261.596332) (xy 362.940199 -261.561301)
			(xy 362.906699 -261.52068) (xy 362.879793 -261.475421) (xy 362.86011 -261.426586) (xy 362.848113 -261.375318)
			(xy 362.844083 -261.32282) (xy 362.581444 -261.32282) (xy 362.58094 -261.349146) (xy 362.572903 -261.401182)
			(xy 362.557017 -261.451381) (xy 362.533654 -261.498566) (xy 362.503362 -261.541632) (xy 362.46685 -261.57957)
			(xy 362.424976 -261.611489) (xy 362.37872 -261.636642) (xy 362.329167 -261.65444) (xy 362.277477 -261.664464)
			(xy 362.224863 -261.666481) (xy 362.172558 -261.660443) (xy 362.121787 -261.646491) (xy 362.073742 -261.624952)
			(xy 362.029547 -261.596332) (xy 361.990239 -261.561301) (xy 361.956739 -261.52068) (xy 361.929833 -261.475421)
			(xy 361.91015 -261.426586) (xy 361.898153 -261.375318) (xy 361.894123 -261.32282) (xy 361.631484 -261.32282)
			(xy 361.63098 -261.349146) (xy 361.622943 -261.401182) (xy 361.607057 -261.451381) (xy 361.583694 -261.498566)
			(xy 361.553402 -261.541632) (xy 361.51689 -261.57957) (xy 361.475016 -261.611489) (xy 361.42876 -261.636642)
			(xy 361.379207 -261.65444) (xy 361.327517 -261.664464) (xy 361.274903 -261.666481) (xy 361.222598 -261.660443)
			(xy 361.171827 -261.646491) (xy 361.123782 -261.624952) (xy 361.079587 -261.596332) (xy 361.040279 -261.561301)
			(xy 361.006779 -261.52068) (xy 360.979873 -261.475421) (xy 360.96019 -261.426586) (xy 360.948193 -261.375318)
			(xy 360.944163 -261.32282) (xy 360.68127 -261.32282) (xy 360.680766 -261.349146) (xy 360.672729 -261.401182)
			(xy 360.656843 -261.451381) (xy 360.63348 -261.498566) (xy 360.603188 -261.541632) (xy 360.566676 -261.57957)
			(xy 360.524802 -261.611489) (xy 360.478546 -261.636642) (xy 360.428993 -261.65444) (xy 360.377303 -261.664464)
			(xy 360.324689 -261.666481) (xy 360.272384 -261.660443) (xy 360.221613 -261.646491) (xy 360.173568 -261.624952)
			(xy 360.129373 -261.596332) (xy 360.090065 -261.561301) (xy 360.056565 -261.52068) (xy 360.029659 -261.475421)
			(xy 360.009976 -261.426586) (xy 359.997979 -261.375318) (xy 359.993949 -261.32282) (xy 359.73131 -261.32282)
			(xy 359.730806 -261.349146) (xy 359.722769 -261.401182) (xy 359.706883 -261.451381) (xy 359.68352 -261.498566)
			(xy 359.653228 -261.541632) (xy 359.616716 -261.57957) (xy 359.574842 -261.611489) (xy 359.528586 -261.636642)
			(xy 359.479033 -261.65444) (xy 359.427343 -261.664464) (xy 359.374729 -261.666481) (xy 359.322424 -261.660443)
			(xy 359.271653 -261.646491) (xy 359.223608 -261.624952) (xy 359.179413 -261.596332) (xy 359.140105 -261.561301)
			(xy 359.106605 -261.52068) (xy 359.079699 -261.475421) (xy 359.060016 -261.426586) (xy 359.048019 -261.375318)
			(xy 359.043989 -261.32282) (xy 358.78135 -261.32282) (xy 358.780846 -261.349146) (xy 358.772809 -261.401182)
			(xy 358.756923 -261.451381) (xy 358.73356 -261.498566) (xy 358.703268 -261.541632) (xy 358.666756 -261.57957)
			(xy 358.624882 -261.611489) (xy 358.578626 -261.636642) (xy 358.529073 -261.65444) (xy 358.477383 -261.664464)
			(xy 358.424769 -261.666481) (xy 358.372464 -261.660443) (xy 358.321693 -261.646491) (xy 358.273648 -261.624952)
			(xy 358.229453 -261.596332) (xy 358.190145 -261.561301) (xy 358.156645 -261.52068) (xy 358.129739 -261.475421)
			(xy 358.110056 -261.426586) (xy 358.098059 -261.375318) (xy 358.094029 -261.32282) (xy 357.83139 -261.32282)
			(xy 357.830886 -261.349146) (xy 357.822849 -261.401182) (xy 357.806963 -261.451381) (xy 357.7836 -261.498566)
			(xy 357.753308 -261.541632) (xy 357.716796 -261.57957) (xy 357.674922 -261.611489) (xy 357.628666 -261.636642)
			(xy 357.579113 -261.65444) (xy 357.527423 -261.664464) (xy 357.474809 -261.666481) (xy 357.422504 -261.660443)
			(xy 357.371733 -261.646491) (xy 357.323688 -261.624952) (xy 357.279493 -261.596332) (xy 357.240185 -261.561301)
			(xy 357.206685 -261.52068) (xy 357.179779 -261.475421) (xy 357.160096 -261.426586) (xy 357.148099 -261.375318)
			(xy 357.144069 -261.32282) (xy 356.88143 -261.32282) (xy 356.880903 -261.349754) (xy 356.87249 -261.402961)
			(xy 356.855872 -261.454202) (xy 356.831458 -261.50222) (xy 356.799846 -261.545837) (xy 356.761812 -261.583984)
			(xy 356.718289 -261.615725) (xy 356.670344 -261.640281) (xy 356.619152 -261.657051) (xy 356.56597 -261.665622)
			(xy 356.539038 -261.666228) (xy 356.537514 -261.666228) (xy 356.516464 -261.66588) (xy 356.474689 -261.66066)
			(xy 356.454202 -261.655814) (xy 356.453948 -261.655814) (xy 356.445365 -261.654077) (xy 356.427954 -261.655852)
			(xy 356.412146 -261.66336) (xy 356.405688 -261.669276) (xy 356.275386 -261.799578) (xy 356.268149 -261.806294)
			(xy 356.249944 -261.813893) (xy 356.24008 -261.81431) (xy 354.144326 -261.81431) (xy 354.134489 -261.814847)
			(xy 354.11633 -261.822436) (xy 354.10902 -261.829042) (xy 353.782122 -262.15594) (xy 353.774248 -262.174228)
			(xy 353.774248 -262.184134) (xy 353.77342 -262.21091) (xy 353.76448 -262.263727) (xy 353.747447 -262.314514)
			(xy 353.722733 -262.36204) (xy 353.690939 -262.405152) (xy 353.652836 -262.442804) (xy 353.609348 -262.474082)
			(xy 353.56153 -262.498227) (xy 353.510543 -262.514653) (xy 353.457624 -262.522963) (xy 353.43084 -262.523478)
			(xy 353.404061 -262.522968) (xy 353.351151 -262.514658) (xy 353.300172 -262.498235) (xy 353.252362 -262.474095)
			(xy 353.20888 -262.442826) (xy 353.170779 -262.405184) (xy 353.138986 -262.362083) (xy 353.114269 -262.314568)
			(xy 353.09723 -262.263793) (xy 353.092258 -262.237474) (xy 353.08921 -262.219186) (xy 353.061016 -262.19531)
			(xy 352.747326 -262.19531) (xy 352.737489 -262.195847) (xy 352.71933 -262.203436) (xy 352.71202 -262.210042)
			(xy 352.327972 -262.59409) (xy 352.321557 -262.601114) (xy 352.314001 -262.618557) (xy 352.313306 -262.637553)
			(xy 352.316034 -262.646668) (xy 352.316034 -262.646922) (xy 352.324144 -262.671532) (xy 352.332819 -262.722614)
			(xy 352.333306 -262.748522) (xy 352.333306 -262.751824) (xy 352.332552 -262.775619) (xy 352.324576 -262.82255)
			(xy 352.309412 -262.867674) (xy 352.287429 -262.909899) (xy 352.259159 -262.9482) (xy 352.225288 -262.98165)
			(xy 352.186635 -263.009438) (xy 352.144139 -263.03089) (xy 352.098828 -263.045487) (xy 352.0518 -263.052874)
			(xy 352.027998 -263.053322) (xy 352.002223 -263.052759) (xy 351.951408 -263.044071) (xy 351.926906 -263.03605)
			(xy 351.926652 -263.03605) (xy 351.917545 -263.033283) (xy 351.898539 -263.033984) (xy 351.881096 -263.041563)
			(xy 351.874074 -263.047988) (xy 351.075752 -263.84631) (xy 359.174291 -263.84631) (xy 359.178321 -263.793812)
			(xy 359.190318 -263.742544) (xy 359.210001 -263.693709) (xy 359.236907 -263.64845) (xy 359.270407 -263.607829)
			(xy 359.309715 -263.572798) (xy 359.35391 -263.544178) (xy 359.401955 -263.522639) (xy 359.452726 -263.508687)
			(xy 359.505031 -263.502649) (xy 359.557645 -263.504666) (xy 359.609335 -263.51469) (xy 359.658888 -263.532488)
			(xy 359.702104 -263.555988) (xy 369.109002 -263.555988) (xy 369.112962 -263.506934) (xy 369.124739 -263.45915)
			(xy 369.14403 -263.413874) (xy 369.170333 -263.372278) (xy 369.202968 -263.335441) (xy 369.241089 -263.304316)
			(xy 369.28371 -263.279709) (xy 369.329726 -263.262257) (xy 369.377945 -263.252413) (xy 369.42712 -263.250432)
			(xy 369.475975 -263.256364) (xy 369.523246 -263.270056) (xy 369.567708 -263.291154) (xy 369.608211 -263.31911)
			(xy 369.643704 -263.353202) (xy 369.673269 -263.392546) (xy 369.69614 -263.436123) (xy 369.711724 -263.482804)
			(xy 369.719619 -263.531381) (xy 369.720114 -263.555988) (xy 370.98911 -263.555988) (xy 370.99307 -263.506934)
			(xy 371.004847 -263.45915) (xy 371.024138 -263.413874) (xy 371.050441 -263.372278) (xy 371.083076 -263.335441)
			(xy 371.121197 -263.304316) (xy 371.163818 -263.279709) (xy 371.209834 -263.262257) (xy 371.258053 -263.252413)
			(xy 371.307228 -263.250432) (xy 371.356083 -263.256364) (xy 371.403354 -263.270056) (xy 371.447816 -263.291154)
			(xy 371.488319 -263.31911) (xy 371.523812 -263.353202) (xy 371.553377 -263.392546) (xy 371.576248 -263.436123)
			(xy 371.591832 -263.482804) (xy 371.599727 -263.531381) (xy 371.600222 -263.555988) (xy 371.599727 -263.580595)
			(xy 371.591832 -263.629172) (xy 371.576248 -263.675853) (xy 371.553377 -263.71943) (xy 371.523812 -263.758774)
			(xy 371.488319 -263.792866) (xy 371.447816 -263.820822) (xy 371.403354 -263.84192) (xy 371.356083 -263.855612)
			(xy 371.307228 -263.861544) (xy 371.258053 -263.859563) (xy 371.209834 -263.849719) (xy 371.163818 -263.832267)
			(xy 371.121197 -263.80766) (xy 371.083076 -263.776535) (xy 371.050441 -263.739698) (xy 371.024138 -263.698102)
			(xy 371.004847 -263.652826) (xy 370.99307 -263.605042) (xy 370.98911 -263.555988) (xy 369.720114 -263.555988)
			(xy 369.719619 -263.580595) (xy 369.711724 -263.629172) (xy 369.69614 -263.675853) (xy 369.673269 -263.71943)
			(xy 369.643704 -263.758774) (xy 369.608211 -263.792866) (xy 369.567708 -263.820822) (xy 369.523246 -263.84192)
			(xy 369.475975 -263.855612) (xy 369.42712 -263.861544) (xy 369.377945 -263.859563) (xy 369.329726 -263.849719)
			(xy 369.28371 -263.832267) (xy 369.241089 -263.80766) (xy 369.202968 -263.776535) (xy 369.170333 -263.739698)
			(xy 369.14403 -263.698102) (xy 369.124739 -263.652826) (xy 369.112962 -263.605042) (xy 369.109002 -263.555988)
			(xy 359.702104 -263.555988) (xy 359.705144 -263.557641) (xy 359.747018 -263.58956) (xy 359.78353 -263.627498)
			(xy 359.813822 -263.670564) (xy 359.837185 -263.717749) (xy 359.853071 -263.767948) (xy 359.861108 -263.819984)
			(xy 359.861612 -263.84631) (xy 359.861108 -263.872636) (xy 359.853071 -263.924672) (xy 359.837185 -263.974871)
			(xy 359.813822 -264.022056) (xy 359.78353 -264.065122) (xy 359.747018 -264.10306) (xy 359.705144 -264.134979)
			(xy 359.658888 -264.160132) (xy 359.609335 -264.17793) (xy 359.557645 -264.187954) (xy 359.505031 -264.189971)
			(xy 359.452726 -264.183933) (xy 359.401955 -264.169981) (xy 359.35391 -264.148442) (xy 359.309715 -264.119822)
			(xy 359.270407 -264.084791) (xy 359.236907 -264.04417) (xy 359.210001 -263.998911) (xy 359.190318 -263.950076)
			(xy 359.178321 -263.898808) (xy 359.174291 -263.84631) (xy 351.075752 -263.84631) (xy 350.554036 -264.368026)
			(xy 351.722194 -264.368026) (xy 351.726154 -264.318972) (xy 351.737931 -264.271188) (xy 351.757222 -264.225912)
			(xy 351.783525 -264.184316) (xy 351.81616 -264.147479) (xy 351.854281 -264.116354) (xy 351.896902 -264.091747)
			(xy 351.942918 -264.074295) (xy 351.991137 -264.064451) (xy 352.040312 -264.06247) (xy 352.089167 -264.068402)
			(xy 352.136438 -264.082094) (xy 352.1809 -264.103192) (xy 352.221403 -264.131148) (xy 352.256896 -264.16524)
			(xy 352.286461 -264.204584) (xy 352.309332 -264.248161) (xy 352.324916 -264.294842) (xy 352.332811 -264.343419)
			(xy 352.333306 -264.368026) (xy 353.602302 -264.368026) (xy 353.606262 -264.318972) (xy 353.618039 -264.271188)
			(xy 353.63733 -264.225912) (xy 353.663633 -264.184316) (xy 353.696268 -264.147479) (xy 353.734389 -264.116354)
			(xy 353.77701 -264.091747) (xy 353.823026 -264.074295) (xy 353.871245 -264.064451) (xy 353.92042 -264.06247)
			(xy 353.969275 -264.068402) (xy 354.016546 -264.082094) (xy 354.061008 -264.103192) (xy 354.101511 -264.131148)
			(xy 354.137004 -264.16524) (xy 354.166569 -264.204584) (xy 354.18944 -264.248161) (xy 354.205024 -264.294842)
			(xy 354.212919 -264.343419) (xy 354.213414 -264.368026) (xy 355.482156 -264.368026) (xy 355.486116 -264.318972)
			(xy 355.497893 -264.271188) (xy 355.517184 -264.225912) (xy 355.543487 -264.184316) (xy 355.576122 -264.147479)
			(xy 355.614243 -264.116354) (xy 355.656864 -264.091747) (xy 355.70288 -264.074295) (xy 355.751099 -264.064451)
			(xy 355.800274 -264.06247) (xy 355.849129 -264.068402) (xy 355.8964 -264.082094) (xy 355.940862 -264.103192)
			(xy 355.981365 -264.131148) (xy 356.016858 -264.16524) (xy 356.046423 -264.204584) (xy 356.069294 -264.248161)
			(xy 356.084878 -264.294842) (xy 356.092773 -264.343419) (xy 356.093268 -264.368026) (xy 363.00208 -264.368026)
			(xy 363.00604 -264.318972) (xy 363.017817 -264.271188) (xy 363.037108 -264.225912) (xy 363.063411 -264.184316)
			(xy 363.096046 -264.147479) (xy 363.134167 -264.116354) (xy 363.176788 -264.091747) (xy 363.222804 -264.074295)
			(xy 363.271023 -264.064451) (xy 363.320198 -264.06247) (xy 363.369053 -264.068402) (xy 363.416324 -264.082094)
			(xy 363.460786 -264.103192) (xy 363.501289 -264.131148) (xy 363.536782 -264.16524) (xy 363.566347 -264.204584)
			(xy 363.589218 -264.248161) (xy 363.604802 -264.294842) (xy 363.612697 -264.343419) (xy 363.613192 -264.368026)
			(xy 364.882188 -264.368026) (xy 364.886148 -264.318972) (xy 364.897925 -264.271188) (xy 364.917216 -264.225912)
			(xy 364.943519 -264.184316) (xy 364.976154 -264.147479) (xy 365.014275 -264.116354) (xy 365.056896 -264.091747)
			(xy 365.102912 -264.074295) (xy 365.151131 -264.064451) (xy 365.200306 -264.06247) (xy 365.249161 -264.068402)
			(xy 365.296432 -264.082094) (xy 365.340894 -264.103192) (xy 365.381397 -264.131148) (xy 365.41689 -264.16524)
			(xy 365.446455 -264.204584) (xy 365.469326 -264.248161) (xy 365.48491 -264.294842) (xy 365.492805 -264.343419)
			(xy 365.4933 -264.368026) (xy 366.762042 -264.368026) (xy 366.766002 -264.318972) (xy 366.777779 -264.271188)
			(xy 366.79707 -264.225912) (xy 366.823373 -264.184316) (xy 366.856008 -264.147479) (xy 366.894129 -264.116354)
			(xy 366.93675 -264.091747) (xy 366.982766 -264.074295) (xy 367.030985 -264.064451) (xy 367.08016 -264.06247)
			(xy 367.129015 -264.068402) (xy 367.176286 -264.082094) (xy 367.220748 -264.103192) (xy 367.261251 -264.131148)
			(xy 367.296744 -264.16524) (xy 367.326309 -264.204584) (xy 367.34918 -264.248161) (xy 367.364764 -264.294842)
			(xy 367.372659 -264.343419) (xy 367.373154 -264.368026) (xy 368.639864 -264.368026) (xy 368.643824 -264.318972)
			(xy 368.655601 -264.271188) (xy 368.674892 -264.225912) (xy 368.701195 -264.184316) (xy 368.73383 -264.147479)
			(xy 368.771951 -264.116354) (xy 368.814572 -264.091747) (xy 368.860588 -264.074295) (xy 368.908807 -264.064451)
			(xy 368.957982 -264.06247) (xy 369.006837 -264.068402) (xy 369.054108 -264.082094) (xy 369.09857 -264.103192)
			(xy 369.139073 -264.131148) (xy 369.174566 -264.16524) (xy 369.204131 -264.204584) (xy 369.227002 -264.248161)
			(xy 369.242586 -264.294842) (xy 369.250481 -264.343419) (xy 369.250935 -264.365994) (xy 370.518956 -264.365994)
			(xy 370.522916 -264.31694) (xy 370.534693 -264.269156) (xy 370.553984 -264.22388) (xy 370.580287 -264.182284)
			(xy 370.612922 -264.145447) (xy 370.651043 -264.114322) (xy 370.693664 -264.089715) (xy 370.73968 -264.072263)
			(xy 370.787899 -264.062419) (xy 370.837074 -264.060438) (xy 370.885929 -264.06637) (xy 370.9332 -264.080062)
			(xy 370.977662 -264.10116) (xy 371.018165 -264.129116) (xy 371.053658 -264.163208) (xy 371.083223 -264.202552)
			(xy 371.106094 -264.246129) (xy 371.121678 -264.29281) (xy 371.129573 -264.341387) (xy 371.130068 -264.365994)
			(xy 372.399064 -264.365994) (xy 372.403024 -264.31694) (xy 372.414801 -264.269156) (xy 372.434092 -264.22388)
			(xy 372.460395 -264.182284) (xy 372.49303 -264.145447) (xy 372.531151 -264.114322) (xy 372.573772 -264.089715)
			(xy 372.619788 -264.072263) (xy 372.668007 -264.062419) (xy 372.717182 -264.060438) (xy 372.766037 -264.06637)
			(xy 372.813308 -264.080062) (xy 372.85777 -264.10116) (xy 372.898273 -264.129116) (xy 372.933766 -264.163208)
			(xy 372.963331 -264.202552) (xy 372.986202 -264.246129) (xy 373.001786 -264.29281) (xy 373.009681 -264.341387)
			(xy 373.010176 -264.365994) (xy 374.278918 -264.365994) (xy 374.282878 -264.31694) (xy 374.294655 -264.269156)
			(xy 374.313946 -264.22388) (xy 374.340249 -264.182284) (xy 374.372884 -264.145447) (xy 374.411005 -264.114322)
			(xy 374.453626 -264.089715) (xy 374.499642 -264.072263) (xy 374.547861 -264.062419) (xy 374.597036 -264.060438)
			(xy 374.645891 -264.06637) (xy 374.693162 -264.080062) (xy 374.737624 -264.10116) (xy 374.778127 -264.129116)
			(xy 374.81362 -264.163208) (xy 374.843185 -264.202552) (xy 374.866056 -264.246129) (xy 374.88164 -264.29281)
			(xy 374.889535 -264.341387) (xy 374.89003 -264.365994) (xy 376.148595 -264.365994) (xy 376.15269 -264.315266)
			(xy 376.164869 -264.265852) (xy 376.184817 -264.219032) (xy 376.212018 -264.176018) (xy 376.245766 -264.137924)
			(xy 376.285188 -264.105737) (xy 376.329262 -264.080291) (xy 376.376848 -264.062244) (xy 376.426712 -264.052064)
			(xy 376.477564 -264.050015) (xy 376.528085 -264.056149) (xy 376.576969 -264.070309) (xy 376.622948 -264.092126)
			(xy 376.664832 -264.121036) (xy 376.701536 -264.156291) (xy 376.732109 -264.196977) (xy 376.75576 -264.24204)
			(xy 376.771876 -264.290314) (xy 376.78004 -264.340548) (xy 376.780552 -264.365994) (xy 377.088649 -264.365994)
			(xy 377.092744 -264.315266) (xy 377.104923 -264.265852) (xy 377.124871 -264.219032) (xy 377.152072 -264.176018)
			(xy 377.18582 -264.137924) (xy 377.225242 -264.105737) (xy 377.269316 -264.080291) (xy 377.316902 -264.062244)
			(xy 377.366766 -264.052064) (xy 377.417618 -264.050015) (xy 377.468139 -264.056149) (xy 377.517023 -264.070309)
			(xy 377.563002 -264.092126) (xy 377.604886 -264.121036) (xy 377.64159 -264.156291) (xy 377.672163 -264.196977)
			(xy 377.695814 -264.24204) (xy 377.71193 -264.290314) (xy 377.720094 -264.340548) (xy 377.720606 -264.365994)
			(xy 377.720094 -264.39144) (xy 377.71193 -264.441674) (xy 377.695814 -264.489948) (xy 377.672163 -264.535011)
			(xy 377.64159 -264.575697) (xy 377.604886 -264.610952) (xy 377.563002 -264.639862) (xy 377.517023 -264.661679)
			(xy 377.468139 -264.675839) (xy 377.417618 -264.681973) (xy 377.366766 -264.679924) (xy 377.316902 -264.669744)
			(xy 377.269316 -264.651697) (xy 377.225242 -264.626251) (xy 377.18582 -264.594064) (xy 377.152072 -264.55597)
			(xy 377.124871 -264.512956) (xy 377.104923 -264.466136) (xy 377.092744 -264.416722) (xy 377.088649 -264.365994)
			(xy 376.780552 -264.365994) (xy 376.78004 -264.39144) (xy 376.771876 -264.441674) (xy 376.75576 -264.489948)
			(xy 376.732109 -264.535011) (xy 376.701536 -264.575697) (xy 376.664832 -264.610952) (xy 376.622948 -264.639862)
			(xy 376.576969 -264.661679) (xy 376.528085 -264.675839) (xy 376.477564 -264.681973) (xy 376.426712 -264.679924)
			(xy 376.376848 -264.669744) (xy 376.329262 -264.651697) (xy 376.285188 -264.626251) (xy 376.245766 -264.594064)
			(xy 376.212018 -264.55597) (xy 376.184817 -264.512956) (xy 376.164869 -264.466136) (xy 376.15269 -264.416722)
			(xy 376.148595 -264.365994) (xy 374.89003 -264.365994) (xy 374.889535 -264.390601) (xy 374.88164 -264.439178)
			(xy 374.866056 -264.485859) (xy 374.843185 -264.529436) (xy 374.81362 -264.56878) (xy 374.778127 -264.602872)
			(xy 374.737624 -264.630828) (xy 374.693162 -264.651926) (xy 374.645891 -264.665618) (xy 374.597036 -264.67155)
			(xy 374.547861 -264.669569) (xy 374.499642 -264.659725) (xy 374.453626 -264.642273) (xy 374.411005 -264.617666)
			(xy 374.372884 -264.586541) (xy 374.340249 -264.549704) (xy 374.313946 -264.508108) (xy 374.294655 -264.462832)
			(xy 374.282878 -264.415048) (xy 374.278918 -264.365994) (xy 373.010176 -264.365994) (xy 373.009681 -264.390601)
			(xy 373.001786 -264.439178) (xy 372.986202 -264.485859) (xy 372.963331 -264.529436) (xy 372.933766 -264.56878)
			(xy 372.898273 -264.602872) (xy 372.85777 -264.630828) (xy 372.813308 -264.651926) (xy 372.766037 -264.665618)
			(xy 372.717182 -264.67155) (xy 372.668007 -264.669569) (xy 372.619788 -264.659725) (xy 372.573772 -264.642273)
			(xy 372.531151 -264.617666) (xy 372.49303 -264.586541) (xy 372.460395 -264.549704) (xy 372.434092 -264.508108)
			(xy 372.414801 -264.462832) (xy 372.403024 -264.415048) (xy 372.399064 -264.365994) (xy 371.130068 -264.365994)
			(xy 371.129573 -264.390601) (xy 371.121678 -264.439178) (xy 371.106094 -264.485859) (xy 371.083223 -264.529436)
			(xy 371.053658 -264.56878) (xy 371.018165 -264.602872) (xy 370.977662 -264.630828) (xy 370.9332 -264.651926)
			(xy 370.885929 -264.665618) (xy 370.837074 -264.67155) (xy 370.787899 -264.669569) (xy 370.73968 -264.659725)
			(xy 370.693664 -264.642273) (xy 370.651043 -264.617666) (xy 370.612922 -264.586541) (xy 370.580287 -264.549704)
			(xy 370.553984 -264.508108) (xy 370.534693 -264.462832) (xy 370.522916 -264.415048) (xy 370.518956 -264.365994)
			(xy 369.250935 -264.365994) (xy 369.250976 -264.368026) (xy 369.250481 -264.392633) (xy 369.242586 -264.44121)
			(xy 369.227002 -264.487891) (xy 369.204131 -264.531468) (xy 369.174566 -264.570812) (xy 369.139073 -264.604904)
			(xy 369.09857 -264.63286) (xy 369.054108 -264.653958) (xy 369.006837 -264.66765) (xy 368.957982 -264.673582)
			(xy 368.908807 -264.671601) (xy 368.860588 -264.661757) (xy 368.814572 -264.644305) (xy 368.771951 -264.619698)
			(xy 368.73383 -264.588573) (xy 368.701195 -264.551736) (xy 368.674892 -264.51014) (xy 368.655601 -264.464864)
			(xy 368.643824 -264.41708) (xy 368.639864 -264.368026) (xy 367.373154 -264.368026) (xy 367.372659 -264.392633)
			(xy 367.364764 -264.44121) (xy 367.34918 -264.487891) (xy 367.326309 -264.531468) (xy 367.296744 -264.570812)
			(xy 367.261251 -264.604904) (xy 367.220748 -264.63286) (xy 367.176286 -264.653958) (xy 367.129015 -264.66765)
			(xy 367.08016 -264.673582) (xy 367.030985 -264.671601) (xy 366.982766 -264.661757) (xy 366.93675 -264.644305)
			(xy 366.894129 -264.619698) (xy 366.856008 -264.588573) (xy 366.823373 -264.551736) (xy 366.79707 -264.51014)
			(xy 366.777779 -264.464864) (xy 366.766002 -264.41708) (xy 366.762042 -264.368026) (xy 365.4933 -264.368026)
			(xy 365.492805 -264.392633) (xy 365.48491 -264.44121) (xy 365.469326 -264.487891) (xy 365.446455 -264.531468)
			(xy 365.41689 -264.570812) (xy 365.381397 -264.604904) (xy 365.340894 -264.63286) (xy 365.296432 -264.653958)
			(xy 365.249161 -264.66765) (xy 365.200306 -264.673582) (xy 365.151131 -264.671601) (xy 365.102912 -264.661757)
			(xy 365.056896 -264.644305) (xy 365.014275 -264.619698) (xy 364.976154 -264.588573) (xy 364.943519 -264.551736)
			(xy 364.917216 -264.51014) (xy 364.897925 -264.464864) (xy 364.886148 -264.41708) (xy 364.882188 -264.368026)
			(xy 363.613192 -264.368026) (xy 363.612697 -264.392633) (xy 363.604802 -264.44121) (xy 363.589218 -264.487891)
			(xy 363.566347 -264.531468) (xy 363.536782 -264.570812) (xy 363.501289 -264.604904) (xy 363.460786 -264.63286)
			(xy 363.416324 -264.653958) (xy 363.369053 -264.66765) (xy 363.320198 -264.673582) (xy 363.271023 -264.671601)
			(xy 363.222804 -264.661757) (xy 363.176788 -264.644305) (xy 363.134167 -264.619698) (xy 363.096046 -264.588573)
			(xy 363.063411 -264.551736) (xy 363.037108 -264.51014) (xy 363.017817 -264.464864) (xy 363.00604 -264.41708)
			(xy 363.00208 -264.368026) (xy 356.093268 -264.368026) (xy 356.092773 -264.392633) (xy 356.084878 -264.44121)
			(xy 356.069294 -264.487891) (xy 356.046423 -264.531468) (xy 356.016858 -264.570812) (xy 355.981365 -264.604904)
			(xy 355.940862 -264.63286) (xy 355.8964 -264.653958) (xy 355.849129 -264.66765) (xy 355.800274 -264.673582)
			(xy 355.751099 -264.671601) (xy 355.70288 -264.661757) (xy 355.656864 -264.644305) (xy 355.614243 -264.619698)
			(xy 355.576122 -264.588573) (xy 355.543487 -264.551736) (xy 355.517184 -264.51014) (xy 355.497893 -264.464864)
			(xy 355.486116 -264.41708) (xy 355.482156 -264.368026) (xy 354.213414 -264.368026) (xy 354.212919 -264.392633)
			(xy 354.205024 -264.44121) (xy 354.18944 -264.487891) (xy 354.166569 -264.531468) (xy 354.137004 -264.570812)
			(xy 354.101511 -264.604904) (xy 354.061008 -264.63286) (xy 354.016546 -264.653958) (xy 353.969275 -264.66765)
			(xy 353.92042 -264.673582) (xy 353.871245 -264.671601) (xy 353.823026 -264.661757) (xy 353.77701 -264.644305)
			(xy 353.734389 -264.619698) (xy 353.696268 -264.588573) (xy 353.663633 -264.551736) (xy 353.63733 -264.51014)
			(xy 353.618039 -264.464864) (xy 353.606262 -264.41708) (xy 353.602302 -264.368026) (xy 352.333306 -264.368026)
			(xy 352.332811 -264.392633) (xy 352.324916 -264.44121) (xy 352.309332 -264.487891) (xy 352.286461 -264.531468)
			(xy 352.256896 -264.570812) (xy 352.221403 -264.604904) (xy 352.1809 -264.63286) (xy 352.136438 -264.653958)
			(xy 352.089167 -264.66765) (xy 352.040312 -264.673582) (xy 351.991137 -264.671601) (xy 351.942918 -264.661757)
			(xy 351.896902 -264.644305) (xy 351.854281 -264.619698) (xy 351.81616 -264.588573) (xy 351.783525 -264.551736)
			(xy 351.757222 -264.51014) (xy 351.737931 -264.464864) (xy 351.726154 -264.41708) (xy 351.722194 -264.368026)
			(xy 350.554036 -264.368026) (xy 350.428814 -264.493248) (xy 350.425258 -264.500614) (xy 350.413728 -264.522932)
			(xy 350.384501 -264.563785) (xy 350.348983 -264.599303) (xy 350.30813 -264.628529) (xy 350.285812 -264.64006)
			(xy 350.278446 -264.643616) (xy 350.059752 -264.86231) (xy 359.174291 -264.86231) (xy 359.178321 -264.809812)
			(xy 359.190318 -264.758544) (xy 359.210001 -264.709709) (xy 359.236907 -264.66445) (xy 359.270407 -264.623829)
			(xy 359.309715 -264.588798) (xy 359.35391 -264.560178) (xy 359.401955 -264.538639) (xy 359.452726 -264.524687)
			(xy 359.505031 -264.518649) (xy 359.557645 -264.520666) (xy 359.609335 -264.53069) (xy 359.658888 -264.548488)
			(xy 359.705144 -264.573641) (xy 359.747018 -264.60556) (xy 359.78353 -264.643498) (xy 359.813822 -264.686564)
			(xy 359.837185 -264.733749) (xy 359.853071 -264.783948) (xy 359.861108 -264.835984) (xy 359.861612 -264.86231)
			(xy 359.861108 -264.888636) (xy 359.853071 -264.940672) (xy 359.837185 -264.990871) (xy 359.813822 -265.038056)
			(xy 359.78353 -265.081122) (xy 359.747018 -265.11906) (xy 359.705144 -265.150979) (xy 359.659131 -265.176)
			(xy 369.109002 -265.176) (xy 369.112962 -265.126946) (xy 369.124739 -265.079162) (xy 369.14403 -265.033886)
			(xy 369.170333 -264.99229) (xy 369.202968 -264.955453) (xy 369.241089 -264.924328) (xy 369.28371 -264.899721)
			(xy 369.329726 -264.882269) (xy 369.377945 -264.872425) (xy 369.42712 -264.870444) (xy 369.475975 -264.876376)
			(xy 369.523246 -264.890068) (xy 369.567708 -264.911166) (xy 369.608211 -264.939122) (xy 369.643704 -264.973214)
			(xy 369.673269 -265.012558) (xy 369.69614 -265.056135) (xy 369.711724 -265.102816) (xy 369.719619 -265.151393)
			(xy 369.720114 -265.176) (xy 370.98911 -265.176) (xy 370.99307 -265.126946) (xy 371.004847 -265.079162)
			(xy 371.024138 -265.033886) (xy 371.050441 -264.99229) (xy 371.083076 -264.955453) (xy 371.121197 -264.924328)
			(xy 371.163818 -264.899721) (xy 371.209834 -264.882269) (xy 371.258053 -264.872425) (xy 371.307228 -264.870444)
			(xy 371.356083 -264.876376) (xy 371.403354 -264.890068) (xy 371.447816 -264.911166) (xy 371.488319 -264.939122)
			(xy 371.523812 -264.973214) (xy 371.553377 -265.012558) (xy 371.576248 -265.056135) (xy 371.591832 -265.102816)
			(xy 371.599727 -265.151393) (xy 371.600222 -265.176) (xy 372.868964 -265.176) (xy 372.872924 -265.126946)
			(xy 372.884701 -265.079162) (xy 372.903992 -265.033886) (xy 372.930295 -264.99229) (xy 372.96293 -264.955453)
			(xy 373.001051 -264.924328) (xy 373.043672 -264.899721) (xy 373.089688 -264.882269) (xy 373.137907 -264.872425)
			(xy 373.187082 -264.870444) (xy 373.235937 -264.876376) (xy 373.283208 -264.890068) (xy 373.32767 -264.911166)
			(xy 373.368173 -264.939122) (xy 373.403666 -264.973214) (xy 373.433231 -265.012558) (xy 373.456102 -265.056135)
			(xy 373.471686 -265.102816) (xy 373.479581 -265.151393) (xy 373.480076 -265.176) (xy 374.749072 -265.176)
			(xy 374.753032 -265.126946) (xy 374.764809 -265.079162) (xy 374.7841 -265.033886) (xy 374.810403 -264.99229)
			(xy 374.843038 -264.955453) (xy 374.881159 -264.924328) (xy 374.92378 -264.899721) (xy 374.969796 -264.882269)
			(xy 375.018015 -264.872425) (xy 375.06719 -264.870444) (xy 375.116045 -264.876376) (xy 375.163316 -264.890068)
			(xy 375.207778 -264.911166) (xy 375.248281 -264.939122) (xy 375.283774 -264.973214) (xy 375.313339 -265.012558)
			(xy 375.33621 -265.056135) (xy 375.351794 -265.102816) (xy 375.359689 -265.151393) (xy 375.360184 -265.176)
			(xy 375.678695 -265.176) (xy 375.68279 -265.125272) (xy 375.694969 -265.075858) (xy 375.714917 -265.029038)
			(xy 375.742118 -264.986024) (xy 375.775866 -264.94793) (xy 375.815288 -264.915743) (xy 375.859362 -264.890297)
			(xy 375.906948 -264.87225) (xy 375.956812 -264.86207) (xy 376.007664 -264.860021) (xy 376.058185 -264.866155)
			(xy 376.107069 -264.880315) (xy 376.153048 -264.902132) (xy 376.194932 -264.931042) (xy 376.231636 -264.966297)
			(xy 376.262209 -265.006983) (xy 376.28586 -265.052046) (xy 376.301976 -265.10032) (xy 376.31014 -265.150554)
			(xy 376.310652 -265.176) (xy 376.628926 -265.176) (xy 376.632886 -265.126946) (xy 376.644663 -265.079162)
			(xy 376.663954 -265.033886) (xy 376.690257 -264.99229) (xy 376.722892 -264.955453) (xy 376.761013 -264.924328)
			(xy 376.803634 -264.899721) (xy 376.84965 -264.882269) (xy 376.897869 -264.872425) (xy 376.947044 -264.870444)
			(xy 376.995899 -264.876376) (xy 377.04317 -264.890068) (xy 377.087632 -264.911166) (xy 377.128135 -264.939122)
			(xy 377.163628 -264.973214) (xy 377.193193 -265.012558) (xy 377.216064 -265.056135) (xy 377.231648 -265.102816)
			(xy 377.239543 -265.151393) (xy 377.240038 -265.176) (xy 377.56898 -265.176) (xy 377.57294 -265.126946)
			(xy 377.584717 -265.079162) (xy 377.604008 -265.033886) (xy 377.630311 -264.99229) (xy 377.662946 -264.955453)
			(xy 377.701067 -264.924328) (xy 377.743688 -264.899721) (xy 377.789704 -264.882269) (xy 377.837923 -264.872425)
			(xy 377.887098 -264.870444) (xy 377.935953 -264.876376) (xy 377.983224 -264.890068) (xy 378.027686 -264.911166)
			(xy 378.068189 -264.939122) (xy 378.103682 -264.973214) (xy 378.133247 -265.012558) (xy 378.156118 -265.056135)
			(xy 378.171702 -265.102816) (xy 378.179597 -265.151393) (xy 378.180092 -265.176) (xy 378.179597 -265.200607)
			(xy 378.171702 -265.249184) (xy 378.156118 -265.295865) (xy 378.133247 -265.339442) (xy 378.103682 -265.378786)
			(xy 378.068189 -265.412878) (xy 378.027686 -265.440834) (xy 377.983224 -265.461932) (xy 377.935953 -265.475624)
			(xy 377.887098 -265.481556) (xy 377.837923 -265.479575) (xy 377.789704 -265.469731) (xy 377.743688 -265.452279)
			(xy 377.701067 -265.427672) (xy 377.662946 -265.396547) (xy 377.630311 -265.35971) (xy 377.604008 -265.318114)
			(xy 377.584717 -265.272838) (xy 377.57294 -265.225054) (xy 377.56898 -265.176) (xy 377.240038 -265.176)
			(xy 377.239543 -265.200607) (xy 377.231648 -265.249184) (xy 377.216064 -265.295865) (xy 377.193193 -265.339442)
			(xy 377.163628 -265.378786) (xy 377.128135 -265.412878) (xy 377.087632 -265.440834) (xy 377.04317 -265.461932)
			(xy 376.995899 -265.475624) (xy 376.947044 -265.481556) (xy 376.897869 -265.479575) (xy 376.84965 -265.469731)
			(xy 376.803634 -265.452279) (xy 376.761013 -265.427672) (xy 376.722892 -265.396547) (xy 376.690257 -265.35971)
			(xy 376.663954 -265.318114) (xy 376.644663 -265.272838) (xy 376.632886 -265.225054) (xy 376.628926 -265.176)
			(xy 376.310652 -265.176) (xy 376.31014 -265.201446) (xy 376.301976 -265.25168) (xy 376.28586 -265.299954)
			(xy 376.262209 -265.345017) (xy 376.231636 -265.385703) (xy 376.194932 -265.420958) (xy 376.153048 -265.449868)
			(xy 376.107069 -265.471685) (xy 376.058185 -265.485845) (xy 376.007664 -265.491979) (xy 375.956812 -265.48993)
			(xy 375.906948 -265.47975) (xy 375.859362 -265.461703) (xy 375.815288 -265.436257) (xy 375.775866 -265.40407)
			(xy 375.742118 -265.365976) (xy 375.714917 -265.322962) (xy 375.694969 -265.276142) (xy 375.68279 -265.226728)
			(xy 375.678695 -265.176) (xy 375.360184 -265.176) (xy 375.359689 -265.200607) (xy 375.351794 -265.249184)
			(xy 375.33621 -265.295865) (xy 375.313339 -265.339442) (xy 375.283774 -265.378786) (xy 375.248281 -265.412878)
			(xy 375.207778 -265.440834) (xy 375.163316 -265.461932) (xy 375.116045 -265.475624) (xy 375.06719 -265.481556)
			(xy 375.018015 -265.479575) (xy 374.969796 -265.469731) (xy 374.92378 -265.452279) (xy 374.881159 -265.427672)
			(xy 374.843038 -265.396547) (xy 374.810403 -265.35971) (xy 374.7841 -265.318114) (xy 374.764809 -265.272838)
			(xy 374.753032 -265.225054) (xy 374.749072 -265.176) (xy 373.480076 -265.176) (xy 373.479581 -265.200607)
			(xy 373.471686 -265.249184) (xy 373.456102 -265.295865) (xy 373.433231 -265.339442) (xy 373.403666 -265.378786)
			(xy 373.368173 -265.412878) (xy 373.32767 -265.440834) (xy 373.283208 -265.461932) (xy 373.235937 -265.475624)
			(xy 373.187082 -265.481556) (xy 373.137907 -265.479575) (xy 373.089688 -265.469731) (xy 373.043672 -265.452279)
			(xy 373.001051 -265.427672) (xy 372.96293 -265.396547) (xy 372.930295 -265.35971) (xy 372.903992 -265.318114)
			(xy 372.884701 -265.272838) (xy 372.872924 -265.225054) (xy 372.868964 -265.176) (xy 371.600222 -265.176)
			(xy 371.599727 -265.200607) (xy 371.591832 -265.249184) (xy 371.576248 -265.295865) (xy 371.553377 -265.339442)
			(xy 371.523812 -265.378786) (xy 371.488319 -265.412878) (xy 371.447816 -265.440834) (xy 371.403354 -265.461932)
			(xy 371.356083 -265.475624) (xy 371.307228 -265.481556) (xy 371.258053 -265.479575) (xy 371.209834 -265.469731)
			(xy 371.163818 -265.452279) (xy 371.121197 -265.427672) (xy 371.083076 -265.396547) (xy 371.050441 -265.35971)
			(xy 371.024138 -265.318114) (xy 371.004847 -265.272838) (xy 370.99307 -265.225054) (xy 370.98911 -265.176)
			(xy 369.720114 -265.176) (xy 369.719619 -265.200607) (xy 369.711724 -265.249184) (xy 369.69614 -265.295865)
			(xy 369.673269 -265.339442) (xy 369.643704 -265.378786) (xy 369.608211 -265.412878) (xy 369.567708 -265.440834)
			(xy 369.523246 -265.461932) (xy 369.475975 -265.475624) (xy 369.42712 -265.481556) (xy 369.377945 -265.479575)
			(xy 369.329726 -265.469731) (xy 369.28371 -265.452279) (xy 369.241089 -265.427672) (xy 369.202968 -265.396547)
			(xy 369.170333 -265.35971) (xy 369.14403 -265.318114) (xy 369.124739 -265.272838) (xy 369.112962 -265.225054)
			(xy 369.109002 -265.176) (xy 359.659131 -265.176) (xy 359.658888 -265.176132) (xy 359.609335 -265.19393)
			(xy 359.557645 -265.203954) (xy 359.505031 -265.205971) (xy 359.452726 -265.199933) (xy 359.401955 -265.185981)
			(xy 359.35391 -265.164442) (xy 359.309715 -265.135822) (xy 359.270407 -265.100791) (xy 359.236907 -265.06017)
			(xy 359.210001 -265.014911) (xy 359.190318 -264.966076) (xy 359.178321 -264.914808) (xy 359.174291 -264.86231)
			(xy 350.059752 -264.86231) (xy 349.955866 -264.966196) (xy 349.948507 -264.974393) (xy 349.940943 -264.995059)
			(xy 349.942654 -265.016999) (xy 349.947484 -265.026902) (xy 349.959678 -265.049844) (xy 349.977001 -265.098823)
			(xy 349.985797 -265.150024) (xy 349.986346 -265.176) (xy 349.985875 -265.199992) (xy 349.97837 -265.247386)
			(xy 349.963543 -265.293023) (xy 349.94176 -265.335778) (xy 349.913557 -265.3746) (xy 349.879629 -265.408532)
			(xy 349.840811 -265.43674) (xy 349.798058 -265.458528) (xy 349.752423 -265.473361) (xy 349.70503 -265.480872)
			(xy 349.681038 -265.481308) (xy 349.655059 -265.480789) (xy 349.60385 -265.472002) (xy 349.554867 -265.454675)
			(xy 349.53194 -265.442446) (xy 349.522064 -265.437517) (xy 349.500085 -265.435769) (xy 349.479402 -265.443405)
			(xy 349.471234 -265.450828) (xy 349.007684 -265.914378) (xy 349.000966 -265.921614) (xy 348.99336 -265.939819)
			(xy 348.992952 -265.949684) (xy 348.992952 -265.986006) (xy 349.845388 -265.986006) (xy 349.849348 -265.936952)
			(xy 349.861125 -265.889168) (xy 349.880416 -265.843892) (xy 349.906719 -265.802296) (xy 349.939354 -265.765459)
			(xy 349.977475 -265.734334) (xy 350.020096 -265.709727) (xy 350.066112 -265.692275) (xy 350.114331 -265.682431)
			(xy 350.163506 -265.68045) (xy 350.212361 -265.686382) (xy 350.259632 -265.700074) (xy 350.304094 -265.721172)
			(xy 350.344597 -265.749128) (xy 350.38009 -265.78322) (xy 350.409655 -265.822564) (xy 350.432526 -265.866141)
			(xy 350.44811 -265.912822) (xy 350.456005 -265.961399) (xy 350.4565 -265.986006) (xy 350.456005 -266.010613)
			(xy 350.44811 -266.05919) (xy 350.432526 -266.105871) (xy 350.409655 -266.149448) (xy 350.38009 -266.188792)
			(xy 350.344597 -266.222884) (xy 350.304094 -266.25084) (xy 350.259632 -266.271938) (xy 350.212361 -266.28563)
			(xy 350.163506 -266.291562) (xy 350.114331 -266.289581) (xy 350.066112 -266.279737) (xy 350.020096 -266.262285)
			(xy 349.977475 -266.237678) (xy 349.939354 -266.206553) (xy 349.906719 -266.169716) (xy 349.880416 -266.12812)
			(xy 349.861125 -266.082844) (xy 349.849348 -266.03506) (xy 349.845388 -265.986006) (xy 348.992952 -265.986006)
			(xy 348.992952 -266.129008) (xy 348.993378 -266.139076) (xy 349.0011 -266.157674) (xy 349.007938 -266.165076)
			(xy 349.408496 -266.565634) (xy 349.41557 -266.572185) (xy 349.433225 -266.579894) (xy 349.452479 -266.580526)
			(xy 349.470602 -266.573991) (xy 349.478092 -266.56792) (xy 349.478346 -266.567666) (xy 349.499483 -266.549708)
			(xy 349.546919 -266.52098) (xy 349.598762 -266.501288) (xy 349.653309 -266.491282) (xy 349.681038 -266.490704)
			(xy 349.705027 -266.491177) (xy 349.752413 -266.498688) (xy 349.798041 -266.513519) (xy 349.840788 -266.535305)
			(xy 349.8796 -266.563509) (xy 349.913523 -266.597438) (xy 349.941721 -266.636255) (xy 349.9635 -266.679005)
			(xy 349.978323 -266.724635) (xy 349.985826 -266.772023) (xy 349.986346 -266.796012) (xy 349.985943 -266.817715)
			(xy 349.979754 -266.860678) (xy 349.967545 -266.902333) (xy 349.958914 -266.92225) (xy 349.958914 -266.922504)
			(xy 349.95866 -266.922758) (xy 349.954139 -266.934654) (xy 349.95612 -266.959992) (xy 349.96247 -266.971018)
			(xy 350.007428 -267.041122) (xy 350.012282 -267.048082) (xy 350.025607 -267.058573) (xy 350.041622 -267.064155)
			(xy 350.0501 -267.06449) (xy 351.192084 -267.06449) (xy 351.200573 -267.064186) (xy 351.216617 -267.058638)
			(xy 351.229943 -267.04812) (xy 351.234756 -267.041122) (xy 351.279714 -266.971018) (xy 351.284049 -266.963775)
			(xy 351.288131 -266.947404) (xy 351.286658 -266.930597) (xy 351.283524 -266.922758) (xy 351.28327 -266.922504)
			(xy 351.28327 -266.92225) (xy 351.274627 -266.902338) (xy 351.262423 -266.860681) (xy 351.256244 -266.817716)
			(xy 351.255838 -266.796012) (xy 351.256283 -266.77202) (xy 351.263789 -266.724625) (xy 351.278617 -266.678989)
			(xy 351.300402 -266.636235) (xy 351.328609 -266.597415) (xy 351.362541 -266.563486) (xy 351.401364 -266.535285)
			(xy 351.44412 -266.513504) (xy 351.489758 -266.498681) (xy 351.537153 -266.491181) (xy 351.561146 -266.490704)
			(xy 351.588219 -266.491291) (xy 351.641516 -266.500846) (xy 351.692293 -266.519647) (xy 351.73896 -266.547106)
			(xy 351.780056 -266.582362) (xy 351.79762 -266.602972) (xy 351.804478 -266.611354) (xy 351.823528 -266.621006)
			(xy 351.907856 -266.625324) (xy 351.918485 -266.625312) (xy 351.938301 -266.617694) (xy 351.94621 -266.610592)
			(xy 352.094292 -266.46251) (xy 352.1011 -266.455186) (xy 352.108832 -266.436763) (xy 352.108901 -266.416782)
			(xy 352.105468 -266.407392) (xy 352.06559 -266.308586) (xy 352.040698 -266.291568) (xy 352.025204 -266.291314)
			(xy 352.001513 -266.290416) (xy 351.954824 -266.282199) (xy 351.909966 -266.266864) (xy 351.868018 -266.244778)
			(xy 351.829988 -266.216473) (xy 351.796791 -266.18263) (xy 351.769225 -266.144061) (xy 351.747953 -266.101694)
			(xy 351.733486 -266.056549) (xy 351.726172 -266.00971) (xy 351.725738 -265.986006) (xy 351.72626 -265.960751)
			(xy 351.734573 -265.910929) (xy 351.750974 -265.863155) (xy 351.775015 -265.818732) (xy 351.806039 -265.778872)
			(xy 351.843201 -265.744662) (xy 351.885487 -265.717036) (xy 351.931743 -265.696746) (xy 351.980708 -265.684346)
			(xy 352.031046 -265.680175) (xy 352.081384 -265.684346) (xy 352.130349 -265.696746) (xy 352.176605 -265.717036)
			(xy 352.218891 -265.744662) (xy 352.256053 -265.778872) (xy 352.287077 -265.818732) (xy 352.311118 -265.863155)
			(xy 352.327519 -265.910929) (xy 352.335832 -265.960751) (xy 352.336354 -265.986006) (xy 353.60535 -265.986006)
			(xy 353.60931 -265.936952) (xy 353.621087 -265.889168) (xy 353.640378 -265.843892) (xy 353.666681 -265.802296)
			(xy 353.699316 -265.765459) (xy 353.737437 -265.734334) (xy 353.780058 -265.709727) (xy 353.826074 -265.692275)
			(xy 353.874293 -265.682431) (xy 353.923468 -265.68045) (xy 353.972323 -265.686382) (xy 354.019594 -265.700074)
			(xy 354.064056 -265.721172) (xy 354.104559 -265.749128) (xy 354.140052 -265.78322) (xy 354.169617 -265.822564)
			(xy 354.192488 -265.866141) (xy 354.208072 -265.912822) (xy 354.215967 -265.961399) (xy 354.216462 -265.986006)
			(xy 354.215967 -266.010613) (xy 354.208072 -266.05919) (xy 354.192488 -266.105871) (xy 354.169617 -266.149448)
			(xy 354.140052 -266.188792) (xy 354.104559 -266.222884) (xy 354.064056 -266.25084) (xy 354.019594 -266.271938)
			(xy 353.972323 -266.28563) (xy 353.923468 -266.291562) (xy 353.874293 -266.289581) (xy 353.826074 -266.279737)
			(xy 353.780058 -266.262285) (xy 353.737437 -266.237678) (xy 353.699316 -266.206553) (xy 353.666681 -266.169716)
			(xy 353.640378 -266.12812) (xy 353.621087 -266.082844) (xy 353.60931 -266.03506) (xy 353.60535 -265.986006)
			(xy 352.336354 -265.986006) (xy 352.33596 -266.006849) (xy 352.33022 -266.048139) (xy 352.324924 -266.068302)
			(xy 352.321876 -266.079986) (xy 352.326194 -266.1031) (xy 352.381058 -266.175744) (xy 352.388653 -266.184726)
			(xy 352.409698 -266.195178) (xy 352.421444 -266.19581) (xy 353.399598 -266.19581) (xy 353.409433 -266.196351)
			(xy 353.427586 -266.203946) (xy 353.434904 -266.210542) (xy 354.233226 -267.008864) (xy 354.240624 -267.01571)
			(xy 354.259223 -267.023441) (xy 354.269294 -267.02385) (xy 354.936044 -267.02385) (xy 354.948117 -267.023184)
			(xy 354.96961 -267.012185) (xy 354.977192 -267.002768) (xy 355.031548 -266.92733) (xy 355.035104 -266.903708)
			(xy 355.031294 -266.89177) (xy 355.024082 -266.868489) (xy 355.016295 -266.820379) (xy 355.0158 -266.796012)
			(xy 355.0158 -266.792456) (xy 355.016533 -266.768647) (xy 355.024476 -266.721683) (xy 355.039615 -266.676521)
			(xy 355.061583 -266.634259) (xy 355.089848 -266.59592) (xy 355.123724 -266.562436) (xy 355.162389 -266.534619)
			(xy 355.204904 -266.513144) (xy 355.250239 -266.498531) (xy 355.297292 -266.491136) (xy 355.321108 -266.490704)
			(xy 355.344313 -266.491138) (xy 355.390188 -266.498166) (xy 355.434469 -266.512058) (xy 355.476137 -266.532495)
			(xy 355.51423 -266.559004) (xy 355.547871 -266.590976) (xy 355.562408 -266.609068) (xy 355.569266 -266.617704)
			(xy 355.588316 -266.627864) (xy 355.67366 -266.633198) (xy 355.684498 -266.633406) (xy 355.704764 -266.625769)
			(xy 355.712776 -266.618466) (xy 355.868732 -266.46251) (xy 355.875618 -266.45507) (xy 355.883368 -266.436357)
			(xy 355.883259 -266.416103) (xy 355.879654 -266.40663) (xy 355.84384 -266.322302) (xy 355.839523 -266.313344)
			(xy 355.825402 -266.299372) (xy 355.807036 -266.2918) (xy 355.797104 -266.291314) (xy 355.791008 -266.291314)
			(xy 355.765749 -266.290822) (xy 355.715921 -266.282508) (xy 355.66814 -266.266106) (xy 355.623711 -266.242064)
			(xy 355.583846 -266.211036) (xy 355.549631 -266.173869) (xy 355.522 -266.131578) (xy 355.501707 -266.085316)
			(xy 355.489306 -266.036345) (xy 355.485134 -265.986) (xy 355.489306 -265.935655) (xy 355.501707 -265.886684)
			(xy 355.522 -265.840422) (xy 355.549631 -265.798131) (xy 355.583846 -265.760964) (xy 355.623711 -265.729936)
			(xy 355.66814 -265.705894) (xy 355.715921 -265.689492) (xy 355.765749 -265.681178) (xy 355.791008 -265.680698)
			(xy 355.81471 -265.681146) (xy 355.861544 -265.688472) (xy 355.906684 -265.702946) (xy 355.949045 -265.724221)
			(xy 355.98761 -265.751786) (xy 356.021454 -265.784978) (xy 356.049762 -265.823001) (xy 356.071855 -265.864941)
			(xy 356.087203 -265.909792) (xy 356.095436 -265.956475) (xy 356.096316 -265.980164) (xy 356.096316 -265.986006)
			(xy 357.365312 -265.986006) (xy 357.369272 -265.936952) (xy 357.381049 -265.889168) (xy 357.40034 -265.843892)
			(xy 357.426643 -265.802296) (xy 357.459278 -265.765459) (xy 357.497399 -265.734334) (xy 357.54002 -265.709727)
			(xy 357.586036 -265.692275) (xy 357.634255 -265.682431) (xy 357.68343 -265.68045) (xy 357.732285 -265.686382)
			(xy 357.779556 -265.700074) (xy 357.824018 -265.721172) (xy 357.864521 -265.749128) (xy 357.900014 -265.78322)
			(xy 357.929579 -265.822564) (xy 357.95245 -265.866141) (xy 357.968034 -265.912822) (xy 357.975929 -265.961399)
			(xy 357.976424 -265.986006) (xy 361.118924 -265.986006) (xy 361.122884 -265.936952) (xy 361.134661 -265.889168)
			(xy 361.153952 -265.843892) (xy 361.180255 -265.802296) (xy 361.21289 -265.765459) (xy 361.251011 -265.734334)
			(xy 361.293632 -265.709727) (xy 361.339648 -265.692275) (xy 361.387867 -265.682431) (xy 361.437042 -265.68045)
			(xy 361.485897 -265.686382) (xy 361.533168 -265.700074) (xy 361.57763 -265.721172) (xy 361.618133 -265.749128)
			(xy 361.653626 -265.78322) (xy 361.683191 -265.822564) (xy 361.706062 -265.866141) (xy 361.721646 -265.912822)
			(xy 361.729541 -265.961399) (xy 361.730036 -265.986006) (xy 361.729541 -266.010613) (xy 361.721646 -266.05919)
			(xy 361.706062 -266.105871) (xy 361.683191 -266.149448) (xy 361.653626 -266.188792) (xy 361.618133 -266.222884)
			(xy 361.57763 -266.25084) (xy 361.533168 -266.271938) (xy 361.485897 -266.28563) (xy 361.437042 -266.291562)
			(xy 361.387867 -266.289581) (xy 361.339648 -266.279737) (xy 361.293632 -266.262285) (xy 361.251011 -266.237678)
			(xy 361.21289 -266.206553) (xy 361.180255 -266.169716) (xy 361.153952 -266.12812) (xy 361.134661 -266.082844)
			(xy 361.122884 -266.03506) (xy 361.118924 -265.986006) (xy 357.976424 -265.986006) (xy 357.975929 -266.010613)
			(xy 357.968034 -266.05919) (xy 357.95245 -266.105871) (xy 357.929579 -266.149448) (xy 357.900014 -266.188792)
			(xy 357.864521 -266.222884) (xy 357.824018 -266.25084) (xy 357.779556 -266.271938) (xy 357.732285 -266.28563)
			(xy 357.68343 -266.291562) (xy 357.634255 -266.289581) (xy 357.586036 -266.279737) (xy 357.54002 -266.262285)
			(xy 357.497399 -266.237678) (xy 357.459278 -266.206553) (xy 357.426643 -266.169716) (xy 357.40034 -266.12812)
			(xy 357.381049 -266.082844) (xy 357.369272 -266.03506) (xy 357.365312 -265.986006) (xy 356.096316 -265.986006)
			(xy 356.096316 -265.98626) (xy 356.095762 -266.011948) (xy 356.087131 -266.062594) (xy 356.070172 -266.111091)
			(xy 356.058216 -266.133834) (xy 356.055168 -266.139422) (xy 356.051866 -266.151868) (xy 356.051866 -266.158472)
			(xy 356.052349 -266.168486) (xy 356.060002 -266.186993) (xy 356.074155 -266.201163) (xy 356.092653 -266.208839)
			(xy 356.102666 -266.209272) (xy 356.143052 -266.209272) (xy 356.143814 -266.20851) (xy 357.148638 -266.20851)
			(xy 357.158478 -266.209041) (xy 357.176646 -266.21662) (xy 357.183944 -266.223242) (xy 357.997506 -267.036804)
			(xy 358.004905 -267.043649) (xy 358.023503 -267.051381) (xy 358.033574 -267.05179) (xy 358.477058 -267.05179)
			(xy 358.487123 -267.051356) (xy 358.505711 -267.043626) (xy 358.513126 -267.036804) (xy 358.982264 -266.567666)
			(xy 358.989663 -266.560822) (xy 359.008262 -266.553101) (xy 359.018332 -266.55268) (xy 360.802428 -266.55268)
			(xy 360.812496 -266.553108) (xy 360.831095 -266.560827) (xy 360.838496 -266.567666) (xy 361.307634 -267.036804)
			(xy 361.315035 -267.043645) (xy 361.333633 -267.051366) (xy 361.343702 -267.05179) (xy 361.519978 -267.05179)
			(xy 361.532485 -267.051145) (xy 361.554588 -267.039427) (xy 361.562142 -267.029438) (xy 361.615228 -266.95019)
			(xy 361.617768 -266.92479) (xy 361.612942 -266.913106) (xy 361.602137 -266.885174) (xy 361.590377 -266.826459)
			(xy 361.589574 -266.79652) (xy 361.589574 -266.79144) (xy 361.590382 -266.767686) (xy 361.598449 -266.720847)
			(xy 361.613677 -266.675825) (xy 361.635699 -266.633707) (xy 361.663983 -266.595512) (xy 361.697845 -266.562161)
			(xy 361.736466 -266.534461) (xy 361.778914 -266.513082) (xy 361.824163 -266.49854) (xy 361.871118 -266.491187)
			(xy 361.894882 -266.490704) (xy 361.922019 -266.491293) (xy 361.97544 -266.500887) (xy 362.026321 -266.519777)
			(xy 362.073061 -266.547367) (xy 362.094018 -266.564618) (xy 362.097682 -266.5676) (xy 362.105862 -266.572325)
			(xy 362.110274 -266.574016) (xy 362.119418 -266.577318) (xy 362.196634 -266.574524) (xy 362.206147 -266.573805)
			(xy 362.22365 -266.566249) (xy 362.23067 -266.559792) (xy 362.50118 -266.289282) (xy 362.508416 -266.282564)
			(xy 362.526621 -266.27496) (xy 362.536486 -266.27455) (xy 362.94568 -266.27455) (xy 362.954413 -266.274204)
			(xy 362.970862 -266.268332) (xy 362.984353 -266.25724) (xy 362.989114 -266.249912) (xy 363.03966 -266.166092)
			(xy 363.040422 -266.139422) (xy 363.034326 -266.127738) (xy 363.023315 -266.105666) (xy 363.00777 -266.058857)
			(xy 362.999937 -266.01016) (xy 362.999528 -265.985498) (xy 362.999528 -265.980418) (xy 363.000482 -265.955465)
			(xy 363.009506 -265.906356) (xy 363.026399 -265.859368) (xy 363.050712 -265.815755) (xy 363.081797 -265.776679)
			(xy 363.118825 -265.743181) (xy 363.160809 -265.716153) (xy 363.206631 -265.696316) (xy 363.255071 -265.684199)
			(xy 363.304836 -265.680123) (xy 363.354601 -265.684199) (xy 363.403041 -265.696316) (xy 363.448863 -265.716153)
			(xy 363.490847 -265.743181) (xy 363.527875 -265.776679) (xy 363.55896 -265.815755) (xy 363.583273 -265.859368)
			(xy 363.600166 -265.906356) (xy 363.60919 -265.955465) (xy 363.610144 -265.980418) (xy 363.610144 -265.985498)
			(xy 363.610136 -265.986006) (xy 364.878886 -265.986006) (xy 364.882846 -265.936952) (xy 364.894623 -265.889168)
			(xy 364.913914 -265.843892) (xy 364.940217 -265.802296) (xy 364.972852 -265.765459) (xy 365.010973 -265.734334)
			(xy 365.053594 -265.709727) (xy 365.09961 -265.692275) (xy 365.147829 -265.682431) (xy 365.197004 -265.68045)
			(xy 365.245859 -265.686382) (xy 365.29313 -265.700074) (xy 365.337592 -265.721172) (xy 365.378095 -265.749128)
			(xy 365.413588 -265.78322) (xy 365.443153 -265.822564) (xy 365.466024 -265.866141) (xy 365.481608 -265.912822)
			(xy 365.489503 -265.961399) (xy 365.489998 -265.986006) (xy 365.489503 -266.010613) (xy 365.481608 -266.05919)
			(xy 365.466024 -266.105871) (xy 365.443153 -266.149448) (xy 365.413588 -266.188792) (xy 365.378095 -266.222884)
			(xy 365.337592 -266.25084) (xy 365.29313 -266.271938) (xy 365.245859 -266.28563) (xy 365.197004 -266.291562)
			(xy 365.147829 -266.289581) (xy 365.09961 -266.279737) (xy 365.053594 -266.262285) (xy 365.010973 -266.237678)
			(xy 364.972852 -266.206553) (xy 364.940217 -266.169716) (xy 364.913914 -266.12812) (xy 364.894623 -266.082844)
			(xy 364.882846 -266.03506) (xy 364.878886 -265.986006) (xy 363.610136 -265.986006) (xy 363.609733 -266.010161)
			(xy 363.601918 -266.058861) (xy 363.586361 -266.105668) (xy 363.575346 -266.127738) (xy 363.56925 -266.139422)
			(xy 363.570012 -266.166092) (xy 363.620558 -266.249912) (xy 363.625368 -266.257199) (xy 363.638858 -266.268267)
			(xy 363.655269 -266.274193) (xy 363.663992 -266.27455) (xy 363.775498 -266.27455) (xy 363.785334 -266.27509)
			(xy 363.803493 -266.282678) (xy 363.810804 -266.289282) (xy 364.543086 -267.021564) (xy 364.550487 -267.028401)
			(xy 364.569086 -267.03611) (xy 364.579154 -267.03655) (xy 365.274352 -267.03655) (xy 365.286674 -267.035951)
			(xy 365.308489 -267.024489) (xy 365.316008 -267.014706) (xy 365.362236 -266.948158) (xy 365.368614 -266.937762)
			(xy 365.371808 -266.913619) (xy 365.368332 -266.90193) (xy 365.368332 -266.901422) (xy 365.359552 -266.875893)
			(xy 365.350092 -266.822748) (xy 365.349536 -266.795758) (xy 365.349536 -266.79017) (xy 365.350437 -266.766482)
			(xy 365.358658 -266.7198) (xy 365.373997 -266.67495) (xy 365.396085 -266.63301) (xy 365.424391 -266.594989)
			(xy 365.458235 -266.561801) (xy 365.496803 -266.534245) (xy 365.539167 -266.512981) (xy 365.584309 -266.498523)
			(xy 365.631143 -266.491217) (xy 365.654844 -266.490704) (xy 365.655098 -266.490704) (xy 365.682318 -266.491332)
			(xy 365.73589 -266.50103) (xy 365.786901 -266.52005) (xy 365.833745 -266.547791) (xy 365.854742 -266.565126)
			(xy 365.861346 -266.570968) (xy 365.88573 -266.580366) (xy 365.889957 -266.581867) (xy 365.898772 -266.583523)
			(xy 365.903256 -266.583668) (xy 365.92383 -266.583922) (xy 365.934026 -266.583566) (xy 365.952885 -266.57583)
			(xy 365.960406 -266.568936) (xy 366.24006 -266.289282) (xy 366.247295 -266.282561) (xy 366.2655 -266.274949)
			(xy 366.275366 -266.27455) (xy 366.705642 -266.27455) (xy 366.71437 -266.274194) (xy 366.730803 -266.268309)
			(xy 366.744277 -266.257212) (xy 366.749076 -266.249912) (xy 366.799622 -266.166092) (xy 366.800384 -266.139422)
			(xy 366.794288 -266.127738) (xy 366.783279 -266.105666) (xy 366.767735 -266.058856) (xy 366.759903 -266.01016)
			(xy 366.75949 -265.985498) (xy 366.75949 -265.980418) (xy 366.760444 -265.955465) (xy 366.769468 -265.906356)
			(xy 366.786361 -265.859368) (xy 366.810674 -265.815755) (xy 366.841759 -265.776679) (xy 366.878787 -265.743181)
			(xy 366.920771 -265.716153) (xy 366.966593 -265.696316) (xy 367.015033 -265.684199) (xy 367.064798 -265.680123)
			(xy 367.114563 -265.684199) (xy 367.163003 -265.696316) (xy 367.208825 -265.716153) (xy 367.250809 -265.743181)
			(xy 367.287837 -265.776679) (xy 367.318922 -265.815755) (xy 367.343235 -265.859368) (xy 367.360128 -265.906356)
			(xy 367.369152 -265.955465) (xy 367.370106 -265.980418) (xy 367.370106 -265.985498) (xy 367.370098 -265.986006)
			(xy 368.639102 -265.986006) (xy 368.643062 -265.936952) (xy 368.654839 -265.889168) (xy 368.67413 -265.843892)
			(xy 368.700433 -265.802296) (xy 368.733068 -265.765459) (xy 368.771189 -265.734334) (xy 368.81381 -265.709727)
			(xy 368.859826 -265.692275) (xy 368.908045 -265.682431) (xy 368.95722 -265.68045) (xy 369.006075 -265.686382)
			(xy 369.053346 -265.700074) (xy 369.097808 -265.721172) (xy 369.138311 -265.749128) (xy 369.173804 -265.78322)
			(xy 369.203369 -265.822564) (xy 369.22624 -265.866141) (xy 369.241824 -265.912822) (xy 369.249719 -265.961399)
			(xy 369.250214 -265.986006) (xy 369.249719 -266.010613) (xy 369.241824 -266.05919) (xy 369.22624 -266.105871)
			(xy 369.203369 -266.149448) (xy 369.173804 -266.188792) (xy 369.138311 -266.222884) (xy 369.097808 -266.25084)
			(xy 369.053346 -266.271938) (xy 369.006075 -266.28563) (xy 368.95722 -266.291562) (xy 368.908045 -266.289581)
			(xy 368.859826 -266.279737) (xy 368.81381 -266.262285) (xy 368.771189 -266.237678) (xy 368.733068 -266.206553)
			(xy 368.700433 -266.169716) (xy 368.67413 -266.12812) (xy 368.654839 -266.082844) (xy 368.643062 -266.03506)
			(xy 368.639102 -265.986006) (xy 367.370098 -265.986006) (xy 367.369695 -266.010161) (xy 367.361879 -266.058861)
			(xy 367.346321 -266.105666) (xy 367.335308 -266.127738) (xy 367.329212 -266.139422) (xy 367.329974 -266.166092)
			(xy 367.38052 -266.249912) (xy 367.385333 -266.257193) (xy 367.398825 -266.268244) (xy 367.415235 -266.274151)
			(xy 367.423954 -266.27455) (xy 367.555018 -266.27455) (xy 367.564861 -266.275075) (xy 367.58304 -266.282644)
			(xy 367.590324 -266.289282) (xy 368.322606 -267.021564) (xy 368.330003 -267.028413) (xy 368.348601 -267.036151)
			(xy 368.358674 -267.03655) (xy 369.034314 -267.03655) (xy 369.046641 -267.03596) (xy 369.06847 -267.024507)
			(xy 369.07597 -267.014706) (xy 369.122198 -266.948158) (xy 369.12857 -266.937761) (xy 369.13176 -266.913621)
			(xy 369.128294 -266.90193) (xy 369.128294 -266.901422) (xy 369.119515 -266.875893) (xy 369.110056 -266.822748)
			(xy 369.109498 -266.795758) (xy 369.109498 -266.79017) (xy 369.110399 -266.766481) (xy 369.118619 -266.719797)
			(xy 369.133958 -266.674944) (xy 369.156046 -266.633001) (xy 369.184351 -266.594977) (xy 369.218195 -266.561786)
			(xy 369.256762 -266.534225) (xy 369.299126 -266.512957) (xy 369.344269 -266.498494) (xy 369.391104 -266.491182)
			(xy 369.414806 -266.490704) (xy 369.442533 -266.491308) (xy 369.497078 -266.501313) (xy 369.548924 -266.520993)
			(xy 369.596368 -266.549702) (xy 369.617498 -266.567666) (xy 369.624864 -266.57427) (xy 369.642898 -266.580874)
			(xy 369.720876 -266.578588) (xy 369.730447 -266.577888) (xy 369.748064 -266.570311) (xy 369.755166 -266.563856)
			(xy 370.09578 -266.223242) (xy 370.103019 -266.216529) (xy 370.121223 -266.208931) (xy 370.131086 -266.20851)
			(xy 370.438172 -266.20851) (xy 370.450153 -266.207868) (xy 370.471502 -266.196995) (xy 370.479066 -266.187682)
			(xy 370.533422 -266.11326) (xy 370.537232 -266.089638) (xy 370.533676 -266.077954) (xy 370.527017 -266.055553)
			(xy 370.519867 -266.009372) (xy 370.519452 -265.986006) (xy 370.519452 -265.98245) (xy 370.52025 -265.957387)
			(xy 370.529018 -265.90802) (xy 370.545734 -265.860748) (xy 370.569949 -265.816842) (xy 370.601012 -265.777483)
			(xy 370.638088 -265.743728) (xy 370.680181 -265.716484) (xy 370.72616 -265.696484) (xy 370.774788 -265.684264)
			(xy 370.82476 -265.680154) (xy 370.874732 -265.684264) (xy 370.92336 -265.696484) (xy 370.969339 -265.716484)
			(xy 371.011432 -265.743728) (xy 371.048508 -265.777483) (xy 371.079571 -265.816842) (xy 371.103786 -265.860748)
			(xy 371.120502 -265.90802) (xy 371.12927 -265.957387) (xy 371.130068 -265.98245) (xy 371.130068 -265.984228)
			(xy 371.130068 -265.986006) (xy 372.399064 -265.986006) (xy 372.403024 -265.936952) (xy 372.414801 -265.889168)
			(xy 372.434092 -265.843892) (xy 372.460395 -265.802296) (xy 372.49303 -265.765459) (xy 372.531151 -265.734334)
			(xy 372.573772 -265.709727) (xy 372.619788 -265.692275) (xy 372.668007 -265.682431) (xy 372.717182 -265.68045)
			(xy 372.766037 -265.686382) (xy 372.813308 -265.700074) (xy 372.85777 -265.721172) (xy 372.898273 -265.749128)
			(xy 372.933766 -265.78322) (xy 372.963331 -265.822564) (xy 372.986202 -265.866141) (xy 373.001786 -265.912822)
			(xy 373.009681 -265.961399) (xy 373.010176 -265.986006) (xy 374.278918 -265.986006) (xy 374.282878 -265.936952)
			(xy 374.294655 -265.889168) (xy 374.313946 -265.843892) (xy 374.340249 -265.802296) (xy 374.372884 -265.765459)
			(xy 374.411005 -265.734334) (xy 374.453626 -265.709727) (xy 374.499642 -265.692275) (xy 374.547861 -265.682431)
			(xy 374.597036 -265.68045) (xy 374.645891 -265.686382) (xy 374.693162 -265.700074) (xy 374.737624 -265.721172)
			(xy 374.778127 -265.749128) (xy 374.81362 -265.78322) (xy 374.843185 -265.822564) (xy 374.866056 -265.866141)
			(xy 374.88164 -265.912822) (xy 374.889535 -265.961399) (xy 374.89003 -265.986006) (xy 376.148595 -265.986006)
			(xy 376.15269 -265.935278) (xy 376.164869 -265.885864) (xy 376.184817 -265.839044) (xy 376.212018 -265.79603)
			(xy 376.245766 -265.757936) (xy 376.285188 -265.725749) (xy 376.329262 -265.700303) (xy 376.376848 -265.682256)
			(xy 376.426712 -265.672076) (xy 376.477564 -265.670027) (xy 376.528085 -265.676161) (xy 376.576969 -265.690321)
			(xy 376.622948 -265.712138) (xy 376.664832 -265.741048) (xy 376.701536 -265.776303) (xy 376.732109 -265.816989)
			(xy 376.75576 -265.862052) (xy 376.771876 -265.910326) (xy 376.78004 -265.96056) (xy 376.780552 -265.986006)
			(xy 377.09908 -265.986006) (xy 377.10304 -265.936952) (xy 377.114817 -265.889168) (xy 377.134108 -265.843892)
			(xy 377.160411 -265.802296) (xy 377.193046 -265.765459) (xy 377.231167 -265.734334) (xy 377.273788 -265.709727)
			(xy 377.319804 -265.692275) (xy 377.368023 -265.682431) (xy 377.417198 -265.68045) (xy 377.466053 -265.686382)
			(xy 377.513324 -265.700074) (xy 377.557786 -265.721172) (xy 377.598289 -265.749128) (xy 377.633782 -265.78322)
			(xy 377.663347 -265.822564) (xy 377.686218 -265.866141) (xy 377.701802 -265.912822) (xy 377.709697 -265.961399)
			(xy 377.710192 -265.986006) (xy 377.709697 -266.010613) (xy 377.701802 -266.05919) (xy 377.686218 -266.105871)
			(xy 377.663347 -266.149448) (xy 377.633782 -266.188792) (xy 377.598289 -266.222884) (xy 377.557786 -266.25084)
			(xy 377.513324 -266.271938) (xy 377.466053 -266.28563) (xy 377.417198 -266.291562) (xy 377.368023 -266.289581)
			(xy 377.319804 -266.279737) (xy 377.273788 -266.262285) (xy 377.231167 -266.237678) (xy 377.193046 -266.206553)
			(xy 377.160411 -266.169716) (xy 377.134108 -266.12812) (xy 377.114817 -266.082844) (xy 377.10304 -266.03506)
			(xy 377.09908 -265.986006) (xy 376.780552 -265.986006) (xy 376.78004 -266.011452) (xy 376.771876 -266.061686)
			(xy 376.75576 -266.10996) (xy 376.732109 -266.155023) (xy 376.701536 -266.195709) (xy 376.664832 -266.230964)
			(xy 376.622948 -266.259874) (xy 376.576969 -266.281691) (xy 376.528085 -266.295851) (xy 376.477564 -266.301985)
			(xy 376.426712 -266.299936) (xy 376.376848 -266.289756) (xy 376.329262 -266.271709) (xy 376.285188 -266.246263)
			(xy 376.245766 -266.214076) (xy 376.212018 -266.175982) (xy 376.184817 -266.132968) (xy 376.164869 -266.086148)
			(xy 376.15269 -266.036734) (xy 376.148595 -265.986006) (xy 374.89003 -265.986006) (xy 374.889535 -266.010613)
			(xy 374.88164 -266.05919) (xy 374.866056 -266.105871) (xy 374.843185 -266.149448) (xy 374.81362 -266.188792)
			(xy 374.778127 -266.222884) (xy 374.737624 -266.25084) (xy 374.693162 -266.271938) (xy 374.645891 -266.28563)
			(xy 374.597036 -266.291562) (xy 374.547861 -266.289581) (xy 374.499642 -266.279737) (xy 374.453626 -266.262285)
			(xy 374.411005 -266.237678) (xy 374.372884 -266.206553) (xy 374.340249 -266.169716) (xy 374.313946 -266.12812)
			(xy 374.294655 -266.082844) (xy 374.282878 -266.03506) (xy 374.278918 -265.986006) (xy 373.010176 -265.986006)
			(xy 373.009681 -266.010613) (xy 373.001786 -266.05919) (xy 372.986202 -266.105871) (xy 372.963331 -266.149448)
			(xy 372.933766 -266.188792) (xy 372.898273 -266.222884) (xy 372.85777 -266.25084) (xy 372.813308 -266.271938)
			(xy 372.766037 -266.28563) (xy 372.717182 -266.291562) (xy 372.668007 -266.289581) (xy 372.619788 -266.279737)
			(xy 372.573772 -266.262285) (xy 372.531151 -266.237678) (xy 372.49303 -266.206553) (xy 372.460395 -266.169716)
			(xy 372.434092 -266.12812) (xy 372.414801 -266.082844) (xy 372.403024 -266.03506) (xy 372.399064 -265.986006)
			(xy 371.130068 -265.986006) (xy 371.129605 -266.009368) (xy 371.122469 -266.055546) (xy 371.115844 -266.077954)
			(xy 371.112288 -266.089638) (xy 371.116098 -266.11326) (xy 371.170454 -266.187682) (xy 371.178059 -266.196945)
			(xy 371.199384 -266.207815) (xy 371.211348 -266.20851) (xy 371.278658 -266.20851) (xy 371.288496 -266.209044)
			(xy 371.306659 -266.216629) (xy 371.313964 -266.223242) (xy 372.112286 -267.021564) (xy 372.119687 -267.028401)
			(xy 372.138286 -267.03611) (xy 372.148354 -267.03655) (xy 372.794276 -267.03655) (xy 372.806607 -267.035968)
			(xy 372.82845 -267.024524) (xy 372.835932 -267.014706) (xy 372.88216 -266.948158) (xy 372.888536 -266.937762)
			(xy 372.891728 -266.91362) (xy 372.888256 -266.90193) (xy 372.888256 -266.901422) (xy 372.879475 -266.875894)
			(xy 372.870014 -266.822748) (xy 372.86946 -266.795758) (xy 372.86946 -266.79017) (xy 372.870433 -266.765231)
			(xy 372.879489 -266.716154) (xy 372.896404 -266.669202) (xy 372.92073 -266.625625) (xy 372.951817 -266.586584)
			(xy 372.988839 -266.553118) (xy 373.03081 -266.526117) (xy 373.076613 -266.506301) (xy 373.125028 -266.494196)
			(xy 373.174768 -266.490125) (xy 373.224508 -266.494196) (xy 373.272923 -266.506301) (xy 373.318726 -266.526117)
			(xy 373.360697 -266.553118) (xy 373.397719 -266.586584) (xy 373.428806 -266.625625) (xy 373.453132 -266.669202)
			(xy 373.470047 -266.716154) (xy 373.479103 -266.765231) (xy 373.480076 -266.79017) (xy 373.480076 -266.795758)
			(xy 373.479526 -266.82275) (xy 373.470075 -266.875898) (xy 373.46128 -266.901422) (xy 373.46128 -266.90193)
			(xy 373.457787 -266.913622) (xy 373.460963 -266.937778) (xy 373.467376 -266.948158) (xy 373.513604 -267.014706)
			(xy 373.521216 -267.024378) (xy 373.542976 -267.035799) (xy 373.55526 -267.03655) (xy 373.73433 -267.03655)
			(xy 373.746655 -267.035956) (xy 373.768478 -267.024499) (xy 373.775986 -267.014706) (xy 373.822214 -266.948158)
			(xy 373.828584 -266.93776) (xy 373.831774 -266.913621) (xy 373.82831 -266.90193) (xy 373.82831 -266.901422)
			(xy 373.81953 -266.875893) (xy 373.810071 -266.822748) (xy 373.809514 -266.795758) (xy 373.809514 -266.79017)
			(xy 373.810415 -266.766482) (xy 373.818636 -266.719798) (xy 373.833974 -266.674946) (xy 373.856062 -266.633005)
			(xy 373.884368 -266.594982) (xy 373.918212 -266.561792) (xy 373.956779 -266.534233) (xy 373.999143 -266.512967)
			(xy 374.044286 -266.498506) (xy 374.091121 -266.491197) (xy 374.114822 -266.490704) (xy 374.138812 -266.491176)
			(xy 374.1862 -266.498685) (xy 374.23183 -266.513515) (xy 374.274579 -266.5353) (xy 374.313394 -266.563504)
			(xy 374.347319 -266.597432) (xy 374.375518 -266.63625) (xy 374.397298 -266.679001) (xy 374.412123 -266.724633)
			(xy 374.419626 -266.772022) (xy 374.42013 -266.796012) (xy 374.749072 -266.796012) (xy 374.753032 -266.746958)
			(xy 374.764809 -266.699174) (xy 374.7841 -266.653898) (xy 374.810403 -266.612302) (xy 374.843038 -266.575465)
			(xy 374.881159 -266.54434) (xy 374.92378 -266.519733) (xy 374.969796 -266.502281) (xy 375.018015 -266.492437)
			(xy 375.06719 -266.490456) (xy 375.116045 -266.496388) (xy 375.163316 -266.51008) (xy 375.207778 -266.531178)
			(xy 375.248281 -266.559134) (xy 375.283774 -266.593226) (xy 375.313339 -266.63257) (xy 375.33621 -266.676147)
			(xy 375.351794 -266.722828) (xy 375.359689 -266.771405) (xy 375.360184 -266.796012) (xy 375.678695 -266.796012)
			(xy 375.68279 -266.745284) (xy 375.694969 -266.69587) (xy 375.714917 -266.64905) (xy 375.742118 -266.606036)
			(xy 375.775866 -266.567942) (xy 375.815288 -266.535755) (xy 375.859362 -266.510309) (xy 375.906948 -266.492262)
			(xy 375.956812 -266.482082) (xy 376.007664 -266.480033) (xy 376.058185 -266.486167) (xy 376.107069 -266.500327)
			(xy 376.153048 -266.522144) (xy 376.194932 -266.551054) (xy 376.231636 -266.586309) (xy 376.262209 -266.626995)
			(xy 376.28586 -266.672058) (xy 376.301976 -266.720332) (xy 376.31014 -266.770566) (xy 376.310652 -266.796012)
			(xy 376.628926 -266.796012) (xy 376.632886 -266.746958) (xy 376.644663 -266.699174) (xy 376.663954 -266.653898)
			(xy 376.690257 -266.612302) (xy 376.722892 -266.575465) (xy 376.761013 -266.54434) (xy 376.803634 -266.519733)
			(xy 376.84965 -266.502281) (xy 376.897869 -266.492437) (xy 376.947044 -266.490456) (xy 376.995899 -266.496388)
			(xy 377.04317 -266.51008) (xy 377.087632 -266.531178) (xy 377.128135 -266.559134) (xy 377.163628 -266.593226)
			(xy 377.193193 -266.63257) (xy 377.216064 -266.676147) (xy 377.231648 -266.722828) (xy 377.239543 -266.771405)
			(xy 377.240038 -266.796012) (xy 377.558549 -266.796012) (xy 377.562644 -266.745284) (xy 377.574823 -266.69587)
			(xy 377.594771 -266.64905) (xy 377.621972 -266.606036) (xy 377.65572 -266.567942) (xy 377.695142 -266.535755)
			(xy 377.739216 -266.510309) (xy 377.786802 -266.492262) (xy 377.836666 -266.482082) (xy 377.887518 -266.480033)
			(xy 377.938039 -266.486167) (xy 377.986923 -266.500327) (xy 378.032902 -266.522144) (xy 378.074786 -266.551054)
			(xy 378.11149 -266.586309) (xy 378.142063 -266.626995) (xy 378.165714 -266.672058) (xy 378.18183 -266.720332)
			(xy 378.189994 -266.770566) (xy 378.190506 -266.796012) (xy 378.189994 -266.821458) (xy 378.18183 -266.871692)
			(xy 378.165714 -266.919966) (xy 378.142063 -266.965029) (xy 378.11149 -267.005715) (xy 378.074786 -267.04097)
			(xy 378.032902 -267.06988) (xy 377.986923 -267.091697) (xy 377.938039 -267.105857) (xy 377.887518 -267.111991)
			(xy 377.836666 -267.109942) (xy 377.786802 -267.099762) (xy 377.739216 -267.081715) (xy 377.695142 -267.056269)
			(xy 377.65572 -267.024082) (xy 377.621972 -266.985988) (xy 377.594771 -266.942974) (xy 377.574823 -266.896154)
			(xy 377.562644 -266.84674) (xy 377.558549 -266.796012) (xy 377.240038 -266.796012) (xy 377.239543 -266.820619)
			(xy 377.231648 -266.869196) (xy 377.216064 -266.915877) (xy 377.193193 -266.959454) (xy 377.163628 -266.998798)
			(xy 377.128135 -267.03289) (xy 377.087632 -267.060846) (xy 377.04317 -267.081944) (xy 376.995899 -267.095636)
			(xy 376.947044 -267.101568) (xy 376.897869 -267.099587) (xy 376.84965 -267.089743) (xy 376.803634 -267.072291)
			(xy 376.761013 -267.047684) (xy 376.722892 -267.016559) (xy 376.690257 -266.979722) (xy 376.663954 -266.938126)
			(xy 376.644663 -266.89285) (xy 376.632886 -266.845066) (xy 376.628926 -266.796012) (xy 376.310652 -266.796012)
			(xy 376.31014 -266.821458) (xy 376.301976 -266.871692) (xy 376.28586 -266.919966) (xy 376.262209 -266.965029)
			(xy 376.231636 -267.005715) (xy 376.194932 -267.04097) (xy 376.153048 -267.06988) (xy 376.107069 -267.091697)
			(xy 376.058185 -267.105857) (xy 376.007664 -267.111991) (xy 375.956812 -267.109942) (xy 375.906948 -267.099762)
			(xy 375.859362 -267.081715) (xy 375.815288 -267.056269) (xy 375.775866 -267.024082) (xy 375.742118 -266.985988)
			(xy 375.714917 -266.942974) (xy 375.694969 -266.896154) (xy 375.68279 -266.84674) (xy 375.678695 -266.796012)
			(xy 375.360184 -266.796012) (xy 375.359689 -266.820619) (xy 375.351794 -266.869196) (xy 375.33621 -266.915877)
			(xy 375.313339 -266.959454) (xy 375.283774 -266.998798) (xy 375.248281 -267.03289) (xy 375.207778 -267.060846)
			(xy 375.163316 -267.081944) (xy 375.116045 -267.095636) (xy 375.06719 -267.101568) (xy 375.018015 -267.099587)
			(xy 374.969796 -267.089743) (xy 374.92378 -267.072291) (xy 374.881159 -267.047684) (xy 374.843038 -267.016559)
			(xy 374.810403 -266.979722) (xy 374.7841 -266.938126) (xy 374.764809 -266.89285) (xy 374.753032 -266.845066)
			(xy 374.749072 -266.796012) (xy 374.42013 -266.796012) (xy 374.419559 -266.822548) (xy 374.410381 -266.87482)
			(xy 374.392305 -266.924718) (xy 374.365874 -266.970739) (xy 374.331884 -267.011498) (xy 374.29136 -267.045767)
			(xy 374.268746 -267.059664) (xy 374.258586 -267.06576) (xy 374.245632 -267.085064) (xy 374.233948 -267.174726)
			(xy 374.233694 -267.179044) (xy 374.233734 -267.189614) (xy 374.241327 -267.209315) (xy 374.248426 -267.217144)
			(xy 374.37949 -267.348208) (xy 374.414034 -267.352272) (xy 374.42902 -267.343382) (xy 374.452765 -267.329998)
			(xy 374.503834 -267.31096) (xy 374.557471 -267.30129) (xy 374.584722 -267.30071) (xy 374.590818 -267.30071)
			(xy 374.61679 -267.301753) (xy 374.667828 -267.311576) (xy 374.716468 -267.329897) (xy 374.761304 -267.356186)
			(xy 374.801043 -267.389686) (xy 374.834537 -267.42943) (xy 374.860821 -267.474269) (xy 374.879135 -267.522911)
			(xy 374.888951 -267.573951) (xy 374.89003 -267.599922) (xy 374.89003 -267.606018) (xy 374.889431 -267.633268)
			(xy 374.879764 -267.686904) (xy 374.860741 -267.737975) (xy 374.847358 -267.76172) (xy 374.838468 -267.776706)
			(xy 374.842532 -267.81125) (xy 374.946926 -267.915644) (xy 374.954323 -267.922492) (xy 374.972922 -267.930226)
			(xy 374.982994 -267.93063) (xy 376.12701 -267.93063)
		)
		(stroke
			(width 0)
			(type solid)
		)
		(fill yes)
		(layer "In4.Cu")
		(net "PVDD11_S3_P0")
	)
	(gr_poly
		(pts
			(xy 131.16179 -268.682724) (xy 131.171626 -268.682185) (xy 131.189785 -268.674596) (xy 131.197096 -268.667992)
			(xy 131.472432 -268.392656) (xy 131.479138 -268.385415) (xy 131.486717 -268.36721) (xy 131.487164 -268.35735)
			(xy 131.487164 -268.009624) (xy 131.486708 -267.998964) (xy 131.478028 -267.979493) (xy 131.4704 -267.972032)
			(xy 131.407662 -267.915644) (xy 131.387342 -267.90904) (xy 131.376674 -267.910056) (xy 131.34467 -267.91158)
			(xy 131.318812 -267.911035) (xy 131.267835 -267.902322) (xy 131.219054 -267.885149) (xy 131.17386 -267.860008)
			(xy 131.133545 -267.827616) (xy 131.09926 -267.788898) (xy 131.071985 -267.744959) (xy 131.052497 -267.697056)
			(xy 131.041354 -267.646554) (xy 131.039616 -267.62075) (xy 131.039362 -267.614146) (xy 131.039362 -267.606272)
			(xy 131.039883 -267.581037) (xy 131.048178 -267.531254) (xy 131.06454 -267.483511) (xy 131.088523 -267.439104)
			(xy 131.119476 -267.39924) (xy 131.13766 -267.381736) (xy 131.14528 -267.374624) (xy 131.155186 -267.353288)
			(xy 131.158769 -267.344506) (xy 131.159808 -267.325582) (xy 131.157218 -267.316458) (xy 131.150868 -267.295122)
			(xy 131.150868 -267.294868) (xy 131.14909 -267.288264) (xy 131.126738 -267.204952) (xy 131.124452 -267.196062)
			(xy 131.124452 -267.195808) (xy 131.12242 -267.18768) (xy 131.122166 -267.186918) (xy 131.112768 -267.151866)
			(xy 131.109662 -267.142119) (xy 131.097082 -267.12601) (xy 131.088384 -267.120624) (xy 131.025392 -267.085318)
			(xy 131.015445 -267.080359) (xy 130.99331 -267.078642) (xy 130.98272 -267.082016) (xy 130.982212 -267.082016)
			(xy 130.956284 -267.091107) (xy 130.902238 -267.100955) (xy 130.87477 -267.101574) (xy 130.869182 -267.101574)
			(xy 130.861054 -267.10132) (xy 130.835204 -267.099616) (xy 130.784587 -267.088598) (xy 130.736557 -267.069194)
			(xy 130.692492 -267.041961) (xy 130.653656 -267.00768) (xy 130.621164 -266.967336) (xy 130.595948 -266.922086)
			(xy 130.578732 -266.873229) (xy 130.57001 -266.822167) (xy 130.569462 -266.796266) (xy 130.569926 -266.771657)
			(xy 130.577812 -266.723076) (xy 130.59339 -266.676389) (xy 130.616258 -266.632807) (xy 130.645821 -266.593458)
			(xy 130.681315 -266.559362) (xy 130.721819 -266.531403) (xy 130.766285 -266.510305) (xy 130.81356 -266.496614)
			(xy 130.83794 -266.493244) (xy 130.85191 -266.491466) (xy 130.8735 -266.474956) (xy 130.911854 -266.3825)
			(xy 130.914939 -266.374048) (xy 130.915602 -266.356079) (xy 130.910024 -266.338985) (xy 130.904742 -266.3317)
			(xy 130.885915 -266.307025) (xy 130.85324 -266.254254) (xy 130.826604 -266.198192) (xy 130.806333 -266.139528)
			(xy 130.792677 -266.07898) (xy 130.785804 -266.017294) (xy 130.785362 -265.98626) (xy 130.78595 -265.949455)
			(xy 130.795612 -265.876481) (xy 130.814765 -265.805406) (xy 130.843077 -265.737458) (xy 130.861054 -265.705336)
			(xy 130.905758 -265.628374) (xy 130.911545 -265.617161) (xy 130.912482 -265.591976) (xy 130.907536 -265.580368)
			(xy 130.871214 -265.506708) (xy 130.865159 -265.495752) (xy 130.844906 -265.48109) (xy 130.832606 -265.478768)
			(xy 130.808599 -265.474923) (xy 130.762131 -265.460627) (xy 130.718512 -265.439155) (xy 130.678842 -265.411048)
			(xy 130.644123 -265.377016) (xy 130.615229 -265.337916) (xy 130.592889 -265.294736) (xy 130.577666 -265.248563)
			(xy 130.569945 -265.200562) (xy 130.569462 -265.176254) (xy 130.569926 -265.151646) (xy 130.577814 -265.103066)
			(xy 130.593394 -265.056381) (xy 130.616262 -265.0128) (xy 130.645826 -264.973453) (xy 130.681319 -264.939359)
			(xy 130.721823 -264.911401) (xy 130.766288 -264.890304) (xy 130.813562 -264.876614) (xy 130.83794 -264.873232)
			(xy 130.85191 -264.871454) (xy 130.8735 -264.854944) (xy 130.917188 -264.749788) (xy 130.913378 -264.722356)
			(xy 130.904742 -264.711688) (xy 130.880271 -264.679207) (xy 130.839983 -264.608568) (xy 130.824478 -264.570972)
			(xy 130.819398 -264.558018) (xy 130.797808 -264.541) (xy 130.684016 -264.526014) (xy 130.658616 -264.536936)
			(xy 130.650234 -264.547858) (xy 130.635733 -264.56669) (xy 130.60188 -264.600049) (xy 130.563267 -264.627761)
			(xy 130.520828 -264.649155) (xy 130.475585 -264.663715) (xy 130.428634 -264.67109) (xy 130.40487 -264.671556)
			(xy 130.380879 -264.671083) (xy 130.333488 -264.663574) (xy 130.287855 -264.648744) (xy 130.245103 -264.62696)
			(xy 130.206284 -264.598757) (xy 130.172355 -264.564829) (xy 130.14415 -264.526012) (xy 130.122363 -264.483262)
			(xy 130.107531 -264.437629) (xy 130.100018 -264.390239) (xy 130.099562 -264.366248) (xy 130.100031 -264.342011)
			(xy 130.107695 -264.294147) (xy 130.122824 -264.248094) (xy 130.145036 -264.205008) (xy 130.173775 -264.165972)
			(xy 130.208319 -264.131965) (xy 130.2478 -264.103841) (xy 130.291228 -264.082307) (xy 130.337513 -264.067901)
			(xy 130.361436 -264.063988) (xy 130.373882 -264.06221) (xy 130.40487 -264.060686) (xy 130.428653 -264.061137)
			(xy 130.475646 -264.068501) (xy 130.52093 -264.083058) (xy 130.563412 -264.104455) (xy 130.602066 -264.132175)
			(xy 130.635959 -264.165549) (xy 130.650488 -264.184384) (xy 130.65887 -264.19556) (xy 130.68427 -264.206482)
			(xy 130.797808 -264.191496) (xy 130.819398 -264.174478) (xy 130.824478 -264.161524) (xy 130.832352 -264.141889)
			(xy 130.850661 -264.103749) (xy 130.861054 -264.085324) (xy 131.009898 -263.829038) (xy 131.029579 -263.79642)
			(xy 131.07648 -263.736388) (xy 131.10337 -263.709404) (xy 131.103624 -263.70915) (xy 131.108704 -263.70407)
			(xy 131.122166 -263.680956) (xy 131.123944 -263.674098) (xy 131.134173 -263.636831) (xy 131.163485 -263.565324)
			(xy 131.182364 -263.531604) (xy 131.230878 -263.448292) (xy 131.236013 -263.438369) (xy 131.238041 -263.416144)
			(xy 131.230452 -263.395157) (xy 131.223004 -263.386824) (xy 131.18973 -263.35355) (xy 131.182618 -263.346184)
			(xy 131.163822 -263.338564) (xy 130.323082 -263.338564) (xy 130.311142 -263.3392) (xy 130.289802 -263.349921)
			(xy 130.282188 -263.359138) (xy 130.234944 -263.422892) (xy 130.231134 -263.447022) (xy 130.234944 -263.45896)
			(xy 130.242071 -263.482646) (xy 130.249726 -263.531511) (xy 130.250184 -263.556242) (xy 130.249698 -263.581032)
			(xy 130.241942 -263.63) (xy 130.226621 -263.677153) (xy 130.204112 -263.721328) (xy 130.17497 -263.761439)
			(xy 130.139913 -263.796496) (xy 130.099802 -263.825638) (xy 130.055627 -263.848147) (xy 130.008474 -263.863468)
			(xy 129.959506 -263.871224) (xy 129.909926 -263.871224) (xy 129.860958 -263.863468) (xy 129.813805 -263.848147)
			(xy 129.76963 -263.825638) (xy 129.729519 -263.796496) (xy 129.694462 -263.761439) (xy 129.66532 -263.721328)
			(xy 129.642811 -263.677153) (xy 129.62749 -263.63) (xy 129.619734 -263.581032) (xy 129.619248 -263.556242)
			(xy 129.619659 -263.531507) (xy 129.627307 -263.482633) (xy 129.634488 -263.45896) (xy 129.638298 -263.447022)
			(xy 129.634488 -263.422892) (xy 129.587244 -263.359138) (xy 129.579631 -263.349914) (xy 129.558294 -263.33918)
			(xy 129.54635 -263.338564) (xy 129.383028 -263.338564) (xy 129.371094 -263.339211) (xy 129.349773 -263.349945)
			(xy 129.342134 -263.359138) (xy 129.29489 -263.423146) (xy 129.2883 -263.433078) (xy 129.284185 -263.456526)
			(xy 129.287016 -263.468104) (xy 129.287016 -263.468358) (xy 129.293033 -263.489766) (xy 129.299541 -263.533755)
			(xy 129.29997 -263.555988) (xy 129.29997 -263.559544) (xy 129.299191 -263.58462) (xy 129.290456 -263.634021)
			(xy 129.273762 -263.681328) (xy 129.24956 -263.72527) (xy 129.2185 -263.764665) (xy 129.181417 -263.798453)
			(xy 129.13931 -263.825724) (xy 129.093312 -263.845744) (xy 129.04466 -263.857977) (xy 128.994662 -263.862091)
			(xy 128.944664 -263.857977) (xy 128.896012 -263.845744) (xy 128.850014 -263.825724) (xy 128.807907 -263.798453)
			(xy 128.770824 -263.764665) (xy 128.739764 -263.72527) (xy 128.715562 -263.681328) (xy 128.698868 -263.634021)
			(xy 128.690133 -263.58462) (xy 128.689354 -263.559544) (xy 128.689354 -263.555988) (xy 128.68975 -263.533752)
			(xy 128.696249 -263.489756) (xy 128.702308 -263.468358) (xy 128.702308 -263.468104) (xy 128.705156 -263.456525)
			(xy 128.701047 -263.433069) (xy 128.694434 -263.423146) (xy 128.64719 -263.359138) (xy 128.639574 -263.349923)
			(xy 128.618236 -263.339212) (xy 128.606296 -263.338564) (xy 128.443228 -263.338564) (xy 128.431294 -263.339211)
			(xy 128.409973 -263.349945) (xy 128.402334 -263.359138) (xy 128.35509 -263.422892) (xy 128.35128 -263.447022)
			(xy 128.35509 -263.45896) (xy 128.362323 -263.482628) (xy 128.370111 -263.531499) (xy 128.370584 -263.556242)
			(xy 128.370097 -263.581052) (xy 128.362335 -263.63006) (xy 128.347002 -263.67725) (xy 128.324475 -263.721461)
			(xy 128.29531 -263.761604) (xy 128.260224 -263.79669) (xy 128.220081 -263.825855) (xy 128.17587 -263.848382)
			(xy 128.12868 -263.863715) (xy 128.079672 -263.871477) (xy 128.030052 -263.871477) (xy 127.981044 -263.863715)
			(xy 127.933854 -263.848382) (xy 127.889643 -263.825855) (xy 127.8495 -263.79669) (xy 127.814414 -263.761604)
			(xy 127.785249 -263.721461) (xy 127.762722 -263.67725) (xy 127.747389 -263.63006) (xy 127.739627 -263.581052)
			(xy 127.73914 -263.556242) (xy 127.739659 -263.531502) (xy 127.747435 -263.482635) (xy 127.754634 -263.45896)
			(xy 127.758444 -263.447022) (xy 127.754634 -263.422892) (xy 127.70739 -263.359138) (xy 127.699774 -263.349923)
			(xy 127.678436 -263.339212) (xy 127.666496 -263.338564) (xy 127.503174 -263.338564) (xy 127.491235 -263.339201)
			(xy 127.469898 -263.349924) (xy 127.46228 -263.359138) (xy 127.415036 -263.423146) (xy 127.408442 -263.433077)
			(xy 127.404323 -263.456527) (xy 127.407162 -263.468104) (xy 127.407162 -263.468358) (xy 127.413179 -263.489766)
			(xy 127.419688 -263.533755) (xy 127.420116 -263.555988) (xy 127.420116 -263.559544) (xy 127.419337 -263.58462)
			(xy 127.410602 -263.634021) (xy 127.393908 -263.681328) (xy 127.369706 -263.72527) (xy 127.338646 -263.764665)
			(xy 127.301563 -263.798453) (xy 127.259456 -263.825724) (xy 127.213458 -263.845744) (xy 127.164806 -263.857977)
			(xy 127.114808 -263.862091) (xy 127.06481 -263.857977) (xy 127.016158 -263.845744) (xy 126.97016 -263.825724)
			(xy 126.928053 -263.798453) (xy 126.89097 -263.764665) (xy 126.85991 -263.72527) (xy 126.835708 -263.681328)
			(xy 126.819014 -263.634021) (xy 126.810279 -263.58462) (xy 126.8095 -263.559544) (xy 126.8095 -263.555988)
			(xy 126.809896 -263.533752) (xy 126.816394 -263.489756) (xy 126.822454 -263.468358) (xy 126.822454 -263.468104)
			(xy 126.825304 -263.456526) (xy 126.821191 -263.433071) (xy 126.81458 -263.423146) (xy 126.767336 -263.359138)
			(xy 126.759723 -263.349915) (xy 126.738386 -263.339185) (xy 126.726442 -263.338564) (xy 125.623066 -263.338564)
			(xy 125.611127 -263.339203) (xy 125.589794 -263.349928) (xy 125.582172 -263.359138) (xy 125.534928 -263.423146)
			(xy 125.528335 -263.433077) (xy 125.524216 -263.456527) (xy 125.527054 -263.468104) (xy 125.527054 -263.468358)
			(xy 125.533071 -263.489766) (xy 125.539581 -263.533755) (xy 125.540008 -263.555988) (xy 125.540008 -263.559544)
			(xy 125.539229 -263.58462) (xy 125.530494 -263.634021) (xy 125.5138 -263.681328) (xy 125.489598 -263.72527)
			(xy 125.458538 -263.764665) (xy 125.421455 -263.798453) (xy 125.379348 -263.825724) (xy 125.33335 -263.845744)
			(xy 125.284698 -263.857977) (xy 125.2347 -263.862091) (xy 125.184702 -263.857977) (xy 125.13605 -263.845744)
			(xy 125.090052 -263.825724) (xy 125.047945 -263.798453) (xy 125.010862 -263.764665) (xy 124.979802 -263.72527)
			(xy 124.9556 -263.681328) (xy 124.938906 -263.634021) (xy 124.930171 -263.58462) (xy 124.929392 -263.559544)
			(xy 124.929392 -263.555988) (xy 124.929788 -263.533752) (xy 124.936285 -263.489756) (xy 124.942346 -263.468358)
			(xy 124.942346 -263.468104) (xy 124.945196 -263.456526) (xy 124.941082 -263.433071) (xy 124.934472 -263.423146)
			(xy 124.887228 -263.359138) (xy 124.879614 -263.349916) (xy 124.858277 -263.339189) (xy 124.846334 -263.338564)
			(xy 124.085858 -263.338564) (xy 124.076017 -263.338035) (xy 124.057842 -263.330462) (xy 124.050552 -263.323832)
			(xy 123.779788 -263.053068) (xy 123.767342 -263.04621) (xy 123.759976 -263.044686) (xy 123.735689 -263.038912)
			(xy 123.689273 -263.02054) (xy 123.646463 -262.994866) (xy 123.608398 -262.962571) (xy 123.576091 -262.924516)
			(xy 123.550403 -262.881714) (xy 123.532017 -262.835305) (xy 123.526296 -262.811006) (xy 123.524772 -262.80364)
			(xy 123.517914 -262.791194) (xy 123.19127 -262.46455) (xy 123.184158 -262.457184) (xy 123.165362 -262.449564)
			(xy 123.142248 -262.449564) (xy 123.132218 -262.449975) (xy 123.113678 -262.457635) (xy 123.099482 -262.471807)
			(xy 123.091791 -262.490334) (xy 123.091448 -262.500364) (xy 123.091448 -262.51027) (xy 123.09856 -262.528304)
			(xy 123.105418 -262.535416) (xy 123.121196 -262.552551) (xy 123.147897 -262.590714) (xy 123.168488 -262.632492)
			(xy 123.18249 -262.676914) (xy 123.189579 -262.722948) (xy 123.19 -262.746236) (xy 123.189527 -262.770225)
			(xy 123.182016 -262.817612) (xy 123.167185 -262.863241) (xy 123.1454 -262.905988) (xy 123.117196 -262.944801)
			(xy 123.083267 -262.978724) (xy 123.04445 -263.006923) (xy 123.0017 -263.028702) (xy 122.956069 -263.043526)
			(xy 122.908681 -263.05103) (xy 122.884692 -263.051544) (xy 122.860989 -263.051096) (xy 122.814153 -263.04377)
			(xy 122.76901 -263.029297) (xy 122.726646 -263.008023) (xy 122.688077 -262.980459) (xy 122.65423 -262.947267)
			(xy 122.625917 -262.909244) (xy 122.603819 -262.867304) (xy 122.588466 -262.822453) (xy 122.580226 -262.775769)
			(xy 122.579384 -262.752078) (xy 122.579384 -262.747506) (xy 122.579785 -262.721598) (xy 122.588319 -262.670494)
			(xy 122.605379 -262.621572) (xy 122.617484 -262.598662) (xy 122.624088 -262.586724) (xy 122.62358 -262.5598)
			(xy 122.573542 -262.47471) (xy 122.568794 -262.467207) (xy 122.555169 -262.45584) (xy 122.538473 -262.449828)
			(xy 122.5296 -262.449564) (xy 122.29973 -262.449564) (xy 122.290877 -262.449948) (xy 122.274224 -262.455965)
			(xy 122.26059 -262.467264) (xy 122.255788 -262.47471) (xy 122.20575 -262.5598) (xy 122.205242 -262.586724)
			(xy 122.211846 -262.598662) (xy 122.223887 -262.6216) (xy 122.240928 -262.670517) (xy 122.249494 -262.721604)
			(xy 122.249946 -262.747506) (xy 122.249946 -262.752078) (xy 122.248973 -262.777017) (xy 122.239917 -262.826094)
			(xy 122.223002 -262.873046) (xy 122.198676 -262.916623) (xy 122.167589 -262.955664) (xy 122.130567 -262.98913)
			(xy 122.088596 -263.016131) (xy 122.042793 -263.035947) (xy 121.994378 -263.048052) (xy 121.944638 -263.052123)
			(xy 121.894898 -263.048052) (xy 121.846483 -263.035947) (xy 121.80068 -263.016131) (xy 121.758709 -262.98913)
			(xy 121.721687 -262.955664) (xy 121.6906 -262.916623) (xy 121.666274 -262.873046) (xy 121.649359 -262.826094)
			(xy 121.640303 -262.777017) (xy 121.63933 -262.752078) (xy 121.63933 -262.747506) (xy 121.639731 -262.721598)
			(xy 121.648266 -262.670495) (xy 121.665329 -262.621573) (xy 121.67743 -262.598662) (xy 121.684034 -262.586724)
			(xy 121.683526 -262.5598) (xy 121.633488 -262.47471) (xy 121.628738 -262.467213) (xy 121.61511 -262.455861)
			(xy 121.598416 -262.449866) (xy 121.589546 -262.449564) (xy 119.640858 -262.449564) (xy 119.631017 -262.449035)
			(xy 119.612842 -262.441462) (xy 119.605552 -262.434832) (xy 119.00027 -261.82955) (xy 118.993158 -261.822184)
			(xy 118.974362 -261.814564) (xy 117.79631 -261.814564) (xy 117.793516 -261.814564) (xy 117.781229 -261.815818)
			(xy 117.760045 -261.828462) (xy 117.75313 -261.838694) (xy 117.750844 -261.842504) (xy 117.71122 -261.921498)
			(xy 117.707308 -261.930102) (xy 117.705504 -261.948904) (xy 117.710653 -261.967076) (xy 117.716046 -261.974838)
			(xy 117.716046 -261.975092) (xy 117.73205 -261.997475) (xy 117.757474 -262.04627) (xy 117.774792 -262.098495)
			(xy 117.783562 -262.152813) (xy 117.784118 -262.180324) (xy 117.784118 -262.18769) (xy 117.783046 -262.214297)
			(xy 117.773703 -262.266718) (xy 117.756383 -262.317069) (xy 117.731499 -262.364144) (xy 117.69965 -262.406816)
			(xy 117.661597 -262.444061) (xy 117.618252 -262.474989) (xy 117.570654 -262.498856) (xy 117.519943 -262.515093)
			(xy 117.467334 -262.52331) (xy 117.414086 -262.52331) (xy 117.361477 -262.515093) (xy 117.310766 -262.498856)
			(xy 117.263168 -262.474989) (xy 117.219823 -262.444061) (xy 117.18177 -262.406816) (xy 117.149921 -262.364144)
			(xy 117.125037 -262.317069) (xy 117.107717 -262.266718) (xy 117.098374 -262.214297) (xy 117.097302 -262.18769)
			(xy 117.097302 -262.180324) (xy 117.097844 -262.152812) (xy 117.106614 -262.098492) (xy 117.123934 -262.046266)
			(xy 117.14936 -261.997469) (xy 117.165374 -261.975092) (xy 117.165374 -261.974838) (xy 117.170679 -261.967034)
			(xy 117.175792 -261.948886) (xy 117.174045 -261.930113) (xy 117.1702 -261.921498) (xy 117.130576 -261.842504)
			(xy 117.12829 -261.838694) (xy 117.121209 -261.828633) (xy 117.100119 -261.816035) (xy 117.087904 -261.814564)
			(xy 116.661438 -261.814564) (xy 116.651598 -261.814031) (xy 116.633429 -261.806454) (xy 116.626132 -261.799832)
			(xy 116.445792 -261.619492) (xy 116.437173 -261.611867) (xy 116.415443 -261.604388) (xy 116.392619 -261.607063)
			(xy 116.382546 -261.612634) (xy 116.361756 -261.625373) (xy 116.317344 -261.645497) (xy 116.270535 -261.659145)
			(xy 116.222267 -261.666045) (xy 116.197888 -261.666482) (xy 116.190268 -261.666482) (xy 116.163673 -261.665398)
			(xy 116.11128 -261.656034) (xy 116.060958 -261.638697) (xy 116.013915 -261.613804) (xy 115.971276 -261.581949)
			(xy 115.934063 -261.543897) (xy 115.903167 -261.500558) (xy 115.879329 -261.452971) (xy 115.863119 -261.402276)
			(xy 115.854926 -261.349686) (xy 115.85448 -261.323074) (xy 115.855011 -261.29609) (xy 115.863457 -261.242786)
			(xy 115.880137 -261.19146) (xy 115.90464 -261.143375) (xy 115.936363 -261.099715) (xy 115.974526 -261.061554)
			(xy 116.018187 -261.029833) (xy 116.066273 -261.005332) (xy 116.1176 -260.988654) (xy 116.170904 -260.98021)
			(xy 116.197888 -260.979666) (xy 116.225361 -260.980228) (xy 116.279596 -260.989039) (xy 116.305838 -260.997192)
			(xy 116.317522 -261.001002) (xy 116.341652 -260.997192) (xy 116.416582 -260.94309) (xy 116.425966 -260.935479)
			(xy 116.436971 -260.914005) (xy 116.437664 -260.901942) (xy 116.437664 -260.260846) (xy 116.437065 -260.248524)
			(xy 116.425605 -260.226707) (xy 116.41582 -260.21919) (xy 116.338604 -260.16585) (xy 116.313966 -260.162802)
			(xy 116.302282 -260.16712) (xy 116.273766 -260.177066) (xy 116.214362 -260.187921) (xy 116.184172 -260.18871)
			(xy 116.178076 -260.18871) (xy 116.151298 -260.187883) (xy 116.098476 -260.178945) (xy 116.047683 -260.161913)
			(xy 116.000151 -260.137201) (xy 115.957033 -260.105408) (xy 115.919374 -260.067306) (xy 115.888088 -260.023818)
			(xy 115.863935 -259.975999) (xy 115.847499 -259.925011) (xy 115.83918 -259.872088) (xy 115.838732 -259.845302)
			(xy 115.839162 -259.820583) (xy 115.846248 -259.771654) (xy 115.860274 -259.724247) (xy 115.88095 -259.679339)
			(xy 115.90785 -259.637859) (xy 115.923822 -259.618988) (xy 115.924076 -259.61848) (xy 115.928602 -259.612974)
			(xy 115.934653 -259.600077) (xy 115.936014 -259.59308) (xy 115.936873 -259.58576) (xy 115.934798 -259.571176)
			(xy 115.93195 -259.564378) (xy 115.894866 -259.482336) (xy 115.88877 -259.46862) (xy 115.863624 -259.452364)
			(xy 113.915698 -259.452364) (xy 113.905948 -259.45279) (xy 113.887858 -259.460068) (xy 113.873819 -259.4736)
			(xy 113.86947 -259.482336) (xy 113.832386 -259.564378) (xy 113.829578 -259.571187) (xy 113.827503 -259.585761)
			(xy 113.828322 -259.59308) (xy 113.829706 -259.600067) (xy 113.835767 -259.612952) (xy 113.84026 -259.61848)
			(xy 113.840514 -259.618988) (xy 113.856483 -259.637863) (xy 113.883397 -259.679336) (xy 113.904082 -259.724242)
			(xy 113.918109 -259.771651) (xy 113.925188 -259.820582) (xy 113.925604 -259.845302) (xy 113.925124 -259.871001)
			(xy 113.917463 -259.921825) (xy 113.902314 -259.970939) (xy 113.880013 -260.017247) (xy 113.85106 -260.059714)
			(xy 113.8161 -260.097391) (xy 113.775916 -260.129437) (xy 113.731404 -260.155136) (xy 113.683559 -260.173913)
			(xy 113.63345 -260.185351) (xy 113.582196 -260.189192) (xy 113.530942 -260.185351) (xy 113.480833 -260.173913)
			(xy 113.432988 -260.155136) (xy 113.388476 -260.129437) (xy 113.348292 -260.097391) (xy 113.313332 -260.059714)
			(xy 113.284379 -260.017247) (xy 113.262078 -259.970939) (xy 113.246929 -259.921825) (xy 113.239268 -259.871001)
			(xy 113.238788 -259.845302) (xy 113.239217 -259.820582) (xy 113.246303 -259.771653) (xy 113.260327 -259.724245)
			(xy 113.281002 -259.679336) (xy 113.307899 -259.637853) (xy 113.323878 -259.618988) (xy 113.324132 -259.61848)
			(xy 113.328661 -259.612976) (xy 113.334718 -259.600079) (xy 113.33607 -259.59308) (xy 113.336929 -259.58576)
			(xy 113.334852 -259.571177) (xy 113.332006 -259.564378) (xy 113.294922 -259.482336) (xy 113.288826 -259.46862)
			(xy 113.26368 -259.452364) (xy 113.029746 -259.452364) (xy 113.019682 -259.452799) (xy 113.001097 -259.460534)
			(xy 112.993678 -259.46735) (xy 112.990884 -259.470144) (xy 112.981994 -259.473954) (xy 112.977366 -259.475727)
			(xy 112.967645 -259.477646) (xy 112.96269 -259.477764) (xy 112.962436 -259.477764) (xy 111.886238 -259.477764)
			(xy 111.876398 -259.477231) (xy 111.858229 -259.469654) (xy 111.850932 -259.463032) (xy 111.502698 -259.114798)
			(xy 111.47298 -259.108956) (xy 111.458756 -259.114544) (xy 111.428776 -259.125665) (xy 111.366006 -259.137816)
			(xy 111.334042 -259.138674) (xy 111.327946 -259.138674) (xy 111.301401 -259.137842) (xy 111.249035 -259.129001)
			(xy 111.198655 -259.112205) (xy 111.15146 -259.087852) (xy 111.108578 -259.056524) (xy 111.07103 -259.018968)
			(xy 111.039711 -258.976079) (xy 111.015368 -258.92888) (xy 110.998581 -258.878496) (xy 110.989752 -258.826128)
			(xy 110.988856 -258.799584) (xy 110.988856 -258.795012) (xy 110.989623 -258.762666) (xy 111.00177 -258.699123)
			(xy 111.012986 -258.668774) (xy 111.018574 -258.65455) (xy 111.012732 -258.624832) (xy 110.96625 -258.57835)
			(xy 110.959138 -258.570984) (xy 110.940342 -258.563364) (xy 109.255814 -258.563364) (xy 109.243834 -258.564008)
			(xy 109.222486 -258.574881) (xy 109.21492 -258.584192) (xy 109.160564 -258.658106) (xy 109.1565 -258.681982)
			(xy 109.160056 -258.693412) (xy 109.167304 -258.718249) (xy 109.17509 -258.769397) (xy 109.17555 -258.795266)
			(xy 109.17555 -258.798314) (xy 109.174812 -258.824887) (xy 109.166146 -258.877332) (xy 109.149504 -258.927817)
			(xy 109.125283 -258.975135) (xy 109.094061 -259.018156) (xy 109.056583 -259.055853) (xy 109.013745 -259.087326)
			(xy 108.96657 -259.111824) (xy 108.916183 -259.128761) (xy 108.863789 -259.137732) (xy 108.837222 -259.138674)
			(xy 108.831888 -259.138674) (xy 108.806119 -259.13819) (xy 108.755166 -259.130445) (xy 108.705941 -259.115177)
			(xy 108.682536 -259.104384) (xy 108.682282 -259.104384) (xy 108.674431 -259.100963) (xy 108.657427 -259.099001)
			(xy 108.640718 -259.102713) (xy 108.63326 -259.106924) (xy 108.56214 -259.151374) (xy 108.555003 -259.156212)
			(xy 108.544235 -259.169664) (xy 108.53857 -259.185937) (xy 108.538264 -259.194554) (xy 108.538264 -259.446014)
			(xy 108.538612 -259.454618) (xy 108.544315 -259.470855) (xy 108.555047 -259.484309) (xy 108.56214 -259.489194)
			(xy 108.63326 -259.533644) (xy 108.6407 -259.537917) (xy 108.657426 -259.541691) (xy 108.674455 -259.539694)
			(xy 108.682282 -259.536184) (xy 108.682536 -259.536184) (xy 108.705972 -259.525355) (xy 108.755284 -259.510071)
			(xy 108.806329 -259.502345) (xy 108.832142 -259.501894) (xy 108.840016 -259.501894) (xy 108.866594 -259.502999)
			(xy 108.918949 -259.512398) (xy 108.969228 -259.52976) (xy 109.016227 -259.554669) (xy 109.058822 -259.586529)
			(xy 109.095993 -259.624579) (xy 109.12685 -259.667906) (xy 109.150655 -259.715474) (xy 109.166838 -259.766145)
			(xy 109.175011 -259.818706) (xy 109.17555 -259.845302) (xy 110.988351 -259.845302) (xy 110.992381 -259.792804)
			(xy 111.004378 -259.741536) (xy 111.024061 -259.692701) (xy 111.050967 -259.647442) (xy 111.084467 -259.606821)
			(xy 111.123775 -259.57179) (xy 111.16797 -259.54317) (xy 111.216015 -259.521631) (xy 111.266786 -259.507679)
			(xy 111.319091 -259.501641) (xy 111.371705 -259.503658) (xy 111.423395 -259.513682) (xy 111.472948 -259.53148)
			(xy 111.519204 -259.556633) (xy 111.561078 -259.588552) (xy 111.59759 -259.62649) (xy 111.627882 -259.669556)
			(xy 111.651245 -259.716741) (xy 111.667131 -259.76694) (xy 111.675168 -259.818976) (xy 111.675672 -259.845302)
			(xy 111.675168 -259.871628) (xy 111.667131 -259.923664) (xy 111.651245 -259.973863) (xy 111.627882 -260.021048)
			(xy 111.59759 -260.064114) (xy 111.561078 -260.102052) (xy 111.519204 -260.133971) (xy 111.472948 -260.159124)
			(xy 111.423395 -260.176922) (xy 111.371705 -260.186946) (xy 111.319091 -260.188963) (xy 111.266786 -260.182925)
			(xy 111.216015 -260.168973) (xy 111.16797 -260.147434) (xy 111.123775 -260.118814) (xy 111.084467 -260.083783)
			(xy 111.050967 -260.043162) (xy 111.024061 -259.997903) (xy 111.004378 -259.949068) (xy 110.992381 -259.8978)
			(xy 110.988351 -259.845302) (xy 109.17555 -259.845302) (xy 109.175041 -259.872035) (xy 109.166755 -259.924854)
			(xy 109.150385 -259.975751) (xy 109.126326 -260.023497) (xy 109.095158 -260.066938) (xy 109.057635 -260.105025)
			(xy 109.014664 -260.136836) (xy 108.967282 -260.161605) (xy 108.916634 -260.178732) (xy 108.863944 -260.187804)
			(xy 108.837222 -260.18871) (xy 108.831888 -260.18871) (xy 108.806119 -260.188226) (xy 108.755165 -260.180482)
			(xy 108.70594 -260.165216) (xy 108.682536 -260.15442) (xy 108.682282 -260.15442) (xy 108.67443 -260.151002)
			(xy 108.657427 -260.149043) (xy 108.640718 -260.15275) (xy 108.63326 -260.15696) (xy 108.56214 -260.20141)
			(xy 108.555007 -260.20625) (xy 108.544249 -260.219703) (xy 108.538595 -260.235975) (xy 108.538264 -260.24459)
			(xy 108.538264 -260.881368) (xy 108.538264 -260.88467) (xy 108.538898 -260.891002) (xy 108.542869 -260.903087)
			(xy 108.546138 -260.908546) (xy 108.551726 -260.915912) (xy 108.603288 -260.972046) (xy 108.619798 -260.980174)
			(xy 108.62945 -260.98119) (xy 108.654702 -260.983979) (xy 108.704052 -260.996047) (xy 108.751086 -261.015253)
			(xy 108.794777 -261.041178) (xy 108.834173 -261.073255) (xy 108.868414 -261.110786) (xy 108.896753 -261.152952)
			(xy 108.918571 -261.198832) (xy 108.933393 -261.247426) (xy 108.940895 -261.297672) (xy 108.941362 -261.323074)
			(xy 109.204001 -261.323074) (xy 109.208031 -261.270576) (xy 109.220028 -261.219308) (xy 109.239711 -261.170473)
			(xy 109.266617 -261.125214) (xy 109.300117 -261.084593) (xy 109.339425 -261.049562) (xy 109.38362 -261.020942)
			(xy 109.431665 -260.999403) (xy 109.482436 -260.985451) (xy 109.534741 -260.979413) (xy 109.587355 -260.98143)
			(xy 109.639045 -260.991454) (xy 109.688598 -261.009252) (xy 109.734854 -261.034405) (xy 109.776728 -261.066324)
			(xy 109.81324 -261.104262) (xy 109.843532 -261.147328) (xy 109.866895 -261.194513) (xy 109.882781 -261.244712)
			(xy 109.890818 -261.296748) (xy 109.891322 -261.323074) (xy 110.153961 -261.323074) (xy 110.157991 -261.270576)
			(xy 110.169988 -261.219308) (xy 110.189671 -261.170473) (xy 110.216577 -261.125214) (xy 110.250077 -261.084593)
			(xy 110.289385 -261.049562) (xy 110.33358 -261.020942) (xy 110.381625 -260.999403) (xy 110.432396 -260.985451)
			(xy 110.484701 -260.979413) (xy 110.537315 -260.98143) (xy 110.589005 -260.991454) (xy 110.638558 -261.009252)
			(xy 110.684814 -261.034405) (xy 110.726688 -261.066324) (xy 110.7632 -261.104262) (xy 110.793492 -261.147328)
			(xy 110.816855 -261.194513) (xy 110.832741 -261.244712) (xy 110.840778 -261.296748) (xy 110.841282 -261.323074)
			(xy 111.103921 -261.323074) (xy 111.107951 -261.270576) (xy 111.119948 -261.219308) (xy 111.139631 -261.170473)
			(xy 111.166537 -261.125214) (xy 111.200037 -261.084593) (xy 111.239345 -261.049562) (xy 111.28354 -261.020942)
			(xy 111.331585 -260.999403) (xy 111.382356 -260.985451) (xy 111.434661 -260.979413) (xy 111.487275 -260.98143)
			(xy 111.538965 -260.991454) (xy 111.588518 -261.009252) (xy 111.634774 -261.034405) (xy 111.676648 -261.066324)
			(xy 111.71316 -261.104262) (xy 111.743452 -261.147328) (xy 111.766815 -261.194513) (xy 111.782701 -261.244712)
			(xy 111.790738 -261.296748) (xy 111.791242 -261.323074) (xy 112.053881 -261.323074) (xy 112.057911 -261.270576)
			(xy 112.069908 -261.219308) (xy 112.089591 -261.170473) (xy 112.116497 -261.125214) (xy 112.149997 -261.084593)
			(xy 112.189305 -261.049562) (xy 112.2335 -261.020942) (xy 112.281545 -260.999403) (xy 112.332316 -260.985451)
			(xy 112.384621 -260.979413) (xy 112.437235 -260.98143) (xy 112.488925 -260.991454) (xy 112.538478 -261.009252)
			(xy 112.584734 -261.034405) (xy 112.626608 -261.066324) (xy 112.66312 -261.104262) (xy 112.693412 -261.147328)
			(xy 112.716775 -261.194513) (xy 112.732661 -261.244712) (xy 112.740698 -261.296748) (xy 112.741202 -261.323074)
			(xy 113.004095 -261.323074) (xy 113.008125 -261.270576) (xy 113.020122 -261.219308) (xy 113.039805 -261.170473)
			(xy 113.066711 -261.125214) (xy 113.100211 -261.084593) (xy 113.139519 -261.049562) (xy 113.183714 -261.020942)
			(xy 113.231759 -260.999403) (xy 113.28253 -260.985451) (xy 113.334835 -260.979413) (xy 113.387449 -260.98143)
			(xy 113.439139 -260.991454) (xy 113.488692 -261.009252) (xy 113.534948 -261.034405) (xy 113.576822 -261.066324)
			(xy 113.613334 -261.104262) (xy 113.643626 -261.147328) (xy 113.666989 -261.194513) (xy 113.682875 -261.244712)
			(xy 113.690912 -261.296748) (xy 113.691416 -261.323074) (xy 113.954055 -261.323074) (xy 113.958085 -261.270576)
			(xy 113.970082 -261.219308) (xy 113.989765 -261.170473) (xy 114.016671 -261.125214) (xy 114.050171 -261.084593)
			(xy 114.089479 -261.049562) (xy 114.133674 -261.020942) (xy 114.181719 -260.999403) (xy 114.23249 -260.985451)
			(xy 114.284795 -260.979413) (xy 114.337409 -260.98143) (xy 114.389099 -260.991454) (xy 114.438652 -261.009252)
			(xy 114.484908 -261.034405) (xy 114.526782 -261.066324) (xy 114.563294 -261.104262) (xy 114.593586 -261.147328)
			(xy 114.616949 -261.194513) (xy 114.632835 -261.244712) (xy 114.640872 -261.296748) (xy 114.641376 -261.323074)
			(xy 114.904015 -261.323074) (xy 114.908045 -261.270576) (xy 114.920042 -261.219308) (xy 114.939725 -261.170473)
			(xy 114.966631 -261.125214) (xy 115.000131 -261.084593) (xy 115.039439 -261.049562) (xy 115.083634 -261.020942)
			(xy 115.131679 -260.999403) (xy 115.18245 -260.985451) (xy 115.234755 -260.979413) (xy 115.287369 -260.98143)
			(xy 115.339059 -260.991454) (xy 115.388612 -261.009252) (xy 115.434868 -261.034405) (xy 115.476742 -261.066324)
			(xy 115.513254 -261.104262) (xy 115.543546 -261.147328) (xy 115.566909 -261.194513) (xy 115.582795 -261.244712)
			(xy 115.590832 -261.296748) (xy 115.591336 -261.323074) (xy 115.590832 -261.3494) (xy 115.582795 -261.401436)
			(xy 115.566909 -261.451635) (xy 115.543546 -261.49882) (xy 115.513254 -261.541886) (xy 115.476742 -261.579824)
			(xy 115.434868 -261.611743) (xy 115.388612 -261.636896) (xy 115.339059 -261.654694) (xy 115.287369 -261.664718)
			(xy 115.234755 -261.666735) (xy 115.18245 -261.660697) (xy 115.131679 -261.646745) (xy 115.083634 -261.625206)
			(xy 115.039439 -261.596586) (xy 115.000131 -261.561555) (xy 114.966631 -261.520934) (xy 114.939725 -261.475675)
			(xy 114.920042 -261.42684) (xy 114.908045 -261.375572) (xy 114.904015 -261.323074) (xy 114.641376 -261.323074)
			(xy 114.640872 -261.3494) (xy 114.632835 -261.401436) (xy 114.616949 -261.451635) (xy 114.593586 -261.49882)
			(xy 114.563294 -261.541886) (xy 114.526782 -261.579824) (xy 114.484908 -261.611743) (xy 114.438652 -261.636896)
			(xy 114.389099 -261.654694) (xy 114.337409 -261.664718) (xy 114.284795 -261.666735) (xy 114.23249 -261.660697)
			(xy 114.181719 -261.646745) (xy 114.133674 -261.625206) (xy 114.089479 -261.596586) (xy 114.050171 -261.561555)
			(xy 114.016671 -261.520934) (xy 113.989765 -261.475675) (xy 113.970082 -261.42684) (xy 113.958085 -261.375572)
			(xy 113.954055 -261.323074) (xy 113.691416 -261.323074) (xy 113.690912 -261.3494) (xy 113.682875 -261.401436)
			(xy 113.666989 -261.451635) (xy 113.643626 -261.49882) (xy 113.613334 -261.541886) (xy 113.576822 -261.579824)
			(xy 113.534948 -261.611743) (xy 113.488692 -261.636896) (xy 113.439139 -261.654694) (xy 113.387449 -261.664718)
			(xy 113.334835 -261.666735) (xy 113.28253 -261.660697) (xy 113.231759 -261.646745) (xy 113.183714 -261.625206)
			(xy 113.139519 -261.596586) (xy 113.100211 -261.561555) (xy 113.066711 -261.520934) (xy 113.039805 -261.475675)
			(xy 113.020122 -261.42684) (xy 113.008125 -261.375572) (xy 113.004095 -261.323074) (xy 112.741202 -261.323074)
			(xy 112.740698 -261.3494) (xy 112.732661 -261.401436) (xy 112.716775 -261.451635) (xy 112.693412 -261.49882)
			(xy 112.66312 -261.541886) (xy 112.626608 -261.579824) (xy 112.584734 -261.611743) (xy 112.538478 -261.636896)
			(xy 112.488925 -261.654694) (xy 112.437235 -261.664718) (xy 112.384621 -261.666735) (xy 112.332316 -261.660697)
			(xy 112.281545 -261.646745) (xy 112.2335 -261.625206) (xy 112.189305 -261.596586) (xy 112.149997 -261.561555)
			(xy 112.116497 -261.520934) (xy 112.089591 -261.475675) (xy 112.069908 -261.42684) (xy 112.057911 -261.375572)
			(xy 112.053881 -261.323074) (xy 111.791242 -261.323074) (xy 111.790738 -261.3494) (xy 111.782701 -261.401436)
			(xy 111.766815 -261.451635) (xy 111.743452 -261.49882) (xy 111.71316 -261.541886) (xy 111.676648 -261.579824)
			(xy 111.634774 -261.611743) (xy 111.588518 -261.636896) (xy 111.538965 -261.654694) (xy 111.487275 -261.664718)
			(xy 111.434661 -261.666735) (xy 111.382356 -261.660697) (xy 111.331585 -261.646745) (xy 111.28354 -261.625206)
			(xy 111.239345 -261.596586) (xy 111.200037 -261.561555) (xy 111.166537 -261.520934) (xy 111.139631 -261.475675)
			(xy 111.119948 -261.42684) (xy 111.107951 -261.375572) (xy 111.103921 -261.323074) (xy 110.841282 -261.323074)
			(xy 110.840778 -261.3494) (xy 110.832741 -261.401436) (xy 110.816855 -261.451635) (xy 110.793492 -261.49882)
			(xy 110.7632 -261.541886) (xy 110.726688 -261.579824) (xy 110.684814 -261.611743) (xy 110.638558 -261.636896)
			(xy 110.589005 -261.654694) (xy 110.537315 -261.664718) (xy 110.484701 -261.666735) (xy 110.432396 -261.660697)
			(xy 110.381625 -261.646745) (xy 110.33358 -261.625206) (xy 110.289385 -261.596586) (xy 110.250077 -261.561555)
			(xy 110.216577 -261.520934) (xy 110.189671 -261.475675) (xy 110.169988 -261.42684) (xy 110.157991 -261.375572)
			(xy 110.153961 -261.323074) (xy 109.891322 -261.323074) (xy 109.890818 -261.3494) (xy 109.882781 -261.401436)
			(xy 109.866895 -261.451635) (xy 109.843532 -261.49882) (xy 109.81324 -261.541886) (xy 109.776728 -261.579824)
			(xy 109.734854 -261.611743) (xy 109.688598 -261.636896) (xy 109.639045 -261.654694) (xy 109.587355 -261.664718)
			(xy 109.534741 -261.666735) (xy 109.482436 -261.660697) (xy 109.431665 -261.646745) (xy 109.38362 -261.625206)
			(xy 109.339425 -261.596586) (xy 109.300117 -261.561555) (xy 109.266617 -261.520934) (xy 109.239711 -261.475675)
			(xy 109.220028 -261.42684) (xy 109.208031 -261.375572) (xy 109.204001 -261.323074) (xy 108.941362 -261.323074)
			(xy 108.940862 -261.350061) (xy 108.932422 -261.403372) (xy 108.915744 -261.454705) (xy 108.891241 -261.502797)
			(xy 108.859515 -261.546463) (xy 108.821348 -261.584628) (xy 108.77768 -261.616351) (xy 108.729587 -261.640852)
			(xy 108.678252 -261.657526) (xy 108.624941 -261.665964) (xy 108.597954 -261.666482) (xy 108.579329 -261.666271)
			(xy 108.54229 -261.662329) (xy 108.52404 -261.658608) (xy 108.51134 -261.655814) (xy 108.486448 -261.66318)
			(xy 108.349796 -261.799832) (xy 108.342557 -261.806544) (xy 108.324353 -261.814138) (xy 108.31449 -261.814564)
			(xy 106.178858 -261.814564) (xy 106.169018 -261.815094) (xy 106.150846 -261.82267) (xy 106.143552 -261.829296)
			(xy 105.840784 -262.132064) (xy 105.833164 -262.151876) (xy 105.833672 -262.162798) (xy 105.83418 -262.180324)
			(xy 105.833676 -262.207309) (xy 105.82523 -262.260615) (xy 105.808548 -262.311943) (xy 105.784042 -262.360029)
			(xy 105.752316 -262.40369) (xy 105.71415 -262.44185) (xy 105.670485 -262.47357) (xy 105.622395 -262.498068)
			(xy 105.571064 -262.514742) (xy 105.517757 -262.52318) (xy 105.490772 -262.523732) (xy 105.463995 -262.523217)
			(xy 105.41109 -262.514899) (xy 105.360117 -262.498471) (xy 105.312312 -262.474328) (xy 105.268835 -262.443058)
			(xy 105.230738 -262.405418) (xy 105.198946 -262.362321) (xy 105.174229 -262.314811) (xy 105.157186 -262.26404)
			(xy 105.15219 -262.237728) (xy 105.149142 -262.21944) (xy 105.120948 -262.195564) (xy 104.781858 -262.195564)
			(xy 104.772018 -262.196094) (xy 104.753846 -262.20367) (xy 104.746552 -262.210296) (xy 104.381046 -262.575802)
			(xy 104.375927 -262.581262) (xy 104.368838 -262.594435) (xy 104.367076 -262.60171) (xy 104.365552 -262.60933)
			(xy 104.367076 -262.624316) (xy 104.36987 -262.631428) (xy 104.380535 -262.658872) (xy 104.392311 -262.716554)
			(xy 104.393238 -262.745982) (xy 104.393238 -262.751062) (xy 104.392575 -262.774773) (xy 104.384817 -262.821565)
			(xy 104.369917 -262.866595) (xy 104.348233 -262.90878) (xy 104.320288 -262.947105) (xy 104.286752 -262.980647)
			(xy 104.248433 -263.008601) (xy 104.206253 -263.030293) (xy 104.161226 -263.045202) (xy 104.114435 -263.052969)
			(xy 104.090724 -263.053576) (xy 104.087676 -263.053576) (xy 104.057734 -263.052801) (xy 103.999015 -263.041037)
			(xy 103.97109 -263.030208) (xy 103.963966 -263.027586) (xy 103.948859 -263.026161) (xy 103.941372 -263.027414)
			(xy 103.934096 -263.029168) (xy 103.920927 -263.036268) (xy 103.915464 -263.041384) (xy 103.110284 -263.846564)
			(xy 111.234223 -263.846564) (xy 111.238253 -263.794066) (xy 111.25025 -263.742798) (xy 111.269933 -263.693963)
			(xy 111.296839 -263.648704) (xy 111.330339 -263.608083) (xy 111.369647 -263.573052) (xy 111.413842 -263.544432)
			(xy 111.461887 -263.522893) (xy 111.512658 -263.508941) (xy 111.564963 -263.502903) (xy 111.617577 -263.50492)
			(xy 111.669267 -263.514944) (xy 111.71882 -263.532742) (xy 111.762036 -263.556242) (xy 121.168934 -263.556242)
			(xy 121.172894 -263.507188) (xy 121.184671 -263.459404) (xy 121.203962 -263.414128) (xy 121.230265 -263.372532)
			(xy 121.2629 -263.335695) (xy 121.301021 -263.30457) (xy 121.343642 -263.279963) (xy 121.389658 -263.262511)
			(xy 121.437877 -263.252667) (xy 121.487052 -263.250686) (xy 121.535907 -263.256618) (xy 121.583178 -263.27031)
			(xy 121.62764 -263.291408) (xy 121.668143 -263.319364) (xy 121.703636 -263.353456) (xy 121.733201 -263.3928)
			(xy 121.756072 -263.436377) (xy 121.771656 -263.483058) (xy 121.779551 -263.531635) (xy 121.780046 -263.556242)
			(xy 123.049042 -263.556242) (xy 123.053002 -263.507188) (xy 123.064779 -263.459404) (xy 123.08407 -263.414128)
			(xy 123.110373 -263.372532) (xy 123.143008 -263.335695) (xy 123.181129 -263.30457) (xy 123.22375 -263.279963)
			(xy 123.269766 -263.262511) (xy 123.317985 -263.252667) (xy 123.36716 -263.250686) (xy 123.416015 -263.256618)
			(xy 123.463286 -263.27031) (xy 123.507748 -263.291408) (xy 123.548251 -263.319364) (xy 123.583744 -263.353456)
			(xy 123.613309 -263.3928) (xy 123.63618 -263.436377) (xy 123.651764 -263.483058) (xy 123.659659 -263.531635)
			(xy 123.660154 -263.556242) (xy 123.659659 -263.580849) (xy 123.651764 -263.629426) (xy 123.63618 -263.676107)
			(xy 123.613309 -263.719684) (xy 123.583744 -263.759028) (xy 123.548251 -263.79312) (xy 123.507748 -263.821076)
			(xy 123.463286 -263.842174) (xy 123.416015 -263.855866) (xy 123.36716 -263.861798) (xy 123.317985 -263.859817)
			(xy 123.269766 -263.849973) (xy 123.22375 -263.832521) (xy 123.181129 -263.807914) (xy 123.143008 -263.776789)
			(xy 123.110373 -263.739952) (xy 123.08407 -263.698356) (xy 123.064779 -263.65308) (xy 123.053002 -263.605296)
			(xy 123.049042 -263.556242) (xy 121.780046 -263.556242) (xy 121.779551 -263.580849) (xy 121.771656 -263.629426)
			(xy 121.756072 -263.676107) (xy 121.733201 -263.719684) (xy 121.703636 -263.759028) (xy 121.668143 -263.79312)
			(xy 121.62764 -263.821076) (xy 121.583178 -263.842174) (xy 121.535907 -263.855866) (xy 121.487052 -263.861798)
			(xy 121.437877 -263.859817) (xy 121.389658 -263.849973) (xy 121.343642 -263.832521) (xy 121.301021 -263.807914)
			(xy 121.2629 -263.776789) (xy 121.230265 -263.739952) (xy 121.203962 -263.698356) (xy 121.184671 -263.65308)
			(xy 121.172894 -263.605296) (xy 121.168934 -263.556242) (xy 111.762036 -263.556242) (xy 111.765076 -263.557895)
			(xy 111.80695 -263.589814) (xy 111.843462 -263.627752) (xy 111.873754 -263.670818) (xy 111.897117 -263.718003)
			(xy 111.913003 -263.768202) (xy 111.92104 -263.820238) (xy 111.921544 -263.846564) (xy 111.92104 -263.87289)
			(xy 111.913003 -263.924926) (xy 111.897117 -263.975125) (xy 111.873754 -264.02231) (xy 111.843462 -264.065376)
			(xy 111.80695 -264.103314) (xy 111.765076 -264.135233) (xy 111.71882 -264.160386) (xy 111.669267 -264.178184)
			(xy 111.617577 -264.188208) (xy 111.564963 -264.190225) (xy 111.512658 -264.184187) (xy 111.461887 -264.170235)
			(xy 111.413842 -264.148696) (xy 111.369647 -264.120076) (xy 111.330339 -264.085045) (xy 111.296839 -264.044424)
			(xy 111.269933 -263.999165) (xy 111.25025 -263.95033) (xy 111.238253 -263.899062) (xy 111.234223 -263.846564)
			(xy 103.110284 -263.846564) (xy 102.588568 -264.36828) (xy 103.782126 -264.36828) (xy 103.786086 -264.319226)
			(xy 103.797863 -264.271442) (xy 103.817154 -264.226166) (xy 103.843457 -264.18457) (xy 103.876092 -264.147733)
			(xy 103.914213 -264.116608) (xy 103.956834 -264.092001) (xy 104.00285 -264.074549) (xy 104.051069 -264.064705)
			(xy 104.100244 -264.062724) (xy 104.149099 -264.068656) (xy 104.19637 -264.082348) (xy 104.240832 -264.103446)
			(xy 104.281335 -264.131402) (xy 104.316828 -264.165494) (xy 104.346393 -264.204838) (xy 104.369264 -264.248415)
			(xy 104.384848 -264.295096) (xy 104.392743 -264.343673) (xy 104.393238 -264.36828) (xy 105.662234 -264.36828)
			(xy 105.666194 -264.319226) (xy 105.677971 -264.271442) (xy 105.697262 -264.226166) (xy 105.723565 -264.18457)
			(xy 105.7562 -264.147733) (xy 105.794321 -264.116608) (xy 105.836942 -264.092001) (xy 105.882958 -264.074549)
			(xy 105.931177 -264.064705) (xy 105.980352 -264.062724) (xy 106.029207 -264.068656) (xy 106.076478 -264.082348)
			(xy 106.12094 -264.103446) (xy 106.161443 -264.131402) (xy 106.196936 -264.165494) (xy 106.226501 -264.204838)
			(xy 106.249372 -264.248415) (xy 106.264956 -264.295096) (xy 106.272851 -264.343673) (xy 106.273346 -264.36828)
			(xy 107.542088 -264.36828) (xy 107.546048 -264.319226) (xy 107.557825 -264.271442) (xy 107.577116 -264.226166)
			(xy 107.603419 -264.18457) (xy 107.636054 -264.147733) (xy 107.674175 -264.116608) (xy 107.716796 -264.092001)
			(xy 107.762812 -264.074549) (xy 107.811031 -264.064705) (xy 107.860206 -264.062724) (xy 107.909061 -264.068656)
			(xy 107.956332 -264.082348) (xy 108.000794 -264.103446) (xy 108.041297 -264.131402) (xy 108.07679 -264.165494)
			(xy 108.106355 -264.204838) (xy 108.129226 -264.248415) (xy 108.14481 -264.295096) (xy 108.152705 -264.343673)
			(xy 108.1532 -264.36828) (xy 115.062012 -264.36828) (xy 115.065972 -264.319226) (xy 115.077749 -264.271442)
			(xy 115.09704 -264.226166) (xy 115.123343 -264.18457) (xy 115.155978 -264.147733) (xy 115.194099 -264.116608)
			(xy 115.23672 -264.092001) (xy 115.282736 -264.074549) (xy 115.330955 -264.064705) (xy 115.38013 -264.062724)
			(xy 115.428985 -264.068656) (xy 115.476256 -264.082348) (xy 115.520718 -264.103446) (xy 115.561221 -264.131402)
			(xy 115.596714 -264.165494) (xy 115.626279 -264.204838) (xy 115.64915 -264.248415) (xy 115.664734 -264.295096)
			(xy 115.672629 -264.343673) (xy 115.673124 -264.36828) (xy 116.94212 -264.36828) (xy 116.94608 -264.319226)
			(xy 116.957857 -264.271442) (xy 116.977148 -264.226166) (xy 117.003451 -264.18457) (xy 117.036086 -264.147733)
			(xy 117.074207 -264.116608) (xy 117.116828 -264.092001) (xy 117.162844 -264.074549) (xy 117.211063 -264.064705)
			(xy 117.260238 -264.062724) (xy 117.309093 -264.068656) (xy 117.356364 -264.082348) (xy 117.400826 -264.103446)
			(xy 117.441329 -264.131402) (xy 117.476822 -264.165494) (xy 117.506387 -264.204838) (xy 117.529258 -264.248415)
			(xy 117.544842 -264.295096) (xy 117.552737 -264.343673) (xy 117.553232 -264.36828) (xy 118.821974 -264.36828)
			(xy 118.825934 -264.319226) (xy 118.837711 -264.271442) (xy 118.857002 -264.226166) (xy 118.883305 -264.18457)
			(xy 118.91594 -264.147733) (xy 118.954061 -264.116608) (xy 118.996682 -264.092001) (xy 119.042698 -264.074549)
			(xy 119.090917 -264.064705) (xy 119.140092 -264.062724) (xy 119.188947 -264.068656) (xy 119.236218 -264.082348)
			(xy 119.28068 -264.103446) (xy 119.321183 -264.131402) (xy 119.356676 -264.165494) (xy 119.386241 -264.204838)
			(xy 119.409112 -264.248415) (xy 119.424696 -264.295096) (xy 119.432591 -264.343673) (xy 119.433086 -264.36828)
			(xy 120.699796 -264.36828) (xy 120.703756 -264.319226) (xy 120.715533 -264.271442) (xy 120.734824 -264.226166)
			(xy 120.761127 -264.18457) (xy 120.793762 -264.147733) (xy 120.831883 -264.116608) (xy 120.874504 -264.092001)
			(xy 120.92052 -264.074549) (xy 120.968739 -264.064705) (xy 121.017914 -264.062724) (xy 121.066769 -264.068656)
			(xy 121.11404 -264.082348) (xy 121.158502 -264.103446) (xy 121.199005 -264.131402) (xy 121.234498 -264.165494)
			(xy 121.264063 -264.204838) (xy 121.286934 -264.248415) (xy 121.302518 -264.295096) (xy 121.310413 -264.343673)
			(xy 121.310867 -264.366248) (xy 122.578888 -264.366248) (xy 122.582848 -264.317194) (xy 122.594625 -264.26941)
			(xy 122.613916 -264.224134) (xy 122.640219 -264.182538) (xy 122.672854 -264.145701) (xy 122.710975 -264.114576)
			(xy 122.753596 -264.089969) (xy 122.799612 -264.072517) (xy 122.847831 -264.062673) (xy 122.897006 -264.060692)
			(xy 122.945861 -264.066624) (xy 122.993132 -264.080316) (xy 123.037594 -264.101414) (xy 123.078097 -264.12937)
			(xy 123.11359 -264.163462) (xy 123.143155 -264.202806) (xy 123.166026 -264.246383) (xy 123.18161 -264.293064)
			(xy 123.189505 -264.341641) (xy 123.19 -264.366248) (xy 124.458996 -264.366248) (xy 124.462956 -264.317194)
			(xy 124.474733 -264.26941) (xy 124.494024 -264.224134) (xy 124.520327 -264.182538) (xy 124.552962 -264.145701)
			(xy 124.591083 -264.114576) (xy 124.633704 -264.089969) (xy 124.67972 -264.072517) (xy 124.727939 -264.062673)
			(xy 124.777114 -264.060692) (xy 124.825969 -264.066624) (xy 124.87324 -264.080316) (xy 124.917702 -264.101414)
			(xy 124.958205 -264.12937) (xy 124.993698 -264.163462) (xy 125.023263 -264.202806) (xy 125.046134 -264.246383)
			(xy 125.061718 -264.293064) (xy 125.069613 -264.341641) (xy 125.070108 -264.366248) (xy 126.33885 -264.366248)
			(xy 126.34281 -264.317194) (xy 126.354587 -264.26941) (xy 126.373878 -264.224134) (xy 126.400181 -264.182538)
			(xy 126.432816 -264.145701) (xy 126.470937 -264.114576) (xy 126.513558 -264.089969) (xy 126.559574 -264.072517)
			(xy 126.607793 -264.062673) (xy 126.656968 -264.060692) (xy 126.705823 -264.066624) (xy 126.753094 -264.080316)
			(xy 126.797556 -264.101414) (xy 126.838059 -264.12937) (xy 126.873552 -264.163462) (xy 126.903117 -264.202806)
			(xy 126.925988 -264.246383) (xy 126.941572 -264.293064) (xy 126.949467 -264.341641) (xy 126.949962 -264.366248)
			(xy 128.208527 -264.366248) (xy 128.212622 -264.31552) (xy 128.224801 -264.266106) (xy 128.244749 -264.219286)
			(xy 128.27195 -264.176272) (xy 128.305698 -264.138178) (xy 128.34512 -264.105991) (xy 128.389194 -264.080545)
			(xy 128.43678 -264.062498) (xy 128.486644 -264.052318) (xy 128.537496 -264.050269) (xy 128.588017 -264.056403)
			(xy 128.636901 -264.070563) (xy 128.68288 -264.09238) (xy 128.724764 -264.12129) (xy 128.761468 -264.156545)
			(xy 128.792041 -264.197231) (xy 128.815692 -264.242294) (xy 128.831808 -264.290568) (xy 128.839972 -264.340802)
			(xy 128.840484 -264.366248) (xy 129.148581 -264.366248) (xy 129.152676 -264.31552) (xy 129.164855 -264.266106)
			(xy 129.184803 -264.219286) (xy 129.212004 -264.176272) (xy 129.245752 -264.138178) (xy 129.285174 -264.105991)
			(xy 129.329248 -264.080545) (xy 129.376834 -264.062498) (xy 129.426698 -264.052318) (xy 129.47755 -264.050269)
			(xy 129.528071 -264.056403) (xy 129.576955 -264.070563) (xy 129.622934 -264.09238) (xy 129.664818 -264.12129)
			(xy 129.701522 -264.156545) (xy 129.732095 -264.197231) (xy 129.755746 -264.242294) (xy 129.771862 -264.290568)
			(xy 129.780026 -264.340802) (xy 129.780538 -264.366248) (xy 129.780026 -264.391694) (xy 129.771862 -264.441928)
			(xy 129.755746 -264.490202) (xy 129.732095 -264.535265) (xy 129.701522 -264.575951) (xy 129.664818 -264.611206)
			(xy 129.622934 -264.640116) (xy 129.576955 -264.661933) (xy 129.528071 -264.676093) (xy 129.47755 -264.682227)
			(xy 129.426698 -264.680178) (xy 129.376834 -264.669998) (xy 129.329248 -264.651951) (xy 129.285174 -264.626505)
			(xy 129.245752 -264.594318) (xy 129.212004 -264.556224) (xy 129.184803 -264.51321) (xy 129.164855 -264.46639)
			(xy 129.152676 -264.416976) (xy 129.148581 -264.366248) (xy 128.840484 -264.366248) (xy 128.839972 -264.391694)
			(xy 128.831808 -264.441928) (xy 128.815692 -264.490202) (xy 128.792041 -264.535265) (xy 128.761468 -264.575951)
			(xy 128.724764 -264.611206) (xy 128.68288 -264.640116) (xy 128.636901 -264.661933) (xy 128.588017 -264.676093)
			(xy 128.537496 -264.682227) (xy 128.486644 -264.680178) (xy 128.43678 -264.669998) (xy 128.389194 -264.651951)
			(xy 128.34512 -264.626505) (xy 128.305698 -264.594318) (xy 128.27195 -264.556224) (xy 128.244749 -264.51321)
			(xy 128.224801 -264.46639) (xy 128.212622 -264.416976) (xy 128.208527 -264.366248) (xy 126.949962 -264.366248)
			(xy 126.949467 -264.390855) (xy 126.941572 -264.439432) (xy 126.925988 -264.486113) (xy 126.903117 -264.52969)
			(xy 126.873552 -264.569034) (xy 126.838059 -264.603126) (xy 126.797556 -264.631082) (xy 126.753094 -264.65218)
			(xy 126.705823 -264.665872) (xy 126.656968 -264.671804) (xy 126.607793 -264.669823) (xy 126.559574 -264.659979)
			(xy 126.513558 -264.642527) (xy 126.470937 -264.61792) (xy 126.432816 -264.586795) (xy 126.400181 -264.549958)
			(xy 126.373878 -264.508362) (xy 126.354587 -264.463086) (xy 126.34281 -264.415302) (xy 126.33885 -264.366248)
			(xy 125.070108 -264.366248) (xy 125.069613 -264.390855) (xy 125.061718 -264.439432) (xy 125.046134 -264.486113)
			(xy 125.023263 -264.52969) (xy 124.993698 -264.569034) (xy 124.958205 -264.603126) (xy 124.917702 -264.631082)
			(xy 124.87324 -264.65218) (xy 124.825969 -264.665872) (xy 124.777114 -264.671804) (xy 124.727939 -264.669823)
			(xy 124.67972 -264.659979) (xy 124.633704 -264.642527) (xy 124.591083 -264.61792) (xy 124.552962 -264.586795)
			(xy 124.520327 -264.549958) (xy 124.494024 -264.508362) (xy 124.474733 -264.463086) (xy 124.462956 -264.415302)
			(xy 124.458996 -264.366248) (xy 123.19 -264.366248) (xy 123.189505 -264.390855) (xy 123.18161 -264.439432)
			(xy 123.166026 -264.486113) (xy 123.143155 -264.52969) (xy 123.11359 -264.569034) (xy 123.078097 -264.603126)
			(xy 123.037594 -264.631082) (xy 122.993132 -264.65218) (xy 122.945861 -264.665872) (xy 122.897006 -264.671804)
			(xy 122.847831 -264.669823) (xy 122.799612 -264.659979) (xy 122.753596 -264.642527) (xy 122.710975 -264.61792)
			(xy 122.672854 -264.586795) (xy 122.640219 -264.549958) (xy 122.613916 -264.508362) (xy 122.594625 -264.463086)
			(xy 122.582848 -264.415302) (xy 122.578888 -264.366248) (xy 121.310867 -264.366248) (xy 121.310908 -264.36828)
			(xy 121.310413 -264.392887) (xy 121.302518 -264.441464) (xy 121.286934 -264.488145) (xy 121.264063 -264.531722)
			(xy 121.234498 -264.571066) (xy 121.199005 -264.605158) (xy 121.158502 -264.633114) (xy 121.11404 -264.654212)
			(xy 121.066769 -264.667904) (xy 121.017914 -264.673836) (xy 120.968739 -264.671855) (xy 120.92052 -264.662011)
			(xy 120.874504 -264.644559) (xy 120.831883 -264.619952) (xy 120.793762 -264.588827) (xy 120.761127 -264.55199)
			(xy 120.734824 -264.510394) (xy 120.715533 -264.465118) (xy 120.703756 -264.417334) (xy 120.699796 -264.36828)
			(xy 119.433086 -264.36828) (xy 119.432591 -264.392887) (xy 119.424696 -264.441464) (xy 119.409112 -264.488145)
			(xy 119.386241 -264.531722) (xy 119.356676 -264.571066) (xy 119.321183 -264.605158) (xy 119.28068 -264.633114)
			(xy 119.236218 -264.654212) (xy 119.188947 -264.667904) (xy 119.140092 -264.673836) (xy 119.090917 -264.671855)
			(xy 119.042698 -264.662011) (xy 118.996682 -264.644559) (xy 118.954061 -264.619952) (xy 118.91594 -264.588827)
			(xy 118.883305 -264.55199) (xy 118.857002 -264.510394) (xy 118.837711 -264.465118) (xy 118.825934 -264.417334)
			(xy 118.821974 -264.36828) (xy 117.553232 -264.36828) (xy 117.552737 -264.392887) (xy 117.544842 -264.441464)
			(xy 117.529258 -264.488145) (xy 117.506387 -264.531722) (xy 117.476822 -264.571066) (xy 117.441329 -264.605158)
			(xy 117.400826 -264.633114) (xy 117.356364 -264.654212) (xy 117.309093 -264.667904) (xy 117.260238 -264.673836)
			(xy 117.211063 -264.671855) (xy 117.162844 -264.662011) (xy 117.116828 -264.644559) (xy 117.074207 -264.619952)
			(xy 117.036086 -264.588827) (xy 117.003451 -264.55199) (xy 116.977148 -264.510394) (xy 116.957857 -264.465118)
			(xy 116.94608 -264.417334) (xy 116.94212 -264.36828) (xy 115.673124 -264.36828) (xy 115.672629 -264.392887)
			(xy 115.664734 -264.441464) (xy 115.64915 -264.488145) (xy 115.626279 -264.531722) (xy 115.596714 -264.571066)
			(xy 115.561221 -264.605158) (xy 115.520718 -264.633114) (xy 115.476256 -264.654212) (xy 115.428985 -264.667904)
			(xy 115.38013 -264.673836) (xy 115.330955 -264.671855) (xy 115.282736 -264.662011) (xy 115.23672 -264.644559)
			(xy 115.194099 -264.619952) (xy 115.155978 -264.588827) (xy 115.123343 -264.55199) (xy 115.09704 -264.510394)
			(xy 115.077749 -264.465118) (xy 115.065972 -264.417334) (xy 115.062012 -264.36828) (xy 108.1532 -264.36828)
			(xy 108.152705 -264.392887) (xy 108.14481 -264.441464) (xy 108.129226 -264.488145) (xy 108.106355 -264.531722)
			(xy 108.07679 -264.571066) (xy 108.041297 -264.605158) (xy 108.000794 -264.633114) (xy 107.956332 -264.654212)
			(xy 107.909061 -264.667904) (xy 107.860206 -264.673836) (xy 107.811031 -264.671855) (xy 107.762812 -264.662011)
			(xy 107.716796 -264.644559) (xy 107.674175 -264.619952) (xy 107.636054 -264.588827) (xy 107.603419 -264.55199)
			(xy 107.577116 -264.510394) (xy 107.557825 -264.465118) (xy 107.546048 -264.417334) (xy 107.542088 -264.36828)
			(xy 106.273346 -264.36828) (xy 106.272851 -264.392887) (xy 106.264956 -264.441464) (xy 106.249372 -264.488145)
			(xy 106.226501 -264.531722) (xy 106.196936 -264.571066) (xy 106.161443 -264.605158) (xy 106.12094 -264.633114)
			(xy 106.076478 -264.654212) (xy 106.029207 -264.667904) (xy 105.980352 -264.673836) (xy 105.931177 -264.671855)
			(xy 105.882958 -264.662011) (xy 105.836942 -264.644559) (xy 105.794321 -264.619952) (xy 105.7562 -264.588827)
			(xy 105.723565 -264.55199) (xy 105.697262 -264.510394) (xy 105.677971 -264.465118) (xy 105.666194 -264.417334)
			(xy 105.662234 -264.36828) (xy 104.393238 -264.36828) (xy 104.392743 -264.392887) (xy 104.384848 -264.441464)
			(xy 104.369264 -264.488145) (xy 104.346393 -264.531722) (xy 104.316828 -264.571066) (xy 104.281335 -264.605158)
			(xy 104.240832 -264.633114) (xy 104.19637 -264.654212) (xy 104.149099 -264.667904) (xy 104.100244 -264.673836)
			(xy 104.051069 -264.671855) (xy 104.00285 -264.662011) (xy 103.956834 -264.644559) (xy 103.914213 -264.619952)
			(xy 103.876092 -264.588827) (xy 103.843457 -264.55199) (xy 103.817154 -264.510394) (xy 103.797863 -264.465118)
			(xy 103.786086 -264.417334) (xy 103.782126 -264.36828) (xy 102.588568 -264.36828) (xy 102.512622 -264.444226)
			(xy 102.508602 -264.448512) (xy 102.502446 -264.458518) (xy 102.50043 -264.464038) (xy 102.492518 -264.486062)
			(xy 102.470954 -264.527593) (xy 102.443305 -264.565348) (xy 102.410221 -264.598443) (xy 102.372475 -264.626103)
			(xy 102.330951 -264.647681) (xy 102.308914 -264.655554) (xy 102.303391 -264.657563) (xy 102.293389 -264.663726)
			(xy 102.289102 -264.667746) (xy 102.094284 -264.862564) (xy 111.234223 -264.862564) (xy 111.238253 -264.810066)
			(xy 111.25025 -264.758798) (xy 111.269933 -264.709963) (xy 111.296839 -264.664704) (xy 111.330339 -264.624083)
			(xy 111.369647 -264.589052) (xy 111.413842 -264.560432) (xy 111.461887 -264.538893) (xy 111.512658 -264.524941)
			(xy 111.564963 -264.518903) (xy 111.617577 -264.52092) (xy 111.669267 -264.530944) (xy 111.71882 -264.548742)
			(xy 111.765076 -264.573895) (xy 111.80695 -264.605814) (xy 111.843462 -264.643752) (xy 111.873754 -264.686818)
			(xy 111.897117 -264.734003) (xy 111.913003 -264.784202) (xy 111.92104 -264.836238) (xy 111.921544 -264.862564)
			(xy 111.92104 -264.88889) (xy 111.913003 -264.940926) (xy 111.897117 -264.991125) (xy 111.873754 -265.03831)
			(xy 111.843462 -265.081376) (xy 111.80695 -265.119314) (xy 111.765076 -265.151233) (xy 111.719063 -265.176254)
			(xy 121.168934 -265.176254) (xy 121.172894 -265.1272) (xy 121.184671 -265.079416) (xy 121.203962 -265.03414)
			(xy 121.230265 -264.992544) (xy 121.2629 -264.955707) (xy 121.301021 -264.924582) (xy 121.343642 -264.899975)
			(xy 121.389658 -264.882523) (xy 121.437877 -264.872679) (xy 121.487052 -264.870698) (xy 121.535907 -264.87663)
			(xy 121.583178 -264.890322) (xy 121.62764 -264.91142) (xy 121.668143 -264.939376) (xy 121.703636 -264.973468)
			(xy 121.733201 -265.012812) (xy 121.756072 -265.056389) (xy 121.771656 -265.10307) (xy 121.779551 -265.151647)
			(xy 121.780046 -265.176254) (xy 123.049042 -265.176254) (xy 123.053002 -265.1272) (xy 123.064779 -265.079416)
			(xy 123.08407 -265.03414) (xy 123.110373 -264.992544) (xy 123.143008 -264.955707) (xy 123.181129 -264.924582)
			(xy 123.22375 -264.899975) (xy 123.269766 -264.882523) (xy 123.317985 -264.872679) (xy 123.36716 -264.870698)
			(xy 123.416015 -264.87663) (xy 123.463286 -264.890322) (xy 123.507748 -264.91142) (xy 123.548251 -264.939376)
			(xy 123.583744 -264.973468) (xy 123.613309 -265.012812) (xy 123.63618 -265.056389) (xy 123.651764 -265.10307)
			(xy 123.659659 -265.151647) (xy 123.660154 -265.176254) (xy 124.928896 -265.176254) (xy 124.932856 -265.1272)
			(xy 124.944633 -265.079416) (xy 124.963924 -265.03414) (xy 124.990227 -264.992544) (xy 125.022862 -264.955707)
			(xy 125.060983 -264.924582) (xy 125.103604 -264.899975) (xy 125.14962 -264.882523) (xy 125.197839 -264.872679)
			(xy 125.247014 -264.870698) (xy 125.295869 -264.87663) (xy 125.34314 -264.890322) (xy 125.387602 -264.91142)
			(xy 125.428105 -264.939376) (xy 125.463598 -264.973468) (xy 125.493163 -265.012812) (xy 125.516034 -265.056389)
			(xy 125.531618 -265.10307) (xy 125.539513 -265.151647) (xy 125.540008 -265.176254) (xy 126.809004 -265.176254)
			(xy 126.812964 -265.1272) (xy 126.824741 -265.079416) (xy 126.844032 -265.03414) (xy 126.870335 -264.992544)
			(xy 126.90297 -264.955707) (xy 126.941091 -264.924582) (xy 126.983712 -264.899975) (xy 127.029728 -264.882523)
			(xy 127.077947 -264.872679) (xy 127.127122 -264.870698) (xy 127.175977 -264.87663) (xy 127.223248 -264.890322)
			(xy 127.26771 -264.91142) (xy 127.308213 -264.939376) (xy 127.343706 -264.973468) (xy 127.373271 -265.012812)
			(xy 127.396142 -265.056389) (xy 127.411726 -265.10307) (xy 127.419621 -265.151647) (xy 127.420116 -265.176254)
			(xy 127.738627 -265.176254) (xy 127.742722 -265.125526) (xy 127.754901 -265.076112) (xy 127.774849 -265.029292)
			(xy 127.80205 -264.986278) (xy 127.835798 -264.948184) (xy 127.87522 -264.915997) (xy 127.919294 -264.890551)
			(xy 127.96688 -264.872504) (xy 128.016744 -264.862324) (xy 128.067596 -264.860275) (xy 128.118117 -264.866409)
			(xy 128.167001 -264.880569) (xy 128.21298 -264.902386) (xy 128.254864 -264.931296) (xy 128.291568 -264.966551)
			(xy 128.322141 -265.007237) (xy 128.345792 -265.0523) (xy 128.361908 -265.100574) (xy 128.370072 -265.150808)
			(xy 128.370584 -265.176254) (xy 128.688858 -265.176254) (xy 128.692818 -265.1272) (xy 128.704595 -265.079416)
			(xy 128.723886 -265.03414) (xy 128.750189 -264.992544) (xy 128.782824 -264.955707) (xy 128.820945 -264.924582)
			(xy 128.863566 -264.899975) (xy 128.909582 -264.882523) (xy 128.957801 -264.872679) (xy 129.006976 -264.870698)
			(xy 129.055831 -264.87663) (xy 129.103102 -264.890322) (xy 129.147564 -264.91142) (xy 129.188067 -264.939376)
			(xy 129.22356 -264.973468) (xy 129.253125 -265.012812) (xy 129.275996 -265.056389) (xy 129.29158 -265.10307)
			(xy 129.299475 -265.151647) (xy 129.29997 -265.176254) (xy 129.628912 -265.176254) (xy 129.632872 -265.1272)
			(xy 129.644649 -265.079416) (xy 129.66394 -265.03414) (xy 129.690243 -264.992544) (xy 129.722878 -264.955707)
			(xy 129.760999 -264.924582) (xy 129.80362 -264.899975) (xy 129.849636 -264.882523) (xy 129.897855 -264.872679)
			(xy 129.94703 -264.870698) (xy 129.995885 -264.87663) (xy 130.043156 -264.890322) (xy 130.087618 -264.91142)
			(xy 130.128121 -264.939376) (xy 130.163614 -264.973468) (xy 130.193179 -265.012812) (xy 130.21605 -265.056389)
			(xy 130.231634 -265.10307) (xy 130.239529 -265.151647) (xy 130.240024 -265.176254) (xy 130.239529 -265.200861)
			(xy 130.231634 -265.249438) (xy 130.21605 -265.296119) (xy 130.193179 -265.339696) (xy 130.163614 -265.37904)
			(xy 130.128121 -265.413132) (xy 130.087618 -265.441088) (xy 130.043156 -265.462186) (xy 129.995885 -265.475878)
			(xy 129.94703 -265.48181) (xy 129.897855 -265.479829) (xy 129.849636 -265.469985) (xy 129.80362 -265.452533)
			(xy 129.760999 -265.427926) (xy 129.722878 -265.396801) (xy 129.690243 -265.359964) (xy 129.66394 -265.318368)
			(xy 129.644649 -265.273092) (xy 129.632872 -265.225308) (xy 129.628912 -265.176254) (xy 129.29997 -265.176254)
			(xy 129.299475 -265.200861) (xy 129.29158 -265.249438) (xy 129.275996 -265.296119) (xy 129.253125 -265.339696)
			(xy 129.22356 -265.37904) (xy 129.188067 -265.413132) (xy 129.147564 -265.441088) (xy 129.103102 -265.462186)
			(xy 129.055831 -265.475878) (xy 129.006976 -265.48181) (xy 128.957801 -265.479829) (xy 128.909582 -265.469985)
			(xy 128.863566 -265.452533) (xy 128.820945 -265.427926) (xy 128.782824 -265.396801) (xy 128.750189 -265.359964)
			(xy 128.723886 -265.318368) (xy 128.704595 -265.273092) (xy 128.692818 -265.225308) (xy 128.688858 -265.176254)
			(xy 128.370584 -265.176254) (xy 128.370072 -265.2017) (xy 128.361908 -265.251934) (xy 128.345792 -265.300208)
			(xy 128.322141 -265.345271) (xy 128.291568 -265.385957) (xy 128.254864 -265.421212) (xy 128.21298 -265.450122)
			(xy 128.167001 -265.471939) (xy 128.118117 -265.486099) (xy 128.067596 -265.492233) (xy 128.016744 -265.490184)
			(xy 127.96688 -265.480004) (xy 127.919294 -265.461957) (xy 127.87522 -265.436511) (xy 127.835798 -265.404324)
			(xy 127.80205 -265.36623) (xy 127.774849 -265.323216) (xy 127.754901 -265.276396) (xy 127.742722 -265.226982)
			(xy 127.738627 -265.176254) (xy 127.420116 -265.176254) (xy 127.419621 -265.200861) (xy 127.411726 -265.249438)
			(xy 127.396142 -265.296119) (xy 127.373271 -265.339696) (xy 127.343706 -265.37904) (xy 127.308213 -265.413132)
			(xy 127.26771 -265.441088) (xy 127.223248 -265.462186) (xy 127.175977 -265.475878) (xy 127.127122 -265.48181)
			(xy 127.077947 -265.479829) (xy 127.029728 -265.469985) (xy 126.983712 -265.452533) (xy 126.941091 -265.427926)
			(xy 126.90297 -265.396801) (xy 126.870335 -265.359964) (xy 126.844032 -265.318368) (xy 126.824741 -265.273092)
			(xy 126.812964 -265.225308) (xy 126.809004 -265.176254) (xy 125.540008 -265.176254) (xy 125.539513 -265.200861)
			(xy 125.531618 -265.249438) (xy 125.516034 -265.296119) (xy 125.493163 -265.339696) (xy 125.463598 -265.37904)
			(xy 125.428105 -265.413132) (xy 125.387602 -265.441088) (xy 125.34314 -265.462186) (xy 125.295869 -265.475878)
			(xy 125.247014 -265.48181) (xy 125.197839 -265.479829) (xy 125.14962 -265.469985) (xy 125.103604 -265.452533)
			(xy 125.060983 -265.427926) (xy 125.022862 -265.396801) (xy 124.990227 -265.359964) (xy 124.963924 -265.318368)
			(xy 124.944633 -265.273092) (xy 124.932856 -265.225308) (xy 124.928896 -265.176254) (xy 123.660154 -265.176254)
			(xy 123.659659 -265.200861) (xy 123.651764 -265.249438) (xy 123.63618 -265.296119) (xy 123.613309 -265.339696)
			(xy 123.583744 -265.37904) (xy 123.548251 -265.413132) (xy 123.507748 -265.441088) (xy 123.463286 -265.462186)
			(xy 123.416015 -265.475878) (xy 123.36716 -265.48181) (xy 123.317985 -265.479829) (xy 123.269766 -265.469985)
			(xy 123.22375 -265.452533) (xy 123.181129 -265.427926) (xy 123.143008 -265.396801) (xy 123.110373 -265.359964)
			(xy 123.08407 -265.318368) (xy 123.064779 -265.273092) (xy 123.053002 -265.225308) (xy 123.049042 -265.176254)
			(xy 121.780046 -265.176254) (xy 121.779551 -265.200861) (xy 121.771656 -265.249438) (xy 121.756072 -265.296119)
			(xy 121.733201 -265.339696) (xy 121.703636 -265.37904) (xy 121.668143 -265.413132) (xy 121.62764 -265.441088)
			(xy 121.583178 -265.462186) (xy 121.535907 -265.475878) (xy 121.487052 -265.48181) (xy 121.437877 -265.479829)
			(xy 121.389658 -265.469985) (xy 121.343642 -265.452533) (xy 121.301021 -265.427926) (xy 121.2629 -265.396801)
			(xy 121.230265 -265.359964) (xy 121.203962 -265.318368) (xy 121.184671 -265.273092) (xy 121.172894 -265.225308)
			(xy 121.168934 -265.176254) (xy 111.719063 -265.176254) (xy 111.71882 -265.176386) (xy 111.669267 -265.194184)
			(xy 111.617577 -265.204208) (xy 111.564963 -265.206225) (xy 111.512658 -265.200187) (xy 111.461887 -265.186235)
			(xy 111.413842 -265.164696) (xy 111.369647 -265.136076) (xy 111.330339 -265.101045) (xy 111.296839 -265.060424)
			(xy 111.269933 -265.015165) (xy 111.25025 -264.96633) (xy 111.238253 -264.915062) (xy 111.234223 -264.862564)
			(xy 102.094284 -264.862564) (xy 102.007924 -264.948924) (xy 102.001738 -264.955573) (xy 101.994132 -264.972049)
			(xy 101.99279 -264.990146) (xy 101.99497 -264.998962) (xy 101.999288 -265.013186) (xy 102.00259 -265.018774)
			(xy 102.016308 -265.042727) (xy 102.035802 -265.094361) (xy 102.045705 -265.148658) (xy 102.046278 -265.176254)
			(xy 102.045835 -265.200249) (xy 102.038334 -265.247648) (xy 102.023509 -265.29329) (xy 102.001726 -265.33605)
			(xy 101.97352 -265.374876) (xy 101.939588 -265.40881) (xy 101.900764 -265.437017) (xy 101.858005 -265.458803)
			(xy 101.812364 -265.47363) (xy 101.764965 -265.481134) (xy 101.74097 -265.481562) (xy 101.713377 -265.480962)
			(xy 101.659087 -265.47105) (xy 101.607453 -265.451569) (xy 101.58349 -265.437874) (xy 101.577902 -265.434572)
			(xy 101.56444 -265.430508) (xy 101.555528 -265.428226) (xy 101.537185 -265.429436) (xy 101.520429 -265.437)
			(xy 101.51364 -265.443208) (xy 101.042216 -265.914632) (xy 101.035503 -265.92187) (xy 101.027912 -265.940075)
			(xy 101.027484 -265.949938) (xy 101.027484 -265.98626) (xy 101.90532 -265.98626) (xy 101.90928 -265.937206)
			(xy 101.921057 -265.889422) (xy 101.940348 -265.844146) (xy 101.966651 -265.80255) (xy 101.999286 -265.765713)
			(xy 102.037407 -265.734588) (xy 102.080028 -265.709981) (xy 102.126044 -265.692529) (xy 102.174263 -265.682685)
			(xy 102.223438 -265.680704) (xy 102.272293 -265.686636) (xy 102.319564 -265.700328) (xy 102.364026 -265.721426)
			(xy 102.404529 -265.749382) (xy 102.440022 -265.783474) (xy 102.469587 -265.822818) (xy 102.492458 -265.866395)
			(xy 102.508042 -265.913076) (xy 102.515937 -265.961653) (xy 102.516432 -265.98626) (xy 102.515937 -266.010867)
			(xy 102.508042 -266.059444) (xy 102.492458 -266.106125) (xy 102.469587 -266.149702) (xy 102.440022 -266.189046)
			(xy 102.404529 -266.223138) (xy 102.364026 -266.251094) (xy 102.319564 -266.272192) (xy 102.272293 -266.285884)
			(xy 102.223438 -266.291816) (xy 102.174263 -266.289835) (xy 102.126044 -266.279991) (xy 102.080028 -266.262539)
			(xy 102.037407 -266.237932) (xy 101.999286 -266.206807) (xy 101.966651 -266.16997) (xy 101.940348 -266.128374)
			(xy 101.921057 -266.083098) (xy 101.90928 -266.035314) (xy 101.90532 -265.98626) (xy 101.027484 -265.98626)
			(xy 101.027484 -266.129262) (xy 101.027918 -266.139328) (xy 101.035646 -266.157917) (xy 101.04247 -266.16533)
			(xy 101.440996 -266.563856) (xy 101.448392 -266.570708) (xy 101.466991 -266.578451) (xy 101.477064 -266.578842)
			(xy 101.497638 -266.578842) (xy 101.502112 -266.578767) (xy 101.510925 -266.577227) (xy 101.515164 -266.575794)
			(xy 101.539294 -266.566904) (xy 101.545898 -266.561316) (xy 101.566626 -266.544853) (xy 101.612577 -266.518587)
			(xy 101.662367 -266.500631) (xy 101.714506 -266.491522) (xy 101.74097 -266.490958) (xy 101.764964 -266.491426)
			(xy 101.812361 -266.498929) (xy 101.858001 -266.513753) (xy 101.900761 -266.535534) (xy 101.939586 -266.563737)
			(xy 101.973522 -266.597665) (xy 102.001732 -266.636485) (xy 102.023523 -266.67924) (xy 102.038357 -266.724877)
			(xy 102.045869 -266.772272) (xy 102.046278 -266.796266) (xy 102.045878 -266.81797) (xy 102.039694 -266.860935)
			(xy 102.027488 -266.902591) (xy 102.018846 -266.922504) (xy 102.018846 -266.922758) (xy 102.018592 -266.923012)
			(xy 102.014083 -266.934906) (xy 102.016088 -266.960229) (xy 102.022402 -266.971272) (xy 102.06736 -267.041376)
			(xy 102.072219 -267.048326) (xy 102.085548 -267.058798) (xy 102.101558 -267.064364) (xy 102.110032 -267.064744)
			(xy 103.252016 -267.064744) (xy 103.260504 -267.064436) (xy 103.276545 -267.058885) (xy 103.289871 -267.04837)
			(xy 103.294688 -267.041376) (xy 103.339646 -266.971272) (xy 103.343988 -266.964028) (xy 103.348084 -266.947654)
			(xy 103.346627 -266.930838) (xy 103.343456 -266.923012) (xy 103.343202 -266.922758) (xy 103.343202 -266.922504)
			(xy 103.334554 -266.902593) (xy 103.322342 -266.860937) (xy 103.316155 -266.81797) (xy 103.31577 -266.796266)
			(xy 103.316198 -266.772758) (xy 103.3234 -266.726298) (xy 103.337643 -266.681493) (xy 103.358589 -266.639402)
			(xy 103.385744 -266.601022) (xy 103.418465 -266.567262) (xy 103.455977 -266.53892) (xy 103.497393 -266.516667)
			(xy 103.541731 -266.501031) (xy 103.587943 -266.49238) (xy 103.611426 -266.491212) (xy 103.618284 -266.490958)
			(xy 103.621078 -266.490958) (xy 103.646778 -266.491487) (xy 103.697453 -266.500099) (xy 103.745967 -266.517081)
			(xy 103.790949 -266.541955) (xy 103.831125 -266.574016) (xy 103.848662 -266.592812) (xy 103.848916 -266.592812)
			(xy 103.856224 -266.600243) (xy 103.8751 -266.609033) (xy 103.885492 -266.60983) (xy 103.957374 -266.611862)
			(xy 103.967764 -266.611622) (xy 103.987029 -266.603877) (xy 103.994712 -266.596876) (xy 104.130094 -266.461494)
			(xy 104.136635 -266.454333) (xy 104.144257 -266.436515) (xy 104.144729 -266.417141) (xy 104.141778 -266.4079)
			(xy 104.105202 -266.309602) (xy 104.08158 -266.291822) (xy 104.066848 -266.290552) (xy 104.04165 -266.288054)
			(xy 103.992527 -266.275781) (xy 103.946101 -266.255574) (xy 103.903643 -266.227987) (xy 103.866316 -266.193775)
			(xy 103.835143 -266.153876) (xy 103.810976 -266.109382) (xy 103.794479 -266.061512) (xy 103.786102 -266.011576)
			(xy 103.78567 -265.98626) (xy 103.786192 -265.961005) (xy 103.794505 -265.911183) (xy 103.810906 -265.863409)
			(xy 103.834947 -265.818986) (xy 103.865971 -265.779126) (xy 103.903133 -265.744916) (xy 103.945419 -265.71729)
			(xy 103.991675 -265.697) (xy 104.04064 -265.6846) (xy 104.090978 -265.680429) (xy 104.141316 -265.6846)
			(xy 104.190281 -265.697) (xy 104.236537 -265.71729) (xy 104.278823 -265.744916) (xy 104.315985 -265.779126)
			(xy 104.347009 -265.818986) (xy 104.37105 -265.863409) (xy 104.387451 -265.911183) (xy 104.395764 -265.961005)
			(xy 104.396286 -265.98626) (xy 105.665282 -265.98626) (xy 105.669242 -265.937206) (xy 105.681019 -265.889422)
			(xy 105.70031 -265.844146) (xy 105.726613 -265.80255) (xy 105.759248 -265.765713) (xy 105.797369 -265.734588)
			(xy 105.83999 -265.709981) (xy 105.886006 -265.692529) (xy 105.934225 -265.682685) (xy 105.9834 -265.680704)
			(xy 106.032255 -265.686636) (xy 106.079526 -265.700328) (xy 106.123988 -265.721426) (xy 106.164491 -265.749382)
			(xy 106.199984 -265.783474) (xy 106.229549 -265.822818) (xy 106.25242 -265.866395) (xy 106.268004 -265.913076)
			(xy 106.275899 -265.961653) (xy 106.276394 -265.98626) (xy 106.275899 -266.010867) (xy 106.268004 -266.059444)
			(xy 106.25242 -266.106125) (xy 106.229549 -266.149702) (xy 106.199984 -266.189046) (xy 106.164491 -266.223138)
			(xy 106.123988 -266.251094) (xy 106.079526 -266.272192) (xy 106.032255 -266.285884) (xy 105.9834 -266.291816)
			(xy 105.934225 -266.289835) (xy 105.886006 -266.279991) (xy 105.83999 -266.262539) (xy 105.797369 -266.237932)
			(xy 105.759248 -266.206807) (xy 105.726613 -266.16997) (xy 105.70031 -266.128374) (xy 105.681019 -266.083098)
			(xy 105.669242 -266.035314) (xy 105.665282 -265.98626) (xy 104.396286 -265.98626) (xy 104.395895 -266.007103)
			(xy 104.39016 -266.048395) (xy 104.384856 -266.068556) (xy 104.381808 -266.08024) (xy 104.386126 -266.103354)
			(xy 104.44099 -266.175998) (xy 104.448584 -266.184982) (xy 104.469629 -266.19543) (xy 104.481376 -266.196064)
			(xy 105.43413 -266.196064) (xy 105.443971 -266.196592) (xy 105.462146 -266.204165) (xy 105.469436 -266.210796)
			(xy 106.267758 -267.009118) (xy 106.275156 -267.015964) (xy 106.293755 -267.02369) (xy 106.303826 -267.024104)
			(xy 106.995976 -267.024104) (xy 107.008043 -267.023429) (xy 107.029518 -267.012416) (xy 107.037124 -267.003022)
			(xy 107.09148 -266.927584) (xy 107.095036 -266.903962) (xy 107.091226 -266.892024) (xy 107.084017 -266.868743)
			(xy 107.076237 -266.820633) (xy 107.075732 -266.796266) (xy 107.075732 -266.793218) (xy 107.076431 -266.769386)
			(xy 107.084317 -266.722368) (xy 107.099417 -266.677148) (xy 107.121362 -266.634824) (xy 107.14962 -266.596426)
			(xy 107.183503 -266.562888) (xy 107.222188 -266.535024) (xy 107.264734 -266.513513) (xy 107.310106 -266.498877)
			(xy 107.357202 -266.491472) (xy 107.38104 -266.490958) (xy 107.407516 -266.491527) (xy 107.459672 -266.500667)
			(xy 107.50947 -266.518668) (xy 107.555417 -266.544988) (xy 107.596135 -266.578839) (xy 107.613704 -266.598654)
			(xy 107.620816 -266.607036) (xy 107.639612 -266.61618) (xy 107.723432 -266.619482) (xy 107.733933 -266.619393)
			(xy 107.753482 -266.611785) (xy 107.761278 -266.60475) (xy 107.903518 -266.46251) (xy 107.910141 -266.455234)
			(xy 107.917793 -266.437127) (xy 107.918104 -266.417471) (xy 107.914948 -266.408154) (xy 107.876594 -266.309348)
			(xy 107.852464 -266.292076) (xy 107.837224 -266.291314) (xy 107.811376 -266.289607) (xy 107.760764 -266.278585)
			(xy 107.712739 -266.259179) (xy 107.668678 -266.231944) (xy 107.629847 -266.197664) (xy 107.597359 -266.15732)
			(xy 107.572147 -266.112072) (xy 107.554934 -266.063218) (xy 107.546214 -266.012159) (xy 107.545632 -265.98626)
			(xy 107.546106 -265.962272) (xy 107.553617 -265.914887) (xy 107.568448 -265.869261) (xy 107.590235 -265.826517)
			(xy 107.618439 -265.787707) (xy 107.652368 -265.753787) (xy 107.691185 -265.725593) (xy 107.733935 -265.703818)
			(xy 107.779565 -265.688998) (xy 107.826952 -265.681499) (xy 107.85094 -265.680952) (xy 107.874829 -265.681418)
			(xy 107.922023 -265.688865) (xy 107.967481 -265.703572) (xy 108.010093 -265.72518) (xy 108.04882 -265.753162)
			(xy 108.082716 -265.786833) (xy 108.110954 -265.825373) (xy 108.132845 -265.867841) (xy 108.147855 -265.9132)
			(xy 108.155616 -265.960343) (xy 108.156248 -265.984228) (xy 108.156248 -265.98499) (xy 108.156228 -265.98626)
			(xy 109.425244 -265.98626) (xy 109.429204 -265.937206) (xy 109.440981 -265.889422) (xy 109.460272 -265.844146)
			(xy 109.486575 -265.80255) (xy 109.51921 -265.765713) (xy 109.557331 -265.734588) (xy 109.599952 -265.709981)
			(xy 109.645968 -265.692529) (xy 109.694187 -265.682685) (xy 109.743362 -265.680704) (xy 109.792217 -265.686636)
			(xy 109.839488 -265.700328) (xy 109.88395 -265.721426) (xy 109.924453 -265.749382) (xy 109.959946 -265.783474)
			(xy 109.989511 -265.822818) (xy 110.012382 -265.866395) (xy 110.027966 -265.913076) (xy 110.035861 -265.961653)
			(xy 110.036356 -265.98626) (xy 113.178856 -265.98626) (xy 113.182816 -265.937206) (xy 113.194593 -265.889422)
			(xy 113.213884 -265.844146) (xy 113.240187 -265.80255) (xy 113.272822 -265.765713) (xy 113.310943 -265.734588)
			(xy 113.353564 -265.709981) (xy 113.39958 -265.692529) (xy 113.447799 -265.682685) (xy 113.496974 -265.680704)
			(xy 113.545829 -265.686636) (xy 113.5931 -265.700328) (xy 113.637562 -265.721426) (xy 113.678065 -265.749382)
			(xy 113.713558 -265.783474) (xy 113.743123 -265.822818) (xy 113.765994 -265.866395) (xy 113.781578 -265.913076)
			(xy 113.789473 -265.961653) (xy 113.789968 -265.98626) (xy 113.789473 -266.010867) (xy 113.781578 -266.059444)
			(xy 113.765994 -266.106125) (xy 113.743123 -266.149702) (xy 113.713558 -266.189046) (xy 113.678065 -266.223138)
			(xy 113.637562 -266.251094) (xy 113.5931 -266.272192) (xy 113.545829 -266.285884) (xy 113.496974 -266.291816)
			(xy 113.447799 -266.289835) (xy 113.39958 -266.279991) (xy 113.353564 -266.262539) (xy 113.310943 -266.237932)
			(xy 113.272822 -266.206807) (xy 113.240187 -266.16997) (xy 113.213884 -266.128374) (xy 113.194593 -266.083098)
			(xy 113.182816 -266.035314) (xy 113.178856 -265.98626) (xy 110.036356 -265.98626) (xy 110.035861 -266.010867)
			(xy 110.027966 -266.059444) (xy 110.012382 -266.106125) (xy 109.989511 -266.149702) (xy 109.959946 -266.189046)
			(xy 109.924453 -266.223138) (xy 109.88395 -266.251094) (xy 109.839488 -266.272192) (xy 109.792217 -266.285884)
			(xy 109.743362 -266.291816) (xy 109.694187 -266.289835) (xy 109.645968 -266.279991) (xy 109.599952 -266.262539)
			(xy 109.557331 -266.237932) (xy 109.51921 -266.206807) (xy 109.486575 -266.16997) (xy 109.460272 -266.128374)
			(xy 109.440981 -266.083098) (xy 109.429204 -266.035314) (xy 109.425244 -265.98626) (xy 108.156228 -265.98626)
			(xy 108.155877 -266.008672) (xy 108.14873 -266.055492) (xy 108.142024 -266.078208) (xy 108.138468 -266.089892)
			(xy 108.142278 -266.113514) (xy 108.196634 -266.187936) (xy 108.204241 -266.197192) (xy 108.225568 -266.208039)
			(xy 108.237528 -266.208764) (xy 109.18317 -266.208764) (xy 109.193008 -266.209299) (xy 109.211173 -266.216882)
			(xy 109.218476 -266.223496) (xy 110.032038 -267.037058) (xy 110.039437 -267.043903) (xy 110.058035 -267.05163)
			(xy 110.068106 -267.052044) (xy 110.687358 -267.052044) (xy 110.697422 -267.051609) (xy 110.716006 -267.043873)
			(xy 110.723426 -267.037058) (xy 111.335058 -266.425426) (xy 111.342459 -266.418586) (xy 111.361057 -266.410869)
			(xy 111.371126 -266.41044) (xy 112.618774 -266.41044) (xy 112.628837 -266.410878) (xy 112.647418 -266.418616)
			(xy 112.654842 -266.425426) (xy 113.266474 -267.037058) (xy 113.273874 -267.043897) (xy 113.292473 -267.051612)
			(xy 113.302542 -267.052044) (xy 113.57991 -267.052044) (xy 113.592412 -267.05139) (xy 113.614495 -267.039659)
			(xy 113.622074 -267.029692) (xy 113.67516 -266.950444) (xy 113.6777 -266.925044) (xy 113.672874 -266.91336)
			(xy 113.66219 -266.885855) (xy 113.650414 -266.828044) (xy 113.649506 -266.798552) (xy 113.649506 -266.793472)
			(xy 113.650186 -266.769627) (xy 113.658041 -266.722576) (xy 113.673118 -266.67732) (xy 113.69505 -266.63496)
			(xy 113.723303 -266.596526) (xy 113.757189 -266.562953) (xy 113.795885 -266.535059) (xy 113.838448 -266.513523)
			(xy 113.883842 -266.498868) (xy 113.930963 -266.491451) (xy 113.954814 -266.490958) (xy 113.978951 -266.491416)
			(xy 114.026625 -266.499012) (xy 114.07251 -266.514012) (xy 114.115464 -266.536043) (xy 114.154418 -266.564556)
			(xy 114.17173 -266.581382) (xy 114.171984 -266.581636) (xy 114.179396 -266.58832) (xy 114.197829 -266.595917)
			(xy 114.217767 -266.595917) (xy 114.2362 -266.58832) (xy 114.243612 -266.581636) (xy 114.535712 -266.289536)
			(xy 114.542948 -266.282818) (xy 114.561153 -266.275216) (xy 114.571018 -266.274804) (xy 115.005612 -266.274804)
			(xy 115.014341 -266.274453) (xy 115.030778 -266.268571) (xy 115.044252 -266.257471) (xy 115.049046 -266.250166)
			(xy 115.099592 -266.166346) (xy 115.100354 -266.139676) (xy 115.094258 -266.127992) (xy 115.08325 -266.10592)
			(xy 115.06771 -266.05911) (xy 115.059883 -266.010414) (xy 115.05946 -265.985752) (xy 115.05946 -265.980672)
			(xy 115.060414 -265.955719) (xy 115.069438 -265.90661) (xy 115.086331 -265.859622) (xy 115.110644 -265.816009)
			(xy 115.141729 -265.776933) (xy 115.178757 -265.743435) (xy 115.220741 -265.716407) (xy 115.266563 -265.69657)
			(xy 115.315003 -265.684453) (xy 115.364768 -265.680377) (xy 115.414533 -265.684453) (xy 115.462973 -265.69657)
			(xy 115.508795 -265.716407) (xy 115.550779 -265.743435) (xy 115.587807 -265.776933) (xy 115.618892 -265.816009)
			(xy 115.643205 -265.859622) (xy 115.660098 -265.90661) (xy 115.669122 -265.955719) (xy 115.670076 -265.980672)
			(xy 115.670076 -265.985752) (xy 115.670068 -265.98626) (xy 116.938818 -265.98626) (xy 116.942778 -265.937206)
			(xy 116.954555 -265.889422) (xy 116.973846 -265.844146) (xy 117.000149 -265.80255) (xy 117.032784 -265.765713)
			(xy 117.070905 -265.734588) (xy 117.113526 -265.709981) (xy 117.159542 -265.692529) (xy 117.207761 -265.682685)
			(xy 117.256936 -265.680704) (xy 117.305791 -265.686636) (xy 117.353062 -265.700328) (xy 117.397524 -265.721426)
			(xy 117.438027 -265.749382) (xy 117.47352 -265.783474) (xy 117.503085 -265.822818) (xy 117.525956 -265.866395)
			(xy 117.54154 -265.913076) (xy 117.549435 -265.961653) (xy 117.54993 -265.98626) (xy 117.549435 -266.010867)
			(xy 117.54154 -266.059444) (xy 117.525956 -266.106125) (xy 117.503085 -266.149702) (xy 117.47352 -266.189046)
			(xy 117.438027 -266.223138) (xy 117.397524 -266.251094) (xy 117.353062 -266.272192) (xy 117.305791 -266.285884)
			(xy 117.256936 -266.291816) (xy 117.207761 -266.289835) (xy 117.159542 -266.279991) (xy 117.113526 -266.262539)
			(xy 117.070905 -266.237932) (xy 117.032784 -266.206807) (xy 117.000149 -266.16997) (xy 116.973846 -266.128374)
			(xy 116.954555 -266.083098) (xy 116.942778 -266.035314) (xy 116.938818 -265.98626) (xy 115.670068 -265.98626)
			(xy 115.669669 -266.010416) (xy 115.661858 -266.059118) (xy 115.646305 -266.105927) (xy 115.635278 -266.127992)
			(xy 115.629182 -266.139676) (xy 115.629944 -266.166346) (xy 115.68049 -266.250166) (xy 115.685305 -266.257444)
			(xy 115.698799 -266.268491) (xy 115.715206 -266.274401) (xy 115.723924 -266.274804) (xy 115.81003 -266.274804)
			(xy 115.819871 -266.275333) (xy 115.838042 -266.28291) (xy 115.845336 -266.289536) (xy 116.577618 -267.021818)
			(xy 116.585014 -267.02867) (xy 116.603613 -267.036411) (xy 116.613686 -267.036804) (xy 117.334284 -267.036804)
			(xy 117.346616 -267.036222) (xy 117.368465 -267.024784) (xy 117.37594 -267.01496) (xy 117.422168 -266.948412)
			(xy 117.428532 -266.938015) (xy 117.431704 -266.91388) (xy 117.428264 -266.902184) (xy 117.428264 -266.901676)
			(xy 117.419487 -266.876147) (xy 117.410034 -266.823002) (xy 117.409468 -266.796012) (xy 117.409468 -266.790424)
			(xy 117.410365 -266.766732) (xy 117.418579 -266.720039) (xy 117.433912 -266.675177) (xy 117.455997 -266.633225)
			(xy 117.484301 -266.595191) (xy 117.518145 -266.56199) (xy 117.556714 -266.53442) (xy 117.599082 -266.513144)
			(xy 117.644229 -266.498673) (xy 117.691071 -266.491356) (xy 117.714776 -266.490958) (xy 117.741111 -266.491491)
			(xy 117.793007 -266.500487) (xy 117.84259 -266.518252) (xy 117.888392 -266.544257) (xy 117.909086 -266.560554)
			(xy 117.916198 -266.56665) (xy 117.933216 -266.572492) (xy 117.97284 -266.571476) (xy 117.982571 -266.570805)
			(xy 118.000476 -266.56311) (xy 118.007638 -266.55649) (xy 118.274592 -266.289536) (xy 118.281826 -266.282814)
			(xy 118.300032 -266.275205) (xy 118.309898 -266.274804) (xy 118.765574 -266.274804) (xy 118.774307 -266.274459)
			(xy 118.790753 -266.268585) (xy 118.804237 -266.257488) (xy 118.809008 -266.250166) (xy 118.859554 -266.166346)
			(xy 118.860316 -266.139676) (xy 118.85422 -266.127992) (xy 118.843213 -266.105919) (xy 118.827675 -266.05911)
			(xy 118.819849 -266.010413) (xy 118.819422 -265.985752) (xy 118.819422 -265.980672) (xy 118.820376 -265.955719)
			(xy 118.8294 -265.90661) (xy 118.846293 -265.859622) (xy 118.870606 -265.816009) (xy 118.901691 -265.776933)
			(xy 118.938719 -265.743435) (xy 118.980703 -265.716407) (xy 119.026525 -265.69657) (xy 119.074965 -265.684453)
			(xy 119.12473 -265.680377) (xy 119.174495 -265.684453) (xy 119.222935 -265.69657) (xy 119.268757 -265.716407)
			(xy 119.310741 -265.743435) (xy 119.347769 -265.776933) (xy 119.378854 -265.816009) (xy 119.403167 -265.859622)
			(xy 119.42006 -265.90661) (xy 119.429084 -265.955719) (xy 119.430038 -265.980672) (xy 119.430038 -265.985752)
			(xy 119.43003 -265.98626) (xy 120.699034 -265.98626) (xy 120.702994 -265.937206) (xy 120.714771 -265.889422)
			(xy 120.734062 -265.844146) (xy 120.760365 -265.80255) (xy 120.793 -265.765713) (xy 120.831121 -265.734588)
			(xy 120.873742 -265.709981) (xy 120.919758 -265.692529) (xy 120.967977 -265.682685) (xy 121.017152 -265.680704)
			(xy 121.066007 -265.686636) (xy 121.113278 -265.700328) (xy 121.15774 -265.721426) (xy 121.198243 -265.749382)
			(xy 121.233736 -265.783474) (xy 121.263301 -265.822818) (xy 121.286172 -265.866395) (xy 121.301756 -265.913076)
			(xy 121.309651 -265.961653) (xy 121.310146 -265.98626) (xy 121.309651 -266.010867) (xy 121.301756 -266.059444)
			(xy 121.286172 -266.106125) (xy 121.263301 -266.149702) (xy 121.233736 -266.189046) (xy 121.198243 -266.223138)
			(xy 121.15774 -266.251094) (xy 121.113278 -266.272192) (xy 121.066007 -266.285884) (xy 121.017152 -266.291816)
			(xy 120.967977 -266.289835) (xy 120.919758 -266.279991) (xy 120.873742 -266.262539) (xy 120.831121 -266.237932)
			(xy 120.793 -266.206807) (xy 120.760365 -266.16997) (xy 120.734062 -266.128374) (xy 120.714771 -266.083098)
			(xy 120.702994 -266.035314) (xy 120.699034 -265.98626) (xy 119.43003 -265.98626) (xy 119.429631 -266.010416)
			(xy 119.421822 -266.059119) (xy 119.406271 -266.105929) (xy 119.39524 -266.127992) (xy 119.389144 -266.139676)
			(xy 119.389906 -266.166346) (xy 119.440452 -266.250166) (xy 119.445265 -266.257448) (xy 119.458758 -266.268505)
			(xy 119.475166 -266.274427) (xy 119.483886 -266.274804) (xy 119.58955 -266.274804) (xy 119.599389 -266.275337)
			(xy 119.617555 -266.282919) (xy 119.624856 -266.289536) (xy 120.357138 -267.021818) (xy 120.364535 -267.028667)
			(xy 120.383134 -267.036401) (xy 120.393206 -267.036804) (xy 121.094246 -267.036804) (xy 121.106571 -267.036209)
			(xy 121.128397 -267.024756) (xy 121.135902 -267.01496) (xy 121.18213 -266.948412) (xy 121.188498 -266.938016)
			(xy 121.191672 -266.913879) (xy 121.188226 -266.902184) (xy 121.188226 -266.901676) (xy 121.17945 -266.876147)
			(xy 121.169998 -266.823002) (xy 121.16943 -266.796012) (xy 121.16943 -266.790424) (xy 121.170327 -266.766734)
			(xy 121.178541 -266.720044) (xy 121.193876 -266.675186) (xy 121.215961 -266.633239) (xy 121.244266 -266.59521)
			(xy 121.278111 -266.562015) (xy 121.316681 -266.534452) (xy 121.359048 -266.513184) (xy 121.404195 -266.498721)
			(xy 121.451035 -266.491413) (xy 121.474738 -266.490958) (xy 121.500751 -266.491484) (xy 121.552024 -266.500297)
			(xy 121.601066 -266.517663) (xy 121.64646 -266.543079) (xy 121.667016 -266.55903) (xy 121.667524 -266.559538)
			(xy 121.675012 -266.56493) (xy 121.692586 -266.570508) (xy 121.701814 -266.57046) (xy 121.768108 -266.567158)
			(xy 121.777408 -266.566275) (xy 121.794471 -266.558712) (xy 121.801382 -266.552426) (xy 122.130312 -266.223496)
			(xy 122.13755 -266.216782) (xy 122.155755 -266.209187) (xy 122.165618 -266.208764) (xy 122.498104 -266.208764)
			(xy 122.510083 -266.208117) (xy 122.531429 -266.197244) (xy 122.538998 -266.187936) (xy 122.593354 -266.113514)
			(xy 122.597164 -266.089892) (xy 122.593608 -266.078208) (xy 122.586896 -266.055559) (xy 122.579754 -266.008864)
			(xy 122.579384 -265.985244) (xy 122.579384 -265.984228) (xy 122.580064 -265.959083) (xy 122.588638 -265.909521)
			(xy 122.60522 -265.862034) (xy 122.62936 -265.817908) (xy 122.660407 -265.778335) (xy 122.69752 -265.744386)
			(xy 122.739695 -265.716978) (xy 122.785792 -265.696855) (xy 122.834564 -265.684558) (xy 122.884692 -265.680422)
			(xy 122.93482 -265.684558) (xy 122.983592 -265.696855) (xy 123.029689 -265.716978) (xy 123.071864 -265.744386)
			(xy 123.108977 -265.778335) (xy 123.140024 -265.817908) (xy 123.164164 -265.862034) (xy 123.180746 -265.909521)
			(xy 123.18932 -265.959083) (xy 123.19 -265.984228) (xy 123.19 -265.98499) (xy 123.18998 -265.98626)
			(xy 124.458996 -265.98626) (xy 124.462956 -265.937206) (xy 124.474733 -265.889422) (xy 124.494024 -265.844146)
			(xy 124.520327 -265.80255) (xy 124.552962 -265.765713) (xy 124.591083 -265.734588) (xy 124.633704 -265.709981)
			(xy 124.67972 -265.692529) (xy 124.727939 -265.682685) (xy 124.777114 -265.680704) (xy 124.825969 -265.686636)
			(xy 124.87324 -265.700328) (xy 124.917702 -265.721426) (xy 124.958205 -265.749382) (xy 124.993698 -265.783474)
			(xy 125.023263 -265.822818) (xy 125.046134 -265.866395) (xy 125.061718 -265.913076) (xy 125.069613 -265.961653)
			(xy 125.070108 -265.98626) (xy 126.33885 -265.98626) (xy 126.34281 -265.937206) (xy 126.354587 -265.889422)
			(xy 126.373878 -265.844146) (xy 126.400181 -265.80255) (xy 126.432816 -265.765713) (xy 126.470937 -265.734588)
			(xy 126.513558 -265.709981) (xy 126.559574 -265.692529) (xy 126.607793 -265.682685) (xy 126.656968 -265.680704)
			(xy 126.705823 -265.686636) (xy 126.753094 -265.700328) (xy 126.797556 -265.721426) (xy 126.838059 -265.749382)
			(xy 126.873552 -265.783474) (xy 126.903117 -265.822818) (xy 126.925988 -265.866395) (xy 126.941572 -265.913076)
			(xy 126.949467 -265.961653) (xy 126.949962 -265.98626) (xy 128.208527 -265.98626) (xy 128.212622 -265.935532)
			(xy 128.224801 -265.886118) (xy 128.244749 -265.839298) (xy 128.27195 -265.796284) (xy 128.305698 -265.75819)
			(xy 128.34512 -265.726003) (xy 128.389194 -265.700557) (xy 128.43678 -265.68251) (xy 128.486644 -265.67233)
			(xy 128.537496 -265.670281) (xy 128.588017 -265.676415) (xy 128.636901 -265.690575) (xy 128.68288 -265.712392)
			(xy 128.724764 -265.741302) (xy 128.761468 -265.776557) (xy 128.792041 -265.817243) (xy 128.815692 -265.862306)
			(xy 128.831808 -265.91058) (xy 128.839972 -265.960814) (xy 128.840484 -265.98626) (xy 129.159012 -265.98626)
			(xy 129.162972 -265.937206) (xy 129.174749 -265.889422) (xy 129.19404 -265.844146) (xy 129.220343 -265.80255)
			(xy 129.252978 -265.765713) (xy 129.291099 -265.734588) (xy 129.33372 -265.709981) (xy 129.379736 -265.692529)
			(xy 129.427955 -265.682685) (xy 129.47713 -265.680704) (xy 129.525985 -265.686636) (xy 129.573256 -265.700328)
			(xy 129.617718 -265.721426) (xy 129.658221 -265.749382) (xy 129.693714 -265.783474) (xy 129.723279 -265.822818)
			(xy 129.74615 -265.866395) (xy 129.761734 -265.913076) (xy 129.769629 -265.961653) (xy 129.770124 -265.98626)
			(xy 129.769629 -266.010867) (xy 129.761734 -266.059444) (xy 129.74615 -266.106125) (xy 129.723279 -266.149702)
			(xy 129.693714 -266.189046) (xy 129.658221 -266.223138) (xy 129.617718 -266.251094) (xy 129.573256 -266.272192)
			(xy 129.525985 -266.285884) (xy 129.47713 -266.291816) (xy 129.427955 -266.289835) (xy 129.379736 -266.279991)
			(xy 129.33372 -266.262539) (xy 129.291099 -266.237932) (xy 129.252978 -266.206807) (xy 129.220343 -266.16997)
			(xy 129.19404 -266.128374) (xy 129.174749 -266.083098) (xy 129.162972 -266.035314) (xy 129.159012 -265.98626)
			(xy 128.840484 -265.98626) (xy 128.839972 -266.011706) (xy 128.831808 -266.06194) (xy 128.815692 -266.110214)
			(xy 128.792041 -266.155277) (xy 128.761468 -266.195963) (xy 128.724764 -266.231218) (xy 128.68288 -266.260128)
			(xy 128.636901 -266.281945) (xy 128.588017 -266.296105) (xy 128.537496 -266.302239) (xy 128.486644 -266.30019)
			(xy 128.43678 -266.29001) (xy 128.389194 -266.271963) (xy 128.34512 -266.246517) (xy 128.305698 -266.21433)
			(xy 128.27195 -266.176236) (xy 128.244749 -266.133222) (xy 128.224801 -266.086402) (xy 128.212622 -266.036988)
			(xy 128.208527 -265.98626) (xy 126.949962 -265.98626) (xy 126.949467 -266.010867) (xy 126.941572 -266.059444)
			(xy 126.925988 -266.106125) (xy 126.903117 -266.149702) (xy 126.873552 -266.189046) (xy 126.838059 -266.223138)
			(xy 126.797556 -266.251094) (xy 126.753094 -266.272192) (xy 126.705823 -266.285884) (xy 126.656968 -266.291816)
			(xy 126.607793 -266.289835) (xy 126.559574 -266.279991) (xy 126.513558 -266.262539) (xy 126.470937 -266.237932)
			(xy 126.432816 -266.206807) (xy 126.400181 -266.16997) (xy 126.373878 -266.128374) (xy 126.354587 -266.083098)
			(xy 126.34281 -266.035314) (xy 126.33885 -265.98626) (xy 125.070108 -265.98626) (xy 125.069613 -266.010867)
			(xy 125.061718 -266.059444) (xy 125.046134 -266.106125) (xy 125.023263 -266.149702) (xy 124.993698 -266.189046)
			(xy 124.958205 -266.223138) (xy 124.917702 -266.251094) (xy 124.87324 -266.272192) (xy 124.825969 -266.285884)
			(xy 124.777114 -266.291816) (xy 124.727939 -266.289835) (xy 124.67972 -266.279991) (xy 124.633704 -266.262539)
			(xy 124.591083 -266.237932) (xy 124.552962 -266.206807) (xy 124.520327 -266.16997) (xy 124.494024 -266.128374)
			(xy 124.474733 -266.083098) (xy 124.462956 -266.035314) (xy 124.458996 -265.98626) (xy 123.18998 -265.98626)
			(xy 123.18963 -266.008672) (xy 123.182483 -266.055492) (xy 123.175776 -266.078208) (xy 123.17222 -266.089892)
			(xy 123.17603 -266.113514) (xy 123.230386 -266.187936) (xy 123.237989 -266.1972) (xy 123.259316 -266.208067)
			(xy 123.27128 -266.208764) (xy 123.31319 -266.208764) (xy 123.323027 -266.209303) (xy 123.341186 -266.216891)
			(xy 123.348496 -266.223496) (xy 124.146818 -267.021818) (xy 124.154214 -267.02867) (xy 124.172813 -267.036411)
			(xy 124.182886 -267.036804) (xy 124.854208 -267.036804) (xy 124.866537 -267.036217) (xy 124.888378 -267.024773)
			(xy 124.895864 -267.01496) (xy 124.942092 -266.948412) (xy 124.948454 -266.938014) (xy 124.951624 -266.913881)
			(xy 124.948188 -266.902184) (xy 124.948188 -266.901676) (xy 124.939411 -266.876147) (xy 124.929957 -266.823002)
			(xy 124.929392 -266.796012) (xy 124.929392 -266.790424) (xy 124.930365 -266.765485) (xy 124.939421 -266.716408)
			(xy 124.956336 -266.669456) (xy 124.980662 -266.625879) (xy 125.011749 -266.586838) (xy 125.048771 -266.553372)
			(xy 125.090742 -266.526371) (xy 125.136545 -266.506555) (xy 125.18496 -266.49445) (xy 125.2347 -266.490379)
			(xy 125.28444 -266.49445) (xy 125.332855 -266.506555) (xy 125.378658 -266.526371) (xy 125.420629 -266.553372)
			(xy 125.457651 -266.586838) (xy 125.488738 -266.625879) (xy 125.513064 -266.669456) (xy 125.529979 -266.716408)
			(xy 125.539035 -266.765485) (xy 125.540008 -266.790424) (xy 125.540008 -266.796012) (xy 125.539453 -266.823003)
			(xy 125.529994 -266.876148) (xy 125.521212 -266.901676) (xy 125.521212 -266.902184) (xy 125.51773 -266.913873)
			(xy 125.52093 -266.938014) (xy 125.527308 -266.948412) (xy 125.573536 -267.01496) (xy 125.581146 -267.024634)
			(xy 125.602907 -267.036053) (xy 125.615192 -267.036804) (xy 125.812042 -267.036804) (xy 125.821865 -267.036281)
			(xy 125.839991 -267.028692) (xy 125.853847 -267.014759) (xy 125.861336 -266.996592) (xy 125.861826 -266.986766)
			(xy 125.861826 -266.796266) (xy 125.862308 -266.771676) (xy 125.870002 -266.723101) (xy 125.885199 -266.676328)
			(xy 125.907526 -266.632509) (xy 125.936434 -266.592721) (xy 125.971209 -266.557946) (xy 126.010997 -266.529038)
			(xy 126.054816 -266.506711) (xy 126.101589 -266.491514) (xy 126.150164 -266.48382) (xy 126.199344 -266.48382)
			(xy 126.247919 -266.491514) (xy 126.294692 -266.506711) (xy 126.338511 -266.529038) (xy 126.378299 -266.557946)
			(xy 126.413074 -266.592721) (xy 126.441982 -266.632509) (xy 126.464309 -266.676328) (xy 126.479506 -266.723101)
			(xy 126.4872 -266.771676) (xy 126.487682 -266.796266) (xy 126.809004 -266.796266) (xy 126.812964 -266.747212)
			(xy 126.824741 -266.699428) (xy 126.844032 -266.654152) (xy 126.870335 -266.612556) (xy 126.90297 -266.575719)
			(xy 126.941091 -266.544594) (xy 126.983712 -266.519987) (xy 127.029728 -266.502535) (xy 127.077947 -266.492691)
			(xy 127.127122 -266.49071) (xy 127.175977 -266.496642) (xy 127.223248 -266.510334) (xy 127.26771 -266.531432)
			(xy 127.308213 -266.559388) (xy 127.343706 -266.59348) (xy 127.373271 -266.632824) (xy 127.396142 -266.676401)
			(xy 127.411726 -266.723082) (xy 127.419621 -266.771659) (xy 127.420116 -266.796266) (xy 127.738627 -266.796266)
			(xy 127.742722 -266.745538) (xy 127.754901 -266.696124) (xy 127.774849 -266.649304) (xy 127.80205 -266.60629)
			(xy 127.835798 -266.568196) (xy 127.87522 -266.536009) (xy 127.919294 -266.510563) (xy 127.96688 -266.492516)
			(xy 128.016744 -266.482336) (xy 128.067596 -266.480287) (xy 128.118117 -266.486421) (xy 128.167001 -266.500581)
			(xy 128.21298 -266.522398) (xy 128.254864 -266.551308) (xy 128.291568 -266.586563) (xy 128.322141 -266.627249)
			(xy 128.345792 -266.672312) (xy 128.361908 -266.720586) (xy 128.370072 -266.77082) (xy 128.370584 -266.796266)
			(xy 128.688858 -266.796266) (xy 128.692818 -266.747212) (xy 128.704595 -266.699428) (xy 128.723886 -266.654152)
			(xy 128.750189 -266.612556) (xy 128.782824 -266.575719) (xy 128.820945 -266.544594) (xy 128.863566 -266.519987)
			(xy 128.909582 -266.502535) (xy 128.957801 -266.492691) (xy 129.006976 -266.49071) (xy 129.055831 -266.496642)
			(xy 129.103102 -266.510334) (xy 129.147564 -266.531432) (xy 129.188067 -266.559388) (xy 129.22356 -266.59348)
			(xy 129.253125 -266.632824) (xy 129.275996 -266.676401) (xy 129.29158 -266.723082) (xy 129.299475 -266.771659)
			(xy 129.29997 -266.796266) (xy 129.618481 -266.796266) (xy 129.622576 -266.745538) (xy 129.634755 -266.696124)
			(xy 129.654703 -266.649304) (xy 129.681904 -266.60629) (xy 129.715652 -266.568196) (xy 129.755074 -266.536009)
			(xy 129.799148 -266.510563) (xy 129.846734 -266.492516) (xy 129.896598 -266.482336) (xy 129.94745 -266.480287)
			(xy 129.997971 -266.486421) (xy 130.046855 -266.500581) (xy 130.092834 -266.522398) (xy 130.134718 -266.551308)
			(xy 130.171422 -266.586563) (xy 130.201995 -266.627249) (xy 130.225646 -266.672312) (xy 130.241762 -266.720586)
			(xy 130.249926 -266.77082) (xy 130.250438 -266.796266) (xy 130.249926 -266.821712) (xy 130.241762 -266.871946)
			(xy 130.225646 -266.92022) (xy 130.201995 -266.965283) (xy 130.171422 -267.005969) (xy 130.134718 -267.041224)
			(xy 130.092834 -267.070134) (xy 130.046855 -267.091951) (xy 129.997971 -267.106111) (xy 129.94745 -267.112245)
			(xy 129.896598 -267.110196) (xy 129.846734 -267.100016) (xy 129.799148 -267.081969) (xy 129.755074 -267.056523)
			(xy 129.715652 -267.024336) (xy 129.681904 -266.986242) (xy 129.654703 -266.943228) (xy 129.634755 -266.896408)
			(xy 129.622576 -266.846994) (xy 129.618481 -266.796266) (xy 129.29997 -266.796266) (xy 129.299475 -266.820873)
			(xy 129.29158 -266.86945) (xy 129.275996 -266.916131) (xy 129.253125 -266.959708) (xy 129.22356 -266.999052)
			(xy 129.188067 -267.033144) (xy 129.147564 -267.0611) (xy 129.103102 -267.082198) (xy 129.055831 -267.09589)
			(xy 129.006976 -267.101822) (xy 128.957801 -267.099841) (xy 128.909582 -267.089997) (xy 128.863566 -267.072545)
			(xy 128.820945 -267.047938) (xy 128.782824 -267.016813) (xy 128.750189 -266.979976) (xy 128.723886 -266.93838)
			(xy 128.704595 -266.893104) (xy 128.692818 -266.84532) (xy 128.688858 -266.796266) (xy 128.370584 -266.796266)
			(xy 128.370072 -266.821712) (xy 128.361908 -266.871946) (xy 128.345792 -266.92022) (xy 128.322141 -266.965283)
			(xy 128.291568 -267.005969) (xy 128.254864 -267.041224) (xy 128.21298 -267.070134) (xy 128.167001 -267.091951)
			(xy 128.118117 -267.106111) (xy 128.067596 -267.112245) (xy 128.016744 -267.110196) (xy 127.96688 -267.100016)
			(xy 127.919294 -267.081969) (xy 127.87522 -267.056523) (xy 127.835798 -267.024336) (xy 127.80205 -266.986242)
			(xy 127.774849 -266.943228) (xy 127.754901 -266.896408) (xy 127.742722 -266.846994) (xy 127.738627 -266.796266)
			(xy 127.420116 -266.796266) (xy 127.419621 -266.820873) (xy 127.411726 -266.86945) (xy 127.396142 -266.916131)
			(xy 127.373271 -266.959708) (xy 127.343706 -266.999052) (xy 127.308213 -267.033144) (xy 127.26771 -267.0611)
			(xy 127.223248 -267.082198) (xy 127.175977 -267.09589) (xy 127.127122 -267.101822) (xy 127.077947 -267.099841)
			(xy 127.029728 -267.089997) (xy 126.983712 -267.072545) (xy 126.941091 -267.047938) (xy 126.90297 -267.016813)
			(xy 126.870335 -266.979976) (xy 126.844032 -266.93838) (xy 126.824741 -266.893104) (xy 126.812964 -266.84532)
			(xy 126.809004 -266.796266) (xy 126.487682 -266.796266) (xy 126.487682 -267.204952) (xy 126.488199 -267.215881)
			(xy 126.497284 -267.235761) (xy 126.505208 -267.243306) (xy 126.569978 -267.29944) (xy 126.590806 -267.305536)
			(xy 126.601982 -267.304012) (xy 126.612594 -267.302602) (xy 126.633949 -267.301079) (xy 126.644654 -267.300964)
			(xy 126.66865 -267.301407) (xy 126.716053 -267.308908) (xy 126.761699 -267.323732) (xy 126.804463 -267.345514)
			(xy 126.843293 -267.373718) (xy 126.877233 -267.40765) (xy 126.905447 -267.446474) (xy 126.92724 -267.489233)
			(xy 126.942075 -267.534875) (xy 126.949587 -267.582276) (xy 126.949962 -267.606272) (xy 126.949583 -267.627974)
			(xy 126.943439 -267.67094) (xy 126.931271 -267.712602) (xy 126.913325 -267.752121) (xy 126.901956 -267.77061)
			(xy 126.898146 -267.776706) (xy 126.893828 -267.791184) (xy 126.891689 -267.800003) (xy 126.893062 -267.818085)
			(xy 126.900609 -267.834574) (xy 126.906782 -267.841222) (xy 126.981458 -267.915898) (xy 126.98886 -267.922736)
			(xy 127.007458 -267.930449) (xy 127.017526 -267.930884) (xy 128.186942 -267.930884) (xy 128.187704 -267.930884)
			(xy 128.19893 -267.930136) (xy 128.219112 -267.920259) (xy 128.226566 -267.911834) (xy 128.231646 -267.90396)
			(xy 128.272794 -267.827252) (xy 128.276766 -267.818993) (xy 128.279165 -267.800838) (xy 128.275038 -267.782997)
			(xy 128.270254 -267.775182) (xy 128.270254 -267.774928) (xy 128.258231 -267.756087) (xy 128.239231 -267.715631)
			(xy 128.226336 -267.672837) (xy 128.219821 -267.628619) (xy 128.219454 -267.606272) (xy 128.219454 -267.598906)
			(xy 128.220461 -267.575294) (xy 128.228859 -267.528788) (xy 128.244324 -267.484131) (xy 128.266487 -267.442392)
			(xy 128.294818 -267.404567) (xy 128.32864 -267.371561) (xy 128.367146 -267.344162) (xy 128.409414 -267.323025)
			(xy 128.454435 -267.308656) (xy 128.501133 -267.301397) (xy 128.524762 -267.300964) (xy 128.548399 -267.301411)
			(xy 128.595106 -267.308704) (xy 128.640132 -267.323107) (xy 128.682402 -267.344274) (xy 128.720905 -267.371702)
			(xy 128.754723 -267.404734) (xy 128.783047 -267.442582) (xy 128.805203 -267.484343) (xy 128.820659 -267.529018)
			(xy 128.829048 -267.575541) (xy 128.83007 -267.59916) (xy 128.83007 -267.606272) (xy 128.829683 -267.628619)
			(xy 128.823174 -267.672837) (xy 128.810292 -267.715635) (xy 128.79131 -267.756098) (xy 128.77927 -267.774928)
			(xy 128.77927 -267.775182) (xy 128.774504 -267.783008) (xy 128.770353 -267.80084) (xy 128.772767 -267.818989)
			(xy 128.77673 -267.827252) (xy 128.817878 -267.90396) (xy 128.822958 -267.911834) (xy 128.830435 -267.920235)
			(xy 128.8506 -267.930135) (xy 128.86182 -267.930884) (xy 129.126996 -267.930884) (xy 129.127758 -267.930884)
			(xy 129.139747 -267.929991) (xy 129.160956 -267.918735) (xy 129.168398 -267.909294) (xy 129.1717 -267.90396)
			(xy 129.214372 -267.824966) (xy 129.212594 -267.796772) (xy 129.204466 -267.784834) (xy 129.191406 -267.765017)
			(xy 129.170759 -267.722286) (xy 129.156766 -267.676938) (xy 129.149745 -267.630002) (xy 129.149348 -267.606272)
			(xy 129.149834 -267.581482) (xy 129.15759 -267.532514) (xy 129.172911 -267.485361) (xy 129.19542 -267.441186)
			(xy 129.224562 -267.401075) (xy 129.259619 -267.366018) (xy 129.29973 -267.336876) (xy 129.343905 -267.314367)
			(xy 129.391058 -267.299046) (xy 129.440026 -267.29129) (xy 129.489606 -267.29129) (xy 129.538574 -267.299046)
			(xy 129.585727 -267.314367) (xy 129.629902 -267.336876) (xy 129.670013 -267.366018) (xy 129.70507 -267.401075)
			(xy 129.734212 -267.441186) (xy 129.756721 -267.485361) (xy 129.772042 -267.532514) (xy 129.779798 -267.581482)
			(xy 129.780284 -267.606272) (xy 130.099066 -267.606272) (xy 130.103026 -267.557218) (xy 130.114803 -267.509434)
			(xy 130.134094 -267.464158) (xy 130.160397 -267.422562) (xy 130.193032 -267.385725) (xy 130.231153 -267.3546)
			(xy 130.273774 -267.329993) (xy 130.31979 -267.312541) (xy 130.368009 -267.302697) (xy 130.417184 -267.300716)
			(xy 130.466039 -267.306648) (xy 130.51331 -267.32034) (xy 130.557772 -267.341438) (xy 130.598275 -267.369394)
			(xy 130.633768 -267.403486) (xy 130.663333 -267.44283) (xy 130.686204 -267.486407) (xy 130.701788 -267.533088)
			(xy 130.709683 -267.581665) (xy 130.710178 -267.606272) (xy 130.709683 -267.630879) (xy 130.701788 -267.679456)
			(xy 130.686204 -267.726137) (xy 130.663333 -267.769714) (xy 130.633768 -267.809058) (xy 130.598275 -267.84315)
			(xy 130.557772 -267.871106) (xy 130.51331 -267.892204) (xy 130.466039 -267.905896) (xy 130.417184 -267.911828)
			(xy 130.368009 -267.909847) (xy 130.31979 -267.900003) (xy 130.273774 -267.882551) (xy 130.231153 -267.857944)
			(xy 130.193032 -267.826819) (xy 130.160397 -267.789982) (xy 130.134094 -267.748386) (xy 130.114803 -267.70311)
			(xy 130.103026 -267.655326) (xy 130.099066 -267.606272) (xy 129.780284 -267.606272) (xy 129.77987 -267.629998)
			(xy 129.772804 -267.676922) (xy 129.758813 -267.722264) (xy 129.738208 -267.76501) (xy 129.725166 -267.784834)
			(xy 129.717038 -267.796518) (xy 129.715514 -267.824712) (xy 129.757932 -267.90396) (xy 129.761742 -267.91031)
			(xy 129.769202 -267.919419) (xy 129.790124 -267.930159) (xy 129.801874 -267.930884) (xy 129.85623 -267.930884)
			(xy 129.866071 -267.931412) (xy 129.884244 -267.938987) (xy 129.891536 -267.945616) (xy 130.118104 -268.172184)
			(xy 130.120644 -268.174216) (xy 130.136235 -268.186602) (xy 130.164385 -268.214764) (xy 130.176778 -268.23035)
			(xy 130.17881 -268.23289) (xy 130.613658 -268.667738) (xy 130.621057 -268.674582) (xy 130.639656 -268.682305)
			(xy 130.649726 -268.682724)
		)
		(stroke
			(width 0)
			(type solid)
		)
		(fill yes)
		(layer "In4.Cu")
		(net "PVDD11_S3_P1")
	)
	(gr_poly
		(pts
			(xy 341.886032 -267.20292) (xy 341.896265 -267.202441) (xy 341.915107 -267.194449) (xy 341.92937 -267.17977)
			(xy 341.93353 -267.170408) (xy 341.96782 -267.081762) (xy 341.970312 -267.074463) (xy 341.971227 -267.059074)
			(xy 341.969598 -267.051536) (xy 341.968328 -267.045948) (xy 341.949551 -267.030911) (xy 341.916343 -266.996108)
			(xy 341.888806 -266.956667) (xy 341.867577 -266.913501) (xy 341.85315 -266.867612) (xy 341.845859 -266.820064)
			(xy 341.845392 -266.796012) (xy 341.845879 -266.771202) (xy 341.853641 -266.722194) (xy 341.868974 -266.675004)
			(xy 341.891501 -266.630793) (xy 341.920666 -266.59065) (xy 341.955752 -266.555564) (xy 341.995895 -266.526399)
			(xy 342.040106 -266.503872) (xy 342.087296 -266.488539) (xy 342.136304 -266.480777) (xy 342.185924 -266.480777)
			(xy 342.234932 -266.488539) (xy 342.282122 -266.503872) (xy 342.326333 -266.526399) (xy 342.366476 -266.555564)
			(xy 342.401562 -266.59065) (xy 342.430727 -266.630793) (xy 342.453254 -266.675004) (xy 342.468587 -266.722194)
			(xy 342.476349 -266.771202) (xy 342.476836 -266.796012) (xy 342.795364 -266.796012) (xy 342.799324 -266.746958)
			(xy 342.811101 -266.699174) (xy 342.830392 -266.653898) (xy 342.856695 -266.612302) (xy 342.88933 -266.575465)
			(xy 342.927451 -266.54434) (xy 342.970072 -266.519733) (xy 343.016088 -266.502281) (xy 343.064307 -266.492437)
			(xy 343.113482 -266.490456) (xy 343.162337 -266.496388) (xy 343.209608 -266.51008) (xy 343.25407 -266.531178)
			(xy 343.294573 -266.559134) (xy 343.330066 -266.593226) (xy 343.359631 -266.63257) (xy 343.382502 -266.676147)
			(xy 343.398086 -266.722828) (xy 343.405981 -266.771405) (xy 343.406476 -266.796012) (xy 343.405981 -266.820619)
			(xy 343.398086 -266.869196) (xy 343.382502 -266.915877) (xy 343.359631 -266.959454) (xy 343.330066 -266.998798)
			(xy 343.294573 -267.03289) (xy 343.25407 -267.060846) (xy 343.209608 -267.081944) (xy 343.162337 -267.095636)
			(xy 343.113482 -267.101568) (xy 343.064307 -267.099587) (xy 343.016088 -267.089743) (xy 342.970072 -267.072291)
			(xy 342.927451 -267.047684) (xy 342.88933 -267.016559) (xy 342.856695 -266.979722) (xy 342.830392 -266.938126)
			(xy 342.811101 -266.89285) (xy 342.799324 -266.845066) (xy 342.795364 -266.796012) (xy 342.476836 -266.796012)
			(xy 342.47626 -266.823268) (xy 342.466887 -266.876969) (xy 342.448422 -266.92826) (xy 342.421416 -266.975613)
			(xy 342.386672 -267.017618) (xy 342.366346 -267.035788) (xy 342.360408 -267.041153) (xy 342.35199 -267.054751)
			(xy 342.349836 -267.062458) (xy 342.34882 -267.06703) (xy 342.388698 -267.170408) (xy 342.392802 -267.179813)
			(xy 342.407054 -267.194551) (xy 342.425944 -267.202519) (xy 342.436196 -267.20292) (xy 343.76614 -267.20292)
			(xy 343.776383 -267.202458) (xy 343.795254 -267.194485) (xy 343.809546 -267.179807) (xy 343.813638 -267.170408)
			(xy 343.847928 -267.081762) (xy 343.85042 -267.074463) (xy 343.851335 -267.059074) (xy 343.849706 -267.051536)
			(xy 343.848436 -267.045948) (xy 343.829658 -267.030911) (xy 343.79645 -266.996109) (xy 343.768912 -266.956667)
			(xy 343.747683 -266.913501) (xy 343.733255 -266.867612) (xy 343.725963 -266.820064) (xy 343.7255 -266.796012)
			(xy 343.725987 -266.771202) (xy 343.733749 -266.722194) (xy 343.749082 -266.675004) (xy 343.771609 -266.630793)
			(xy 343.800774 -266.59065) (xy 343.83586 -266.555564) (xy 343.876003 -266.526399) (xy 343.920214 -266.503872)
			(xy 343.967404 -266.488539) (xy 344.016412 -266.480777) (xy 344.066032 -266.480777) (xy 344.11504 -266.488539)
			(xy 344.16223 -266.503872) (xy 344.206441 -266.526399) (xy 344.246584 -266.555564) (xy 344.28167 -266.59065)
			(xy 344.310835 -266.630793) (xy 344.333362 -266.675004) (xy 344.348695 -266.722194) (xy 344.356457 -266.771202)
			(xy 344.356944 -266.796012) (xy 344.356368 -266.823268) (xy 344.346995 -266.87697) (xy 344.328531 -266.92826)
			(xy 344.301525 -266.975614) (xy 344.266782 -267.01762) (xy 344.246454 -267.035788) (xy 344.240516 -267.041152)
			(xy 344.232096 -267.054751) (xy 344.229944 -267.062458) (xy 344.228928 -267.06703) (xy 344.268806 -267.170408)
			(xy 344.272911 -267.179812) (xy 344.287163 -267.194547) (xy 344.306052 -267.202512) (xy 344.316304 -267.20292)
			(xy 345.114372 -267.20292) (xy 345.124245 -267.202451) (xy 345.142532 -267.194996) (xy 345.149932 -267.188442)
			(xy 345.150186 -267.188188) (xy 345.627706 -266.710668) (xy 345.631516 -266.699238) (xy 345.639399 -266.677025)
			(xy 345.661028 -266.63515) (xy 345.688835 -266.597095) (xy 345.72216 -266.563765) (xy 345.760211 -266.535952)
			(xy 345.802083 -266.514317) (xy 345.824302 -266.506452) (xy 345.835732 -266.502642) (xy 346.139008 -266.199366)
			(xy 346.142818 -266.164314) (xy 346.133166 -266.149074) (xy 346.118381 -266.12447) (xy 346.097306 -266.071086)
			(xy 346.08658 -266.014703) (xy 346.085922 -265.986006) (xy 346.086368 -265.962013) (xy 346.093874 -265.914619)
			(xy 346.108702 -265.868982) (xy 346.130488 -265.826228) (xy 346.158694 -265.787408) (xy 346.192626 -265.753478)
			(xy 346.231448 -265.725275) (xy 346.274205 -265.703493) (xy 346.319842 -265.688668) (xy 346.367237 -265.681166)
			(xy 346.39123 -265.680698) (xy 346.415467 -265.681165) (xy 346.463332 -265.688827) (xy 346.509386 -265.703954)
			(xy 346.552472 -265.726166) (xy 346.591508 -265.754906) (xy 346.625514 -265.789451) (xy 346.653637 -265.828934)
			(xy 346.675169 -265.872363) (xy 346.68957 -265.918649) (xy 346.69349 -265.942572) (xy 346.695268 -265.956034)
			(xy 346.696792 -265.985244) (xy 346.696792 -265.990324) (xy 346.695803 -266.017385) (xy 346.685446 -266.07053)
			(xy 346.676218 -266.095988) (xy 346.671646 -266.107926) (xy 346.67444 -266.13231) (xy 346.72778 -266.210288)
			(xy 346.729812 -266.213082) (xy 346.737306 -266.221595) (xy 346.757613 -266.231629) (xy 346.768928 -266.232386)
			(xy 347.892624 -266.232386) (xy 347.893386 -266.232386) (xy 347.905127 -266.231616) (xy 347.926044 -266.220898)
			(xy 347.933518 -266.211812) (xy 347.934534 -266.210288) (xy 347.980762 -266.142724) (xy 347.987043 -266.132135)
			(xy 347.989842 -266.107714) (xy 347.986096 -266.095988) (xy 347.986096 -266.095734) (xy 347.97665 -266.069355)
			(xy 347.966428 -266.014272) (xy 347.965776 -265.98626) (xy 347.965776 -265.986006) (xy 347.966246 -265.962014)
			(xy 347.973751 -265.914621) (xy 347.988578 -265.868985) (xy 348.010361 -265.82623) (xy 348.038564 -265.787409)
			(xy 348.072493 -265.753478) (xy 348.111311 -265.725273) (xy 348.154064 -265.703487) (xy 348.199699 -265.688657)
			(xy 348.247092 -265.681148) (xy 348.271084 -265.680698) (xy 348.29585 -265.681178) (xy 348.344733 -265.689175)
			(xy 348.391683 -265.70496) (xy 348.435468 -265.728119) (xy 348.474938 -265.758045) (xy 348.492318 -265.775694)
			(xy 348.492572 -265.775694) (xy 348.499864 -265.782809) (xy 348.518471 -265.791063) (xy 348.52864 -265.791696)
			(xy 348.599506 -265.792712) (xy 348.609486 -265.792372) (xy 348.628041 -265.785045) (xy 348.635574 -265.778488)
			(xy 348.635828 -265.778234) (xy 349.87484 -264.539222) (xy 349.880428 -264.50798) (xy 349.873824 -264.493502)
			(xy 349.865013 -264.473412) (xy 349.852586 -264.431342) (xy 349.846294 -264.387928) (xy 349.845884 -264.365994)
			(xy 349.845884 -264.361168) (xy 349.846712 -264.337428) (xy 349.854812 -264.290623) (xy 349.870064 -264.245637)
			(xy 349.8921 -264.203557) (xy 349.920389 -264.165399) (xy 349.954247 -264.132083) (xy 349.992856 -264.104413)
			(xy 350.035286 -264.083059) (xy 350.080512 -264.068534) (xy 350.127441 -264.061191) (xy 350.151192 -264.060686)
			(xy 350.173129 -264.061061) (xy 350.21655 -264.067339) (xy 350.258622 -264.079783) (xy 350.2787 -264.088626)
			(xy 350.293178 -264.09523) (xy 350.32442 -264.089642) (xy 350.456754 -263.957308) (xy 350.46424 -263.949102)
			(xy 350.471883 -263.928276) (xy 350.471486 -263.917176) (xy 350.465136 -263.841992) (xy 350.46372 -263.831044)
			(xy 350.452917 -263.81182) (xy 350.444308 -263.804908) (xy 350.444054 -263.804908) (xy 350.424565 -263.79046)
			(xy 350.389991 -263.756431) (xy 350.361231 -263.717363) (xy 350.339008 -263.674241) (xy 350.32388 -263.628149)
			(xy 350.316229 -263.580244) (xy 350.315784 -263.555988) (xy 350.316256 -263.531997) (xy 350.323763 -263.484606)
			(xy 350.338591 -263.438974) (xy 350.360375 -263.396222) (xy 350.388579 -263.357404) (xy 350.422507 -263.323476)
			(xy 350.461325 -263.295273) (xy 350.504077 -263.27349) (xy 350.54971 -263.258662) (xy 350.597101 -263.251155)
			(xy 350.621092 -263.25068) (xy 350.645343 -263.251152) (xy 350.693235 -263.258824) (xy 350.739315 -263.273963)
			(xy 350.782426 -263.296187) (xy 350.821487 -263.32494) (xy 350.855519 -263.359499) (xy 350.870012 -263.37895)
			(xy 350.870012 -263.379204) (xy 350.876935 -263.387799) (xy 350.896153 -263.398606) (xy 350.907096 -263.400032)
			(xy 350.98228 -263.406382) (xy 350.993371 -263.406717) (xy 351.014184 -263.399092) (xy 351.022412 -263.39165)
			(xy 351.718626 -262.695436) (xy 351.7265 -262.685276) (xy 351.730564 -262.678418) (xy 351.732342 -262.67156)
			(xy 351.738579 -262.649172) (xy 351.756895 -262.60646) (xy 351.781471 -262.567017) (xy 351.811739 -262.531753)
			(xy 351.847001 -262.501482) (xy 351.886443 -262.476904) (xy 351.929153 -262.458585) (xy 351.951544 -262.452358)
			(xy 351.952306 -262.452358) (xy 351.958642 -262.450396) (xy 351.970088 -262.443703) (xy 351.974912 -262.43915)
			(xy 352.58502 -261.829042) (xy 352.592261 -261.822335) (xy 352.610465 -261.814751) (xy 352.620326 -261.81431)
			(xy 353.595178 -261.81431) (xy 353.605015 -261.813773) (xy 353.623175 -261.806185) (xy 353.630484 -261.799578)
			(xy 353.77882 -261.651242) (xy 353.786061 -261.644535) (xy 353.804265 -261.636951) (xy 353.814126 -261.63651)
			(xy 354.024184 -261.63651) (xy 354.025454 -261.63651) (xy 354.034025 -261.635964) (xy 354.050077 -261.629883)
			(xy 354.063211 -261.618832) (xy 354.067872 -261.611618) (xy 354.07092 -261.605522) (xy 354.10648 -261.52221)
			(xy 354.109954 -261.512913) (xy 354.110269 -261.493088) (xy 354.103041 -261.474624) (xy 354.096574 -261.467092)
			(xy 354.078886 -261.447809) (xy 354.048963 -261.404884) (xy 354.025897 -261.357917) (xy 354.010221 -261.307995)
			(xy 354.002298 -261.256273) (xy 354.001832 -261.23011) (xy 354.002312 -261.204411) (xy 354.009973 -261.153587)
			(xy 354.025122 -261.104473) (xy 354.047423 -261.058165) (xy 354.076376 -261.015698) (xy 354.111336 -260.978021)
			(xy 354.15152 -260.945975) (xy 354.196032 -260.920276) (xy 354.243877 -260.901499) (xy 354.293986 -260.890061)
			(xy 354.34524 -260.886221) (xy 354.396494 -260.890061) (xy 354.446603 -260.901499) (xy 354.494448 -260.920276)
			(xy 354.53896 -260.945975) (xy 354.579144 -260.978021) (xy 354.614104 -261.015698) (xy 354.643057 -261.058165)
			(xy 354.665358 -261.104473) (xy 354.680507 -261.153587) (xy 354.688168 -261.204411) (xy 354.688648 -261.23011)
			(xy 354.688158 -261.256271) (xy 354.680229 -261.30799) (xy 354.664557 -261.35791) (xy 354.641502 -261.404879)
			(xy 354.611597 -261.447813) (xy 354.593906 -261.467092) (xy 354.587406 -261.4746) (xy 354.580187 -261.49308)
			(xy 354.580501 -261.512917) (xy 354.584 -261.52221) (xy 354.61956 -261.605522) (xy 354.622608 -261.611618)
			(xy 354.627274 -261.618827) (xy 354.640413 -261.629867) (xy 354.656457 -261.635959) (xy 354.665026 -261.63651)
			(xy 355.198934 -261.63651) (xy 355.19995 -261.63651) (xy 355.212029 -261.635588) (xy 355.233373 -261.6242)
			(xy 355.240844 -261.614666) (xy 355.242622 -261.611618) (xy 355.292914 -261.526528) (xy 355.293168 -261.499604)
			(xy 355.286564 -261.487666) (xy 355.273306 -261.462233) (xy 355.254517 -261.408048) (xy 355.244989 -261.351495)
			(xy 355.2444 -261.32282) (xy 355.244654 -261.317994) (xy 355.244908 -261.308088) (xy 355.24653 -261.281882)
			(xy 355.256738 -261.230381) (xy 355.274666 -261.181034) (xy 355.299897 -261.13499) (xy 355.331842 -261.093324)
			(xy 355.369757 -261.057007) (xy 355.412759 -261.026883) (xy 355.459845 -261.003657) (xy 355.509918 -260.987868)
			(xy 355.56181 -260.979886) (xy 355.588062 -260.979412) (xy 355.615051 -260.979911) (xy 355.668364 -260.98835)
			(xy 355.719701 -261.005026) (xy 355.767796 -261.029528) (xy 355.811466 -261.061253) (xy 355.849635 -261.09942)
			(xy 355.881362 -261.143088) (xy 355.905867 -261.191182) (xy 355.922546 -261.242518) (xy 355.930988 -261.295831)
			(xy 355.93147 -261.32282) (xy 355.931021 -261.347904) (xy 355.923745 -261.397542) (xy 355.909335 -261.445597)
			(xy 355.888097 -261.491048) (xy 355.860481 -261.532932) (xy 355.844094 -261.551928) (xy 355.837744 -261.55904)
			(xy 355.83114 -261.576312) (xy 355.83114 -261.58571) (xy 355.831562 -261.595727) (xy 355.839235 -261.614234)
			(xy 355.853408 -261.628393) (xy 355.871923 -261.636048) (xy 355.88194 -261.63651) (xy 355.90988 -261.63651)
			(xy 355.919717 -261.635973) (xy 355.937876 -261.628384) (xy 355.945186 -261.621778) (xy 356.180644 -261.38632)
			(xy 356.187947 -261.378233) (xy 356.195578 -261.357844) (xy 356.195376 -261.34695) (xy 356.194614 -261.330694)
			(xy 356.194614 -261.32282) (xy 356.195111 -261.296551) (xy 356.203104 -261.244626) (xy 356.218906 -261.194522)
			(xy 356.24215 -261.147407) (xy 356.272294 -261.104378) (xy 356.290118 -261.085076) (xy 356.296976 -261.078218)
			(xy 356.307644 -261.052056) (xy 356.309414 -261.047428) (xy 356.311326 -261.037706) (xy 356.311454 -261.032752)
			(xy 356.311454 -257.544316) (xy 356.311014 -257.534254) (xy 356.303273 -257.515676) (xy 356.296468 -257.508248)
			(xy 355.97084 -257.18262) (xy 355.963728 -257.175254) (xy 355.944932 -257.167634) (xy 354.758244 -257.167634)
			(xy 354.757482 -257.167634) (xy 354.747979 -257.16817) (xy 354.730365 -257.175348) (xy 354.723192 -257.181604)
			(xy 354.716334 -257.189986) (xy 354.67036 -257.25755) (xy 354.666989 -257.262732) (xy 354.662622 -257.274294)
			(xy 354.661724 -257.28041) (xy 354.660454 -257.292856) (xy 354.665026 -257.304794) (xy 354.665026 -257.305048)
			(xy 354.676025 -257.335112) (xy 354.687908 -257.398011) (xy 354.688648 -257.430016) (xy 354.688118 -257.457001)
			(xy 354.679673 -257.510308) (xy 354.662994 -257.561637) (xy 354.638492 -257.609725) (xy 354.60677 -257.653389)
			(xy 354.568608 -257.691554) (xy 354.524946 -257.72328) (xy 354.482371 -257.744976) (xy 355.513897 -257.744976)
			(xy 355.517927 -257.692478) (xy 355.529924 -257.64121) (xy 355.549607 -257.592375) (xy 355.576513 -257.547116)
			(xy 355.610013 -257.506495) (xy 355.649321 -257.471464) (xy 355.693516 -257.442844) (xy 355.741561 -257.421305)
			(xy 355.792332 -257.407353) (xy 355.844637 -257.401315) (xy 355.897251 -257.403332) (xy 355.948941 -257.413356)
			(xy 355.998494 -257.431154) (xy 356.04475 -257.456307) (xy 356.086624 -257.488226) (xy 356.123136 -257.526164)
			(xy 356.153428 -257.56923) (xy 356.176791 -257.616415) (xy 356.192677 -257.666614) (xy 356.200714 -257.71865)
			(xy 356.201218 -257.744976) (xy 356.200714 -257.771302) (xy 356.192677 -257.823338) (xy 356.176791 -257.873537)
			(xy 356.153428 -257.920722) (xy 356.123136 -257.963788) (xy 356.086624 -258.001726) (xy 356.04475 -258.033645)
			(xy 355.998494 -258.058798) (xy 355.948941 -258.076596) (xy 355.897251 -258.08662) (xy 355.844637 -258.088637)
			(xy 355.792332 -258.082599) (xy 355.741561 -258.068647) (xy 355.693516 -258.047108) (xy 355.649321 -258.018488)
			(xy 355.610013 -257.983457) (xy 355.576513 -257.942836) (xy 355.549607 -257.897577) (xy 355.529924 -257.848742)
			(xy 355.517927 -257.797474) (xy 355.513897 -257.744976) (xy 354.482371 -257.744976) (xy 354.476859 -257.747785)
			(xy 354.425531 -257.764467) (xy 354.372225 -257.772916) (xy 354.34524 -257.773424) (xy 354.317718 -257.772876)
			(xy 354.263381 -257.764089) (xy 354.21114 -257.74675) (xy 354.162332 -257.721303) (xy 354.118207 -257.688399)
			(xy 354.079893 -257.64888) (xy 354.048371 -257.603756) (xy 354.024447 -257.554184) (xy 354.008734 -257.501431)
			(xy 354.004626 -257.474212) (xy 354.002848 -257.459734) (xy 354.001578 -257.430016) (xy 354.002291 -257.397946)
			(xy 354.014178 -257.334918) (xy 354.0252 -257.304794) (xy 354.030026 -257.29311) (xy 354.027232 -257.268218)
			(xy 353.974146 -257.189986) (xy 353.967288 -257.181604) (xy 353.960127 -257.175328) (xy 353.942506 -257.168153)
			(xy 353.932998 -257.167634) (xy 353.81565 -257.167634) (xy 353.805899 -257.167121) (xy 353.787867 -257.159675)
			(xy 353.780598 -257.153156) (xy 353.757992 -257.130296) (xy 353.750593 -257.123451) (xy 353.731995 -257.11572)
			(xy 353.721924 -257.11531) (xy 348.937326 -257.11531) (xy 348.927489 -257.114774) (xy 348.909327 -257.107187)
			(xy 348.90202 -257.100578) (xy 348.169738 -256.368296) (xy 348.162626 -256.36093) (xy 348.14383 -256.35331)
			(xy 347.394276 -256.35331) (xy 347.385636 -256.353644) (xy 347.369341 -256.359392) (xy 347.355901 -256.370252)
			(xy 347.351096 -256.37744) (xy 347.299788 -256.460244) (xy 347.298518 -256.486406) (xy 347.30436 -256.498344)
			(xy 347.314447 -256.519561) (xy 347.3287 -256.564325) (xy 347.335917 -256.610745) (xy 347.336364 -256.634234)
			(xy 347.335915 -256.658224) (xy 347.328404 -256.705613) (xy 347.313572 -256.751243) (xy 347.291784 -256.793991)
			(xy 347.263577 -256.832805) (xy 347.229645 -256.866728) (xy 347.190825 -256.894925) (xy 347.148071 -256.916702)
			(xy 347.102437 -256.931522) (xy 347.055046 -256.939021) (xy 347.031056 -256.939542) (xy 347.005342 -256.939016)
			(xy 346.954639 -256.930406) (xy 346.906096 -256.913422) (xy 346.861086 -256.888542) (xy 346.820882 -256.856472)
			(xy 346.786621 -256.818117) (xy 346.759272 -256.774564) (xy 346.739609 -256.727043) (xy 346.728188 -256.676899)
			(xy 346.726256 -256.651252) (xy 346.725494 -256.639822) (xy 346.725494 -256.634234) (xy 346.725925 -256.610703)
			(xy 346.733135 -256.564195) (xy 346.747389 -256.519343) (xy 346.757498 -256.49809) (xy 346.76334 -256.486152)
			(xy 346.762324 -256.45999) (xy 346.711016 -256.37744) (xy 346.706188 -256.370271) (xy 346.692749 -256.359422)
			(xy 346.676471 -256.353647) (xy 346.667836 -256.35331) (xy 345.514422 -256.35331) (xy 345.505787 -256.353653)
			(xy 345.489505 -256.359412) (xy 345.47608 -256.370277) (xy 345.471242 -256.37744) (xy 345.419934 -256.460244)
			(xy 345.418664 -256.486406) (xy 345.424506 -256.498344) (xy 345.434595 -256.519561) (xy 345.44885 -256.564324)
			(xy 345.456068 -256.610745) (xy 345.45651 -256.634234) (xy 345.456037 -256.658224) (xy 345.448527 -256.705611)
			(xy 345.433696 -256.751241) (xy 345.411911 -256.793989) (xy 345.383707 -256.832803) (xy 345.349779 -256.866728)
			(xy 345.310962 -256.894928) (xy 345.268211 -256.916708) (xy 345.22258 -256.931534) (xy 345.175192 -256.939039)
			(xy 345.151202 -256.939542) (xy 345.125491 -256.939011) (xy 345.074795 -256.930395) (xy 345.02626 -256.913406)
			(xy 344.981258 -256.888523) (xy 344.941061 -256.856452) (xy 344.906807 -256.818099) (xy 344.879464 -256.774548)
			(xy 344.859805 -256.727032) (xy 344.848387 -256.676893) (xy 344.846402 -256.651252) (xy 344.84564 -256.639822)
			(xy 344.84564 -256.634234) (xy 344.846071 -256.610703) (xy 344.853282 -256.564196) (xy 344.867538 -256.519345)
			(xy 344.877644 -256.49809) (xy 344.883486 -256.486152) (xy 344.88247 -256.45999) (xy 344.831162 -256.37744)
			(xy 344.826337 -256.370266) (xy 344.812899 -256.359405) (xy 344.79662 -256.353616) (xy 344.787982 -256.35331)
			(xy 343.634314 -256.35331) (xy 343.625679 -256.353654) (xy 343.609399 -256.359415) (xy 343.595976 -256.370281)
			(xy 343.591134 -256.37744) (xy 343.539826 -256.460244) (xy 343.538556 -256.486406) (xy 343.544398 -256.498344)
			(xy 343.554487 -256.519561) (xy 343.568742 -256.564324) (xy 343.57596 -256.610745) (xy 343.576402 -256.634234)
			(xy 343.575929 -256.658223) (xy 343.568418 -256.705611) (xy 343.553588 -256.75124) (xy 343.531803 -256.793987)
			(xy 343.503598 -256.832801) (xy 343.46967 -256.866724) (xy 343.430853 -256.894923) (xy 343.388103 -256.916703)
			(xy 343.342472 -256.931528) (xy 343.295083 -256.939032) (xy 343.271094 -256.939542) (xy 343.245383 -256.939011)
			(xy 343.194688 -256.930393) (xy 343.146154 -256.913403) (xy 343.101153 -256.888521) (xy 343.060958 -256.856449)
			(xy 343.026705 -256.818096) (xy 342.999363 -256.774546) (xy 342.979705 -256.72703) (xy 342.968287 -256.676892)
			(xy 342.966294 -256.651252) (xy 342.965532 -256.639822) (xy 342.965532 -256.634234) (xy 342.965963 -256.610703)
			(xy 342.973173 -256.564196) (xy 342.987429 -256.519344) (xy 342.997536 -256.49809) (xy 343.003378 -256.486152)
			(xy 343.002362 -256.45999) (xy 342.951054 -256.37744) (xy 342.946228 -256.370267) (xy 342.932791 -256.359408)
			(xy 342.916511 -256.353621) (xy 342.907874 -256.35331) (xy 342.69426 -256.35331) (xy 342.685621 -256.353647)
			(xy 342.66933 -256.359398) (xy 342.655895 -256.37026) (xy 342.65108 -256.37744) (xy 342.605868 -256.450338)
			(xy 342.604852 -256.476754) (xy 342.611202 -256.488946) (xy 342.622338 -256.511527) (xy 342.638085 -256.559346)
			(xy 342.646033 -256.609061) (xy 342.646508 -256.634234) (xy 342.646022 -256.659024) (xy 342.638266 -256.707992)
			(xy 342.622945 -256.755145) (xy 342.600436 -256.79932) (xy 342.571294 -256.839431) (xy 342.536237 -256.874488)
			(xy 342.496126 -256.90363) (xy 342.451951 -256.926139) (xy 342.404798 -256.94146) (xy 342.35583 -256.949216)
			(xy 342.30625 -256.949216) (xy 342.257282 -256.94146) (xy 342.210129 -256.926139) (xy 342.165954 -256.90363)
			(xy 342.125843 -256.874488) (xy 342.090786 -256.839431) (xy 342.061644 -256.79932) (xy 342.039135 -256.755145)
			(xy 342.023814 -256.707992) (xy 342.016058 -256.659024) (xy 342.015572 -256.634234) (xy 342.016044 -256.609061)
			(xy 342.023999 -256.559348) (xy 342.039745 -256.511528) (xy 342.050878 -256.488946) (xy 342.057228 -256.476754)
			(xy 342.056212 -256.450338) (xy 342.011 -256.37744) (xy 342.006172 -256.370273) (xy 341.992732 -256.359428)
			(xy 341.976454 -256.353658) (xy 341.96782 -256.35331) (xy 341.756238 -256.35331) (xy 341.752682 -256.353564)
			(xy 341.742137 -256.35479) (xy 341.723356 -256.36463) (xy 341.71636 -256.372614) (xy 341.713058 -256.377186)
			(xy 341.66048 -256.461514) (xy 341.65921 -256.48793) (xy 341.665052 -256.499614) (xy 341.674906 -256.520673)
			(xy 341.688831 -256.565031) (xy 341.695873 -256.610988) (xy 341.696294 -256.634234) (xy 341.695772 -256.659489)
			(xy 341.687459 -256.709311) (xy 341.671058 -256.757085) (xy 341.647017 -256.801508) (xy 341.615993 -256.841368)
			(xy 341.578831 -256.875578) (xy 341.536545 -256.903204) (xy 341.490289 -256.923494) (xy 341.441324 -256.935894)
			(xy 341.390986 -256.940065) (xy 341.340648 -256.935894) (xy 341.291683 -256.923494) (xy 341.245427 -256.903204)
			(xy 341.203141 -256.875578) (xy 341.165979 -256.841368) (xy 341.134955 -256.801508) (xy 341.110914 -256.757085)
			(xy 341.094513 -256.709311) (xy 341.0862 -256.659489) (xy 341.085678 -256.634234) (xy 341.086117 -256.610989)
			(xy 341.093165 -256.565038) (xy 341.10709 -256.520683) (xy 341.11692 -256.499614) (xy 341.122762 -256.48793)
			(xy 341.121492 -256.461514) (xy 341.068914 -256.377186) (xy 341.065612 -256.372614) (xy 341.058594 -256.364655)
			(xy 341.039828 -256.354799) (xy 341.02929 -256.353564) (xy 341.025734 -256.35331) (xy 340.816438 -256.35331)
			(xy 340.812882 -256.353564) (xy 340.802337 -256.35479) (xy 340.783556 -256.36463) (xy 340.77656 -256.372614)
			(xy 340.773258 -256.377186) (xy 340.72068 -256.461514) (xy 340.71941 -256.48793) (xy 340.725252 -256.499614)
			(xy 340.735106 -256.520673) (xy 340.749031 -256.565031) (xy 340.756073 -256.610988) (xy 340.756494 -256.634234)
			(xy 340.756021 -256.658223) (xy 340.74851 -256.70561) (xy 340.73368 -256.751238) (xy 340.711894 -256.793985)
			(xy 340.68369 -256.832798) (xy 340.649762 -256.866721) (xy 340.610944 -256.894919) (xy 340.568194 -256.916698)
			(xy 340.522563 -256.931522) (xy 340.475175 -256.939025) (xy 340.451186 -256.939542) (xy 340.438423 -256.939404)
			(xy 340.412989 -256.937244) (xy 340.400386 -256.935224) (xy 340.400386 -256.935478) (xy 340.377583 -256.931192)
			(xy 340.333526 -256.916648) (xy 340.29217 -256.895615) (xy 340.254466 -256.868577) (xy 340.237572 -256.852674)
			(xy 340.222586 -256.837942) (xy 340.181184 -256.838196) (xy 340.019386 -256.999994) (xy 340.011987 -257.006839)
			(xy 339.993389 -257.014569) (xy 339.983318 -257.01498) (xy 339.007704 -257.01498) (xy 339.002686 -257.015077)
			(xy 338.992837 -257.017004) (xy 338.988146 -257.01879) (xy 338.962492 -257.029458) (xy 338.955634 -257.036062)
			(xy 338.931708 -257.058321) (xy 338.879536 -257.097676) (xy 338.823109 -257.130643) (xy 338.763207 -257.156767)
			(xy 338.700655 -257.175689) (xy 338.636316 -257.187148) (xy 338.571078 -257.190985) (xy 338.50584 -257.187148)
			(xy 338.441501 -257.175689) (xy 338.378949 -257.156767) (xy 338.319047 -257.130643) (xy 338.26262 -257.097676)
			(xy 338.210448 -257.058321) (xy 338.186522 -257.036062) (xy 338.179664 -257.029458) (xy 338.15401 -257.01879)
			(xy 338.149323 -257.016991) (xy 338.139471 -257.015071) (xy 338.134452 -257.01498) (xy 328.404982 -257.01498)
			(xy 328.394913 -257.015406) (xy 328.376311 -257.023123) (xy 328.368914 -257.029966) (xy 328.182986 -257.215894)
			(xy 328.17562 -257.223006) (xy 328.168 -257.241802) (xy 328.168 -257.930142) (xy 346.651329 -257.930142)
			(xy 346.655359 -257.877644) (xy 346.667356 -257.826376) (xy 346.687039 -257.777541) (xy 346.713945 -257.732282)
			(xy 346.747445 -257.691661) (xy 346.786753 -257.65663) (xy 346.830948 -257.62801) (xy 346.878993 -257.606471)
			(xy 346.929764 -257.592519) (xy 346.982069 -257.586481) (xy 347.034683 -257.588498) (xy 347.086373 -257.598522)
			(xy 347.135926 -257.61632) (xy 347.182182 -257.641473) (xy 347.224056 -257.673392) (xy 347.260568 -257.71133)
			(xy 347.29086 -257.754396) (xy 347.314223 -257.801581) (xy 347.330109 -257.85178) (xy 347.338146 -257.903816)
			(xy 347.33865 -257.930142) (xy 348.551249 -257.930142) (xy 348.555279 -257.877644) (xy 348.567276 -257.826376)
			(xy 348.586959 -257.777541) (xy 348.613865 -257.732282) (xy 348.647365 -257.691661) (xy 348.686673 -257.65663)
			(xy 348.730868 -257.62801) (xy 348.778913 -257.606471) (xy 348.829684 -257.592519) (xy 348.881989 -257.586481)
			(xy 348.934603 -257.588498) (xy 348.986293 -257.598522) (xy 349.035846 -257.61632) (xy 349.082102 -257.641473)
			(xy 349.123976 -257.673392) (xy 349.160488 -257.71133) (xy 349.19078 -257.754396) (xy 349.214143 -257.801581)
			(xy 349.230029 -257.85178) (xy 349.238066 -257.903816) (xy 349.23857 -257.930142) (xy 350.451169 -257.930142)
			(xy 350.455199 -257.877644) (xy 350.467196 -257.826376) (xy 350.486879 -257.777541) (xy 350.513785 -257.732282)
			(xy 350.547285 -257.691661) (xy 350.586593 -257.65663) (xy 350.630788 -257.62801) (xy 350.678833 -257.606471)
			(xy 350.729604 -257.592519) (xy 350.781909 -257.586481) (xy 350.834523 -257.588498) (xy 350.886213 -257.598522)
			(xy 350.935766 -257.61632) (xy 350.982022 -257.641473) (xy 351.023896 -257.673392) (xy 351.060408 -257.71133)
			(xy 351.0907 -257.754396) (xy 351.114063 -257.801581) (xy 351.129949 -257.85178) (xy 351.137986 -257.903816)
			(xy 351.13849 -257.930142) (xy 351.137986 -257.956468) (xy 351.129949 -258.008504) (xy 351.114063 -258.058703)
			(xy 351.0907 -258.105888) (xy 351.060408 -258.148954) (xy 351.023896 -258.186892) (xy 350.982022 -258.218811)
			(xy 350.935766 -258.243964) (xy 350.886213 -258.261762) (xy 350.834523 -258.271786) (xy 350.781909 -258.273803)
			(xy 350.729604 -258.267765) (xy 350.678833 -258.253813) (xy 350.630788 -258.232274) (xy 350.586593 -258.203654)
			(xy 350.547285 -258.168623) (xy 350.513785 -258.128002) (xy 350.486879 -258.082743) (xy 350.467196 -258.033908)
			(xy 350.455199 -257.98264) (xy 350.451169 -257.930142) (xy 349.23857 -257.930142) (xy 349.238066 -257.956468)
			(xy 349.230029 -258.008504) (xy 349.214143 -258.058703) (xy 349.19078 -258.105888) (xy 349.160488 -258.148954)
			(xy 349.123976 -258.186892) (xy 349.082102 -258.218811) (xy 349.035846 -258.243964) (xy 348.986293 -258.261762)
			(xy 348.934603 -258.271786) (xy 348.881989 -258.273803) (xy 348.829684 -258.267765) (xy 348.778913 -258.253813)
			(xy 348.730868 -258.232274) (xy 348.686673 -258.203654) (xy 348.647365 -258.168623) (xy 348.613865 -258.128002)
			(xy 348.586959 -258.082743) (xy 348.567276 -258.033908) (xy 348.555279 -257.98264) (xy 348.551249 -257.930142)
			(xy 347.33865 -257.930142) (xy 347.338146 -257.956468) (xy 347.330109 -258.008504) (xy 347.314223 -258.058703)
			(xy 347.29086 -258.105888) (xy 347.260568 -258.148954) (xy 347.224056 -258.186892) (xy 347.182182 -258.218811)
			(xy 347.135926 -258.243964) (xy 347.086373 -258.261762) (xy 347.034683 -258.271786) (xy 346.982069 -258.273803)
			(xy 346.929764 -258.267765) (xy 346.878993 -258.253813) (xy 346.830948 -258.232274) (xy 346.786753 -258.203654)
			(xy 346.747445 -258.168623) (xy 346.713945 -258.128002) (xy 346.687039 -258.082743) (xy 346.667356 -258.033908)
			(xy 346.655359 -257.98264) (xy 346.651329 -257.930142) (xy 328.168 -257.930142) (xy 328.168 -258.379976)
			(xy 354.001327 -258.379976) (xy 354.005357 -258.327478) (xy 354.017354 -258.27621) (xy 354.037037 -258.227375)
			(xy 354.063943 -258.182116) (xy 354.097443 -258.141495) (xy 354.136751 -258.106464) (xy 354.180946 -258.077844)
			(xy 354.228991 -258.056305) (xy 354.279762 -258.042353) (xy 354.332067 -258.036315) (xy 354.384681 -258.038332)
			(xy 354.436371 -258.048356) (xy 354.485924 -258.066154) (xy 354.53218 -258.091307) (xy 354.574054 -258.123226)
			(xy 354.610566 -258.161164) (xy 354.640858 -258.20423) (xy 354.664221 -258.251415) (xy 354.680107 -258.301614)
			(xy 354.688144 -258.35365) (xy 354.688648 -258.379976) (xy 354.688144 -258.406302) (xy 354.680107 -258.458338)
			(xy 354.664221 -258.508537) (xy 354.640858 -258.555722) (xy 354.610566 -258.598788) (xy 354.574054 -258.636726)
			(xy 354.53218 -258.668645) (xy 354.485924 -258.693798) (xy 354.436371 -258.711596) (xy 354.384681 -258.72162)
			(xy 354.332067 -258.723637) (xy 354.279762 -258.717599) (xy 354.228991 -258.703647) (xy 354.180946 -258.682108)
			(xy 354.136751 -258.653488) (xy 354.097443 -258.618457) (xy 354.063943 -258.577836) (xy 354.037037 -258.532577)
			(xy 354.017354 -258.483742) (xy 354.005357 -258.432474) (xy 354.001327 -258.379976) (xy 328.168 -258.379976)
			(xy 328.168 -258.830064) (xy 346.651329 -258.830064) (xy 346.655359 -258.777566) (xy 346.667356 -258.726298)
			(xy 346.687039 -258.677463) (xy 346.713945 -258.632204) (xy 346.747445 -258.591583) (xy 346.786753 -258.556552)
			(xy 346.830948 -258.527932) (xy 346.878993 -258.506393) (xy 346.929764 -258.492441) (xy 346.982069 -258.486403)
			(xy 347.034683 -258.48842) (xy 347.086373 -258.498444) (xy 347.135926 -258.516242) (xy 347.182182 -258.541395)
			(xy 347.224056 -258.573314) (xy 347.260568 -258.611252) (xy 347.29086 -258.654318) (xy 347.314223 -258.701503)
			(xy 347.330109 -258.751702) (xy 347.338146 -258.803738) (xy 347.33865 -258.830064) (xy 348.551249 -258.830064)
			(xy 348.555279 -258.777566) (xy 348.567276 -258.726298) (xy 348.586959 -258.677463) (xy 348.613865 -258.632204)
			(xy 348.647365 -258.591583) (xy 348.686673 -258.556552) (xy 348.730868 -258.527932) (xy 348.778913 -258.506393)
			(xy 348.829684 -258.492441) (xy 348.881989 -258.486403) (xy 348.934603 -258.48842) (xy 348.986293 -258.498444)
			(xy 349.035846 -258.516242) (xy 349.082102 -258.541395) (xy 349.123976 -258.573314) (xy 349.160488 -258.611252)
			(xy 349.19078 -258.654318) (xy 349.214143 -258.701503) (xy 349.230029 -258.751702) (xy 349.238066 -258.803738)
			(xy 349.23857 -258.830064) (xy 350.451169 -258.830064) (xy 350.455199 -258.777566) (xy 350.467196 -258.726298)
			(xy 350.486879 -258.677463) (xy 350.513785 -258.632204) (xy 350.547285 -258.591583) (xy 350.586593 -258.556552)
			(xy 350.630788 -258.527932) (xy 350.678833 -258.506393) (xy 350.729604 -258.492441) (xy 350.781909 -258.486403)
			(xy 350.834523 -258.48842) (xy 350.886213 -258.498444) (xy 350.935766 -258.516242) (xy 350.982022 -258.541395)
			(xy 351.023896 -258.573314) (xy 351.060408 -258.611252) (xy 351.0907 -258.654318) (xy 351.114063 -258.701503)
			(xy 351.129949 -258.751702) (xy 351.137986 -258.803738) (xy 351.13849 -258.830064) (xy 351.137986 -258.85639)
			(xy 351.129949 -258.908426) (xy 351.114063 -258.958625) (xy 351.0907 -259.00581) (xy 351.060408 -259.048876)
			(xy 351.023896 -259.086814) (xy 350.982022 -259.118733) (xy 350.935766 -259.143886) (xy 350.886213 -259.161684)
			(xy 350.834523 -259.171708) (xy 350.781909 -259.173725) (xy 350.729604 -259.167687) (xy 350.678833 -259.153735)
			(xy 350.630788 -259.132196) (xy 350.586593 -259.103576) (xy 350.547285 -259.068545) (xy 350.513785 -259.027924)
			(xy 350.486879 -258.982665) (xy 350.467196 -258.93383) (xy 350.455199 -258.882562) (xy 350.451169 -258.830064)
			(xy 349.23857 -258.830064) (xy 349.238066 -258.85639) (xy 349.230029 -258.908426) (xy 349.214143 -258.958625)
			(xy 349.19078 -259.00581) (xy 349.160488 -259.048876) (xy 349.123976 -259.086814) (xy 349.082102 -259.118733)
			(xy 349.035846 -259.143886) (xy 348.986293 -259.161684) (xy 348.934603 -259.171708) (xy 348.881989 -259.173725)
			(xy 348.829684 -259.167687) (xy 348.778913 -259.153735) (xy 348.730868 -259.132196) (xy 348.686673 -259.103576)
			(xy 348.647365 -259.068545) (xy 348.613865 -259.027924) (xy 348.586959 -258.982665) (xy 348.567276 -258.93383)
			(xy 348.555279 -258.882562) (xy 348.551249 -258.830064) (xy 347.33865 -258.830064) (xy 347.338146 -258.85639)
			(xy 347.330109 -258.908426) (xy 347.314223 -258.958625) (xy 347.29086 -259.00581) (xy 347.260568 -259.048876)
			(xy 347.224056 -259.086814) (xy 347.182182 -259.118733) (xy 347.135926 -259.143886) (xy 347.086373 -259.161684)
			(xy 347.034683 -259.171708) (xy 346.982069 -259.173725) (xy 346.929764 -259.167687) (xy 346.878993 -259.153735)
			(xy 346.830948 -259.132196) (xy 346.786753 -259.103576) (xy 346.747445 -259.068545) (xy 346.713945 -259.027924)
			(xy 346.687039 -258.982665) (xy 346.667356 -258.93383) (xy 346.655359 -258.882562) (xy 346.651329 -258.830064)
			(xy 328.168 -258.830064) (xy 328.168 -259.33019) (xy 354.001327 -259.33019) (xy 354.005357 -259.277692)
			(xy 354.017354 -259.226424) (xy 354.037037 -259.177589) (xy 354.063943 -259.13233) (xy 354.097443 -259.091709)
			(xy 354.136751 -259.056678) (xy 354.180946 -259.028058) (xy 354.228991 -259.006519) (xy 354.279762 -258.992567)
			(xy 354.332067 -258.986529) (xy 354.384681 -258.988546) (xy 354.436371 -258.99857) (xy 354.485924 -259.016368)
			(xy 354.53218 -259.041521) (xy 354.574054 -259.07344) (xy 354.610566 -259.111378) (xy 354.640858 -259.154444)
			(xy 354.664221 -259.201629) (xy 354.680107 -259.251828) (xy 354.688144 -259.303864) (xy 354.688648 -259.33019)
			(xy 354.688144 -259.356516) (xy 354.680107 -259.408552) (xy 354.664221 -259.458751) (xy 354.640858 -259.505936)
			(xy 354.610566 -259.549002) (xy 354.574054 -259.58694) (xy 354.53218 -259.618859) (xy 354.485924 -259.644012)
			(xy 354.436371 -259.66181) (xy 354.384681 -259.671834) (xy 354.332067 -259.673851) (xy 354.279762 -259.667813)
			(xy 354.228991 -259.653861) (xy 354.180946 -259.632322) (xy 354.136751 -259.603702) (xy 354.097443 -259.568671)
			(xy 354.063943 -259.52805) (xy 354.037037 -259.482791) (xy 354.017354 -259.433956) (xy 354.005357 -259.382688)
			(xy 354.001327 -259.33019) (xy 328.168 -259.33019) (xy 328.168 -259.729986) (xy 346.651329 -259.729986)
			(xy 346.655359 -259.677488) (xy 346.667356 -259.62622) (xy 346.687039 -259.577385) (xy 346.713945 -259.532126)
			(xy 346.747445 -259.491505) (xy 346.786753 -259.456474) (xy 346.830948 -259.427854) (xy 346.878993 -259.406315)
			(xy 346.929764 -259.392363) (xy 346.982069 -259.386325) (xy 347.034683 -259.388342) (xy 347.086373 -259.398366)
			(xy 347.135926 -259.416164) (xy 347.182182 -259.441317) (xy 347.224056 -259.473236) (xy 347.260568 -259.511174)
			(xy 347.29086 -259.55424) (xy 347.314223 -259.601425) (xy 347.330109 -259.651624) (xy 347.338146 -259.70366)
			(xy 347.33865 -259.729986) (xy 348.551249 -259.729986) (xy 348.555279 -259.677488) (xy 348.567276 -259.62622)
			(xy 348.586959 -259.577385) (xy 348.613865 -259.532126) (xy 348.647365 -259.491505) (xy 348.686673 -259.456474)
			(xy 348.730868 -259.427854) (xy 348.778913 -259.406315) (xy 348.829684 -259.392363) (xy 348.881989 -259.386325)
			(xy 348.934603 -259.388342) (xy 348.986293 -259.398366) (xy 349.035846 -259.416164) (xy 349.082102 -259.441317)
			(xy 349.123976 -259.473236) (xy 349.160488 -259.511174) (xy 349.19078 -259.55424) (xy 349.214143 -259.601425)
			(xy 349.230029 -259.651624) (xy 349.238066 -259.70366) (xy 349.23857 -259.729986) (xy 350.451169 -259.729986)
			(xy 350.455199 -259.677488) (xy 350.467196 -259.62622) (xy 350.486879 -259.577385) (xy 350.513785 -259.532126)
			(xy 350.547285 -259.491505) (xy 350.586593 -259.456474) (xy 350.630788 -259.427854) (xy 350.678833 -259.406315)
			(xy 350.729604 -259.392363) (xy 350.781909 -259.386325) (xy 350.834523 -259.388342) (xy 350.886213 -259.398366)
			(xy 350.935766 -259.416164) (xy 350.982022 -259.441317) (xy 351.023896 -259.473236) (xy 351.060408 -259.511174)
			(xy 351.0907 -259.55424) (xy 351.114063 -259.601425) (xy 351.129949 -259.651624) (xy 351.137986 -259.70366)
			(xy 351.13849 -259.729986) (xy 351.137986 -259.756312) (xy 351.129949 -259.808348) (xy 351.114063 -259.858547)
			(xy 351.0907 -259.905732) (xy 351.060408 -259.948798) (xy 351.023896 -259.986736) (xy 350.982022 -260.018655)
			(xy 350.935766 -260.043808) (xy 350.886213 -260.061606) (xy 350.834523 -260.07163) (xy 350.781909 -260.073647)
			(xy 350.729604 -260.067609) (xy 350.678833 -260.053657) (xy 350.630788 -260.032118) (xy 350.586593 -260.003498)
			(xy 350.547285 -259.968467) (xy 350.513785 -259.927846) (xy 350.486879 -259.882587) (xy 350.467196 -259.833752)
			(xy 350.455199 -259.782484) (xy 350.451169 -259.729986) (xy 349.23857 -259.729986) (xy 349.238066 -259.756312)
			(xy 349.230029 -259.808348) (xy 349.214143 -259.858547) (xy 349.19078 -259.905732) (xy 349.160488 -259.948798)
			(xy 349.123976 -259.986736) (xy 349.082102 -260.018655) (xy 349.035846 -260.043808) (xy 348.986293 -260.061606)
			(xy 348.934603 -260.07163) (xy 348.881989 -260.073647) (xy 348.829684 -260.067609) (xy 348.778913 -260.053657)
			(xy 348.730868 -260.032118) (xy 348.686673 -260.003498) (xy 348.647365 -259.968467) (xy 348.613865 -259.927846)
			(xy 348.586959 -259.882587) (xy 348.567276 -259.833752) (xy 348.555279 -259.782484) (xy 348.551249 -259.729986)
			(xy 347.33865 -259.729986) (xy 347.338146 -259.756312) (xy 347.330109 -259.808348) (xy 347.314223 -259.858547)
			(xy 347.29086 -259.905732) (xy 347.260568 -259.948798) (xy 347.224056 -259.986736) (xy 347.182182 -260.018655)
			(xy 347.135926 -260.043808) (xy 347.086373 -260.061606) (xy 347.034683 -260.07163) (xy 346.982069 -260.073647)
			(xy 346.929764 -260.067609) (xy 346.878993 -260.053657) (xy 346.830948 -260.032118) (xy 346.786753 -260.003498)
			(xy 346.747445 -259.968467) (xy 346.713945 -259.927846) (xy 346.687039 -259.882587) (xy 346.667356 -259.833752)
			(xy 346.655359 -259.782484) (xy 346.651329 -259.729986) (xy 328.168 -259.729986) (xy 328.168 -260.28015)
			(xy 354.001327 -260.28015) (xy 354.005357 -260.227652) (xy 354.017354 -260.176384) (xy 354.037037 -260.127549)
			(xy 354.063943 -260.08229) (xy 354.097443 -260.041669) (xy 354.136751 -260.006638) (xy 354.180946 -259.978018)
			(xy 354.228991 -259.956479) (xy 354.279762 -259.942527) (xy 354.332067 -259.936489) (xy 354.384681 -259.938506)
			(xy 354.436371 -259.94853) (xy 354.485924 -259.966328) (xy 354.53218 -259.991481) (xy 354.574054 -260.0234)
			(xy 354.610566 -260.061338) (xy 354.640858 -260.104404) (xy 354.664221 -260.151589) (xy 354.680107 -260.201788)
			(xy 354.688144 -260.253824) (xy 354.688648 -260.28015) (xy 354.688144 -260.306476) (xy 354.680107 -260.358512)
			(xy 354.664221 -260.408711) (xy 354.640858 -260.455896) (xy 354.610566 -260.498962) (xy 354.574054 -260.5369)
			(xy 354.53218 -260.568819) (xy 354.485924 -260.593972) (xy 354.436371 -260.61177) (xy 354.384681 -260.621794)
			(xy 354.332067 -260.623811) (xy 354.279762 -260.617773) (xy 354.228991 -260.603821) (xy 354.180946 -260.582282)
			(xy 354.136751 -260.553662) (xy 354.097443 -260.518631) (xy 354.063943 -260.47801) (xy 354.037037 -260.432751)
			(xy 354.017354 -260.383916) (xy 354.005357 -260.332648) (xy 354.001327 -260.28015) (xy 328.168 -260.28015)
			(xy 328.168 -261.098538) (xy 328.168464 -261.108413) (xy 328.175912 -261.126707) (xy 328.182478 -261.134098)
			(xy 328.182732 -261.134352) (xy 328.457814 -261.409434) (xy 328.458322 -261.409942) (xy 328.465701 -261.41653)
			(xy 328.484 -261.423993) (xy 328.493882 -261.42442) (xy 329.114912 -261.42442) (xy 329.123722 -261.424001)
			(xy 329.140278 -261.41796) (xy 329.153829 -261.406691) (xy 329.1586 -261.399274) (xy 329.209908 -261.312406)
			(xy 329.210416 -261.285482) (xy 329.203812 -261.273544) (xy 329.191773 -261.250606) (xy 329.174733 -261.201689)
			(xy 329.166167 -261.150602) (xy 329.165712 -261.1247) (xy 329.165712 -261.120128) (xy 329.166685 -261.095189)
			(xy 329.175741 -261.046112) (xy 329.192656 -260.99916) (xy 329.216982 -260.955583) (xy 329.248069 -260.916542)
			(xy 329.285091 -260.883076) (xy 329.327062 -260.856075) (xy 329.372865 -260.836259) (xy 329.42128 -260.824154)
			(xy 329.47102 -260.820083) (xy 329.52076 -260.824154) (xy 329.569175 -260.836259) (xy 329.614978 -260.856075)
			(xy 329.656949 -260.883076) (xy 329.693971 -260.916542) (xy 329.725058 -260.955583) (xy 329.749384 -260.99916)
			(xy 329.766299 -261.046112) (xy 329.775355 -261.095189) (xy 329.776328 -261.120128) (xy 329.776328 -261.1247)
			(xy 329.775927 -261.150608) (xy 329.767392 -261.201712) (xy 329.750331 -261.250634) (xy 329.738228 -261.273544)
			(xy 329.731624 -261.285482) (xy 329.732132 -261.312406) (xy 329.78344 -261.399274) (xy 329.788203 -261.406705)
			(xy 329.801735 -261.418016) (xy 329.81831 -261.424045) (xy 329.827128 -261.42442) (xy 330.054966 -261.42442)
			(xy 330.063771 -261.423993) (xy 330.080314 -261.417939) (xy 330.09385 -261.406666) (xy 330.098654 -261.399274)
			(xy 330.149962 -261.312406) (xy 330.15047 -261.285482) (xy 330.143866 -261.273544) (xy 330.131828 -261.250605)
			(xy 330.114791 -261.201688) (xy 330.106226 -261.150601) (xy 330.105766 -261.1247) (xy 330.105766 -261.120128)
			(xy 330.106739 -261.095189) (xy 330.115795 -261.046112) (xy 330.13271 -260.99916) (xy 330.157036 -260.955583)
			(xy 330.188123 -260.916542) (xy 330.225145 -260.883076) (xy 330.267116 -260.856075) (xy 330.312919 -260.836259)
			(xy 330.361334 -260.824154) (xy 330.411074 -260.820083) (xy 330.460814 -260.824154) (xy 330.509229 -260.836259)
			(xy 330.555032 -260.856075) (xy 330.597003 -260.883076) (xy 330.634025 -260.916542) (xy 330.665112 -260.955583)
			(xy 330.689438 -260.99916) (xy 330.706353 -261.046112) (xy 330.715409 -261.095189) (xy 330.716382 -261.120128)
			(xy 330.716382 -261.1247) (xy 330.71598 -261.150608) (xy 330.707445 -261.201711) (xy 330.690382 -261.250632)
			(xy 330.678282 -261.273544) (xy 330.671678 -261.285482) (xy 330.672186 -261.312406) (xy 330.723494 -261.399274)
			(xy 330.728259 -261.406699) (xy 330.741794 -261.417996) (xy 330.758367 -261.424007) (xy 330.767182 -261.42442)
			(xy 330.99502 -261.42442) (xy 331.003829 -261.424) (xy 331.020383 -261.417957) (xy 331.033932 -261.406687)
			(xy 331.038708 -261.399274) (xy 331.090016 -261.312406) (xy 331.090524 -261.285482) (xy 331.08392 -261.273544)
			(xy 331.07188 -261.250606) (xy 331.05484 -261.201689) (xy 331.046274 -261.150602) (xy 331.04582 -261.1247)
			(xy 331.04582 -261.120128) (xy 331.046793 -261.095189) (xy 331.055849 -261.046112) (xy 331.072764 -260.99916)
			(xy 331.09709 -260.955583) (xy 331.128177 -260.916542) (xy 331.165199 -260.883076) (xy 331.20717 -260.856075)
			(xy 331.252973 -260.836259) (xy 331.301388 -260.824154) (xy 331.351128 -260.820083) (xy 331.400868 -260.824154)
			(xy 331.449283 -260.836259) (xy 331.495086 -260.856075) (xy 331.537057 -260.883076) (xy 331.574079 -260.916542)
			(xy 331.605166 -260.955583) (xy 331.629492 -260.99916) (xy 331.646407 -261.046112) (xy 331.655463 -261.095189)
			(xy 331.656436 -261.120128) (xy 331.656436 -261.1247) (xy 331.656034 -261.150608) (xy 331.647498 -261.20171)
			(xy 331.630432 -261.25063) (xy 331.618336 -261.273544) (xy 331.611732 -261.285482) (xy 331.61224 -261.312406)
			(xy 331.663548 -261.399274) (xy 331.668311 -261.406705) (xy 331.681844 -261.418014) (xy 331.698418 -261.424039)
			(xy 331.707236 -261.42442) (xy 331.935074 -261.42442) (xy 331.943878 -261.423992) (xy 331.960419 -261.417936)
			(xy 331.973953 -261.406663) (xy 331.978762 -261.399274) (xy 332.03007 -261.312406) (xy 332.030578 -261.285482)
			(xy 332.023974 -261.273544) (xy 332.011936 -261.250605) (xy 331.994898 -261.201688) (xy 331.986333 -261.150601)
			(xy 331.985874 -261.1247) (xy 331.985874 -261.120128) (xy 331.986847 -261.095189) (xy 331.995903 -261.046112)
			(xy 332.012818 -260.99916) (xy 332.037144 -260.955583) (xy 332.068231 -260.916542) (xy 332.105253 -260.883076)
			(xy 332.147224 -260.856075) (xy 332.193027 -260.836259) (xy 332.241442 -260.824154) (xy 332.291182 -260.820083)
			(xy 332.340922 -260.824154) (xy 332.389337 -260.836259) (xy 332.43514 -260.856075) (xy 332.477111 -260.883076)
			(xy 332.514133 -260.916542) (xy 332.54522 -260.955583) (xy 332.569546 -260.99916) (xy 332.586461 -261.046112)
			(xy 332.595517 -261.095189) (xy 332.59649 -261.120128) (xy 332.59649 -261.1247) (xy 332.596088 -261.150608)
			(xy 332.587553 -261.201711) (xy 332.570491 -261.250632) (xy 332.55839 -261.273544) (xy 332.551786 -261.285482)
			(xy 332.552294 -261.312406) (xy 332.603602 -261.399274) (xy 332.608368 -261.406699) (xy 332.621903 -261.417993)
			(xy 332.638476 -261.424001) (xy 332.64729 -261.42442) (xy 332.874874 -261.42442) (xy 332.883678 -261.423992)
			(xy 332.900219 -261.417936) (xy 332.913753 -261.406663) (xy 332.918562 -261.399274) (xy 332.96987 -261.312406)
			(xy 332.970378 -261.285482) (xy 332.963774 -261.273544) (xy 332.951736 -261.250605) (xy 332.934698 -261.201688)
			(xy 332.926133 -261.150601) (xy 332.925674 -261.1247) (xy 332.925674 -261.120128) (xy 332.926647 -261.095189)
			(xy 332.935703 -261.046112) (xy 332.952618 -260.99916) (xy 332.976944 -260.955583) (xy 333.008031 -260.916542)
			(xy 333.045053 -260.883076) (xy 333.087024 -260.856075) (xy 333.132827 -260.836259) (xy 333.181242 -260.824154)
			(xy 333.230982 -260.820083) (xy 333.280722 -260.824154) (xy 333.329137 -260.836259) (xy 333.37494 -260.856075)
			(xy 333.416911 -260.883076) (xy 333.453933 -260.916542) (xy 333.48502 -260.955583) (xy 333.509346 -260.99916)
			(xy 333.526261 -261.046112) (xy 333.535317 -261.095189) (xy 333.53629 -261.120128) (xy 333.53629 -261.1247)
			(xy 333.535888 -261.150608) (xy 333.527353 -261.201711) (xy 333.510291 -261.250632) (xy 333.49819 -261.273544)
			(xy 333.491586 -261.285482) (xy 333.492094 -261.312406) (xy 333.543402 -261.399274) (xy 333.548168 -261.406699)
			(xy 333.561703 -261.417993) (xy 333.578276 -261.424001) (xy 333.58709 -261.42442) (xy 333.814928 -261.42442)
			(xy 333.823736 -261.423999) (xy 333.840289 -261.417954) (xy 333.853835 -261.406683) (xy 333.858616 -261.399274)
			(xy 333.909924 -261.312406) (xy 333.910432 -261.285482) (xy 333.903828 -261.273544) (xy 333.891788 -261.250606)
			(xy 333.874747 -261.201689) (xy 333.866181 -261.150602) (xy 333.865728 -261.1247) (xy 333.865728 -261.120128)
			(xy 333.866701 -261.095189) (xy 333.875757 -261.046112) (xy 333.892672 -260.99916) (xy 333.916998 -260.955583)
			(xy 333.948085 -260.916542) (xy 333.985107 -260.883076) (xy 334.027078 -260.856075) (xy 334.072881 -260.836259)
			(xy 334.121296 -260.824154) (xy 334.171036 -260.820083) (xy 334.220776 -260.824154) (xy 334.269191 -260.836259)
			(xy 334.314994 -260.856075) (xy 334.356965 -260.883076) (xy 334.393987 -260.916542) (xy 334.425074 -260.955583)
			(xy 334.4494 -260.99916) (xy 334.466315 -261.046112) (xy 334.475371 -261.095189) (xy 334.476344 -261.120128)
			(xy 334.476344 -261.1247) (xy 334.475942 -261.150608) (xy 334.467406 -261.201711) (xy 334.450341 -261.250631)
			(xy 334.438244 -261.273544) (xy 334.43164 -261.285482) (xy 334.432148 -261.312406) (xy 334.483456 -261.399274)
			(xy 334.488219 -261.406704) (xy 334.501752 -261.418011) (xy 334.518327 -261.424034) (xy 334.527144 -261.42442)
			(xy 335.695036 -261.42442) (xy 335.703844 -261.423998) (xy 335.720394 -261.417951) (xy 335.733938 -261.40668)
			(xy 335.738724 -261.399274) (xy 335.790032 -261.312406) (xy 335.79054 -261.285482) (xy 335.783936 -261.273544)
			(xy 335.771896 -261.250606) (xy 335.754854 -261.201689) (xy 335.746288 -261.150602) (xy 335.745836 -261.1247)
			(xy 335.745836 -261.120128) (xy 335.746809 -261.095189) (xy 335.755865 -261.046112) (xy 335.77278 -260.99916)
			(xy 335.797106 -260.955583) (xy 335.828193 -260.916542) (xy 335.865215 -260.883076) (xy 335.907186 -260.856075)
			(xy 335.952989 -260.836259) (xy 336.001404 -260.824154) (xy 336.051144 -260.820083) (xy 336.100884 -260.824154)
			(xy 336.149299 -260.836259) (xy 336.195102 -260.856075) (xy 336.237073 -260.883076) (xy 336.274095 -260.916542)
			(xy 336.305182 -260.955583) (xy 336.329508 -260.99916) (xy 336.346423 -261.046112) (xy 336.355479 -261.095189)
			(xy 336.356452 -261.120128) (xy 336.356452 -261.1247) (xy 336.35605 -261.150608) (xy 336.347514 -261.201711)
			(xy 336.33045 -261.250631) (xy 336.318352 -261.273544) (xy 336.311748 -261.285482) (xy 336.312256 -261.312406)
			(xy 336.363564 -261.399274) (xy 336.368328 -261.406703) (xy 336.381861 -261.418008) (xy 336.398435 -261.424028)
			(xy 336.407252 -261.42442) (xy 336.63509 -261.42442) (xy 336.643902 -261.424005) (xy 336.660464 -261.417968)
			(xy 336.67402 -261.4067) (xy 336.678778 -261.399274) (xy 336.730086 -261.312406) (xy 336.730594 -261.285482)
			(xy 336.72399 -261.273544) (xy 336.711951 -261.250606) (xy 336.694913 -261.201688) (xy 336.686347 -261.150601)
			(xy 336.68589 -261.1247) (xy 336.68589 -261.120128) (xy 336.686863 -261.095189) (xy 336.695919 -261.046112)
			(xy 336.712834 -260.99916) (xy 336.73716 -260.955583) (xy 336.768247 -260.916542) (xy 336.805269 -260.883076)
			(xy 336.84724 -260.856075) (xy 336.893043 -260.836259) (xy 336.941458 -260.824154) (xy 336.991198 -260.820083)
			(xy 337.040938 -260.824154) (xy 337.089353 -260.836259) (xy 337.135156 -260.856075) (xy 337.177127 -260.883076)
			(xy 337.214149 -260.916542) (xy 337.245236 -260.955583) (xy 337.269562 -260.99916) (xy 337.286477 -261.046112)
			(xy 337.295533 -261.095189) (xy 337.296506 -261.120128) (xy 337.296506 -261.1247) (xy 337.296104 -261.150608)
			(xy 337.28757 -261.201711) (xy 337.270508 -261.250633) (xy 337.258406 -261.273544) (xy 337.251802 -261.285482)
			(xy 337.25231 -261.312406) (xy 337.303618 -261.399274) (xy 337.308384 -261.406697) (xy 337.32192 -261.417987)
			(xy 337.338493 -261.42399) (xy 337.347306 -261.42442) (xy 337.57489 -261.42442) (xy 337.583702 -261.424005)
			(xy 337.600264 -261.417968) (xy 337.61382 -261.4067) (xy 337.618578 -261.399274) (xy 337.669886 -261.312406)
			(xy 337.670394 -261.285482) (xy 337.66379 -261.273544) (xy 337.651751 -261.250606) (xy 337.634713 -261.201688)
			(xy 337.626147 -261.150601) (xy 337.62569 -261.1247) (xy 337.62569 -261.120128) (xy 337.626663 -261.095189)
			(xy 337.635719 -261.046112) (xy 337.652634 -260.99916) (xy 337.67696 -260.955583) (xy 337.708047 -260.916542)
			(xy 337.745069 -260.883076) (xy 337.78704 -260.856075) (xy 337.832843 -260.836259) (xy 337.881258 -260.824154)
			(xy 337.930998 -260.820083) (xy 337.980738 -260.824154) (xy 338.029153 -260.836259) (xy 338.074956 -260.856075)
			(xy 338.116927 -260.883076) (xy 338.153949 -260.916542) (xy 338.185036 -260.955583) (xy 338.209362 -260.99916)
			(xy 338.226277 -261.046112) (xy 338.235333 -261.095189) (xy 338.236306 -261.120128) (xy 338.236306 -261.1247)
			(xy 338.235904 -261.150608) (xy 338.22737 -261.201711) (xy 338.210308 -261.250633) (xy 338.198206 -261.273544)
			(xy 338.191602 -261.285482) (xy 338.19211 -261.312406) (xy 338.243418 -261.399274) (xy 338.248184 -261.406697)
			(xy 338.26172 -261.417987) (xy 338.278293 -261.42399) (xy 338.287106 -261.42442) (xy 338.514944 -261.42442)
			(xy 338.523751 -261.423996) (xy 338.540299 -261.417948) (xy 338.553841 -261.406676) (xy 338.558632 -261.399274)
			(xy 338.60994 -261.312406) (xy 338.610448 -261.285482) (xy 338.603844 -261.273544) (xy 338.591803 -261.250606)
			(xy 338.574762 -261.201689) (xy 338.566195 -261.150602) (xy 338.565744 -261.1247) (xy 338.565744 -261.120128)
			(xy 338.566717 -261.095189) (xy 338.575773 -261.046112) (xy 338.592688 -260.99916) (xy 338.617014 -260.955583)
			(xy 338.648101 -260.916542) (xy 338.685123 -260.883076) (xy 338.727094 -260.856075) (xy 338.772897 -260.836259)
			(xy 338.821312 -260.824154) (xy 338.871052 -260.820083) (xy 338.920792 -260.824154) (xy 338.969207 -260.836259)
			(xy 339.01501 -260.856075) (xy 339.056981 -260.883076) (xy 339.094003 -260.916542) (xy 339.12509 -260.955583)
			(xy 339.149416 -260.99916) (xy 339.166331 -261.046112) (xy 339.175387 -261.095189) (xy 339.17636 -261.120128)
			(xy 339.17636 -261.1247) (xy 339.175958 -261.150608) (xy 339.167422 -261.201711) (xy 339.150358 -261.250631)
			(xy 339.13826 -261.273544) (xy 339.131656 -261.285482) (xy 339.132164 -261.312406) (xy 339.183472 -261.399274)
			(xy 339.188236 -261.406702) (xy 339.20177 -261.418005) (xy 339.218344 -261.424023) (xy 339.22716 -261.42442)
			(xy 339.454998 -261.42442) (xy 339.463809 -261.424004) (xy 339.480369 -261.417965) (xy 339.493923 -261.406697)
			(xy 339.498686 -261.399274) (xy 339.549994 -261.312406) (xy 339.550502 -261.285482) (xy 339.543898 -261.273544)
			(xy 339.531859 -261.250606) (xy 339.51482 -261.201688) (xy 339.506254 -261.150601) (xy 339.505798 -261.1247)
			(xy 339.505798 -261.120128) (xy 339.506694 -261.096436) (xy 339.514908 -261.049745) (xy 339.530242 -261.004884)
			(xy 339.552326 -260.962934) (xy 339.580631 -260.924902) (xy 339.614475 -260.891703) (xy 339.653045 -260.864136)
			(xy 339.695413 -260.842864) (xy 339.74056 -260.828397) (xy 339.787402 -260.821084) (xy 339.811106 -260.820662)
			(xy 339.83487 -260.821115) (xy 339.881822 -260.82848) (xy 339.927067 -260.843031) (xy 339.969511 -260.864417)
			(xy 340.008129 -260.892121) (xy 340.041987 -260.925474) (xy 340.070269 -260.96367) (xy 340.092291 -261.005787)
			(xy 340.107522 -261.050807) (xy 340.115593 -261.097644) (xy 340.116414 -261.121398) (xy 340.116414 -261.126224)
			(xy 340.116058 -261.147094) (xy 340.110342 -261.188441) (xy 340.099046 -261.228624) (xy 340.091014 -261.24789)
			(xy 340.091014 -261.248144) (xy 340.087732 -261.256551) (xy 340.086679 -261.274556) (xy 340.091926 -261.291812)
			(xy 340.09711 -261.299198) (xy 340.159594 -261.380986) (xy 340.185248 -261.3914) (xy 340.198964 -261.389368)
			(xy 340.219354 -261.386509) (xy 340.260418 -261.383456) (xy 340.281006 -261.383272) (xy 340.301595 -261.383453)
			(xy 340.342658 -261.386507) (xy 340.363048 -261.389368) (xy 340.376764 -261.3914) (xy 340.402418 -261.380986)
			(xy 340.465156 -261.299452) (xy 340.470345 -261.292016) (xy 340.475619 -261.274678) (xy 340.474558 -261.256588)
			(xy 340.471252 -261.248144) (xy 340.471252 -261.24789) (xy 340.463291 -261.228734) (xy 340.452033 -261.188808)
			(xy 340.446284 -261.147726) (xy 340.445852 -261.126986) (xy 340.445852 -261.121398) (xy 340.446656 -261.09764)
			(xy 340.454715 -261.050793) (xy 340.469938 -261.005762) (xy 340.491957 -260.963635) (xy 340.520239 -260.925429)
			(xy 340.554102 -260.892069) (xy 340.592726 -260.864361) (xy 340.635177 -260.842974) (xy 340.680431 -260.828426)
			(xy 340.727393 -260.821067) (xy 340.75116 -260.820662) (xy 340.775156 -260.821105) (xy 340.822558 -260.828607)
			(xy 340.868203 -260.843431) (xy 340.910967 -260.865214) (xy 340.949797 -260.893419) (xy 340.983736 -260.92735)
			(xy 341.011949 -260.966173) (xy 341.033742 -261.008932) (xy 341.048577 -261.054574) (xy 341.056089 -261.101974)
			(xy 341.056468 -261.12597) (xy 342.32521 -261.12597) (xy 342.32917 -261.076916) (xy 342.340947 -261.029132)
			(xy 342.360238 -260.983856) (xy 342.386541 -260.94226) (xy 342.419176 -260.905423) (xy 342.457297 -260.874298)
			(xy 342.499918 -260.849691) (xy 342.545934 -260.832239) (xy 342.594153 -260.822395) (xy 342.643328 -260.820414)
			(xy 342.692183 -260.826346) (xy 342.739454 -260.840038) (xy 342.783916 -260.861136) (xy 342.824419 -260.889092)
			(xy 342.859912 -260.923184) (xy 342.889477 -260.962528) (xy 342.912348 -261.006105) (xy 342.927932 -261.052786)
			(xy 342.935827 -261.101363) (xy 342.936322 -261.12597) (xy 343.265264 -261.12597) (xy 343.269224 -261.076916)
			(xy 343.281001 -261.029132) (xy 343.300292 -260.983856) (xy 343.326595 -260.94226) (xy 343.35923 -260.905423)
			(xy 343.397351 -260.874298) (xy 343.439972 -260.849691) (xy 343.485988 -260.832239) (xy 343.534207 -260.822395)
			(xy 343.583382 -260.820414) (xy 343.632237 -260.826346) (xy 343.679508 -260.840038) (xy 343.72397 -260.861136)
			(xy 343.764473 -260.889092) (xy 343.799966 -260.923184) (xy 343.829531 -260.962528) (xy 343.852402 -261.006105)
			(xy 343.867986 -261.052786) (xy 343.875881 -261.101363) (xy 343.876376 -261.12597) (xy 344.205318 -261.12597)
			(xy 344.209278 -261.076916) (xy 344.221055 -261.029132) (xy 344.240346 -260.983856) (xy 344.266649 -260.94226)
			(xy 344.299284 -260.905423) (xy 344.337405 -260.874298) (xy 344.380026 -260.849691) (xy 344.426042 -260.832239)
			(xy 344.474261 -260.822395) (xy 344.523436 -260.820414) (xy 344.572291 -260.826346) (xy 344.619562 -260.840038)
			(xy 344.664024 -260.861136) (xy 344.704527 -260.889092) (xy 344.74002 -260.923184) (xy 344.769585 -260.962528)
			(xy 344.792456 -261.006105) (xy 344.80804 -261.052786) (xy 344.815935 -261.101363) (xy 344.81643 -261.12597)
			(xy 346.085426 -261.12597) (xy 346.089386 -261.076916) (xy 346.101163 -261.029132) (xy 346.120454 -260.983856)
			(xy 346.146757 -260.94226) (xy 346.179392 -260.905423) (xy 346.217513 -260.874298) (xy 346.260134 -260.849691)
			(xy 346.30615 -260.832239) (xy 346.354369 -260.822395) (xy 346.403544 -260.820414) (xy 346.452399 -260.826346)
			(xy 346.49967 -260.840038) (xy 346.544132 -260.861136) (xy 346.584635 -260.889092) (xy 346.620128 -260.923184)
			(xy 346.649693 -260.962528) (xy 346.672564 -261.006105) (xy 346.688148 -261.052786) (xy 346.696043 -261.101363)
			(xy 346.696538 -261.12597) (xy 347.96528 -261.12597) (xy 347.96924 -261.076916) (xy 347.981017 -261.029132)
			(xy 348.000308 -260.983856) (xy 348.026611 -260.94226) (xy 348.059246 -260.905423) (xy 348.097367 -260.874298)
			(xy 348.139988 -260.849691) (xy 348.186004 -260.832239) (xy 348.234223 -260.822395) (xy 348.283398 -260.820414)
			(xy 348.332253 -260.826346) (xy 348.379524 -260.840038) (xy 348.423986 -260.861136) (xy 348.464489 -260.889092)
			(xy 348.499982 -260.923184) (xy 348.529547 -260.962528) (xy 348.552418 -261.006105) (xy 348.568002 -261.052786)
			(xy 348.575897 -261.101363) (xy 348.576392 -261.12597) (xy 348.905334 -261.12597) (xy 348.909294 -261.076916)
			(xy 348.921071 -261.029132) (xy 348.940362 -260.983856) (xy 348.966665 -260.94226) (xy 348.9993 -260.905423)
			(xy 349.037421 -260.874298) (xy 349.080042 -260.849691) (xy 349.126058 -260.832239) (xy 349.174277 -260.822395)
			(xy 349.223452 -260.820414) (xy 349.272307 -260.826346) (xy 349.319578 -260.840038) (xy 349.36404 -260.861136)
			(xy 349.404543 -260.889092) (xy 349.440036 -260.923184) (xy 349.469601 -260.962528) (xy 349.492472 -261.006105)
			(xy 349.508056 -261.052786) (xy 349.515951 -261.101363) (xy 349.516446 -261.12597) (xy 349.845388 -261.12597)
			(xy 349.849348 -261.076916) (xy 349.861125 -261.029132) (xy 349.880416 -260.983856) (xy 349.906719 -260.94226)
			(xy 349.939354 -260.905423) (xy 349.977475 -260.874298) (xy 350.020096 -260.849691) (xy 350.066112 -260.832239)
			(xy 350.114331 -260.822395) (xy 350.163506 -260.820414) (xy 350.212361 -260.826346) (xy 350.259632 -260.840038)
			(xy 350.304094 -260.861136) (xy 350.344597 -260.889092) (xy 350.38009 -260.923184) (xy 350.409655 -260.962528)
			(xy 350.432526 -261.006105) (xy 350.44811 -261.052786) (xy 350.456005 -261.101363) (xy 350.4565 -261.12597)
			(xy 350.456459 -261.128002) (xy 350.78214 -261.128002) (xy 350.7861 -261.078948) (xy 350.797877 -261.031164)
			(xy 350.817168 -260.985888) (xy 350.843471 -260.944292) (xy 350.876106 -260.907455) (xy 350.914227 -260.87633)
			(xy 350.956848 -260.851723) (xy 351.002864 -260.834271) (xy 351.051083 -260.824427) (xy 351.100258 -260.822446)
			(xy 351.149113 -260.828378) (xy 351.196384 -260.84207) (xy 351.240846 -260.863168) (xy 351.281349 -260.891124)
			(xy 351.316842 -260.925216) (xy 351.346407 -260.96456) (xy 351.369278 -261.008137) (xy 351.384862 -261.054818)
			(xy 351.392757 -261.103395) (xy 351.393252 -261.128002) (xy 351.722194 -261.128002) (xy 351.726154 -261.078948)
			(xy 351.737931 -261.031164) (xy 351.757222 -260.985888) (xy 351.783525 -260.944292) (xy 351.81616 -260.907455)
			(xy 351.854281 -260.87633) (xy 351.896902 -260.851723) (xy 351.942918 -260.834271) (xy 351.991137 -260.824427)
			(xy 352.040312 -260.822446) (xy 352.089167 -260.828378) (xy 352.136438 -260.84207) (xy 352.1809 -260.863168)
			(xy 352.221403 -260.891124) (xy 352.256896 -260.925216) (xy 352.286461 -260.96456) (xy 352.309332 -261.008137)
			(xy 352.324916 -261.054818) (xy 352.332811 -261.103395) (xy 352.333306 -261.128002) (xy 352.332811 -261.152609)
			(xy 352.324916 -261.201186) (xy 352.309332 -261.247867) (xy 352.286461 -261.291444) (xy 352.256896 -261.330788)
			(xy 352.221403 -261.36488) (xy 352.1809 -261.392836) (xy 352.136438 -261.413934) (xy 352.089167 -261.427626)
			(xy 352.040312 -261.433558) (xy 351.991137 -261.431577) (xy 351.942918 -261.421733) (xy 351.896902 -261.404281)
			(xy 351.854281 -261.379674) (xy 351.81616 -261.348549) (xy 351.783525 -261.311712) (xy 351.757222 -261.270116)
			(xy 351.737931 -261.22484) (xy 351.726154 -261.177056) (xy 351.722194 -261.128002) (xy 351.393252 -261.128002)
			(xy 351.392757 -261.152609) (xy 351.384862 -261.201186) (xy 351.369278 -261.247867) (xy 351.346407 -261.291444)
			(xy 351.316842 -261.330788) (xy 351.281349 -261.36488) (xy 351.240846 -261.392836) (xy 351.196384 -261.413934)
			(xy 351.149113 -261.427626) (xy 351.100258 -261.433558) (xy 351.051083 -261.431577) (xy 351.002864 -261.421733)
			(xy 350.956848 -261.404281) (xy 350.914227 -261.379674) (xy 350.876106 -261.348549) (xy 350.843471 -261.311712)
			(xy 350.817168 -261.270116) (xy 350.797877 -261.22484) (xy 350.7861 -261.177056) (xy 350.78214 -261.128002)
			(xy 350.456459 -261.128002) (xy 350.456005 -261.150577) (xy 350.44811 -261.199154) (xy 350.432526 -261.245835)
			(xy 350.409655 -261.289412) (xy 350.38009 -261.328756) (xy 350.344597 -261.362848) (xy 350.304094 -261.390804)
			(xy 350.259632 -261.411902) (xy 350.212361 -261.425594) (xy 350.163506 -261.431526) (xy 350.114331 -261.429545)
			(xy 350.066112 -261.419701) (xy 350.020096 -261.402249) (xy 349.977475 -261.377642) (xy 349.939354 -261.346517)
			(xy 349.906719 -261.30968) (xy 349.880416 -261.268084) (xy 349.861125 -261.222808) (xy 349.849348 -261.175024)
			(xy 349.845388 -261.12597) (xy 349.516446 -261.12597) (xy 349.515951 -261.150577) (xy 349.508056 -261.199154)
			(xy 349.492472 -261.245835) (xy 349.469601 -261.289412) (xy 349.440036 -261.328756) (xy 349.404543 -261.362848)
			(xy 349.36404 -261.390804) (xy 349.319578 -261.411902) (xy 349.272307 -261.425594) (xy 349.223452 -261.431526)
			(xy 349.174277 -261.429545) (xy 349.126058 -261.419701) (xy 349.080042 -261.402249) (xy 349.037421 -261.377642)
			(xy 348.9993 -261.346517) (xy 348.966665 -261.30968) (xy 348.940362 -261.268084) (xy 348.921071 -261.222808)
			(xy 348.909294 -261.175024) (xy 348.905334 -261.12597) (xy 348.576392 -261.12597) (xy 348.575897 -261.150577)
			(xy 348.568002 -261.199154) (xy 348.552418 -261.245835) (xy 348.529547 -261.289412) (xy 348.499982 -261.328756)
			(xy 348.464489 -261.362848) (xy 348.423986 -261.390804) (xy 348.379524 -261.411902) (xy 348.332253 -261.425594)
			(xy 348.283398 -261.431526) (xy 348.234223 -261.429545) (xy 348.186004 -261.419701) (xy 348.139988 -261.402249)
			(xy 348.097367 -261.377642) (xy 348.059246 -261.346517) (xy 348.026611 -261.30968) (xy 348.000308 -261.268084)
			(xy 347.981017 -261.222808) (xy 347.96924 -261.175024) (xy 347.96528 -261.12597) (xy 346.696538 -261.12597)
			(xy 346.696043 -261.150577) (xy 346.688148 -261.199154) (xy 346.672564 -261.245835) (xy 346.649693 -261.289412)
			(xy 346.620128 -261.328756) (xy 346.584635 -261.362848) (xy 346.544132 -261.390804) (xy 346.49967 -261.411902)
			(xy 346.452399 -261.425594) (xy 346.403544 -261.431526) (xy 346.354369 -261.429545) (xy 346.30615 -261.419701)
			(xy 346.260134 -261.402249) (xy 346.217513 -261.377642) (xy 346.179392 -261.346517) (xy 346.146757 -261.30968)
			(xy 346.120454 -261.268084) (xy 346.101163 -261.222808) (xy 346.089386 -261.175024) (xy 346.085426 -261.12597)
			(xy 344.81643 -261.12597) (xy 344.815935 -261.150577) (xy 344.80804 -261.199154) (xy 344.792456 -261.245835)
			(xy 344.769585 -261.289412) (xy 344.74002 -261.328756) (xy 344.704527 -261.362848) (xy 344.664024 -261.390804)
			(xy 344.619562 -261.411902) (xy 344.572291 -261.425594) (xy 344.523436 -261.431526) (xy 344.474261 -261.429545)
			(xy 344.426042 -261.419701) (xy 344.380026 -261.402249) (xy 344.337405 -261.377642) (xy 344.299284 -261.346517)
			(xy 344.266649 -261.30968) (xy 344.240346 -261.268084) (xy 344.221055 -261.222808) (xy 344.209278 -261.175024)
			(xy 344.205318 -261.12597) (xy 343.876376 -261.12597) (xy 343.875881 -261.150577) (xy 343.867986 -261.199154)
			(xy 343.852402 -261.245835) (xy 343.829531 -261.289412) (xy 343.799966 -261.328756) (xy 343.764473 -261.362848)
			(xy 343.72397 -261.390804) (xy 343.679508 -261.411902) (xy 343.632237 -261.425594) (xy 343.583382 -261.431526)
			(xy 343.534207 -261.429545) (xy 343.485988 -261.419701) (xy 343.439972 -261.402249) (xy 343.397351 -261.377642)
			(xy 343.35923 -261.346517) (xy 343.326595 -261.30968) (xy 343.300292 -261.268084) (xy 343.281001 -261.222808)
			(xy 343.269224 -261.175024) (xy 343.265264 -261.12597) (xy 342.936322 -261.12597) (xy 342.935827 -261.150577)
			(xy 342.927932 -261.199154) (xy 342.912348 -261.245835) (xy 342.889477 -261.289412) (xy 342.859912 -261.328756)
			(xy 342.824419 -261.362848) (xy 342.783916 -261.390804) (xy 342.739454 -261.411902) (xy 342.692183 -261.425594)
			(xy 342.643328 -261.431526) (xy 342.594153 -261.429545) (xy 342.545934 -261.419701) (xy 342.499918 -261.402249)
			(xy 342.457297 -261.377642) (xy 342.419176 -261.346517) (xy 342.386541 -261.30968) (xy 342.360238 -261.268084)
			(xy 342.340947 -261.222808) (xy 342.32917 -261.175024) (xy 342.32521 -261.12597) (xy 341.056468 -261.12597)
			(xy 341.056328 -261.138733) (xy 341.054163 -261.164166) (xy 341.05215 -261.17677) (xy 341.052404 -261.17677)
			(xy 341.048172 -261.199355) (xy 341.033834 -261.24301) (xy 341.013131 -261.284031) (xy 340.986529 -261.321497)
			(xy 340.97087 -261.338314) (xy 340.963758 -261.34568) (xy 340.956646 -261.36346) (xy 340.956646 -261.37362)
			(xy 340.95707 -261.383635) (xy 340.964745 -261.402137) (xy 340.978918 -261.416292) (xy 340.99743 -261.423943)
			(xy 341.007446 -261.42442) (xy 341.016082 -261.42442) (xy 341.107522 -261.51586) (xy 341.110954 -261.519479)
			(xy 341.116452 -261.527798) (xy 341.118444 -261.53237) (xy 341.125302 -261.54888) (xy 341.127349 -261.553524)
			(xy 341.132985 -261.561962) (xy 341.136478 -261.565644) (xy 341.193882 -261.623048) (xy 341.21217 -261.630668)
			(xy 341.22233 -261.630668) (xy 341.246494 -261.631232) (xy 341.29419 -261.639052) (xy 341.340059 -261.654286)
			(xy 341.382957 -261.676553) (xy 341.421812 -261.705299) (xy 341.455655 -261.739806) (xy 341.483641 -261.779211)
			(xy 341.505072 -261.822533) (xy 341.519413 -261.868689) (xy 341.52332 -261.892542) (xy 341.52459 -261.90194)
			(xy 341.526622 -261.935976) (xy 341.85531 -261.935976) (xy 341.85927 -261.886922) (xy 341.871047 -261.839138)
			(xy 341.890338 -261.793862) (xy 341.916641 -261.752266) (xy 341.949276 -261.715429) (xy 341.987397 -261.684304)
			(xy 342.030018 -261.659697) (xy 342.076034 -261.642245) (xy 342.124253 -261.632401) (xy 342.173428 -261.63042)
			(xy 342.222283 -261.636352) (xy 342.269554 -261.650044) (xy 342.314016 -261.671142) (xy 342.354519 -261.699098)
			(xy 342.390012 -261.73319) (xy 342.419577 -261.772534) (xy 342.442448 -261.816111) (xy 342.458032 -261.862792)
			(xy 342.465927 -261.911369) (xy 342.466422 -261.935976) (xy 342.795364 -261.935976) (xy 342.799324 -261.886922)
			(xy 342.811101 -261.839138) (xy 342.830392 -261.793862) (xy 342.856695 -261.752266) (xy 342.88933 -261.715429)
			(xy 342.927451 -261.684304) (xy 342.970072 -261.659697) (xy 343.016088 -261.642245) (xy 343.064307 -261.632401)
			(xy 343.113482 -261.63042) (xy 343.162337 -261.636352) (xy 343.209608 -261.650044) (xy 343.25407 -261.671142)
			(xy 343.294573 -261.699098) (xy 343.330066 -261.73319) (xy 343.359631 -261.772534) (xy 343.382502 -261.816111)
			(xy 343.398086 -261.862792) (xy 343.405981 -261.911369) (xy 343.406476 -261.935976) (xy 343.724987 -261.935976)
			(xy 343.729082 -261.885248) (xy 343.741261 -261.835834) (xy 343.761209 -261.789014) (xy 343.78841 -261.746)
			(xy 343.822158 -261.707906) (xy 343.86158 -261.675719) (xy 343.905654 -261.650273) (xy 343.95324 -261.632226)
			(xy 344.003104 -261.622046) (xy 344.053956 -261.619997) (xy 344.104477 -261.626131) (xy 344.153361 -261.640291)
			(xy 344.19934 -261.662108) (xy 344.241224 -261.691018) (xy 344.277928 -261.726273) (xy 344.308501 -261.766959)
			(xy 344.332152 -261.812022) (xy 344.348268 -261.860296) (xy 344.356432 -261.91053) (xy 344.356944 -261.935976)
			(xy 345.615272 -261.935976) (xy 345.619232 -261.886922) (xy 345.631009 -261.839138) (xy 345.6503 -261.793862)
			(xy 345.676603 -261.752266) (xy 345.709238 -261.715429) (xy 345.747359 -261.684304) (xy 345.78998 -261.659697)
			(xy 345.835996 -261.642245) (xy 345.884215 -261.632401) (xy 345.93339 -261.63042) (xy 345.982245 -261.636352)
			(xy 346.029516 -261.650044) (xy 346.073978 -261.671142) (xy 346.114481 -261.699098) (xy 346.149974 -261.73319)
			(xy 346.179539 -261.772534) (xy 346.20241 -261.816111) (xy 346.217994 -261.862792) (xy 346.225889 -261.911369)
			(xy 346.226384 -261.935976) (xy 347.49538 -261.935976) (xy 347.49934 -261.886922) (xy 347.511117 -261.839138)
			(xy 347.530408 -261.793862) (xy 347.556711 -261.752266) (xy 347.589346 -261.715429) (xy 347.627467 -261.684304)
			(xy 347.670088 -261.659697) (xy 347.716104 -261.642245) (xy 347.764323 -261.632401) (xy 347.813498 -261.63042)
			(xy 347.862353 -261.636352) (xy 347.909624 -261.650044) (xy 347.954086 -261.671142) (xy 347.994589 -261.699098)
			(xy 348.030082 -261.73319) (xy 348.059647 -261.772534) (xy 348.082518 -261.816111) (xy 348.098102 -261.862792)
			(xy 348.105997 -261.911369) (xy 348.106492 -261.935976) (xy 349.375234 -261.935976) (xy 349.379194 -261.886922)
			(xy 349.390971 -261.839138) (xy 349.410262 -261.793862) (xy 349.436565 -261.752266) (xy 349.4692 -261.715429)
			(xy 349.507321 -261.684304) (xy 349.549942 -261.659697) (xy 349.595958 -261.642245) (xy 349.644177 -261.632401)
			(xy 349.693352 -261.63042) (xy 349.742207 -261.636352) (xy 349.789478 -261.650044) (xy 349.83394 -261.671142)
			(xy 349.874443 -261.699098) (xy 349.909936 -261.73319) (xy 349.939501 -261.772534) (xy 349.962372 -261.816111)
			(xy 349.977956 -261.862792) (xy 349.985851 -261.911369) (xy 349.986346 -261.935976) (xy 350.315288 -261.935976)
			(xy 350.319248 -261.886922) (xy 350.331025 -261.839138) (xy 350.350316 -261.793862) (xy 350.376619 -261.752266)
			(xy 350.409254 -261.715429) (xy 350.447375 -261.684304) (xy 350.489996 -261.659697) (xy 350.536012 -261.642245)
			(xy 350.584231 -261.632401) (xy 350.633406 -261.63042) (xy 350.682261 -261.636352) (xy 350.729532 -261.650044)
			(xy 350.773994 -261.671142) (xy 350.814497 -261.699098) (xy 350.84999 -261.73319) (xy 350.879555 -261.772534)
			(xy 350.902426 -261.816111) (xy 350.91801 -261.862792) (xy 350.925905 -261.911369) (xy 350.9264 -261.935976)
			(xy 350.925905 -261.960583) (xy 350.91801 -262.00916) (xy 350.902426 -262.055841) (xy 350.879555 -262.099418)
			(xy 350.84999 -262.138762) (xy 350.814497 -262.172854) (xy 350.773994 -262.20081) (xy 350.729532 -262.221908)
			(xy 350.682261 -262.2356) (xy 350.633406 -262.241532) (xy 350.584231 -262.239551) (xy 350.536012 -262.229707)
			(xy 350.489996 -262.212255) (xy 350.447375 -262.187648) (xy 350.409254 -262.156523) (xy 350.376619 -262.119686)
			(xy 350.350316 -262.07809) (xy 350.331025 -262.032814) (xy 350.319248 -261.98503) (xy 350.315288 -261.935976)
			(xy 349.986346 -261.935976) (xy 349.985851 -261.960583) (xy 349.977956 -262.00916) (xy 349.962372 -262.055841)
			(xy 349.939501 -262.099418) (xy 349.909936 -262.138762) (xy 349.874443 -262.172854) (xy 349.83394 -262.20081)
			(xy 349.789478 -262.221908) (xy 349.742207 -262.2356) (xy 349.693352 -262.241532) (xy 349.644177 -262.239551)
			(xy 349.595958 -262.229707) (xy 349.549942 -262.212255) (xy 349.507321 -262.187648) (xy 349.4692 -262.156523)
			(xy 349.436565 -262.119686) (xy 349.410262 -262.07809) (xy 349.390971 -262.032814) (xy 349.379194 -261.98503)
			(xy 349.375234 -261.935976) (xy 348.106492 -261.935976) (xy 348.105997 -261.960583) (xy 348.098102 -262.00916)
			(xy 348.082518 -262.055841) (xy 348.059647 -262.099418) (xy 348.030082 -262.138762) (xy 347.994589 -262.172854)
			(xy 347.954086 -262.20081) (xy 347.909624 -262.221908) (xy 347.862353 -262.2356) (xy 347.813498 -262.241532)
			(xy 347.764323 -262.239551) (xy 347.716104 -262.229707) (xy 347.670088 -262.212255) (xy 347.627467 -262.187648)
			(xy 347.589346 -262.156523) (xy 347.556711 -262.119686) (xy 347.530408 -262.07809) (xy 347.511117 -262.032814)
			(xy 347.49934 -261.98503) (xy 347.49538 -261.935976) (xy 346.226384 -261.935976) (xy 346.225889 -261.960583)
			(xy 346.217994 -262.00916) (xy 346.20241 -262.055841) (xy 346.179539 -262.099418) (xy 346.149974 -262.138762)
			(xy 346.114481 -262.172854) (xy 346.073978 -262.20081) (xy 346.029516 -262.221908) (xy 345.982245 -262.2356)
			(xy 345.93339 -262.241532) (xy 345.884215 -262.239551) (xy 345.835996 -262.229707) (xy 345.78998 -262.212255)
			(xy 345.747359 -262.187648) (xy 345.709238 -262.156523) (xy 345.676603 -262.119686) (xy 345.6503 -262.07809)
			(xy 345.631009 -262.032814) (xy 345.619232 -261.98503) (xy 345.615272 -261.935976) (xy 344.356944 -261.935976)
			(xy 344.356432 -261.961422) (xy 344.348268 -262.011656) (xy 344.332152 -262.05993) (xy 344.308501 -262.104993)
			(xy 344.277928 -262.145679) (xy 344.241224 -262.180934) (xy 344.19934 -262.209844) (xy 344.153361 -262.231661)
			(xy 344.104477 -262.245821) (xy 344.053956 -262.251955) (xy 344.003104 -262.249906) (xy 343.95324 -262.239726)
			(xy 343.905654 -262.221679) (xy 343.86158 -262.196233) (xy 343.822158 -262.164046) (xy 343.78841 -262.125952)
			(xy 343.761209 -262.082938) (xy 343.741261 -262.036118) (xy 343.729082 -261.986704) (xy 343.724987 -261.935976)
			(xy 343.406476 -261.935976) (xy 343.405981 -261.960583) (xy 343.398086 -262.00916) (xy 343.382502 -262.055841)
			(xy 343.359631 -262.099418) (xy 343.330066 -262.138762) (xy 343.294573 -262.172854) (xy 343.25407 -262.20081)
			(xy 343.209608 -262.221908) (xy 343.162337 -262.2356) (xy 343.113482 -262.241532) (xy 343.064307 -262.239551)
			(xy 343.016088 -262.229707) (xy 342.970072 -262.212255) (xy 342.927451 -262.187648) (xy 342.88933 -262.156523)
			(xy 342.856695 -262.119686) (xy 342.830392 -262.07809) (xy 342.811101 -262.032814) (xy 342.799324 -261.98503)
			(xy 342.795364 -261.935976) (xy 342.466422 -261.935976) (xy 342.465927 -261.960583) (xy 342.458032 -262.00916)
			(xy 342.442448 -262.055841) (xy 342.419577 -262.099418) (xy 342.390012 -262.138762) (xy 342.354519 -262.172854)
			(xy 342.314016 -262.20081) (xy 342.269554 -262.221908) (xy 342.222283 -262.2356) (xy 342.173428 -262.241532)
			(xy 342.124253 -262.239551) (xy 342.076034 -262.229707) (xy 342.030018 -262.212255) (xy 341.987397 -262.187648)
			(xy 341.949276 -262.156523) (xy 341.916641 -262.119686) (xy 341.890338 -262.07809) (xy 341.871047 -262.032814)
			(xy 341.85927 -261.98503) (xy 341.85531 -261.935976) (xy 341.526622 -261.935976) (xy 341.526153 -261.960288)
			(xy 341.518453 -262.008299) (xy 341.503243 -262.054482) (xy 341.480908 -262.097673) (xy 341.452012 -262.136779)
			(xy 341.417284 -262.170813) (xy 341.377603 -262.198915) (xy 341.333971 -262.220375) (xy 341.28749 -262.23465)
			(xy 341.263478 -262.23849) (xy 341.263224 -262.23849) (xy 341.250949 -262.240872) (xy 341.230713 -262.255513)
			(xy 341.224616 -262.26643) (xy 341.188294 -262.34009) (xy 341.183361 -262.351699) (xy 341.184308 -262.376874)
			(xy 341.190072 -262.388096) (xy 341.234776 -262.465058) (xy 341.245247 -262.483537) (xy 341.263682 -262.521806)
			(xy 341.271606 -262.541512) (xy 341.276686 -262.554466) (xy 341.298276 -262.571484) (xy 341.398098 -262.584692)
			(xy 341.404962 -262.585361) (xy 341.418613 -262.58343) (xy 341.425022 -262.580882) (xy 341.431372 -262.578342)
			(xy 341.441532 -262.56996) (xy 341.44585 -262.564372) (xy 341.460351 -262.545538) (xy 341.494203 -262.512172)
			(xy 341.532815 -262.484452) (xy 341.575253 -262.463047) (xy 341.620495 -262.448474) (xy 341.667449 -262.441083)
			(xy 341.691214 -262.440674) (xy 341.71647 -262.441197) (xy 341.766293 -262.449513) (xy 341.814068 -262.465916)
			(xy 341.858491 -262.489958) (xy 341.898351 -262.520985) (xy 341.932561 -262.558148) (xy 341.960188 -262.600436)
			(xy 341.980478 -262.646694) (xy 341.992878 -262.69566) (xy 341.997048 -262.745982) (xy 342.314779 -262.745982)
			(xy 342.318874 -262.695254) (xy 342.331053 -262.64584) (xy 342.351001 -262.59902) (xy 342.378202 -262.556006)
			(xy 342.41195 -262.517912) (xy 342.451372 -262.485725) (xy 342.495446 -262.460279) (xy 342.543032 -262.442232)
			(xy 342.592896 -262.432052) (xy 342.643748 -262.430003) (xy 342.694269 -262.436137) (xy 342.743153 -262.450297)
			(xy 342.789132 -262.472114) (xy 342.831016 -262.501024) (xy 342.86772 -262.536279) (xy 342.898293 -262.576965)
			(xy 342.921944 -262.622028) (xy 342.93806 -262.670302) (xy 342.946224 -262.720536) (xy 342.946736 -262.745982)
			(xy 343.254833 -262.745982) (xy 343.258928 -262.695254) (xy 343.271107 -262.64584) (xy 343.291055 -262.59902)
			(xy 343.318256 -262.556006) (xy 343.352004 -262.517912) (xy 343.391426 -262.485725) (xy 343.4355 -262.460279)
			(xy 343.483086 -262.442232) (xy 343.53295 -262.432052) (xy 343.583802 -262.430003) (xy 343.634323 -262.436137)
			(xy 343.683207 -262.450297) (xy 343.729186 -262.472114) (xy 343.77107 -262.501024) (xy 343.807774 -262.536279)
			(xy 343.838347 -262.576965) (xy 343.861998 -262.622028) (xy 343.878114 -262.670302) (xy 343.886278 -262.720536)
			(xy 343.88679 -262.745982) (xy 344.205318 -262.745982) (xy 344.209278 -262.696928) (xy 344.221055 -262.649144)
			(xy 344.240346 -262.603868) (xy 344.266649 -262.562272) (xy 344.299284 -262.525435) (xy 344.337405 -262.49431)
			(xy 344.380026 -262.469703) (xy 344.426042 -262.452251) (xy 344.474261 -262.442407) (xy 344.523436 -262.440426)
			(xy 344.572291 -262.446358) (xy 344.619562 -262.46005) (xy 344.664024 -262.481148) (xy 344.704527 -262.509104)
			(xy 344.74002 -262.543196) (xy 344.769585 -262.58254) (xy 344.792456 -262.626117) (xy 344.80804 -262.672798)
			(xy 344.815935 -262.721375) (xy 344.81643 -262.745982) (xy 346.085426 -262.745982) (xy 346.089386 -262.696928)
			(xy 346.101163 -262.649144) (xy 346.120454 -262.603868) (xy 346.146757 -262.562272) (xy 346.179392 -262.525435)
			(xy 346.217513 -262.49431) (xy 346.260134 -262.469703) (xy 346.30615 -262.452251) (xy 346.354369 -262.442407)
			(xy 346.403544 -262.440426) (xy 346.452399 -262.446358) (xy 346.49967 -262.46005) (xy 346.544132 -262.481148)
			(xy 346.584635 -262.509104) (xy 346.620128 -262.543196) (xy 346.649693 -262.58254) (xy 346.672564 -262.626117)
			(xy 346.688148 -262.672798) (xy 346.696043 -262.721375) (xy 346.696538 -262.745982) (xy 347.96528 -262.745982)
			(xy 347.96924 -262.696928) (xy 347.981017 -262.649144) (xy 348.000308 -262.603868) (xy 348.026611 -262.562272)
			(xy 348.059246 -262.525435) (xy 348.097367 -262.49431) (xy 348.139988 -262.469703) (xy 348.186004 -262.452251)
			(xy 348.234223 -262.442407) (xy 348.283398 -262.440426) (xy 348.332253 -262.446358) (xy 348.379524 -262.46005)
			(xy 348.423986 -262.481148) (xy 348.464489 -262.509104) (xy 348.499982 -262.543196) (xy 348.529547 -262.58254)
			(xy 348.552418 -262.626117) (xy 348.568002 -262.672798) (xy 348.575897 -262.721375) (xy 348.576392 -262.745982)
			(xy 348.905334 -262.745982) (xy 348.909294 -262.696928) (xy 348.921071 -262.649144) (xy 348.940362 -262.603868)
			(xy 348.966665 -262.562272) (xy 348.9993 -262.525435) (xy 349.037421 -262.49431) (xy 349.080042 -262.469703)
			(xy 349.126058 -262.452251) (xy 349.174277 -262.442407) (xy 349.223452 -262.440426) (xy 349.272307 -262.446358)
			(xy 349.319578 -262.46005) (xy 349.36404 -262.481148) (xy 349.404543 -262.509104) (xy 349.440036 -262.543196)
			(xy 349.469601 -262.58254) (xy 349.492472 -262.626117) (xy 349.508056 -262.672798) (xy 349.515951 -262.721375)
			(xy 349.516446 -262.745982) (xy 349.845388 -262.745982) (xy 349.849348 -262.696928) (xy 349.861125 -262.649144)
			(xy 349.880416 -262.603868) (xy 349.906719 -262.562272) (xy 349.939354 -262.525435) (xy 349.977475 -262.49431)
			(xy 350.020096 -262.469703) (xy 350.066112 -262.452251) (xy 350.114331 -262.442407) (xy 350.163506 -262.440426)
			(xy 350.212361 -262.446358) (xy 350.259632 -262.46005) (xy 350.304094 -262.481148) (xy 350.344597 -262.509104)
			(xy 350.38009 -262.543196) (xy 350.409655 -262.58254) (xy 350.432526 -262.626117) (xy 350.44811 -262.672798)
			(xy 350.456005 -262.721375) (xy 350.4565 -262.745982) (xy 350.456459 -262.748014) (xy 350.78214 -262.748014)
			(xy 350.7861 -262.69896) (xy 350.797877 -262.651176) (xy 350.817168 -262.6059) (xy 350.843471 -262.564304)
			(xy 350.876106 -262.527467) (xy 350.914227 -262.496342) (xy 350.956848 -262.471735) (xy 351.002864 -262.454283)
			(xy 351.051083 -262.444439) (xy 351.100258 -262.442458) (xy 351.149113 -262.44839) (xy 351.196384 -262.462082)
			(xy 351.240846 -262.48318) (xy 351.281349 -262.511136) (xy 351.316842 -262.545228) (xy 351.346407 -262.584572)
			(xy 351.369278 -262.628149) (xy 351.384862 -262.67483) (xy 351.392757 -262.723407) (xy 351.393252 -262.748014)
			(xy 351.392757 -262.772621) (xy 351.384862 -262.821198) (xy 351.369278 -262.867879) (xy 351.346407 -262.911456)
			(xy 351.316842 -262.9508) (xy 351.281349 -262.984892) (xy 351.240846 -263.012848) (xy 351.196384 -263.033946)
			(xy 351.149113 -263.047638) (xy 351.100258 -263.05357) (xy 351.051083 -263.051589) (xy 351.002864 -263.041745)
			(xy 350.956848 -263.024293) (xy 350.914227 -262.999686) (xy 350.876106 -262.968561) (xy 350.843471 -262.931724)
			(xy 350.817168 -262.890128) (xy 350.797877 -262.844852) (xy 350.7861 -262.797068) (xy 350.78214 -262.748014)
			(xy 350.456459 -262.748014) (xy 350.456005 -262.770589) (xy 350.44811 -262.819166) (xy 350.432526 -262.865847)
			(xy 350.409655 -262.909424) (xy 350.38009 -262.948768) (xy 350.344597 -262.98286) (xy 350.304094 -263.010816)
			(xy 350.259632 -263.031914) (xy 350.212361 -263.045606) (xy 350.163506 -263.051538) (xy 350.114331 -263.049557)
			(xy 350.066112 -263.039713) (xy 350.020096 -263.022261) (xy 349.977475 -262.997654) (xy 349.939354 -262.966529)
			(xy 349.906719 -262.929692) (xy 349.880416 -262.888096) (xy 349.861125 -262.84282) (xy 349.849348 -262.795036)
			(xy 349.845388 -262.745982) (xy 349.516446 -262.745982) (xy 349.515951 -262.770589) (xy 349.508056 -262.819166)
			(xy 349.492472 -262.865847) (xy 349.469601 -262.909424) (xy 349.440036 -262.948768) (xy 349.404543 -262.98286)
			(xy 349.36404 -263.010816) (xy 349.319578 -263.031914) (xy 349.272307 -263.045606) (xy 349.223452 -263.051538)
			(xy 349.174277 -263.049557) (xy 349.126058 -263.039713) (xy 349.080042 -263.022261) (xy 349.037421 -262.997654)
			(xy 348.9993 -262.966529) (xy 348.966665 -262.929692) (xy 348.940362 -262.888096) (xy 348.921071 -262.84282)
			(xy 348.909294 -262.795036) (xy 348.905334 -262.745982) (xy 348.576392 -262.745982) (xy 348.575897 -262.770589)
			(xy 348.568002 -262.819166) (xy 348.552418 -262.865847) (xy 348.529547 -262.909424) (xy 348.499982 -262.948768)
			(xy 348.464489 -262.98286) (xy 348.423986 -263.010816) (xy 348.379524 -263.031914) (xy 348.332253 -263.045606)
			(xy 348.283398 -263.051538) (xy 348.234223 -263.049557) (xy 348.186004 -263.039713) (xy 348.139988 -263.022261)
			(xy 348.097367 -262.997654) (xy 348.059246 -262.966529) (xy 348.026611 -262.929692) (xy 348.000308 -262.888096)
			(xy 347.981017 -262.84282) (xy 347.96924 -262.795036) (xy 347.96528 -262.745982) (xy 346.696538 -262.745982)
			(xy 346.696043 -262.770589) (xy 346.688148 -262.819166) (xy 346.672564 -262.865847) (xy 346.649693 -262.909424)
			(xy 346.620128 -262.948768) (xy 346.584635 -262.98286) (xy 346.544132 -263.010816) (xy 346.49967 -263.031914)
			(xy 346.452399 -263.045606) (xy 346.403544 -263.051538) (xy 346.354369 -263.049557) (xy 346.30615 -263.039713)
			(xy 346.260134 -263.022261) (xy 346.217513 -262.997654) (xy 346.179392 -262.966529) (xy 346.146757 -262.929692)
			(xy 346.120454 -262.888096) (xy 346.101163 -262.84282) (xy 346.089386 -262.795036) (xy 346.085426 -262.745982)
			(xy 344.81643 -262.745982) (xy 344.815935 -262.770589) (xy 344.80804 -262.819166) (xy 344.792456 -262.865847)
			(xy 344.769585 -262.909424) (xy 344.74002 -262.948768) (xy 344.704527 -262.98286) (xy 344.664024 -263.010816)
			(xy 344.619562 -263.031914) (xy 344.572291 -263.045606) (xy 344.523436 -263.051538) (xy 344.474261 -263.049557)
			(xy 344.426042 -263.039713) (xy 344.380026 -263.022261) (xy 344.337405 -262.997654) (xy 344.299284 -262.966529)
			(xy 344.266649 -262.929692) (xy 344.240346 -262.888096) (xy 344.221055 -262.84282) (xy 344.209278 -262.795036)
			(xy 344.205318 -262.745982) (xy 343.88679 -262.745982) (xy 343.886278 -262.771428) (xy 343.878114 -262.821662)
			(xy 343.861998 -262.869936) (xy 343.838347 -262.914999) (xy 343.807774 -262.955685) (xy 343.77107 -262.99094)
			(xy 343.729186 -263.01985) (xy 343.683207 -263.041667) (xy 343.634323 -263.055827) (xy 343.583802 -263.061961)
			(xy 343.53295 -263.059912) (xy 343.483086 -263.049732) (xy 343.4355 -263.031685) (xy 343.391426 -263.006239)
			(xy 343.352004 -262.974052) (xy 343.318256 -262.935958) (xy 343.291055 -262.892944) (xy 343.271107 -262.846124)
			(xy 343.258928 -262.79671) (xy 343.254833 -262.745982) (xy 342.946736 -262.745982) (xy 342.946224 -262.771428)
			(xy 342.93806 -262.821662) (xy 342.921944 -262.869936) (xy 342.898293 -262.914999) (xy 342.86772 -262.955685)
			(xy 342.831016 -262.99094) (xy 342.789132 -263.01985) (xy 342.743153 -263.041667) (xy 342.694269 -263.055827)
			(xy 342.643748 -263.061961) (xy 342.592896 -263.059912) (xy 342.543032 -263.049732) (xy 342.495446 -263.031685)
			(xy 342.451372 -263.006239) (xy 342.41195 -262.974052) (xy 342.378202 -262.935958) (xy 342.351001 -262.892944)
			(xy 342.331053 -262.846124) (xy 342.318874 -262.79671) (xy 342.314779 -262.745982) (xy 341.997048 -262.745982)
			(xy 341.997049 -262.746) (xy 341.992878 -262.79634) (xy 341.980478 -262.845306) (xy 341.960188 -262.891564)
			(xy 341.932561 -262.933852) (xy 341.898351 -262.971015) (xy 341.858491 -263.002042) (xy 341.814068 -263.026084)
			(xy 341.766293 -263.042487) (xy 341.71647 -263.050803) (xy 341.691214 -263.05129) (xy 341.66745 -263.050837)
			(xy 341.620496 -263.043469) (xy 341.575253 -263.028908) (xy 341.532815 -263.007508) (xy 341.494209 -262.979786)
			(xy 341.460369 -262.946412) (xy 341.44585 -262.927592) (xy 341.441532 -262.922004) (xy 341.431372 -262.913622)
			(xy 341.425022 -262.911082) (xy 341.418614 -262.908529) (xy 341.404962 -262.906591) (xy 341.398098 -262.907272)
			(xy 341.29853 -262.92048) (xy 341.276686 -262.937498) (xy 341.271606 -262.950452) (xy 341.25687 -262.986192)
			(xy 341.218957 -263.053563) (xy 341.172105 -263.115054) (xy 341.145114 -263.14273) (xy 341.144606 -263.143238)
			(xy 341.137748 -263.15035) (xy 341.126572 -263.176004) (xy 341.124566 -263.180844) (xy 341.122382 -263.191087)
			(xy 341.122254 -263.196324) (xy 341.122254 -263.555988) (xy 341.844879 -263.555988) (xy 341.848974 -263.50526)
			(xy 341.861153 -263.455846) (xy 341.881101 -263.409026) (xy 341.908302 -263.366012) (xy 341.94205 -263.327918)
			(xy 341.981472 -263.295731) (xy 342.025546 -263.270285) (xy 342.073132 -263.252238) (xy 342.122996 -263.242058)
			(xy 342.173848 -263.240009) (xy 342.224369 -263.246143) (xy 342.273253 -263.260303) (xy 342.319232 -263.28212)
			(xy 342.361116 -263.31103) (xy 342.39782 -263.346285) (xy 342.428393 -263.386971) (xy 342.452044 -263.432034)
			(xy 342.46816 -263.480308) (xy 342.476324 -263.530542) (xy 342.476836 -263.555988) (xy 342.795364 -263.555988)
			(xy 342.799324 -263.506934) (xy 342.811101 -263.45915) (xy 342.830392 -263.413874) (xy 342.856695 -263.372278)
			(xy 342.88933 -263.335441) (xy 342.927451 -263.304316) (xy 342.970072 -263.279709) (xy 343.016088 -263.262257)
			(xy 343.064307 -263.252413) (xy 343.113482 -263.250432) (xy 343.162337 -263.256364) (xy 343.209608 -263.270056)
			(xy 343.25407 -263.291154) (xy 343.294573 -263.31911) (xy 343.330066 -263.353202) (xy 343.359631 -263.392546)
			(xy 343.382502 -263.436123) (xy 343.398086 -263.482804) (xy 343.405981 -263.531381) (xy 343.406476 -263.555988)
			(xy 343.724987 -263.555988) (xy 343.729082 -263.50526) (xy 343.741261 -263.455846) (xy 343.761209 -263.409026)
			(xy 343.78841 -263.366012) (xy 343.822158 -263.327918) (xy 343.86158 -263.295731) (xy 343.905654 -263.270285)
			(xy 343.95324 -263.252238) (xy 344.003104 -263.242058) (xy 344.053956 -263.240009) (xy 344.104477 -263.246143)
			(xy 344.153361 -263.260303) (xy 344.19934 -263.28212) (xy 344.241224 -263.31103) (xy 344.277928 -263.346285)
			(xy 344.308501 -263.386971) (xy 344.332152 -263.432034) (xy 344.348268 -263.480308) (xy 344.356432 -263.530542)
			(xy 344.356944 -263.555988) (xy 345.615272 -263.555988) (xy 345.619232 -263.506934) (xy 345.631009 -263.45915)
			(xy 345.6503 -263.413874) (xy 345.676603 -263.372278) (xy 345.709238 -263.335441) (xy 345.747359 -263.304316)
			(xy 345.78998 -263.279709) (xy 345.835996 -263.262257) (xy 345.884215 -263.252413) (xy 345.93339 -263.250432)
			(xy 345.982245 -263.256364) (xy 346.029516 -263.270056) (xy 346.073978 -263.291154) (xy 346.114481 -263.31911)
			(xy 346.149974 -263.353202) (xy 346.179539 -263.392546) (xy 346.20241 -263.436123) (xy 346.217994 -263.482804)
			(xy 346.225889 -263.531381) (xy 346.226384 -263.555988) (xy 347.49538 -263.555988) (xy 347.49934 -263.506934)
			(xy 347.511117 -263.45915) (xy 347.530408 -263.413874) (xy 347.556711 -263.372278) (xy 347.589346 -263.335441)
			(xy 347.627467 -263.304316) (xy 347.670088 -263.279709) (xy 347.716104 -263.262257) (xy 347.764323 -263.252413)
			(xy 347.813498 -263.250432) (xy 347.862353 -263.256364) (xy 347.909624 -263.270056) (xy 347.954086 -263.291154)
			(xy 347.994589 -263.31911) (xy 348.030082 -263.353202) (xy 348.059647 -263.392546) (xy 348.082518 -263.436123)
			(xy 348.098102 -263.482804) (xy 348.105997 -263.531381) (xy 348.106492 -263.555988) (xy 349.375234 -263.555988)
			(xy 349.379194 -263.506934) (xy 349.390971 -263.45915) (xy 349.410262 -263.413874) (xy 349.436565 -263.372278)
			(xy 349.4692 -263.335441) (xy 349.507321 -263.304316) (xy 349.549942 -263.279709) (xy 349.595958 -263.262257)
			(xy 349.644177 -263.252413) (xy 349.693352 -263.250432) (xy 349.742207 -263.256364) (xy 349.789478 -263.270056)
			(xy 349.83394 -263.291154) (xy 349.874443 -263.31911) (xy 349.909936 -263.353202) (xy 349.939501 -263.392546)
			(xy 349.962372 -263.436123) (xy 349.977956 -263.482804) (xy 349.985851 -263.531381) (xy 349.986346 -263.555988)
			(xy 349.985851 -263.580595) (xy 349.977956 -263.629172) (xy 349.962372 -263.675853) (xy 349.939501 -263.71943)
			(xy 349.909936 -263.758774) (xy 349.874443 -263.792866) (xy 349.83394 -263.820822) (xy 349.789478 -263.84192)
			(xy 349.742207 -263.855612) (xy 349.693352 -263.861544) (xy 349.644177 -263.859563) (xy 349.595958 -263.849719)
			(xy 349.549942 -263.832267) (xy 349.507321 -263.80766) (xy 349.4692 -263.776535) (xy 349.436565 -263.739698)
			(xy 349.410262 -263.698102) (xy 349.390971 -263.652826) (xy 349.379194 -263.605042) (xy 349.375234 -263.555988)
			(xy 348.106492 -263.555988) (xy 348.105997 -263.580595) (xy 348.098102 -263.629172) (xy 348.082518 -263.675853)
			(xy 348.059647 -263.71943) (xy 348.030082 -263.758774) (xy 347.994589 -263.792866) (xy 347.954086 -263.820822)
			(xy 347.909624 -263.84192) (xy 347.862353 -263.855612) (xy 347.813498 -263.861544) (xy 347.764323 -263.859563)
			(xy 347.716104 -263.849719) (xy 347.670088 -263.832267) (xy 347.627467 -263.80766) (xy 347.589346 -263.776535)
			(xy 347.556711 -263.739698) (xy 347.530408 -263.698102) (xy 347.511117 -263.652826) (xy 347.49934 -263.605042)
			(xy 347.49538 -263.555988) (xy 346.226384 -263.555988) (xy 346.225889 -263.580595) (xy 346.217994 -263.629172)
			(xy 346.20241 -263.675853) (xy 346.179539 -263.71943) (xy 346.149974 -263.758774) (xy 346.114481 -263.792866)
			(xy 346.073978 -263.820822) (xy 346.029516 -263.84192) (xy 345.982245 -263.855612) (xy 345.93339 -263.861544)
			(xy 345.884215 -263.859563) (xy 345.835996 -263.849719) (xy 345.78998 -263.832267) (xy 345.747359 -263.80766)
			(xy 345.709238 -263.776535) (xy 345.676603 -263.739698) (xy 345.6503 -263.698102) (xy 345.631009 -263.652826)
			(xy 345.619232 -263.605042) (xy 345.615272 -263.555988) (xy 344.356944 -263.555988) (xy 344.356432 -263.581434)
			(xy 344.348268 -263.631668) (xy 344.332152 -263.679942) (xy 344.308501 -263.725005) (xy 344.277928 -263.765691)
			(xy 344.241224 -263.800946) (xy 344.19934 -263.829856) (xy 344.153361 -263.851673) (xy 344.104477 -263.865833)
			(xy 344.053956 -263.871967) (xy 344.003104 -263.869918) (xy 343.95324 -263.859738) (xy 343.905654 -263.841691)
			(xy 343.86158 -263.816245) (xy 343.822158 -263.784058) (xy 343.78841 -263.745964) (xy 343.761209 -263.70295)
			(xy 343.741261 -263.65613) (xy 343.729082 -263.606716) (xy 343.724987 -263.555988) (xy 343.406476 -263.555988)
			(xy 343.405981 -263.580595) (xy 343.398086 -263.629172) (xy 343.382502 -263.675853) (xy 343.359631 -263.71943)
			(xy 343.330066 -263.758774) (xy 343.294573 -263.792866) (xy 343.25407 -263.820822) (xy 343.209608 -263.84192)
			(xy 343.162337 -263.855612) (xy 343.113482 -263.861544) (xy 343.064307 -263.859563) (xy 343.016088 -263.849719)
			(xy 342.970072 -263.832267) (xy 342.927451 -263.80766) (xy 342.88933 -263.776535) (xy 342.856695 -263.739698)
			(xy 342.830392 -263.698102) (xy 342.811101 -263.652826) (xy 342.799324 -263.605042) (xy 342.795364 -263.555988)
			(xy 342.476836 -263.555988) (xy 342.476324 -263.581434) (xy 342.46816 -263.631668) (xy 342.452044 -263.679942)
			(xy 342.428393 -263.725005) (xy 342.39782 -263.765691) (xy 342.361116 -263.800946) (xy 342.319232 -263.829856)
			(xy 342.273253 -263.851673) (xy 342.224369 -263.865833) (xy 342.173848 -263.871967) (xy 342.122996 -263.869918)
			(xy 342.073132 -263.859738) (xy 342.025546 -263.841691) (xy 341.981472 -263.816245) (xy 341.94205 -263.784058)
			(xy 341.908302 -263.745964) (xy 341.881101 -263.70295) (xy 341.861153 -263.65613) (xy 341.848974 -263.606716)
			(xy 341.844879 -263.555988) (xy 341.122254 -263.555988) (xy 341.122254 -263.877806) (xy 341.122449 -263.884474)
			(xy 341.125923 -263.897347) (xy 341.129112 -263.903206) (xy 341.234776 -264.08507) (xy 341.245247 -264.103549)
			(xy 341.263681 -264.141818) (xy 341.271606 -264.161524) (xy 341.276686 -264.174478) (xy 341.298276 -264.191496)
			(xy 341.398098 -264.204704) (xy 341.404962 -264.205373) (xy 341.418613 -264.203442) (xy 341.425022 -264.200894)
			(xy 341.431372 -264.198354) (xy 341.441532 -264.189972) (xy 341.44585 -264.184384) (xy 341.460354 -264.165554)
			(xy 341.49421 -264.132198) (xy 341.532823 -264.104486) (xy 341.575261 -264.083088) (xy 341.6205 -264.068519)
			(xy 341.66745 -264.061131) (xy 341.691214 -264.060686) (xy 341.716469 -264.061209) (xy 341.76629 -264.069524)
			(xy 341.814063 -264.085927) (xy 341.858484 -264.109968) (xy 341.898343 -264.140993) (xy 341.932552 -264.178156)
			(xy 341.960178 -264.220442) (xy 341.980467 -264.266698) (xy 341.992866 -264.315662) (xy 341.997037 -264.365994)
			(xy 342.314779 -264.365994) (xy 342.318874 -264.315266) (xy 342.331053 -264.265852) (xy 342.351001 -264.219032)
			(xy 342.378202 -264.176018) (xy 342.41195 -264.137924) (xy 342.451372 -264.105737) (xy 342.495446 -264.080291)
			(xy 342.543032 -264.062244) (xy 342.592896 -264.052064) (xy 342.643748 -264.050015) (xy 342.694269 -264.056149)
			(xy 342.743153 -264.070309) (xy 342.789132 -264.092126) (xy 342.831016 -264.121036) (xy 342.86772 -264.156291)
			(xy 342.898293 -264.196977) (xy 342.921944 -264.24204) (xy 342.93806 -264.290314) (xy 342.946224 -264.340548)
			(xy 342.946736 -264.365994) (xy 343.254833 -264.365994) (xy 343.258928 -264.315266) (xy 343.271107 -264.265852)
			(xy 343.291055 -264.219032) (xy 343.318256 -264.176018) (xy 343.352004 -264.137924) (xy 343.391426 -264.105737)
			(xy 343.4355 -264.080291) (xy 343.483086 -264.062244) (xy 343.53295 -264.052064) (xy 343.583802 -264.050015)
			(xy 343.634323 -264.056149) (xy 343.683207 -264.070309) (xy 343.729186 -264.092126) (xy 343.77107 -264.121036)
			(xy 343.807774 -264.156291) (xy 343.838347 -264.196977) (xy 343.861998 -264.24204) (xy 343.878114 -264.290314)
			(xy 343.886278 -264.340548) (xy 343.88679 -264.365994) (xy 344.205318 -264.365994) (xy 344.209278 -264.31694)
			(xy 344.221055 -264.269156) (xy 344.240346 -264.22388) (xy 344.266649 -264.182284) (xy 344.299284 -264.145447)
			(xy 344.337405 -264.114322) (xy 344.380026 -264.089715) (xy 344.426042 -264.072263) (xy 344.474261 -264.062419)
			(xy 344.523436 -264.060438) (xy 344.572291 -264.06637) (xy 344.619562 -264.080062) (xy 344.664024 -264.10116)
			(xy 344.704527 -264.129116) (xy 344.74002 -264.163208) (xy 344.769585 -264.202552) (xy 344.792456 -264.246129)
			(xy 344.80804 -264.29281) (xy 344.815935 -264.341387) (xy 344.81643 -264.365994) (xy 346.085426 -264.365994)
			(xy 346.089386 -264.31694) (xy 346.101163 -264.269156) (xy 346.120454 -264.22388) (xy 346.146757 -264.182284)
			(xy 346.179392 -264.145447) (xy 346.217513 -264.114322) (xy 346.260134 -264.089715) (xy 346.30615 -264.072263)
			(xy 346.354369 -264.062419) (xy 346.403544 -264.060438) (xy 346.452399 -264.06637) (xy 346.49967 -264.080062)
			(xy 346.544132 -264.10116) (xy 346.584635 -264.129116) (xy 346.620128 -264.163208) (xy 346.649693 -264.202552)
			(xy 346.672564 -264.246129) (xy 346.688148 -264.29281) (xy 346.696043 -264.341387) (xy 346.696538 -264.365994)
			(xy 347.96528 -264.365994) (xy 347.96924 -264.31694) (xy 347.981017 -264.269156) (xy 348.000308 -264.22388)
			(xy 348.026611 -264.182284) (xy 348.059246 -264.145447) (xy 348.097367 -264.114322) (xy 348.139988 -264.089715)
			(xy 348.186004 -264.072263) (xy 348.234223 -264.062419) (xy 348.283398 -264.060438) (xy 348.332253 -264.06637)
			(xy 348.379524 -264.080062) (xy 348.423986 -264.10116) (xy 348.464489 -264.129116) (xy 348.499982 -264.163208)
			(xy 348.529547 -264.202552) (xy 348.552418 -264.246129) (xy 348.568002 -264.29281) (xy 348.575897 -264.341387)
			(xy 348.576392 -264.365994) (xy 348.905334 -264.365994) (xy 348.909294 -264.31694) (xy 348.921071 -264.269156)
			(xy 348.940362 -264.22388) (xy 348.966665 -264.182284) (xy 348.9993 -264.145447) (xy 349.037421 -264.114322)
			(xy 349.080042 -264.089715) (xy 349.126058 -264.072263) (xy 349.174277 -264.062419) (xy 349.223452 -264.060438)
			(xy 349.272307 -264.06637) (xy 349.319578 -264.080062) (xy 349.36404 -264.10116) (xy 349.404543 -264.129116)
			(xy 349.440036 -264.163208) (xy 349.469601 -264.202552) (xy 349.492472 -264.246129) (xy 349.508056 -264.29281)
			(xy 349.515951 -264.341387) (xy 349.516446 -264.365994) (xy 349.515951 -264.390601) (xy 349.508056 -264.439178)
			(xy 349.492472 -264.485859) (xy 349.469601 -264.529436) (xy 349.440036 -264.56878) (xy 349.404543 -264.602872)
			(xy 349.36404 -264.630828) (xy 349.319578 -264.651926) (xy 349.272307 -264.665618) (xy 349.223452 -264.67155)
			(xy 349.174277 -264.669569) (xy 349.126058 -264.659725) (xy 349.080042 -264.642273) (xy 349.037421 -264.617666)
			(xy 348.9993 -264.586541) (xy 348.966665 -264.549704) (xy 348.940362 -264.508108) (xy 348.921071 -264.462832)
			(xy 348.909294 -264.415048) (xy 348.905334 -264.365994) (xy 348.576392 -264.365994) (xy 348.575897 -264.390601)
			(xy 348.568002 -264.439178) (xy 348.552418 -264.485859) (xy 348.529547 -264.529436) (xy 348.499982 -264.56878)
			(xy 348.464489 -264.602872) (xy 348.423986 -264.630828) (xy 348.379524 -264.651926) (xy 348.332253 -264.665618)
			(xy 348.283398 -264.67155) (xy 348.234223 -264.669569) (xy 348.186004 -264.659725) (xy 348.139988 -264.642273)
			(xy 348.097367 -264.617666) (xy 348.059246 -264.586541) (xy 348.026611 -264.549704) (xy 348.000308 -264.508108)
			(xy 347.981017 -264.462832) (xy 347.96924 -264.415048) (xy 347.96528 -264.365994) (xy 346.696538 -264.365994)
			(xy 346.696043 -264.390601) (xy 346.688148 -264.439178) (xy 346.672564 -264.485859) (xy 346.649693 -264.529436)
			(xy 346.620128 -264.56878) (xy 346.584635 -264.602872) (xy 346.544132 -264.630828) (xy 346.49967 -264.651926)
			(xy 346.452399 -264.665618) (xy 346.403544 -264.67155) (xy 346.354369 -264.669569) (xy 346.30615 -264.659725)
			(xy 346.260134 -264.642273) (xy 346.217513 -264.617666) (xy 346.179392 -264.586541) (xy 346.146757 -264.549704)
			(xy 346.120454 -264.508108) (xy 346.101163 -264.462832) (xy 346.089386 -264.415048) (xy 346.085426 -264.365994)
			(xy 344.81643 -264.365994) (xy 344.815935 -264.390601) (xy 344.80804 -264.439178) (xy 344.792456 -264.485859)
			(xy 344.769585 -264.529436) (xy 344.74002 -264.56878) (xy 344.704527 -264.602872) (xy 344.664024 -264.630828)
			(xy 344.619562 -264.651926) (xy 344.572291 -264.665618) (xy 344.523436 -264.67155) (xy 344.474261 -264.669569)
			(xy 344.426042 -264.659725) (xy 344.380026 -264.642273) (xy 344.337405 -264.617666) (xy 344.299284 -264.586541)
			(xy 344.266649 -264.549704) (xy 344.240346 -264.508108) (xy 344.221055 -264.462832) (xy 344.209278 -264.415048)
			(xy 344.205318 -264.365994) (xy 343.88679 -264.365994) (xy 343.886278 -264.39144) (xy 343.878114 -264.441674)
			(xy 343.861998 -264.489948) (xy 343.838347 -264.535011) (xy 343.807774 -264.575697) (xy 343.77107 -264.610952)
			(xy 343.729186 -264.639862) (xy 343.683207 -264.661679) (xy 343.634323 -264.675839) (xy 343.583802 -264.681973)
			(xy 343.53295 -264.679924) (xy 343.483086 -264.669744) (xy 343.4355 -264.651697) (xy 343.391426 -264.626251)
			(xy 343.352004 -264.594064) (xy 343.318256 -264.55597) (xy 343.291055 -264.512956) (xy 343.271107 -264.466136)
			(xy 343.258928 -264.416722) (xy 343.254833 -264.365994) (xy 342.946736 -264.365994) (xy 342.946224 -264.39144)
			(xy 342.93806 -264.441674) (xy 342.921944 -264.489948) (xy 342.898293 -264.535011) (xy 342.86772 -264.575697)
			(xy 342.831016 -264.610952) (xy 342.789132 -264.639862) (xy 342.743153 -264.661679) (xy 342.694269 -264.675839)
			(xy 342.643748 -264.681973) (xy 342.592896 -264.679924) (xy 342.543032 -264.669744) (xy 342.495446 -264.651697)
			(xy 342.451372 -264.626251) (xy 342.41195 -264.594064) (xy 342.378202 -264.55597) (xy 342.351001 -264.512956)
			(xy 342.331053 -264.466136) (xy 342.318874 -264.416722) (xy 342.314779 -264.365994) (xy 341.997037 -264.365994)
			(xy 341.997037 -264.366) (xy 341.992866 -264.416338) (xy 341.980467 -264.465302) (xy 341.960178 -264.511558)
			(xy 341.932552 -264.553844) (xy 341.898343 -264.591007) (xy 341.858484 -264.622032) (xy 341.814063 -264.646073)
			(xy 341.76629 -264.662476) (xy 341.716469 -264.670791) (xy 341.691214 -264.671302) (xy 341.66745 -264.670849)
			(xy 341.620495 -264.663481) (xy 341.575252 -264.648921) (xy 341.532813 -264.627521) (xy 341.494206 -264.599799)
			(xy 341.460365 -264.566426) (xy 341.44585 -264.547604) (xy 341.441532 -264.542016) (xy 341.431372 -264.533634)
			(xy 341.425022 -264.531094) (xy 341.418614 -264.52854) (xy 341.404962 -264.526602) (xy 341.398098 -264.527284)
			(xy 341.29853 -264.540492) (xy 341.276686 -264.55751) (xy 341.271606 -264.570464) (xy 341.260181 -264.598471)
			(xy 341.232138 -264.652068) (xy 341.198467 -264.70232) (xy 341.159564 -264.74864) (xy 341.138002 -264.769854)
			(xy 341.137748 -264.770108) (xy 341.130691 -264.777558) (xy 341.122684 -264.796432) (xy 341.122254 -264.806684)
			(xy 341.122254 -264.82294) (xy 341.122748 -264.832946) (xy 341.130413 -264.851432) (xy 341.144563 -264.865583)
			(xy 341.163048 -264.87325) (xy 341.173054 -264.87374) (xy 341.176356 -264.87374) (xy 341.179658 -264.873486)
			(xy 341.189958 -264.872174) (xy 341.210677 -264.870775) (xy 341.22106 -264.870692) (xy 341.245055 -264.871135)
			(xy 341.292456 -264.878637) (xy 341.338099 -264.893462) (xy 341.38086 -264.915245) (xy 341.419687 -264.94345)
			(xy 341.453624 -264.977382) (xy 341.481834 -265.016206) (xy 341.503623 -265.058964) (xy 341.518454 -265.104606)
			(xy 341.525962 -265.152005) (xy 341.526368 -265.176) (xy 341.844879 -265.176) (xy 341.848974 -265.125272)
			(xy 341.861153 -265.075858) (xy 341.881101 -265.029038) (xy 341.908302 -264.986024) (xy 341.94205 -264.94793)
			(xy 341.981472 -264.915743) (xy 342.025546 -264.890297) (xy 342.073132 -264.87225) (xy 342.122996 -264.86207)
			(xy 342.173848 -264.860021) (xy 342.224369 -264.866155) (xy 342.273253 -264.880315) (xy 342.319232 -264.902132)
			(xy 342.361116 -264.931042) (xy 342.39782 -264.966297) (xy 342.428393 -265.006983) (xy 342.452044 -265.052046)
			(xy 342.46816 -265.10032) (xy 342.476324 -265.150554) (xy 342.476836 -265.176) (xy 342.795364 -265.176)
			(xy 342.799324 -265.126946) (xy 342.811101 -265.079162) (xy 342.830392 -265.033886) (xy 342.856695 -264.99229)
			(xy 342.88933 -264.955453) (xy 342.927451 -264.924328) (xy 342.970072 -264.899721) (xy 343.016088 -264.882269)
			(xy 343.064307 -264.872425) (xy 343.113482 -264.870444) (xy 343.162337 -264.876376) (xy 343.209608 -264.890068)
			(xy 343.25407 -264.911166) (xy 343.294573 -264.939122) (xy 343.330066 -264.973214) (xy 343.359631 -265.012558)
			(xy 343.382502 -265.056135) (xy 343.398086 -265.102816) (xy 343.405981 -265.151393) (xy 343.406476 -265.176)
			(xy 343.735418 -265.176) (xy 343.739378 -265.126946) (xy 343.751155 -265.079162) (xy 343.770446 -265.033886)
			(xy 343.796749 -264.99229) (xy 343.829384 -264.955453) (xy 343.867505 -264.924328) (xy 343.910126 -264.899721)
			(xy 343.956142 -264.882269) (xy 344.004361 -264.872425) (xy 344.053536 -264.870444) (xy 344.102391 -264.876376)
			(xy 344.149662 -264.890068) (xy 344.194124 -264.911166) (xy 344.234627 -264.939122) (xy 344.27012 -264.973214)
			(xy 344.299685 -265.012558) (xy 344.322556 -265.056135) (xy 344.33814 -265.102816) (xy 344.346035 -265.151393)
			(xy 344.34653 -265.176) (xy 345.615272 -265.176) (xy 345.619232 -265.126946) (xy 345.631009 -265.079162)
			(xy 345.6503 -265.033886) (xy 345.676603 -264.99229) (xy 345.709238 -264.955453) (xy 345.747359 -264.924328)
			(xy 345.78998 -264.899721) (xy 345.835996 -264.882269) (xy 345.884215 -264.872425) (xy 345.93339 -264.870444)
			(xy 345.982245 -264.876376) (xy 346.029516 -264.890068) (xy 346.073978 -264.911166) (xy 346.114481 -264.939122)
			(xy 346.149974 -264.973214) (xy 346.179539 -265.012558) (xy 346.20241 -265.056135) (xy 346.217994 -265.102816)
			(xy 346.225889 -265.151393) (xy 346.226384 -265.176) (xy 347.49538 -265.176) (xy 347.49934 -265.126946)
			(xy 347.511117 -265.079162) (xy 347.530408 -265.033886) (xy 347.556711 -264.99229) (xy 347.589346 -264.955453)
			(xy 347.627467 -264.924328) (xy 347.670088 -264.899721) (xy 347.716104 -264.882269) (xy 347.764323 -264.872425)
			(xy 347.813498 -264.870444) (xy 347.862353 -264.876376) (xy 347.909624 -264.890068) (xy 347.954086 -264.911166)
			(xy 347.994589 -264.939122) (xy 348.030082 -264.973214) (xy 348.059647 -265.012558) (xy 348.082518 -265.056135)
			(xy 348.098102 -265.102816) (xy 348.105997 -265.151393) (xy 348.106492 -265.176) (xy 348.105997 -265.200607)
			(xy 348.098102 -265.249184) (xy 348.082518 -265.295865) (xy 348.059647 -265.339442) (xy 348.030082 -265.378786)
			(xy 347.994589 -265.412878) (xy 347.954086 -265.440834) (xy 347.909624 -265.461932) (xy 347.862353 -265.475624)
			(xy 347.813498 -265.481556) (xy 347.764323 -265.479575) (xy 347.716104 -265.469731) (xy 347.670088 -265.452279)
			(xy 347.627467 -265.427672) (xy 347.589346 -265.396547) (xy 347.556711 -265.35971) (xy 347.530408 -265.318114)
			(xy 347.511117 -265.272838) (xy 347.49934 -265.225054) (xy 347.49538 -265.176) (xy 346.226384 -265.176)
			(xy 346.225889 -265.200607) (xy 346.217994 -265.249184) (xy 346.20241 -265.295865) (xy 346.179539 -265.339442)
			(xy 346.149974 -265.378786) (xy 346.114481 -265.412878) (xy 346.073978 -265.440834) (xy 346.029516 -265.461932)
			(xy 345.982245 -265.475624) (xy 345.93339 -265.481556) (xy 345.884215 -265.479575) (xy 345.835996 -265.469731)
			(xy 345.78998 -265.452279) (xy 345.747359 -265.427672) (xy 345.709238 -265.396547) (xy 345.676603 -265.35971)
			(xy 345.6503 -265.318114) (xy 345.631009 -265.272838) (xy 345.619232 -265.225054) (xy 345.615272 -265.176)
			(xy 344.34653 -265.176) (xy 344.346035 -265.200607) (xy 344.33814 -265.249184) (xy 344.322556 -265.295865)
			(xy 344.299685 -265.339442) (xy 344.27012 -265.378786) (xy 344.234627 -265.412878) (xy 344.194124 -265.440834)
			(xy 344.149662 -265.461932) (xy 344.102391 -265.475624) (xy 344.053536 -265.481556) (xy 344.004361 -265.479575)
			(xy 343.956142 -265.469731) (xy 343.910126 -265.452279) (xy 343.867505 -265.427672) (xy 343.829384 -265.396547)
			(xy 343.796749 -265.35971) (xy 343.770446 -265.318114) (xy 343.751155 -265.272838) (xy 343.739378 -265.225054)
			(xy 343.735418 -265.176) (xy 343.406476 -265.176) (xy 343.405981 -265.200607) (xy 343.398086 -265.249184)
			(xy 343.382502 -265.295865) (xy 343.359631 -265.339442) (xy 343.330066 -265.378786) (xy 343.294573 -265.412878)
			(xy 343.25407 -265.440834) (xy 343.209608 -265.461932) (xy 343.162337 -265.475624) (xy 343.113482 -265.481556)
			(xy 343.064307 -265.479575) (xy 343.016088 -265.469731) (xy 342.970072 -265.452279) (xy 342.927451 -265.427672)
			(xy 342.88933 -265.396547) (xy 342.856695 -265.35971) (xy 342.830392 -265.318114) (xy 342.811101 -265.272838)
			(xy 342.799324 -265.225054) (xy 342.795364 -265.176) (xy 342.476836 -265.176) (xy 342.476324 -265.201446)
			(xy 342.46816 -265.25168) (xy 342.452044 -265.299954) (xy 342.428393 -265.345017) (xy 342.39782 -265.385703)
			(xy 342.361116 -265.420958) (xy 342.319232 -265.449868) (xy 342.273253 -265.471685) (xy 342.224369 -265.485845)
			(xy 342.173848 -265.491979) (xy 342.122996 -265.48993) (xy 342.073132 -265.47975) (xy 342.025546 -265.461703)
			(xy 341.981472 -265.436257) (xy 341.94205 -265.40407) (xy 341.908302 -265.365976) (xy 341.881101 -265.322962)
			(xy 341.861153 -265.276142) (xy 341.848974 -265.226728) (xy 341.844879 -265.176) (xy 341.526368 -265.176)
			(xy 341.526231 -265.188763) (xy 341.524072 -265.214198) (xy 341.52205 -265.2268) (xy 341.522304 -265.2268)
			(xy 341.517835 -265.250543) (xy 341.502402 -265.296322) (xy 341.479955 -265.339102) (xy 341.451055 -265.377815)
			(xy 341.41642 -265.411496) (xy 341.376916 -265.439305) (xy 341.333527 -265.46055) (xy 341.287335 -265.474699)
			(xy 341.263478 -265.478514) (xy 341.263224 -265.478514) (xy 341.250951 -265.480898) (xy 341.23072 -265.495542)
			(xy 341.224616 -265.506454) (xy 341.188294 -265.580114) (xy 341.183342 -265.591725) (xy 341.184256 -265.616919)
			(xy 341.190072 -265.62812) (xy 341.234776 -265.705082) (xy 341.252697 -265.737152) (xy 341.280906 -265.804988)
			(xy 341.29999 -265.875932) (xy 341.309622 -265.948765) (xy 341.310214 -265.985498) (xy 341.310214 -265.986006)
			(xy 342.32521 -265.986006) (xy 342.32917 -265.936952) (xy 342.340947 -265.889168) (xy 342.360238 -265.843892)
			(xy 342.386541 -265.802296) (xy 342.419176 -265.765459) (xy 342.457297 -265.734334) (xy 342.499918 -265.709727)
			(xy 342.545934 -265.692275) (xy 342.594153 -265.682431) (xy 342.643328 -265.68045) (xy 342.692183 -265.686382)
			(xy 342.739454 -265.700074) (xy 342.783916 -265.721172) (xy 342.824419 -265.749128) (xy 342.859912 -265.78322)
			(xy 342.889477 -265.822564) (xy 342.912348 -265.866141) (xy 342.927932 -265.912822) (xy 342.935827 -265.961399)
			(xy 342.936322 -265.986006) (xy 343.254833 -265.986006) (xy 343.258928 -265.935278) (xy 343.271107 -265.885864)
			(xy 343.291055 -265.839044) (xy 343.318256 -265.79603) (xy 343.352004 -265.757936) (xy 343.391426 -265.725749)
			(xy 343.4355 -265.700303) (xy 343.483086 -265.682256) (xy 343.53295 -265.672076) (xy 343.583802 -265.670027)
			(xy 343.634323 -265.676161) (xy 343.683207 -265.690321) (xy 343.729186 -265.712138) (xy 343.77107 -265.741048)
			(xy 343.807774 -265.776303) (xy 343.838347 -265.816989) (xy 343.861998 -265.862052) (xy 343.878114 -265.910326)
			(xy 343.886278 -265.96056) (xy 343.88679 -265.986006) (xy 344.205318 -265.986006) (xy 344.209278 -265.936952)
			(xy 344.221055 -265.889168) (xy 344.240346 -265.843892) (xy 344.266649 -265.802296) (xy 344.299284 -265.765459)
			(xy 344.337405 -265.734334) (xy 344.380026 -265.709727) (xy 344.426042 -265.692275) (xy 344.474261 -265.682431)
			(xy 344.523436 -265.68045) (xy 344.572291 -265.686382) (xy 344.619562 -265.700074) (xy 344.664024 -265.721172)
			(xy 344.704527 -265.749128) (xy 344.74002 -265.78322) (xy 344.769585 -265.822564) (xy 344.792456 -265.866141)
			(xy 344.80804 -265.912822) (xy 344.815935 -265.961399) (xy 344.81643 -265.986006) (xy 344.815935 -266.010613)
			(xy 344.80804 -266.05919) (xy 344.792456 -266.105871) (xy 344.769585 -266.149448) (xy 344.74002 -266.188792)
			(xy 344.704527 -266.222884) (xy 344.664024 -266.25084) (xy 344.619562 -266.271938) (xy 344.572291 -266.28563)
			(xy 344.523436 -266.291562) (xy 344.474261 -266.289581) (xy 344.426042 -266.279737) (xy 344.380026 -266.262285)
			(xy 344.337405 -266.237678) (xy 344.299284 -266.206553) (xy 344.266649 -266.169716) (xy 344.240346 -266.12812)
			(xy 344.221055 -266.082844) (xy 344.209278 -266.03506) (xy 344.205318 -265.986006) (xy 343.88679 -265.986006)
			(xy 343.886278 -266.011452) (xy 343.878114 -266.061686) (xy 343.861998 -266.10996) (xy 343.838347 -266.155023)
			(xy 343.807774 -266.195709) (xy 343.77107 -266.230964) (xy 343.729186 -266.259874) (xy 343.683207 -266.281691)
			(xy 343.634323 -266.295851) (xy 343.583802 -266.301985) (xy 343.53295 -266.299936) (xy 343.483086 -266.289756)
			(xy 343.4355 -266.271709) (xy 343.391426 -266.246263) (xy 343.352004 -266.214076) (xy 343.318256 -266.175982)
			(xy 343.291055 -266.132968) (xy 343.271107 -266.086148) (xy 343.258928 -266.036734) (xy 343.254833 -265.986006)
			(xy 342.936322 -265.986006) (xy 342.935827 -266.010613) (xy 342.927932 -266.05919) (xy 342.912348 -266.105871)
			(xy 342.889477 -266.149448) (xy 342.859912 -266.188792) (xy 342.824419 -266.222884) (xy 342.783916 -266.25084)
			(xy 342.739454 -266.271938) (xy 342.692183 -266.28563) (xy 342.643328 -266.291562) (xy 342.594153 -266.289581)
			(xy 342.545934 -266.279737) (xy 342.499918 -266.262285) (xy 342.457297 -266.237678) (xy 342.419176 -266.206553)
			(xy 342.386541 -266.169716) (xy 342.360238 -266.12812) (xy 342.340947 -266.082844) (xy 342.32917 -266.03506)
			(xy 342.32521 -265.986006) (xy 341.310214 -265.986006) (xy 341.310214 -265.98626) (xy 341.309762 -266.01848)
			(xy 341.302358 -266.082494) (xy 341.287644 -266.145233) (xy 341.265814 -266.205863) (xy 341.237159 -266.263582)
			(xy 341.202058 -266.317624) (xy 341.160977 -266.367272) (xy 341.138002 -266.389866) (xy 341.137748 -266.39012)
			(xy 341.130693 -266.397571) (xy 341.12269 -266.416445) (xy 341.122254 -266.426696) (xy 341.122254 -266.442952)
			(xy 341.122664 -266.452983) (xy 341.130324 -266.471524) (xy 341.144497 -266.485723) (xy 341.163024 -266.493417)
			(xy 341.173054 -266.493752) (xy 341.176356 -266.493752) (xy 341.179658 -266.493498) (xy 341.189958 -266.492186)
			(xy 341.210677 -266.490787) (xy 341.22106 -266.490704) (xy 341.245055 -266.491147) (xy 341.292454 -266.498649)
			(xy 341.338097 -266.513474) (xy 341.380858 -266.535258) (xy 341.419684 -266.563463) (xy 341.453619 -266.597395)
			(xy 341.481828 -266.636219) (xy 341.503615 -266.678977) (xy 341.518444 -266.724618) (xy 341.525951 -266.772017)
			(xy 341.526368 -266.796012) (xy 341.52624 -266.807552) (xy 341.524462 -266.830564) (xy 341.522812 -266.841986)
			(xy 341.522304 -266.845796) (xy 341.522304 -266.846812) (xy 341.518183 -266.8688) (xy 341.504352 -266.911344)
			(xy 341.484454 -266.95141) (xy 341.472012 -266.970002) (xy 341.467948 -266.976098) (xy 341.462614 -266.9921)
			(xy 341.460108 -267.001147) (xy 341.461077 -267.019878) (xy 341.468697 -267.037016) (xy 341.47506 -267.043916)
			(xy 341.619078 -267.187934) (xy 341.619586 -267.188442) (xy 341.626968 -267.19502) (xy 341.645268 -267.20246)
			(xy 341.655146 -267.20292)
		)
		(stroke
			(width 0)
			(type solid)
		)
		(fill yes)
		(layer "In4.Cu")
		(net "PVDDIO_P0")
	)
	(gr_poly
		(pts
			(xy 418.143436 -440.674252) (xy 418.155593 -440.673552) (xy 418.177202 -440.662404) (xy 418.184838 -440.652916)
			(xy 418.239956 -440.574938) (xy 418.243512 -440.550808) (xy 418.239448 -440.539124) (xy 418.229402 -440.508534)
			(xy 418.218542 -440.445076) (xy 418.217858 -440.412886) (xy 418.218344 -440.385635) (xy 418.2261 -440.331687)
			(xy 418.241455 -440.279392) (xy 418.264097 -440.229815) (xy 418.293563 -440.183965) (xy 418.329254 -440.142774)
			(xy 418.370445 -440.107083) (xy 418.416295 -440.077617) (xy 418.465872 -440.054975) (xy 418.518167 -440.03962)
			(xy 418.572115 -440.031864) (xy 418.626617 -440.031864) (xy 418.680565 -440.03962) (xy 418.73286 -440.054975)
			(xy 418.782437 -440.077617) (xy 418.828287 -440.107083) (xy 418.869478 -440.142774) (xy 418.905169 -440.183965)
			(xy 418.934635 -440.229815) (xy 418.957277 -440.279392) (xy 418.972632 -440.331687) (xy 418.980388 -440.385635)
			(xy 418.980874 -440.412886) (xy 418.980188 -440.445076) (xy 418.969341 -440.508538) (xy 418.959284 -440.539124)
			(xy 418.95522 -440.550808) (xy 418.958776 -440.574938) (xy 419.013894 -440.652916) (xy 419.021514 -440.662414)
			(xy 419.043137 -440.673535) (xy 419.055296 -440.674252) (xy 443.233048 -440.674252) (xy 443.243113 -440.673819)
			(xy 443.2617 -440.666087) (xy 443.269116 -440.659266) (xy 444.787782 -439.1406) (xy 444.79463 -439.133202)
			(xy 444.802367 -439.114604) (xy 444.802768 -439.104532) (xy 444.802768 -432.770534) (xy 444.802332 -432.76047)
			(xy 444.794597 -432.741886) (xy 444.787782 -432.734466) (xy 444.12027 -432.066954) (xy 444.112872 -432.060107)
			(xy 444.094274 -432.052375) (xy 444.084202 -432.051968) (xy 432.930554 -432.051968) (xy 432.92176 -432.052329)
			(xy 432.905207 -432.058272) (xy 432.891648 -432.069472) (xy 432.886866 -432.07686) (xy 432.872069 -432.101008)
			(xy 432.83646 -432.145045) (xy 432.794726 -432.183328) (xy 432.747787 -432.215014) (xy 432.696676 -432.239405)
			(xy 432.642518 -432.255965) (xy 432.586507 -432.264329) (xy 432.55819 -432.26482) (xy 432.529212 -432.264288)
			(xy 432.471921 -432.255536) (xy 432.416612 -432.238219) (xy 432.364559 -432.212736) (xy 432.316959 -432.179674)
			(xy 432.274908 -432.139792) (xy 432.239372 -432.09401) (xy 432.211169 -432.043379) (xy 432.200558 -432.016408)
			(xy 432.197002 -432.006502) (xy 432.182016 -431.991008) (xy 432.092354 -431.955194) (xy 432.071018 -431.955702)
			(xy 432.061112 -431.960528) (xy 432.03515 -431.972661) (xy 431.981085 -431.991675) (xy 431.925225 -432.004488)
			(xy 431.868279 -432.010936) (xy 431.839624 -432.011328) (xy 431.808891 -432.010884) (xy 431.747871 -432.003478)
			(xy 431.68819 -431.98877) (xy 431.630716 -431.966976) (xy 431.576289 -431.938414) (xy 431.525701 -431.903499)
			(xy 431.47969 -431.862741) (xy 431.438928 -431.816734) (xy 431.404009 -431.766149) (xy 431.375442 -431.711724)
			(xy 431.353643 -431.654252) (xy 431.33893 -431.594572) (xy 431.331519 -431.533553) (xy 431.331116 -431.50282)
			(xy 431.331575 -431.471849) (xy 431.339097 -431.410365) (xy 431.354033 -431.35025) (xy 431.37616 -431.292394)
			(xy 431.405151 -431.237655) (xy 431.440578 -431.186843) (xy 431.46091 -431.163476) (xy 431.467514 -431.15611)
			(xy 431.474118 -431.138076) (xy 431.472086 -431.05832) (xy 431.471365 -431.048661) (xy 431.463655 -431.030909)
			(xy 431.4571 -431.023776) (xy 429.677322 -429.243998) (xy 429.655732 -429.236378) (xy 429.644302 -429.237648)
			(xy 429.634551 -429.238598) (xy 429.614983 -429.239614) (xy 429.605186 -429.23968) (xy 429.604678 -429.23968)
			(xy 429.577427 -429.239215) (xy 429.52348 -429.231455) (xy 429.471186 -429.216097) (xy 429.421611 -429.193453)
			(xy 429.375762 -429.163984) (xy 429.334575 -429.12829) (xy 429.298886 -429.087098) (xy 429.269423 -429.041245)
			(xy 429.246785 -428.991667) (xy 429.231434 -428.939371) (xy 429.223681 -428.885423) (xy 429.22317 -428.858172)
			(xy 429.22317 -428.857664) (xy 429.22324 -428.847867) (xy 429.224258 -428.8283) (xy 429.225202 -428.818548)
			(xy 429.226472 -428.807118) (xy 429.218852 -428.785528) (xy 428.534322 -428.100998) (xy 428.512732 -428.093378)
			(xy 428.501302 -428.094648) (xy 428.491551 -428.095598) (xy 428.471983 -428.096614) (xy 428.462186 -428.09668)
			(xy 428.461678 -428.09668) (xy 428.434427 -428.096215) (xy 428.38048 -428.088455) (xy 428.328186 -428.073097)
			(xy 428.278611 -428.050453) (xy 428.232762 -428.020984) (xy 428.191575 -427.98529) (xy 428.155886 -427.944098)
			(xy 428.126423 -427.898245) (xy 428.103785 -427.848667) (xy 428.088434 -427.796371) (xy 428.080681 -427.742423)
			(xy 428.08017 -427.715172) (xy 428.08017 -427.714664) (xy 428.08024 -427.704867) (xy 428.081258 -427.6853)
			(xy 428.082202 -427.675548) (xy 428.083472 -427.664118) (xy 428.075852 -427.642528) (xy 427.54169 -427.108366)
			(xy 427.534294 -427.101514) (xy 427.515695 -427.093773) (xy 427.505622 -427.09338) (xy 423.218356 -427.09338)
			(xy 423.20829 -427.092948) (xy 423.189699 -427.08522) (xy 423.182288 -427.078394) (xy 421.095678 -424.991784)
			(xy 421.088282 -424.984932) (xy 421.069683 -424.977192) (xy 421.05961 -424.976798) (xy 421.02913 -424.976798)
			(xy 421.019686 -424.977291) (xy 421.002101 -424.984201) (xy 420.99484 -424.99026) (xy 420.971288 -425.011378)
			(xy 420.919868 -425.048228) (xy 420.864275 -425.078416) (xy 420.805368 -425.101476) (xy 420.744055 -425.117053)
			(xy 420.681284 -425.124905) (xy 420.649654 -425.125388) (xy 420.618925 -425.124921) (xy 420.557916 -425.117508)
			(xy 420.498246 -425.102795) (xy 420.440784 -425.080998) (xy 420.386368 -425.052433) (xy 420.335792 -425.017517)
			(xy 420.289793 -424.97676) (xy 420.249042 -424.930756) (xy 420.214133 -424.880176) (xy 420.185575 -424.825756)
			(xy 420.163785 -424.768291) (xy 420.14908 -424.708619) (xy 420.141675 -424.647609) (xy 420.141146 -424.61688)
			(xy 420.141689 -424.583632) (xy 420.15036 -424.517704) (xy 420.167552 -424.453469) (xy 420.19297 -424.392023)
			(xy 420.226182 -424.334415) (xy 420.266621 -424.281628) (xy 420.289736 -424.257724) (xy 420.304722 -424.242738)
			(xy 420.304722 -424.200828) (xy 420.224204 -424.12031) (xy 420.216795 -424.113624) (xy 420.198359 -424.106039)
			(xy 420.18839 -424.105578) (xy 420.164006 -424.111928) (xy 420.135693 -424.126766) (xy 420.07534 -424.147816)
			(xy 420.012323 -424.158512) (xy 419.980364 -424.159172) (xy 419.979856 -424.159172) (xy 419.952608 -424.158683)
			(xy 419.898667 -424.150921) (xy 419.846379 -424.135562) (xy 419.79681 -424.112917) (xy 419.750968 -424.083449)
			(xy 419.709786 -424.047757) (xy 419.674103 -424.006568) (xy 419.644644 -423.96072) (xy 419.62201 -423.911146)
			(xy 419.606662 -423.858855) (xy 419.598912 -423.804912) (xy 419.598348 -423.777664) (xy 419.598348 -423.777156)
			(xy 419.599017 -423.745197) (xy 419.609708 -423.68218) (xy 419.63075 -423.621825) (xy 419.645592 -423.593514)
			(xy 419.653974 -423.578782) (xy 419.649148 -423.545254) (xy 419.541452 -423.437558) (xy 419.52418 -423.429938)
			(xy 419.514274 -423.429684) (xy 419.482432 -423.428121) (xy 419.419482 -423.41804) (xy 419.358285 -423.400169)
			(xy 419.299801 -423.37479) (xy 419.244948 -423.3423) (xy 419.194587 -423.303209) (xy 419.149506 -423.25813)
			(xy 419.110412 -423.20777) (xy 419.07792 -423.152919) (xy 419.052538 -423.094437) (xy 419.034665 -423.033241)
			(xy 419.024581 -422.970291) (xy 419.023038 -422.938448) (xy 419.022784 -422.928542) (xy 419.015164 -422.91127)
			(xy 418.03701 -421.933116) (xy 418.010594 -421.926258) (xy 417.997386 -421.929814) (xy 417.974519 -421.935615)
			(xy 417.927756 -421.941853) (xy 417.904168 -421.94226) (xy 417.903914 -421.94226) (xy 417.876448 -421.941753)
			(xy 417.822168 -421.933324) (xy 417.769824 -421.916663) (xy 417.720658 -421.892164) (xy 417.675835 -421.86041)
			(xy 417.636418 -421.822151) (xy 417.60334 -421.778296) (xy 417.58997 -421.7543) (xy 417.583366 -421.741854)
			(xy 417.55949 -421.72763) (xy 416.989514 -421.72763) (xy 416.965638 -421.741854) (xy 416.959034 -421.7543)
			(xy 416.945618 -421.778271) (xy 416.912556 -421.822137) (xy 416.87315 -421.860406) (xy 416.828335 -421.892171)
			(xy 416.779175 -421.916679) (xy 416.726834 -421.933347) (xy 416.672555 -421.941781) (xy 416.617625 -421.941781)
			(xy 416.563346 -421.933347) (xy 416.511005 -421.916679) (xy 416.461845 -421.892171) (xy 416.41703 -421.860406)
			(xy 416.377624 -421.822137) (xy 416.344562 -421.778271) (xy 416.331146 -421.7543) (xy 416.324542 -421.741854)
			(xy 416.300666 -421.72763) (xy 415.185098 -421.72763) (xy 415.161222 -421.741854) (xy 415.154618 -421.7543)
			(xy 415.141202 -421.778271) (xy 415.10814 -421.822137) (xy 415.068734 -421.860406) (xy 415.023919 -421.892171)
			(xy 414.974759 -421.916679) (xy 414.922418 -421.933347) (xy 414.868139 -421.941781) (xy 414.813209 -421.941781)
			(xy 414.75893 -421.933347) (xy 414.706589 -421.916679) (xy 414.657429 -421.892171) (xy 414.612614 -421.860406)
			(xy 414.573208 -421.822137) (xy 414.540146 -421.778271) (xy 414.52673 -421.7543) (xy 414.520126 -421.741854)
			(xy 414.49625 -421.72763) (xy 413.926274 -421.72763) (xy 413.902398 -421.741854) (xy 413.895794 -421.7543)
			(xy 413.882378 -421.778271) (xy 413.849316 -421.822137) (xy 413.80991 -421.860406) (xy 413.765095 -421.892171)
			(xy 413.715935 -421.916679) (xy 413.663594 -421.933347) (xy 413.609315 -421.941781) (xy 413.554385 -421.941781)
			(xy 413.500106 -421.933347) (xy 413.447765 -421.916679) (xy 413.398605 -421.892171) (xy 413.35379 -421.860406)
			(xy 413.314384 -421.822137) (xy 413.281322 -421.778271) (xy 413.267906 -421.7543) (xy 413.261302 -421.741854)
			(xy 413.237426 -421.72763) (xy 412.121858 -421.72763) (xy 412.097982 -421.741854) (xy 412.091378 -421.7543)
			(xy 412.077962 -421.778271) (xy 412.0449 -421.822137) (xy 412.005494 -421.860406) (xy 411.960679 -421.892171)
			(xy 411.911519 -421.916679) (xy 411.859178 -421.933347) (xy 411.804899 -421.941781) (xy 411.749969 -421.941781)
			(xy 411.69569 -421.933347) (xy 411.643349 -421.916679) (xy 411.594189 -421.892171) (xy 411.549374 -421.860406)
			(xy 411.509968 -421.822137) (xy 411.476906 -421.778271) (xy 411.46349 -421.7543) (xy 411.456886 -421.741854)
			(xy 411.43301 -421.72763) (xy 410.863034 -421.72763) (xy 410.839158 -421.741854) (xy 410.832554 -421.7543)
			(xy 410.819138 -421.778271) (xy 410.786076 -421.822137) (xy 410.74667 -421.860406) (xy 410.701855 -421.892171)
			(xy 410.652695 -421.916679) (xy 410.600354 -421.933347) (xy 410.546075 -421.941781) (xy 410.491145 -421.941781)
			(xy 410.436866 -421.933347) (xy 410.384525 -421.916679) (xy 410.335365 -421.892171) (xy 410.29055 -421.860406)
			(xy 410.251144 -421.822137) (xy 410.218082 -421.778271) (xy 410.204666 -421.7543) (xy 410.198062 -421.741854)
			(xy 410.174186 -421.72763) (xy 409.058618 -421.72763) (xy 409.034742 -421.741854) (xy 409.028138 -421.7543)
			(xy 409.014722 -421.778271) (xy 408.98166 -421.822137) (xy 408.942254 -421.860406) (xy 408.897439 -421.892171)
			(xy 408.848279 -421.916679) (xy 408.795938 -421.933347) (xy 408.741659 -421.941781) (xy 408.686729 -421.941781)
			(xy 408.63245 -421.933347) (xy 408.580109 -421.916679) (xy 408.530949 -421.892171) (xy 408.486134 -421.860406)
			(xy 408.446728 -421.822137) (xy 408.413666 -421.778271) (xy 408.40025 -421.7543) (xy 408.393646 -421.741854)
			(xy 408.36977 -421.72763) (xy 407.799794 -421.72763) (xy 407.775918 -421.741854) (xy 407.769314 -421.7543)
			(xy 407.755898 -421.778271) (xy 407.722836 -421.822137) (xy 407.68343 -421.860406) (xy 407.638615 -421.892171)
			(xy 407.589455 -421.916679) (xy 407.537114 -421.933347) (xy 407.482835 -421.941781) (xy 407.427905 -421.941781)
			(xy 407.373626 -421.933347) (xy 407.321285 -421.916679) (xy 407.272125 -421.892171) (xy 407.22731 -421.860406)
			(xy 407.187904 -421.822137) (xy 407.154842 -421.778271) (xy 407.141426 -421.7543) (xy 407.134822 -421.741854)
			(xy 407.110946 -421.72763) (xy 405.995378 -421.72763) (xy 405.971502 -421.741854) (xy 405.964898 -421.7543)
			(xy 405.951482 -421.778271) (xy 405.91842 -421.822137) (xy 405.879014 -421.860406) (xy 405.834199 -421.892171)
			(xy 405.785039 -421.916679) (xy 405.732698 -421.933347) (xy 405.678419 -421.941781) (xy 405.623489 -421.941781)
			(xy 405.56921 -421.933347) (xy 405.516869 -421.916679) (xy 405.467709 -421.892171) (xy 405.422894 -421.860406)
			(xy 405.383488 -421.822137) (xy 405.350426 -421.778271) (xy 405.33701 -421.7543) (xy 405.330406 -421.741854)
			(xy 405.30653 -421.72763) (xy 404.736554 -421.72763) (xy 404.712678 -421.741854) (xy 404.706074 -421.7543)
			(xy 404.692658 -421.778271) (xy 404.659596 -421.822137) (xy 404.62019 -421.860406) (xy 404.575375 -421.892171)
			(xy 404.526215 -421.916679) (xy 404.473874 -421.933347) (xy 404.419595 -421.941781) (xy 404.364665 -421.941781)
			(xy 404.310386 -421.933347) (xy 404.258045 -421.916679) (xy 404.208885 -421.892171) (xy 404.16407 -421.860406)
			(xy 404.124664 -421.822137) (xy 404.091602 -421.778271) (xy 404.078186 -421.7543) (xy 404.071582 -421.741854)
			(xy 404.047706 -421.72763) (xy 402.932138 -421.72763) (xy 402.908262 -421.741854) (xy 402.901658 -421.7543)
			(xy 402.888242 -421.778271) (xy 402.85518 -421.822137) (xy 402.815774 -421.860406) (xy 402.770959 -421.892171)
			(xy 402.721799 -421.916679) (xy 402.669458 -421.933347) (xy 402.615179 -421.941781) (xy 402.560249 -421.941781)
			(xy 402.50597 -421.933347) (xy 402.453629 -421.916679) (xy 402.404469 -421.892171) (xy 402.359654 -421.860406)
			(xy 402.320248 -421.822137) (xy 402.287186 -421.778271) (xy 402.27377 -421.7543) (xy 402.267166 -421.741854)
			(xy 402.24329 -421.72763) (xy 401.673314 -421.72763) (xy 401.649438 -421.741854) (xy 401.642834 -421.7543)
			(xy 401.629418 -421.778271) (xy 401.596356 -421.822137) (xy 401.55695 -421.860406) (xy 401.512135 -421.892171)
			(xy 401.462975 -421.916679) (xy 401.410634 -421.933347) (xy 401.356355 -421.941781) (xy 401.301425 -421.941781)
			(xy 401.247146 -421.933347) (xy 401.194805 -421.916679) (xy 401.145645 -421.892171) (xy 401.10083 -421.860406)
			(xy 401.061424 -421.822137) (xy 401.028362 -421.778271) (xy 401.014946 -421.7543) (xy 401.008342 -421.741854)
			(xy 400.984466 -421.72763) (xy 399.868898 -421.72763) (xy 399.845022 -421.741854) (xy 399.838418 -421.7543)
			(xy 399.825002 -421.778271) (xy 399.79194 -421.822137) (xy 399.752534 -421.860406) (xy 399.707719 -421.892171)
			(xy 399.658559 -421.916679) (xy 399.606218 -421.933347) (xy 399.551939 -421.941781) (xy 399.497009 -421.941781)
			(xy 399.44273 -421.933347) (xy 399.390389 -421.916679) (xy 399.341229 -421.892171) (xy 399.296414 -421.860406)
			(xy 399.257008 -421.822137) (xy 399.223946 -421.778271) (xy 399.21053 -421.7543) (xy 399.203926 -421.741854)
			(xy 399.18005 -421.72763) (xy 398.610074 -421.72763) (xy 398.586198 -421.741854) (xy 398.579594 -421.7543)
			(xy 398.566178 -421.778271) (xy 398.533116 -421.822137) (xy 398.49371 -421.860406) (xy 398.448895 -421.892171)
			(xy 398.399735 -421.916679) (xy 398.347394 -421.933347) (xy 398.293115 -421.941781) (xy 398.238185 -421.941781)
			(xy 398.183906 -421.933347) (xy 398.131565 -421.916679) (xy 398.082405 -421.892171) (xy 398.03759 -421.860406)
			(xy 397.998184 -421.822137) (xy 397.965122 -421.778271) (xy 397.951706 -421.7543) (xy 397.945102 -421.741854)
			(xy 397.921226 -421.72763) (xy 396.805658 -421.72763) (xy 396.781782 -421.741854) (xy 396.775178 -421.7543)
			(xy 396.761762 -421.778271) (xy 396.7287 -421.822137) (xy 396.689294 -421.860406) (xy 396.644479 -421.892171)
			(xy 396.595319 -421.916679) (xy 396.542978 -421.933347) (xy 396.488699 -421.941781) (xy 396.433769 -421.941781)
			(xy 396.37949 -421.933347) (xy 396.327149 -421.916679) (xy 396.277989 -421.892171) (xy 396.233174 -421.860406)
			(xy 396.193768 -421.822137) (xy 396.160706 -421.778271) (xy 396.14729 -421.7543) (xy 396.140686 -421.741854)
			(xy 396.11681 -421.72763) (xy 395.546834 -421.72763) (xy 395.522958 -421.741854) (xy 395.516354 -421.7543)
			(xy 395.502938 -421.778271) (xy 395.469876 -421.822137) (xy 395.43047 -421.860406) (xy 395.385655 -421.892171)
			(xy 395.336495 -421.916679) (xy 395.284154 -421.933347) (xy 395.229875 -421.941781) (xy 395.174945 -421.941781)
			(xy 395.120666 -421.933347) (xy 395.068325 -421.916679) (xy 395.019165 -421.892171) (xy 394.97435 -421.860406)
			(xy 394.934944 -421.822137) (xy 394.901882 -421.778271) (xy 394.888466 -421.7543) (xy 394.881862 -421.741854)
			(xy 394.857986 -421.72763) (xy 393.742418 -421.72763) (xy 393.718542 -421.741854) (xy 393.711938 -421.7543)
			(xy 393.698522 -421.778271) (xy 393.66546 -421.822137) (xy 393.626054 -421.860406) (xy 393.581239 -421.892171)
			(xy 393.532079 -421.916679) (xy 393.479738 -421.933347) (xy 393.425459 -421.941781) (xy 393.370529 -421.941781)
			(xy 393.31625 -421.933347) (xy 393.263909 -421.916679) (xy 393.214749 -421.892171) (xy 393.169934 -421.860406)
			(xy 393.130528 -421.822137) (xy 393.097466 -421.778271) (xy 393.08405 -421.7543) (xy 393.077446 -421.741854)
			(xy 393.05357 -421.72763) (xy 392.483594 -421.72763) (xy 392.459718 -421.741854) (xy 392.453114 -421.7543)
			(xy 392.439698 -421.778271) (xy 392.406636 -421.822137) (xy 392.36723 -421.860406) (xy 392.322415 -421.892171)
			(xy 392.273255 -421.916679) (xy 392.220914 -421.933347) (xy 392.166635 -421.941781) (xy 392.111705 -421.941781)
			(xy 392.057426 -421.933347) (xy 392.005085 -421.916679) (xy 391.955925 -421.892171) (xy 391.91111 -421.860406)
			(xy 391.871704 -421.822137) (xy 391.838642 -421.778271) (xy 391.825226 -421.7543) (xy 391.818622 -421.741854)
			(xy 391.794746 -421.72763) (xy 390.679178 -421.72763) (xy 390.655302 -421.741854) (xy 390.648698 -421.7543)
			(xy 390.635282 -421.778271) (xy 390.60222 -421.822137) (xy 390.562814 -421.860406) (xy 390.517999 -421.892171)
			(xy 390.468839 -421.916679) (xy 390.416498 -421.933347) (xy 390.362219 -421.941781) (xy 390.307289 -421.941781)
			(xy 390.25301 -421.933347) (xy 390.200669 -421.916679) (xy 390.151509 -421.892171) (xy 390.106694 -421.860406)
			(xy 390.067288 -421.822137) (xy 390.034226 -421.778271) (xy 390.02081 -421.7543) (xy 390.014206 -421.741854)
			(xy 389.99033 -421.72763) (xy 389.420354 -421.72763) (xy 389.396478 -421.741854) (xy 389.389874 -421.7543)
			(xy 389.376458 -421.778271) (xy 389.343396 -421.822137) (xy 389.30399 -421.860406) (xy 389.259175 -421.892171)
			(xy 389.210015 -421.916679) (xy 389.157674 -421.933347) (xy 389.103395 -421.941781) (xy 389.048465 -421.941781)
			(xy 388.994186 -421.933347) (xy 388.941845 -421.916679) (xy 388.892685 -421.892171) (xy 388.84787 -421.860406)
			(xy 388.808464 -421.822137) (xy 388.775402 -421.778271) (xy 388.761986 -421.7543) (xy 388.755382 -421.741854)
			(xy 388.731506 -421.72763) (xy 387.692138 -421.72763) (xy 387.668262 -421.741854) (xy 387.661658 -421.7543)
			(xy 387.648242 -421.778271) (xy 387.61518 -421.822137) (xy 387.575774 -421.860406) (xy 387.530959 -421.892171)
			(xy 387.481799 -421.916679) (xy 387.429458 -421.933347) (xy 387.375179 -421.941781) (xy 387.320249 -421.941781)
			(xy 387.26597 -421.933347) (xy 387.213629 -421.916679) (xy 387.164469 -421.892171) (xy 387.119654 -421.860406)
			(xy 387.080248 -421.822137) (xy 387.047186 -421.778271) (xy 387.03377 -421.7543) (xy 387.027166 -421.741854)
			(xy 387.00329 -421.72763) (xy 386.357114 -421.72763) (xy 386.333238 -421.741854) (xy 386.326634 -421.7543)
			(xy 386.313218 -421.778271) (xy 386.280156 -421.822137) (xy 386.24075 -421.860406) (xy 386.195935 -421.892171)
			(xy 386.146775 -421.916679) (xy 386.094434 -421.933347) (xy 386.040155 -421.941781) (xy 385.985225 -421.941781)
			(xy 385.930946 -421.933347) (xy 385.878605 -421.916679) (xy 385.829445 -421.892171) (xy 385.78463 -421.860406)
			(xy 385.745224 -421.822137) (xy 385.712162 -421.778271) (xy 385.698746 -421.7543) (xy 385.692142 -421.741854)
			(xy 385.668266 -421.72763) (xy 384.58521 -421.72763) (xy 384.54457 -421.748204) (xy 384.527645 -421.770034)
			(xy 384.488188 -421.808689) (xy 384.443236 -421.840787) (xy 384.393867 -421.865559) (xy 384.341265 -421.882412)
			(xy 384.286692 -421.890941) (xy 384.231456 -421.890941) (xy 384.176883 -421.882412) (xy 384.124281 -421.865559)
			(xy 384.074912 -421.840787) (xy 384.02996 -421.808689) (xy 383.990503 -421.770034) (xy 383.973578 -421.748204)
			(xy 383.932938 -421.72763) (xy 383.293874 -421.72763) (xy 383.269998 -421.741854) (xy 383.263394 -421.7543)
			(xy 383.249978 -421.778271) (xy 383.216916 -421.822137) (xy 383.17751 -421.860406) (xy 383.132695 -421.892171)
			(xy 383.083535 -421.916679) (xy 383.031194 -421.933347) (xy 382.976915 -421.941781) (xy 382.921985 -421.941781)
			(xy 382.867706 -421.933347) (xy 382.815365 -421.916679) (xy 382.766205 -421.892171) (xy 382.72139 -421.860406)
			(xy 382.681984 -421.822137) (xy 382.648922 -421.778271) (xy 382.635506 -421.7543) (xy 382.628902 -421.741854)
			(xy 382.605026 -421.72763) (xy 381.489458 -421.72763) (xy 381.465582 -421.741854) (xy 381.458978 -421.7543)
			(xy 381.445562 -421.778271) (xy 381.4125 -421.822137) (xy 381.373094 -421.860406) (xy 381.328279 -421.892171)
			(xy 381.279119 -421.916679) (xy 381.226778 -421.933347) (xy 381.172499 -421.941781) (xy 381.117569 -421.941781)
			(xy 381.06329 -421.933347) (xy 381.010949 -421.916679) (xy 380.961789 -421.892171) (xy 380.916974 -421.860406)
			(xy 380.877568 -421.822137) (xy 380.844506 -421.778271) (xy 380.83109 -421.7543) (xy 380.824486 -421.741854)
			(xy 380.80061 -421.72763) (xy 380.230634 -421.72763) (xy 380.206758 -421.741854) (xy 380.200154 -421.7543)
			(xy 380.186738 -421.778271) (xy 380.153676 -421.822137) (xy 380.11427 -421.860406) (xy 380.069455 -421.892171)
			(xy 380.020295 -421.916679) (xy 379.967954 -421.933347) (xy 379.913675 -421.941781) (xy 379.858745 -421.941781)
			(xy 379.804466 -421.933347) (xy 379.752125 -421.916679) (xy 379.702965 -421.892171) (xy 379.65815 -421.860406)
			(xy 379.618744 -421.822137) (xy 379.585682 -421.778271) (xy 379.572266 -421.7543) (xy 379.565662 -421.741854)
			(xy 379.541786 -421.72763) (xy 378.426218 -421.72763) (xy 378.402342 -421.741854) (xy 378.395738 -421.7543)
			(xy 378.382322 -421.778271) (xy 378.34926 -421.822137) (xy 378.309854 -421.860406) (xy 378.265039 -421.892171)
			(xy 378.215879 -421.916679) (xy 378.163538 -421.933347) (xy 378.109259 -421.941781) (xy 378.054329 -421.941781)
			(xy 378.00005 -421.933347) (xy 377.947709 -421.916679) (xy 377.898549 -421.892171) (xy 377.853734 -421.860406)
			(xy 377.814328 -421.822137) (xy 377.781266 -421.778271) (xy 377.76785 -421.7543) (xy 377.761246 -421.741854)
			(xy 377.73737 -421.72763) (xy 377.167394 -421.72763) (xy 377.143518 -421.741854) (xy 377.136914 -421.7543)
			(xy 377.123498 -421.778271) (xy 377.090436 -421.822137) (xy 377.05103 -421.860406) (xy 377.006215 -421.892171)
			(xy 376.957055 -421.916679) (xy 376.904714 -421.933347) (xy 376.850435 -421.941781) (xy 376.795505 -421.941781)
			(xy 376.741226 -421.933347) (xy 376.688885 -421.916679) (xy 376.639725 -421.892171) (xy 376.59491 -421.860406)
			(xy 376.555504 -421.822137) (xy 376.522442 -421.778271) (xy 376.509026 -421.7543) (xy 376.502422 -421.741854)
			(xy 376.478546 -421.72763) (xy 375.362978 -421.72763) (xy 375.339102 -421.741854) (xy 375.332498 -421.7543)
			(xy 375.319082 -421.778271) (xy 375.28602 -421.822137) (xy 375.246614 -421.860406) (xy 375.201799 -421.892171)
			(xy 375.152639 -421.916679) (xy 375.100298 -421.933347) (xy 375.046019 -421.941781) (xy 374.991089 -421.941781)
			(xy 374.93681 -421.933347) (xy 374.884469 -421.916679) (xy 374.835309 -421.892171) (xy 374.790494 -421.860406)
			(xy 374.751088 -421.822137) (xy 374.718026 -421.778271) (xy 374.70461 -421.7543) (xy 374.698006 -421.741854)
			(xy 374.67413 -421.72763) (xy 374.104154 -421.72763) (xy 374.080278 -421.741854) (xy 374.073674 -421.7543)
			(xy 374.060258 -421.778271) (xy 374.027196 -421.822137) (xy 373.98779 -421.860406) (xy 373.942975 -421.892171)
			(xy 373.893815 -421.916679) (xy 373.841474 -421.933347) (xy 373.787195 -421.941781) (xy 373.732265 -421.941781)
			(xy 373.677986 -421.933347) (xy 373.625645 -421.916679) (xy 373.576485 -421.892171) (xy 373.53167 -421.860406)
			(xy 373.492264 -421.822137) (xy 373.459202 -421.778271) (xy 373.445786 -421.7543) (xy 373.439182 -421.741854)
			(xy 373.415306 -421.72763) (xy 372.299738 -421.72763) (xy 372.275862 -421.741854) (xy 372.269258 -421.7543)
			(xy 372.255842 -421.778271) (xy 372.22278 -421.822137) (xy 372.183374 -421.860406) (xy 372.138559 -421.892171)
			(xy 372.089399 -421.916679) (xy 372.037058 -421.933347) (xy 371.982779 -421.941781) (xy 371.927849 -421.941781)
			(xy 371.87357 -421.933347) (xy 371.821229 -421.916679) (xy 371.772069 -421.892171) (xy 371.727254 -421.860406)
			(xy 371.687848 -421.822137) (xy 371.654786 -421.778271) (xy 371.64137 -421.7543) (xy 371.634766 -421.741854)
			(xy 371.61089 -421.72763) (xy 371.040914 -421.72763) (xy 371.017038 -421.741854) (xy 371.010434 -421.7543)
			(xy 370.997018 -421.778269) (xy 370.963955 -421.82213) (xy 370.924548 -421.860392) (xy 370.879733 -421.892148)
			(xy 370.830571 -421.916644) (xy 370.778231 -421.9333) (xy 370.723953 -421.941719) (xy 370.69649 -421.94226)
			(xy 370.666911 -421.941682) (xy 370.608564 -421.931913) (xy 370.552636 -421.912631) (xy 370.500667 -421.884365)
			(xy 370.477034 -421.866568) (xy 370.46535 -421.857424) (xy 370.436648 -421.854376) (xy 370.341398 -421.900858)
			(xy 370.333925 -421.904864) (xy 370.321963 -421.916867) (xy 370.314561 -421.932111) (xy 370.313204 -421.940482)
			(xy 370.313204 -422.744392) (xy 370.249196 -422.744392) (xy 370.18087 -422.848786) (xy 370.178584 -422.874186)
			(xy 370.183664 -422.88587) (xy 370.196901 -422.917916) (xy 370.215557 -422.984694) (xy 370.224976 -423.053387)
			(xy 370.225574 -423.088054) (xy 370.225072 -423.120015) (xy 370.217061 -423.183433) (xy 370.201164 -423.245347)
			(xy 370.177632 -423.30478) (xy 370.146838 -423.360795) (xy 370.109265 -423.41251) (xy 370.065508 -423.459107)
			(xy 370.016255 -423.499852) (xy 369.962284 -423.534103) (xy 369.904445 -423.56132) (xy 369.843652 -423.581073)
			(xy 369.780862 -423.593051) (xy 369.717066 -423.597065) (xy 369.65327 -423.593051) (xy 369.59048 -423.581073)
			(xy 369.529687 -423.56132) (xy 369.471848 -423.534103) (xy 369.417877 -423.499852) (xy 369.368624 -423.459107)
			(xy 369.324867 -423.41251) (xy 369.287294 -423.360795) (xy 369.2565 -423.30478) (xy 369.232968 -423.245347)
			(xy 369.217071 -423.183433) (xy 369.20906 -423.120015) (xy 369.208558 -423.088054) (xy 369.209142 -423.053385)
			(xy 369.218556 -422.98469) (xy 369.237215 -422.917911) (xy 369.250468 -422.88587) (xy 369.255548 -422.874186)
			(xy 369.253262 -422.848786) (xy 369.199668 -422.766998) (xy 369.193135 -422.75801) (xy 369.174296 -422.746273)
			(xy 369.163346 -422.744392) (xy 365.345218 -422.744392) (xy 365.333536 -422.746447) (xy 365.313817 -422.759576)
			(xy 365.307372 -422.769538) (xy 365.256318 -422.857676) (xy 365.256318 -422.884346) (xy 365.26343 -422.896538)
			(xy 365.279596 -422.925646) (xy 365.305059 -422.987167) (xy 365.322276 -423.051486) (xy 365.330953 -423.117501)
			(xy 365.331502 -423.150792) (xy 365.331037 -423.181942) (xy 365.323436 -423.243775) (xy 365.308335 -423.304217)
			(xy 365.28596 -423.362359) (xy 365.256647 -423.417331) (xy 365.220835 -423.468309) (xy 365.179062 -423.514527)
			(xy 365.131953 -423.555293) (xy 365.080214 -423.589997) (xy 365.05261 -423.604436) (xy 365.039656 -423.61104)
			(xy 365.02467 -423.635424) (xy 365.02467 -423.65422) (xy 365.025161 -423.664227) (xy 365.032823 -423.682717)
			(xy 365.046974 -423.696871) (xy 365.065463 -423.704537) (xy 365.07547 -423.70502) (xy 365.084614 -423.70502)
			(xy 365.09325 -423.701718) (xy 365.121768 -423.691508) (xy 365.180621 -423.677166) (xy 365.240763 -423.669929)
			(xy 365.27105 -423.66946) (xy 365.271812 -423.66946) (xy 365.303775 -423.669963) (xy 365.367195 -423.677976)
			(xy 365.429112 -423.693875) (xy 365.488548 -423.717408) (xy 365.544565 -423.748205) (xy 365.596281 -423.78578)
			(xy 365.64288 -423.829541) (xy 365.683627 -423.878796) (xy 365.717879 -423.93277) (xy 365.745097 -423.990612)
			(xy 365.76485 -424.051408) (xy 365.776829 -424.114201) (xy 365.780843 -424.178) (xy 365.776829 -424.241799)
			(xy 365.76485 -424.304592) (xy 365.745097 -424.365388) (xy 365.717879 -424.42323) (xy 365.683627 -424.477204)
			(xy 365.64288 -424.526459) (xy 365.596281 -424.57022) (xy 365.544565 -424.607795) (xy 365.488548 -424.638592)
			(xy 365.429112 -424.662125) (xy 365.367195 -424.678024) (xy 365.303775 -424.686037) (xy 365.271812 -424.686476)
			(xy 365.241151 -424.686037) (xy 365.180276 -424.678651) (xy 365.1504 -424.671744) (xy 365.13897 -424.66895)
			(xy 365.116364 -424.673776) (xy 365.044228 -424.730418) (xy 365.035425 -424.737952) (xy 365.025214 -424.758724)
			(xy 365.02467 -424.770296) (xy 365.02467 -425.03725) (xy 365.025101 -425.047317) (xy 365.032825 -425.065911)
			(xy 365.039656 -425.073318) (xy 365.080042 -425.113704) (xy 365.087443 -425.120543) (xy 365.106041 -425.128262)
			(xy 365.11611 -425.12869) (xy 365.198406 -425.128436) (xy 365.216948 -425.120562) (xy 365.224314 -425.113196)
			(xy 365.248282 -425.089674) (xy 365.301331 -425.048495) (xy 365.359337 -425.014655) (xy 365.421292 -424.988741)
			(xy 365.486117 -424.971205) (xy 365.552686 -424.962351) (xy 365.586264 -424.961812) (xy 365.586518 -424.961812)
			(xy 365.617396 -424.962289) (xy 365.678694 -424.969808) (xy 365.738633 -424.984683) (xy 365.796333 -425.006697)
			(xy 365.850948 -425.035528) (xy 365.876586 -425.052744) (xy 365.887508 -425.060618) (xy 365.914432 -425.062904)
			(xy 366.018572 -425.015152) (xy 366.034066 -424.993308) (xy 366.03559 -424.979846) (xy 366.038956 -424.952028)
			(xy 366.052797 -424.897733) (xy 366.07443 -424.846045) (xy 366.103391 -424.798077) (xy 366.139056 -424.754862)
			(xy 366.180658 -424.717327) (xy 366.227303 -424.686281) (xy 366.277988 -424.662392) (xy 366.331621 -424.646172)
			(xy 366.38705 -424.637972) (xy 366.415066 -424.637454) (xy 366.442323 -424.637915) (xy 366.496283 -424.645668)
			(xy 366.54859 -424.661023) (xy 366.59818 -424.683666) (xy 366.644042 -424.713136) (xy 366.685243 -424.748833)
			(xy 366.720944 -424.790031) (xy 366.750418 -424.83589) (xy 366.773065 -424.885478) (xy 366.788424 -424.937784)
			(xy 366.796183 -424.991743) (xy 366.796183 -425.046257) (xy 366.788424 -425.100216) (xy 366.773065 -425.152522)
			(xy 366.750418 -425.20211) (xy 366.720944 -425.247969) (xy 366.685243 -425.289167) (xy 366.644042 -425.324864)
			(xy 366.59818 -425.354334) (xy 366.54859 -425.376977) (xy 366.496283 -425.392332) (xy 366.442323 -425.400085)
			(xy 366.415066 -425.40047) (xy 366.414812 -425.40047) (xy 366.384922 -425.399864) (xy 366.325879 -425.390505)
			(xy 366.269009 -425.372077) (xy 366.242092 -425.359068) (xy 366.230154 -425.352972) (xy 366.20323 -425.354242)
			(xy 366.106456 -425.41571) (xy 366.09401 -425.439586) (xy 366.094518 -425.453048) (xy 366.094772 -425.47032)
			(xy 366.094608 -425.4872) (xy 366.092319 -425.520883) (xy 366.0902 -425.53763) (xy 366.08893 -425.548806)
			(xy 366.095026 -425.569634) (xy 366.152684 -425.63542) (xy 366.160266 -425.643269) (xy 366.180136 -425.652243)
			(xy 366.191038 -425.652692) (xy 367.260378 -425.652692) (xy 367.288572 -425.629324) (xy 367.292128 -425.61129)
			(xy 367.298725 -425.57871) (xy 367.319262 -425.51549) (xy 367.347854 -425.45548) (xy 367.384014 -425.399703)
			(xy 367.405158 -425.374054) (xy 367.417096 -425.341288) (xy 367.417096 -425.340018) (xy 367.416588 -425.309284)
			(xy 367.415969 -425.300097) (xy 367.409078 -425.283035) (xy 367.403126 -425.27601) (xy 367.384486 -425.254817)
			(xy 367.353012 -425.207969) (xy 367.328787 -425.156994) (xy 367.312339 -425.103005) (xy 367.304027 -425.047181)
			(xy 367.303558 -425.018962) (xy 367.304044 -424.991711) (xy 367.3118 -424.937763) (xy 367.327155 -424.885468)
			(xy 367.349797 -424.835891) (xy 367.379263 -424.790041) (xy 367.414954 -424.74885) (xy 367.456145 -424.713159)
			(xy 367.501995 -424.683693) (xy 367.551572 -424.661051) (xy 367.603867 -424.645696) (xy 367.657815 -424.63794)
			(xy 367.712317 -424.63794) (xy 367.766265 -424.645696) (xy 367.81856 -424.661051) (xy 367.868137 -424.683693)
			(xy 367.913987 -424.713159) (xy 367.955178 -424.74885) (xy 367.990869 -424.790041) (xy 368.020335 -424.835891)
			(xy 368.042977 -424.885468) (xy 368.058332 -424.937763) (xy 368.066088 -424.991711) (xy 368.066574 -425.018962)
			(xy 368.066081 -425.046311) (xy 368.058231 -425.100445) (xy 368.042743 -425.152907) (xy 368.031776 -425.177966)
			(xy 368.028331 -425.186434) (xy 368.027021 -425.204657) (xy 368.029236 -425.213526) (xy 368.038126 -425.24299)
			(xy 368.041123 -425.251801) (xy 368.052314 -425.266655) (xy 368.05997 -425.271946) (xy 368.091488 -425.292286)
			(xy 368.148744 -425.340745) (xy 368.174016 -425.368466) (xy 368.212116 -425.385484) (xy 368.238024 -425.378372)
			(xy 368.264371 -425.363219) (xy 368.319673 -425.337999) (xy 368.377355 -425.318837) (xy 368.436755 -425.305953)
			(xy 368.497193 -425.299494) (xy 368.527584 -425.299124) (xy 368.558572 -425.299124) (xy 368.567653 -425.298767)
			(xy 368.584671 -425.29243) (xy 368.598378 -425.280519) (xy 368.603022 -425.272708) (xy 368.617754 -425.246292)
			(xy 368.620686 -425.240627) (xy 368.623894 -425.228284) (xy 368.624104 -425.221908) (xy 368.618008 -425.198032)
			(xy 368.604033 -425.170409) (xy 368.584239 -425.111756) (xy 368.574191 -425.050675) (xy 368.573558 -425.019724)
			(xy 368.573558 -425.018962) (xy 368.574044 -424.991711) (xy 368.5818 -424.937763) (xy 368.597155 -424.885468)
			(xy 368.619797 -424.835891) (xy 368.649263 -424.790041) (xy 368.684954 -424.74885) (xy 368.726145 -424.713159)
			(xy 368.771995 -424.683693) (xy 368.821572 -424.661051) (xy 368.873867 -424.645696) (xy 368.927815 -424.63794)
			(xy 368.982317 -424.63794) (xy 369.036265 -424.645696) (xy 369.08856 -424.661051) (xy 369.138137 -424.683693)
			(xy 369.183987 -424.713159) (xy 369.225178 -424.74885) (xy 369.260869 -424.790041) (xy 369.290335 -424.835891)
			(xy 369.312977 -424.885468) (xy 369.328332 -424.937763) (xy 369.336088 -424.991711) (xy 369.336574 -425.018962)
			(xy 369.336574 -425.019216) (xy 369.336213 -425.043246) (xy 369.330178 -425.090926) (xy 369.318191 -425.137468)
			(xy 369.30965 -425.159932) (xy 369.304824 -425.171616) (xy 369.307618 -425.196762) (xy 369.361974 -425.276772)
			(xy 369.369453 -425.286753) (xy 369.391429 -425.298488) (xy 369.403884 -425.299124) (xy 369.589812 -425.299124)
			(xy 369.602229 -425.298505) (xy 369.624198 -425.286923) (xy 369.631722 -425.277026) (xy 369.686332 -425.19727)
			(xy 369.689126 -425.172632) (xy 369.684554 -425.160694) (xy 369.676448 -425.1387) (xy 369.665041 -425.093235)
			(xy 369.659271 -425.046717) (xy 369.6589 -425.02328) (xy 369.659386 -424.996029) (xy 369.667142 -424.942081)
			(xy 369.682497 -424.889786) (xy 369.705139 -424.840209) (xy 369.734605 -424.794359) (xy 369.770296 -424.753168)
			(xy 369.811487 -424.717477) (xy 369.857337 -424.688011) (xy 369.906914 -424.665369) (xy 369.959209 -424.650014)
			(xy 370.013157 -424.642258) (xy 370.067659 -424.642258) (xy 370.121607 -424.650014) (xy 370.173902 -424.665369)
			(xy 370.223479 -424.688011) (xy 370.269329 -424.717477) (xy 370.31052 -424.753168) (xy 370.346211 -424.794359)
			(xy 370.375677 -424.840209) (xy 370.398319 -424.889786) (xy 370.413674 -424.942081) (xy 370.42143 -424.996029)
			(xy 370.421916 -425.02328) (xy 370.42144 -425.050409) (xy 370.413756 -425.10412) (xy 370.39854 -425.1562)
			(xy 370.376098 -425.2056) (xy 370.346885 -425.251322) (xy 370.311488 -425.292443) (xy 370.270622 -425.328135)
			(xy 370.225112 -425.357677) (xy 370.200682 -425.369482) (xy 370.189252 -425.374816) (xy 370.174012 -425.394374)
			(xy 370.157248 -425.488862) (xy 370.15587 -425.501058) (xy 370.16083 -425.516657) (xy 372.048925 -425.516657)
			(xy 372.048925 -425.462143) (xy 372.056684 -425.408184) (xy 372.072043 -425.355879) (xy 372.09469 -425.306292)
			(xy 372.124164 -425.260434) (xy 372.159865 -425.219237) (xy 372.201066 -425.18354) (xy 372.246928 -425.154071)
			(xy 372.296517 -425.131429) (xy 372.348824 -425.116075) (xy 372.402783 -425.108322) (xy 372.43004 -425.107862)
			(xy 372.454432 -425.108246) (xy 372.502819 -425.114465) (xy 372.550019 -425.126796) (xy 372.595265 -425.145038)
			(xy 372.61673 -425.15663) (xy 372.629176 -425.163742) (xy 372.656608 -425.16298) (xy 372.756176 -425.100242)
			(xy 372.768876 -425.075858) (xy 372.76786 -425.061634) (xy 372.766844 -425.028868) (xy 372.767051 -425.008456)
			(xy 372.770359 -424.967766) (xy 372.773448 -424.947588) (xy 372.774596 -424.938788) (xy 372.77133 -424.921354)
			(xy 372.767098 -424.913552) (xy 372.751858 -424.887898) (xy 372.747084 -424.880415) (xy 372.73343 -424.869094)
			(xy 372.725188 -424.8658) (xy 372.696072 -424.854757) (xy 372.640522 -424.826613) (xy 372.588824 -424.791896)
			(xy 372.541754 -424.751125) (xy 372.500014 -424.704912) (xy 372.46423 -424.653947) (xy 372.434938 -424.598994)
			(xy 372.412576 -424.540875) (xy 372.397478 -424.480461) (xy 372.389871 -424.418654) (xy 372.3894 -424.387518)
			(xy 372.389855 -424.356322) (xy 372.397494 -424.294399) (xy 372.412647 -424.233874) (xy 372.435087 -424.175657)
			(xy 372.464478 -424.12062) (xy 372.500377 -424.06959) (xy 372.542247 -424.023333) (xy 372.589458 -423.982542)
			(xy 372.641303 -423.94783) (xy 372.697004 -423.919718) (xy 372.726204 -423.908728) (xy 372.736364 -423.905172)
			(xy 372.751604 -423.890948) (xy 372.78945 -423.803318) (xy 372.78945 -423.782236) (xy 372.785132 -423.772584)
			(xy 372.775005 -423.74838) (xy 372.760755 -423.697883) (xy 372.753563 -423.64591) (xy 372.753128 -423.619676)
			(xy 372.753128 -423.606976) (xy 372.741952 -423.585386) (xy 372.653814 -423.522902) (xy 372.629684 -423.5196)
			(xy 372.617746 -423.523918) (xy 372.587035 -423.534003) (xy 372.523318 -423.544853) (xy 372.491 -423.545508)
			(xy 372.463749 -423.545022) (xy 372.409801 -423.537266) (xy 372.357506 -423.521911) (xy 372.307929 -423.499269)
			(xy 372.262079 -423.469803) (xy 372.220888 -423.434112) (xy 372.185197 -423.392921) (xy 372.155731 -423.347071)
			(xy 372.133089 -423.297494) (xy 372.117734 -423.245199) (xy 372.109978 -423.191251) (xy 372.109978 -423.136749)
			(xy 372.117734 -423.082801) (xy 372.133089 -423.030506) (xy 372.155731 -422.980929) (xy 372.185197 -422.935079)
			(xy 372.220888 -422.893888) (xy 372.262079 -422.858197) (xy 372.307929 -422.828731) (xy 372.357506 -422.806089)
			(xy 372.409801 -422.790734) (xy 372.463749 -422.782978) (xy 372.518251 -422.782978) (xy 372.572199 -422.790734)
			(xy 372.624494 -422.806089) (xy 372.674071 -422.828731) (xy 372.719921 -422.858197) (xy 372.761112 -422.893888)
			(xy 372.796803 -422.935079) (xy 372.826269 -422.980929) (xy 372.848911 -423.030506) (xy 372.864266 -423.082801)
			(xy 372.872022 -423.136749) (xy 372.872508 -423.164) (xy 372.872508 -423.1767) (xy 372.883684 -423.19829)
			(xy 372.971822 -423.260774) (xy 372.995952 -423.264076) (xy 373.00789 -423.259758) (xy 373.038605 -423.249688)
			(xy 373.102319 -423.238829) (xy 373.134636 -423.238168) (xy 373.161887 -423.238644) (xy 373.215834 -423.246405)
			(xy 373.268127 -423.261764) (xy 373.317703 -423.284407) (xy 373.363552 -423.313875) (xy 373.404741 -423.349567)
			(xy 373.440432 -423.390757) (xy 373.469899 -423.436607) (xy 373.492541 -423.486184) (xy 373.507898 -423.538478)
			(xy 373.515657 -423.592425) (xy 373.516144 -423.619676) (xy 373.515661 -423.647223) (xy 373.507734 -423.701745)
			(xy 373.492041 -423.754558) (xy 373.46891 -423.804562) (xy 373.438822 -423.850715) (xy 373.402404 -423.892057)
			(xy 373.360414 -423.927726) (xy 373.337328 -423.942764) (xy 373.328438 -423.948352) (xy 373.3165 -423.965878)
			(xy 373.298466 -424.059604) (xy 373.303038 -424.079924) (xy 373.309388 -424.08856) (xy 373.329962 -424.119294)
			(xy 373.335626 -424.127374) (xy 373.351605 -424.138909) (xy 373.370752 -424.143573) (xy 373.390246 -424.140678)
			(xy 373.407212 -424.130651) (xy 373.419149 -424.11497) (xy 373.422164 -424.105578) (xy 373.429813 -424.078926)
			(xy 373.451839 -424.028041) (xy 373.481001 -423.980881) (xy 373.516684 -423.938441) (xy 373.558136 -423.901615)
			(xy 373.604484 -423.87118) (xy 373.65475 -423.847775) (xy 373.707875 -423.831896) (xy 373.76274 -423.823877)
			(xy 373.790464 -423.823384) (xy 373.817718 -423.823861) (xy 373.871672 -423.831614) (xy 373.923973 -423.846966)
			(xy 373.973556 -423.869606) (xy 374.019413 -423.899072) (xy 374.060609 -423.934765) (xy 374.096306 -423.975958)
			(xy 374.125777 -424.021812) (xy 374.148421 -424.071394) (xy 374.163779 -424.123693) (xy 374.171537 -424.177646)
			(xy 374.171537 -424.232154) (xy 374.163779 -424.286107) (xy 374.148421 -424.338406) (xy 374.125777 -424.387988)
			(xy 374.096306 -424.433842) (xy 374.060609 -424.475035) (xy 374.019413 -424.510728) (xy 373.973556 -424.540194)
			(xy 373.923973 -424.562834) (xy 373.871672 -424.578186) (xy 373.817718 -424.585939) (xy 373.790464 -424.5864)
			(xy 373.783098 -424.5864) (xy 373.768874 -424.586146) (xy 373.74449 -424.60037) (xy 373.687594 -424.70451)
			(xy 373.689118 -424.732704) (xy 373.696992 -424.744642) (xy 373.713524 -424.769884) (xy 373.741095 -424.82356)
			(xy 373.762118 -424.880123) (xy 373.776298 -424.938777) (xy 373.783433 -424.998696) (xy 373.78386 -425.028868)
			(xy 373.783432 -425.059601) (xy 373.776026 -425.12062) (xy 373.761319 -425.180301) (xy 373.739524 -425.237774)
			(xy 373.71096 -425.2922) (xy 373.676043 -425.342786) (xy 373.635283 -425.388794) (xy 373.589273 -425.429553)
			(xy 373.538686 -425.464468) (xy 373.484259 -425.493031) (xy 373.426786 -425.514823) (xy 373.367104 -425.529529)
			(xy 373.306085 -425.536933) (xy 373.275352 -425.537376) (xy 373.242915 -425.536877) (xy 373.178565 -425.528638)
			(xy 373.115785 -425.512288) (xy 373.055591 -425.488091) (xy 372.998961 -425.45644) (xy 372.972584 -425.437554)
			(xy 372.961154 -425.428918) (xy 372.933976 -425.426378) (xy 372.827296 -425.475908) (xy 372.811802 -425.498768)
			(xy 372.810786 -425.512992) (xy 372.808542 -425.541707) (xy 372.796377 -425.598005) (xy 372.775888 -425.651835)
			(xy 372.747538 -425.701972) (xy 372.711974 -425.747278) (xy 372.670003 -425.786723) (xy 372.622579 -425.819409)
			(xy 372.57078 -425.844595) (xy 372.515783 -425.861707) (xy 372.458839 -425.870357) (xy 372.43004 -425.870878)
			(xy 372.402783 -425.870478) (xy 372.348824 -425.862725) (xy 372.296517 -425.847371) (xy 372.246928 -425.824729)
			(xy 372.201066 -425.79526) (xy 372.159865 -425.759563) (xy 372.124164 -425.718366) (xy 372.09469 -425.672508)
			(xy 372.072043 -425.622921) (xy 372.056684 -425.570616) (xy 372.048925 -425.516657) (xy 370.16083 -425.516657)
			(xy 370.163296 -425.524413) (xy 370.171472 -425.533566) (xy 370.275866 -425.63796) (xy 370.283272 -425.644654)
			(xy 370.301708 -425.652255) (xy 370.31168 -425.652692) (xy 371.35562 -425.652692) (xy 371.387431 -425.653124)
			(xy 371.450652 -425.660254) (xy 371.512677 -425.674423) (xy 371.572723 -425.695451) (xy 371.630036 -425.723074)
			(xy 371.683893 -425.756945) (xy 371.733615 -425.796637) (xy 371.756432 -425.818808) (xy 372.025375 -426.087751)
			(xy 377.666244 -426.087751) (xy 377.666244 -426.023829) (xy 377.674255 -425.960411) (xy 377.690152 -425.898497)
			(xy 377.713684 -425.839064) (xy 377.744478 -425.783049) (xy 377.782051 -425.731334) (xy 377.825808 -425.684737)
			(xy 377.875061 -425.643992) (xy 377.929032 -425.609741) (xy 377.986871 -425.582524) (xy 378.047664 -425.562771)
			(xy 378.110454 -425.550793) (xy 378.17425 -425.54678) (xy 378.238046 -425.550793) (xy 378.300836 -425.562771)
			(xy 378.361629 -425.582524) (xy 378.419468 -425.609741) (xy 378.473439 -425.643992) (xy 378.522692 -425.684737)
			(xy 378.566449 -425.731334) (xy 378.604022 -425.783049) (xy 378.634816 -425.839064) (xy 378.658348 -425.898497)
			(xy 378.674245 -425.960411) (xy 378.682256 -426.023829) (xy 378.682758 -426.05579) (xy 378.682256 -426.087751)
			(xy 378.674245 -426.151169) (xy 378.658348 -426.213083) (xy 378.634816 -426.272516) (xy 378.604022 -426.328531)
			(xy 378.566449 -426.380246) (xy 378.522692 -426.426843) (xy 378.473439 -426.467588) (xy 378.419468 -426.501839)
			(xy 378.361629 -426.529056) (xy 378.300836 -426.548809) (xy 378.238046 -426.560787) (xy 378.17425 -426.564801)
			(xy 378.110454 -426.560787) (xy 378.047664 -426.548809) (xy 377.986871 -426.529056) (xy 377.929032 -426.501839)
			(xy 377.875061 -426.467588) (xy 377.825808 -426.426843) (xy 377.782051 -426.380246) (xy 377.744478 -426.328531)
			(xy 377.713684 -426.272516) (xy 377.690152 -426.213083) (xy 377.674255 -426.151169) (xy 377.666244 -426.087751)
			(xy 372.025375 -426.087751) (xy 372.220744 -426.28312) (xy 372.259352 -426.284898) (xy 372.274592 -426.272452)
			(xy 372.295096 -426.256231) (xy 372.339707 -426.228965) (xy 372.387627 -426.208057) (xy 372.437957 -426.1939)
			(xy 372.48975 -426.186761) (xy 372.515892 -426.186346) (xy 372.516146 -426.186346) (xy 372.543396 -426.186835)
			(xy 372.597341 -426.194596) (xy 372.649633 -426.209955) (xy 372.699208 -426.232598) (xy 372.745056 -426.262065)
			(xy 372.786244 -426.297756) (xy 372.821935 -426.338944) (xy 372.851402 -426.384792) (xy 372.874045 -426.434367)
			(xy 372.889404 -426.486659) (xy 372.897165 -426.540604) (xy 372.897654 -426.567854) (xy 372.897094 -426.597177)
			(xy 372.888088 -426.655128) (xy 372.87034 -426.711025) (xy 372.857776 -426.737526) (xy 372.852442 -426.748448)
			(xy 372.852442 -426.77207) (xy 372.89994 -426.866558) (xy 372.91899 -426.880528) (xy 372.930928 -426.882814)
			(xy 372.964738 -426.889393) (xy 373.030564 -426.909683) (xy 373.093442 -426.937807) (xy 373.152444 -426.973351)
			(xy 373.2067 -427.01579) (xy 373.23141 -427.039786) (xy 373.907812 -427.716188) (xy 373.930008 -427.73898)
			(xy 373.969688 -427.788713) (xy 374.00355 -427.842577) (xy 374.031168 -427.899893) (xy 374.052193 -427.959942)
			(xy 374.066363 -428.021967) (xy 374.073499 -428.085189) (xy 374.073928 -428.117) (xy 374.073514 -428.146946)
			(xy 374.067152 -428.206501) (xy 374.059957 -428.239936) (xy 375.379232 -428.239936) (xy 375.383303 -428.184314)
			(xy 375.395429 -428.129877) (xy 375.415352 -428.077786) (xy 375.442648 -428.029151) (xy 375.476734 -427.985008)
			(xy 375.516883 -427.946299) (xy 375.562241 -427.913848) (xy 375.611841 -427.888347) (xy 375.664625 -427.87034)
			(xy 375.719468 -427.86021) (xy 375.775202 -427.858173) (xy 375.830639 -427.864273) (xy 375.884596 -427.878379)
			(xy 375.935925 -427.900191) (xy 375.983531 -427.929245) (xy 376.026399 -427.96492) (xy 376.063616 -428.006457)
			(xy 376.094389 -428.05297) (xy 376.118061 -428.103467) (xy 376.134129 -428.156874) (xy 376.142249 -428.21205)
			(xy 376.142758 -428.239936) (xy 376.142249 -428.267822) (xy 376.141051 -428.275961) (xy 376.935994 -428.275961)
			(xy 376.935994 -428.212039) (xy 376.944005 -428.148621) (xy 376.959902 -428.086707) (xy 376.983434 -428.027274)
			(xy 377.014228 -427.971259) (xy 377.051801 -427.919544) (xy 377.095558 -427.872947) (xy 377.144811 -427.832202)
			(xy 377.198782 -427.797951) (xy 377.256621 -427.770734) (xy 377.317414 -427.750981) (xy 377.380204 -427.739003)
			(xy 377.444 -427.73499) (xy 377.507796 -427.739003) (xy 377.570586 -427.750981) (xy 377.631379 -427.770734)
			(xy 377.689218 -427.797951) (xy 377.743189 -427.832202) (xy 377.792442 -427.872947) (xy 377.836199 -427.919544)
			(xy 377.873772 -427.971259) (xy 377.904566 -428.027274) (xy 377.928098 -428.086707) (xy 377.943995 -428.148621)
			(xy 377.952006 -428.212039) (xy 377.952508 -428.244) (xy 377.952006 -428.275961) (xy 377.943995 -428.339379)
			(xy 377.928098 -428.401293) (xy 377.904566 -428.460726) (xy 377.873772 -428.516741) (xy 377.836199 -428.568456)
			(xy 377.792442 -428.615053) (xy 377.743189 -428.655798) (xy 377.689218 -428.690049) (xy 377.631379 -428.717266)
			(xy 377.570586 -428.737019) (xy 377.507796 -428.748997) (xy 377.444 -428.753011) (xy 377.380204 -428.748997)
			(xy 377.317414 -428.737019) (xy 377.256621 -428.717266) (xy 377.198782 -428.690049) (xy 377.144811 -428.655798)
			(xy 377.095558 -428.615053) (xy 377.051801 -428.568456) (xy 377.014228 -428.516741) (xy 376.983434 -428.460726)
			(xy 376.959902 -428.401293) (xy 376.944005 -428.339379) (xy 376.935994 -428.275961) (xy 376.141051 -428.275961)
			(xy 376.134129 -428.322998) (xy 376.118061 -428.376405) (xy 376.094389 -428.426902) (xy 376.063616 -428.473415)
			(xy 376.026399 -428.514952) (xy 375.983531 -428.550627) (xy 375.935925 -428.579681) (xy 375.884596 -428.601493)
			(xy 375.830639 -428.615599) (xy 375.775202 -428.621699) (xy 375.719468 -428.619662) (xy 375.664625 -428.609532)
			(xy 375.611841 -428.591525) (xy 375.562241 -428.566024) (xy 375.516883 -428.533573) (xy 375.476734 -428.494864)
			(xy 375.442648 -428.450721) (xy 375.415352 -428.402086) (xy 375.395429 -428.349995) (xy 375.383303 -428.295558)
			(xy 375.379232 -428.239936) (xy 374.059957 -428.239936) (xy 374.054551 -428.265054) (xy 374.035851 -428.321953)
			(xy 374.02389 -428.34941) (xy 374.01754 -428.363888) (xy 374.023128 -428.394876) (xy 375.001028 -429.372776)
			(xy 375.008427 -429.379621) (xy 375.027025 -429.387349) (xy 375.037096 -429.387762) (xy 377.696476 -429.387762)
			(xy 377.706539 -429.387324) (xy 377.72512 -429.379586) (xy 377.732544 -429.372776) (xy 381.226314 -425.879006)
			(xy 381.233135 -425.871665) (xy 381.240883 -425.853202) (xy 381.2413 -425.843192) (xy 381.2413 -425.419266)
			(xy 381.241661 -425.408758) (xy 381.247333 -425.388523) (xy 381.258248 -425.370565) (xy 381.265684 -425.363132)
			(xy 381.272288 -425.356782) (xy 381.28067 -425.340018) (xy 381.289052 -425.254928) (xy 381.284226 -425.236894)
			(xy 381.278638 -425.229274) (xy 381.257903 -425.19953) (xy 381.223184 -425.135874) (xy 381.196663 -425.06839)
			(xy 381.178752 -424.998129) (xy 381.169731 -424.926184) (xy 381.169164 -424.88993) (xy 381.169671 -424.854837)
			(xy 381.178128 -424.785163) (xy 381.194921 -424.717017) (xy 381.219807 -424.651391) (xy 381.252422 -424.589244)
			(xy 381.29229 -424.531482) (xy 381.338831 -424.478946) (xy 381.391364 -424.432404) (xy 381.449125 -424.392533)
			(xy 381.511271 -424.359916) (xy 381.576896 -424.335028) (xy 381.645042 -424.318232) (xy 381.714715 -424.309772)
			(xy 381.749808 -424.309286) (xy 381.782489 -424.309732) (xy 381.847438 -424.317072) (xy 381.911152 -424.331658)
			(xy 381.972825 -424.353307) (xy 382.031678 -424.381743) (xy 382.086965 -424.416608) (xy 382.137988 -424.45746)
			(xy 382.184101 -424.503784) (xy 382.22472 -424.554992) (xy 382.259334 -424.610437) (xy 382.27381 -424.63974)
			(xy 382.279144 -424.65117) (xy 382.298702 -424.665902) (xy 382.392936 -424.682158) (xy 382.405067 -424.683475)
			(xy 382.428276 -424.676052) (xy 382.437386 -424.667934) (xy 382.92024 -424.18508) (xy 382.927637 -424.178231)
			(xy 382.946236 -424.170499) (xy 382.956308 -424.170094) (xy 413.406844 -424.170094) (xy 413.416911 -424.170525)
			(xy 413.435504 -424.17825) (xy 413.442912 -424.18508) (xy 413.935375 -424.677543) (xy 418.871648 -424.677543)
			(xy 418.871648 -424.613621) (xy 418.879659 -424.550203) (xy 418.895556 -424.488289) (xy 418.919088 -424.428856)
			(xy 418.949882 -424.372841) (xy 418.987455 -424.321126) (xy 419.031212 -424.274529) (xy 419.080465 -424.233784)
			(xy 419.134436 -424.199533) (xy 419.192275 -424.172316) (xy 419.253068 -424.152563) (xy 419.315858 -424.140585)
			(xy 419.379654 -424.136572) (xy 419.44345 -424.140585) (xy 419.50624 -424.152563) (xy 419.567033 -424.172316)
			(xy 419.624872 -424.199533) (xy 419.678843 -424.233784) (xy 419.728096 -424.274529) (xy 419.771853 -424.321126)
			(xy 419.809426 -424.372841) (xy 419.84022 -424.428856) (xy 419.863752 -424.488289) (xy 419.879649 -424.550203)
			(xy 419.88766 -424.613621) (xy 419.888162 -424.645582) (xy 419.88766 -424.677543) (xy 419.879649 -424.740961)
			(xy 419.863752 -424.802875) (xy 419.84022 -424.862308) (xy 419.809426 -424.918323) (xy 419.771853 -424.970038)
			(xy 419.728096 -425.016635) (xy 419.678843 -425.05738) (xy 419.624872 -425.091631) (xy 419.567033 -425.118848)
			(xy 419.50624 -425.138601) (xy 419.44345 -425.150579) (xy 419.379654 -425.154593) (xy 419.315858 -425.150579)
			(xy 419.253068 -425.138601) (xy 419.192275 -425.118848) (xy 419.134436 -425.091631) (xy 419.080465 -425.05738)
			(xy 419.031212 -425.016635) (xy 418.987455 -424.970038) (xy 418.949882 -424.918323) (xy 418.919088 -424.862308)
			(xy 418.895556 -424.802875) (xy 418.879659 -424.740961) (xy 418.871648 -424.677543) (xy 413.935375 -424.677543)
			(xy 414.511744 -425.253912) (xy 418.133782 -425.253912) (xy 418.137853 -425.19829) (xy 418.149979 -425.143853)
			(xy 418.169902 -425.091762) (xy 418.197198 -425.043127) (xy 418.231284 -424.998984) (xy 418.271433 -424.960275)
			(xy 418.316791 -424.927824) (xy 418.366391 -424.902323) (xy 418.419175 -424.884316) (xy 418.474018 -424.874186)
			(xy 418.529752 -424.872149) (xy 418.585189 -424.878249) (xy 418.639146 -424.892355) (xy 418.690475 -424.914167)
			(xy 418.738081 -424.943221) (xy 418.780949 -424.978896) (xy 418.818166 -425.020433) (xy 418.848939 -425.066946)
			(xy 418.872611 -425.117443) (xy 418.888679 -425.17085) (xy 418.896799 -425.226026) (xy 418.897308 -425.253912)
			(xy 418.896799 -425.281798) (xy 418.888679 -425.336974) (xy 418.872611 -425.390381) (xy 418.848939 -425.440878)
			(xy 418.818166 -425.487391) (xy 418.780949 -425.528928) (xy 418.738081 -425.564603) (xy 418.690475 -425.593657)
			(xy 418.639146 -425.615469) (xy 418.585189 -425.629575) (xy 418.529752 -425.635675) (xy 418.474018 -425.633638)
			(xy 418.419175 -425.623508) (xy 418.366391 -425.605501) (xy 418.316791 -425.58) (xy 418.271433 -425.547549)
			(xy 418.231284 -425.50884) (xy 418.197198 -425.464697) (xy 418.169902 -425.416062) (xy 418.149979 -425.363971)
			(xy 418.137853 -425.309534) (xy 418.133782 -425.253912) (xy 414.511744 -425.253912) (xy 416.451245 -427.193413)
			(xy 417.79926 -427.193413) (xy 417.79926 -427.129491) (xy 417.807271 -427.066073) (xy 417.823168 -427.004159)
			(xy 417.8467 -426.944726) (xy 417.877494 -426.888711) (xy 417.915067 -426.836996) (xy 417.958824 -426.790399)
			(xy 418.008077 -426.749654) (xy 418.062048 -426.715403) (xy 418.119887 -426.688186) (xy 418.18068 -426.668433)
			(xy 418.24347 -426.656455) (xy 418.307266 -426.652442) (xy 418.371062 -426.656455) (xy 418.433852 -426.668433)
			(xy 418.494645 -426.688186) (xy 418.552484 -426.715403) (xy 418.606455 -426.749654) (xy 418.655708 -426.790399)
			(xy 418.699465 -426.836996) (xy 418.737038 -426.888711) (xy 418.767832 -426.944726) (xy 418.791364 -427.004159)
			(xy 418.807261 -427.066073) (xy 418.815272 -427.129491) (xy 418.815774 -427.161452) (xy 418.815272 -427.193413)
			(xy 418.807261 -427.256831) (xy 418.791364 -427.318745) (xy 418.767832 -427.378178) (xy 418.737038 -427.434193)
			(xy 418.699465 -427.485908) (xy 418.655708 -427.532505) (xy 418.606455 -427.57325) (xy 418.552484 -427.607501)
			(xy 418.49694 -427.633638) (xy 426.190662 -427.633638) (xy 426.194733 -427.578016) (xy 426.206859 -427.523579)
			(xy 426.226782 -427.471488) (xy 426.254078 -427.422853) (xy 426.288164 -427.37871) (xy 426.328313 -427.340001)
			(xy 426.373671 -427.30755) (xy 426.423271 -427.282049) (xy 426.476055 -427.264042) (xy 426.530898 -427.253912)
			(xy 426.586632 -427.251875) (xy 426.642069 -427.257975) (xy 426.696026 -427.272081) (xy 426.747355 -427.293893)
			(xy 426.794961 -427.322947) (xy 426.837829 -427.358622) (xy 426.875046 -427.400159) (xy 426.905819 -427.446672)
			(xy 426.929491 -427.497169) (xy 426.945559 -427.550576) (xy 426.953679 -427.605752) (xy 426.954188 -427.633638)
			(xy 426.953679 -427.661524) (xy 426.945559 -427.7167) (xy 426.929491 -427.770107) (xy 426.905819 -427.820604)
			(xy 426.875046 -427.867117) (xy 426.837829 -427.908654) (xy 426.794961 -427.944329) (xy 426.747355 -427.973383)
			(xy 426.696026 -427.995195) (xy 426.642069 -428.009301) (xy 426.586632 -428.015401) (xy 426.530898 -428.013364)
			(xy 426.476055 -428.003234) (xy 426.423271 -427.985227) (xy 426.373671 -427.959726) (xy 426.328313 -427.927275)
			(xy 426.288164 -427.888566) (xy 426.254078 -427.844423) (xy 426.226782 -427.795788) (xy 426.206859 -427.743697)
			(xy 426.194733 -427.68926) (xy 426.190662 -427.633638) (xy 418.49694 -427.633638) (xy 418.494645 -427.634718)
			(xy 418.433852 -427.654471) (xy 418.371062 -427.666449) (xy 418.307266 -427.670463) (xy 418.24347 -427.666449)
			(xy 418.18068 -427.654471) (xy 418.119887 -427.634718) (xy 418.062048 -427.607501) (xy 418.008077 -427.57325)
			(xy 417.958824 -427.532505) (xy 417.915067 -427.485908) (xy 417.877494 -427.434193) (xy 417.8467 -427.378178)
			(xy 417.823168 -427.318745) (xy 417.807271 -427.256831) (xy 417.79926 -427.193413) (xy 416.451245 -427.193413)
			(xy 416.9283 -427.670468) (xy 416.935136 -427.67787) (xy 416.942846 -427.696468) (xy 416.943286 -427.706536)
			(xy 416.943286 -428.972663) (xy 423.867357 -428.972663) (xy 423.869959 -428.909629) (xy 423.880338 -428.847401)
			(xy 423.898334 -428.786935) (xy 423.923671 -428.729159) (xy 423.95596 -428.674961) (xy 423.994705 -428.625173)
			(xy 424.03931 -428.58056) (xy 424.089092 -428.541807) (xy 424.143285 -428.509509) (xy 424.201056 -428.484163)
			(xy 424.261519 -428.466157) (xy 424.323745 -428.455768) (xy 424.386779 -428.453155) (xy 424.449651 -428.45836)
			(xy 424.511396 -428.471301) (xy 424.571067 -428.491781) (xy 424.627746 -428.519484) (xy 424.680564 -428.553985)
			(xy 424.728708 -428.594754) (xy 424.77144 -428.641165) (xy 424.808103 -428.692506) (xy 424.838133 -428.747987)
			(xy 424.861071 -428.806757) (xy 424.876563 -428.867912) (xy 424.884372 -428.930514) (xy 424.88485 -428.962058)
			(xy 424.88485 -428.964598) (xy 424.88485 -428.974758) (xy 424.892216 -428.993046) (xy 424.95597 -429.058578)
			(xy 424.974004 -429.066452) (xy 424.984164 -429.066706) (xy 425.011004 -429.067839) (xy 425.064003 -429.076591)
			(xy 425.115252 -429.092688) (xy 425.163737 -429.115813) (xy 425.2085 -429.145508) (xy 425.248656 -429.181187)
			(xy 425.283413 -429.222145) (xy 425.312083 -429.267571) (xy 425.3341 -429.316569) (xy 425.349028 -429.368171)
			(xy 425.356572 -429.421355) (xy 425.357036 -429.448214) (xy 425.356535 -429.475464) (xy 425.348778 -429.52941)
			(xy 425.333422 -429.581703) (xy 425.310781 -429.631278) (xy 425.281316 -429.677127) (xy 425.245626 -429.718317)
			(xy 425.204438 -429.754008) (xy 425.158591 -429.783475) (xy 425.109016 -429.806117) (xy 425.056724 -429.821475)
			(xy 425.002778 -429.829234) (xy 424.975528 -429.829722) (xy 424.947111 -429.829189) (xy 424.890909 -429.820734)
			(xy 424.836582 -429.804038) (xy 424.785332 -429.779469) (xy 424.738292 -429.747572) (xy 424.696503 -429.70905)
			(xy 424.66089 -429.664757) (xy 424.632239 -429.615673) (xy 424.611185 -429.562881) (xy 424.60418 -429.535336)
			(xy 424.601894 -429.52543) (xy 424.59021 -429.509174) (xy 424.512994 -429.460406) (xy 424.49369 -429.45685)
			(xy 424.483784 -429.459136) (xy 424.457249 -429.464502) (xy 424.403412 -429.470232) (xy 424.376342 -429.470566)
			(xy 424.344798 -429.470177) (xy 424.282195 -429.462379) (xy 424.221037 -429.446897) (xy 424.162263 -429.423969)
			(xy 424.106777 -429.393947) (xy 424.055431 -429.357293) (xy 424.009012 -429.314569) (xy 423.968235 -429.266431)
			(xy 423.933725 -429.21362) (xy 423.906013 -429.156945) (xy 423.885524 -429.097277) (xy 423.872572 -429.035534)
			(xy 423.867357 -428.972663) (xy 416.943286 -428.972663) (xy 416.943286 -429.461676) (xy 422.339006 -429.461676)
			(xy 422.343077 -429.406054) (xy 422.355203 -429.351617) (xy 422.375126 -429.299526) (xy 422.402422 -429.250891)
			(xy 422.436508 -429.206748) (xy 422.476657 -429.168039) (xy 422.522015 -429.135588) (xy 422.571615 -429.110087)
			(xy 422.624399 -429.09208) (xy 422.679242 -429.08195) (xy 422.734976 -429.079913) (xy 422.790413 -429.086013)
			(xy 422.84437 -429.100119) (xy 422.895699 -429.121931) (xy 422.943305 -429.150985) (xy 422.986173 -429.18666)
			(xy 423.02339 -429.228197) (xy 423.054163 -429.27471) (xy 423.077835 -429.325207) (xy 423.093903 -429.378614)
			(xy 423.102023 -429.43379) (xy 423.102532 -429.461676) (xy 423.102023 -429.489562) (xy 423.093903 -429.544738)
			(xy 423.077835 -429.598145) (xy 423.054163 -429.648642) (xy 423.02339 -429.695155) (xy 422.986173 -429.736692)
			(xy 422.943305 -429.772367) (xy 422.895699 -429.801421) (xy 422.84437 -429.823233) (xy 422.790413 -429.837339)
			(xy 422.734976 -429.843439) (xy 422.679242 -429.841402) (xy 422.624399 -429.831272) (xy 422.571615 -429.813265)
			(xy 422.522015 -429.787764) (xy 422.476657 -429.755313) (xy 422.436508 -429.716604) (xy 422.402422 -429.672461)
			(xy 422.375126 -429.623826) (xy 422.355203 -429.571735) (xy 422.343077 -429.517298) (xy 422.339006 -429.461676)
			(xy 416.943286 -429.461676) (xy 416.943286 -431.533808) (xy 427.540164 -431.533808) (xy 427.544235 -431.478186)
			(xy 427.556361 -431.423749) (xy 427.576284 -431.371658) (xy 427.60358 -431.323023) (xy 427.637666 -431.27888)
			(xy 427.677815 -431.240171) (xy 427.723173 -431.20772) (xy 427.772773 -431.182219) (xy 427.825557 -431.164212)
			(xy 427.8804 -431.154082) (xy 427.936134 -431.152045) (xy 427.991571 -431.158145) (xy 428.045528 -431.172251)
			(xy 428.096857 -431.194063) (xy 428.144463 -431.223117) (xy 428.187331 -431.258792) (xy 428.224548 -431.300329)
			(xy 428.255321 -431.346842) (xy 428.278993 -431.397339) (xy 428.295061 -431.450746) (xy 428.303181 -431.505922)
			(xy 428.303667 -431.532538) (xy 430.17389 -431.532538) (xy 430.177961 -431.476916) (xy 430.190087 -431.422479)
			(xy 430.21001 -431.370388) (xy 430.237306 -431.321753) (xy 430.271392 -431.27761) (xy 430.311541 -431.238901)
			(xy 430.356899 -431.20645) (xy 430.406499 -431.180949) (xy 430.459283 -431.162942) (xy 430.514126 -431.152812)
			(xy 430.56986 -431.150775) (xy 430.625297 -431.156875) (xy 430.679254 -431.170981) (xy 430.730583 -431.192793)
			(xy 430.778189 -431.221847) (xy 430.821057 -431.257522) (xy 430.858274 -431.299059) (xy 430.889047 -431.345572)
			(xy 430.912719 -431.396069) (xy 430.928787 -431.449476) (xy 430.936907 -431.504652) (xy 430.937416 -431.532538)
			(xy 430.936907 -431.560424) (xy 430.928787 -431.6156) (xy 430.912719 -431.669007) (xy 430.889047 -431.719504)
			(xy 430.858274 -431.766017) (xy 430.821057 -431.807554) (xy 430.778189 -431.843229) (xy 430.730583 -431.872283)
			(xy 430.679254 -431.894095) (xy 430.625297 -431.908201) (xy 430.56986 -431.914301) (xy 430.514126 -431.912264)
			(xy 430.459283 -431.902134) (xy 430.406499 -431.884127) (xy 430.356899 -431.858626) (xy 430.311541 -431.826175)
			(xy 430.271392 -431.787466) (xy 430.237306 -431.743323) (xy 430.21001 -431.694688) (xy 430.190087 -431.642597)
			(xy 430.177961 -431.58816) (xy 430.17389 -431.532538) (xy 428.303667 -431.532538) (xy 428.30369 -431.533808)
			(xy 428.303181 -431.561694) (xy 428.295061 -431.61687) (xy 428.278993 -431.670277) (xy 428.255321 -431.720774)
			(xy 428.224548 -431.767287) (xy 428.187331 -431.808824) (xy 428.144463 -431.844499) (xy 428.096857 -431.873553)
			(xy 428.045528 -431.895365) (xy 427.991571 -431.909471) (xy 427.936134 -431.915571) (xy 427.8804 -431.913534)
			(xy 427.825557 -431.903404) (xy 427.772773 -431.885397) (xy 427.723173 -431.859896) (xy 427.677815 -431.827445)
			(xy 427.637666 -431.788736) (xy 427.60358 -431.744593) (xy 427.576284 -431.695958) (xy 427.556361 -431.643867)
			(xy 427.544235 -431.58943) (xy 427.540164 -431.533808) (xy 416.943286 -431.533808) (xy 416.943286 -431.921412)
			(xy 418.997636 -431.921412) (xy 419.001707 -431.86579) (xy 419.013833 -431.811353) (xy 419.033756 -431.759262)
			(xy 419.061052 -431.710627) (xy 419.095138 -431.666484) (xy 419.135287 -431.627775) (xy 419.180645 -431.595324)
			(xy 419.230245 -431.569823) (xy 419.283029 -431.551816) (xy 419.337872 -431.541686) (xy 419.393606 -431.539649)
			(xy 419.449043 -431.545749) (xy 419.503 -431.559855) (xy 419.554329 -431.581667) (xy 419.601935 -431.610721)
			(xy 419.644803 -431.646396) (xy 419.68202 -431.687933) (xy 419.712793 -431.734446) (xy 419.736465 -431.784943)
			(xy 419.752533 -431.83835) (xy 419.760653 -431.893526) (xy 419.761162 -431.921412) (xy 419.760653 -431.949298)
			(xy 419.752533 -432.004474) (xy 419.736465 -432.057881) (xy 419.712793 -432.108378) (xy 419.711828 -432.109837)
			(xy 420.141648 -432.109837) (xy 420.141648 -432.045915) (xy 420.149659 -431.982497) (xy 420.165556 -431.920583)
			(xy 420.189088 -431.86115) (xy 420.219882 -431.805135) (xy 420.257455 -431.75342) (xy 420.301212 -431.706823)
			(xy 420.350465 -431.666078) (xy 420.404436 -431.631827) (xy 420.462275 -431.60461) (xy 420.523068 -431.584857)
			(xy 420.585858 -431.572879) (xy 420.649654 -431.568866) (xy 420.71345 -431.572879) (xy 420.77624 -431.584857)
			(xy 420.837033 -431.60461) (xy 420.894872 -431.631827) (xy 420.948843 -431.666078) (xy 420.998096 -431.706823)
			(xy 421.041853 -431.75342) (xy 421.079426 -431.805135) (xy 421.11022 -431.86115) (xy 421.133752 -431.920583)
			(xy 421.149649 -431.982497) (xy 421.15766 -432.045915) (xy 421.158162 -432.077876) (xy 421.15766 -432.109837)
			(xy 421.149649 -432.173255) (xy 421.133752 -432.235169) (xy 421.11022 -432.294602) (xy 421.079426 -432.350617)
			(xy 421.069637 -432.364091) (xy 428.54473 -432.364091) (xy 428.54473 -432.300169) (xy 428.552741 -432.236751)
			(xy 428.568638 -432.174837) (xy 428.59217 -432.115404) (xy 428.622964 -432.059389) (xy 428.660537 -432.007674)
			(xy 428.704294 -431.961077) (xy 428.753547 -431.920332) (xy 428.807518 -431.886081) (xy 428.865357 -431.858864)
			(xy 428.92615 -431.839111) (xy 428.98894 -431.827133) (xy 429.052736 -431.82312) (xy 429.116532 -431.827133)
			(xy 429.179322 -431.839111) (xy 429.240115 -431.858864) (xy 429.297954 -431.886081) (xy 429.351925 -431.920332)
			(xy 429.401178 -431.961077) (xy 429.444935 -432.007674) (xy 429.482508 -432.059389) (xy 429.513302 -432.115404)
			(xy 429.536834 -432.174837) (xy 429.552731 -432.236751) (xy 429.560742 -432.300169) (xy 429.561244 -432.33213)
			(xy 429.560742 -432.364091) (xy 429.552731 -432.427509) (xy 429.536834 -432.489423) (xy 429.513302 -432.548856)
			(xy 429.482508 -432.604871) (xy 429.444935 -432.656586) (xy 429.401178 -432.703183) (xy 429.351925 -432.743928)
			(xy 429.297954 -432.778179) (xy 429.240115 -432.805396) (xy 429.179322 -432.825149) (xy 429.116532 -432.837127)
			(xy 429.052736 -432.841141) (xy 428.98894 -432.837127) (xy 428.92615 -432.825149) (xy 428.865357 -432.805396)
			(xy 428.807518 -432.778179) (xy 428.753547 -432.743928) (xy 428.704294 -432.703183) (xy 428.660537 -432.656586)
			(xy 428.622964 -432.604871) (xy 428.59217 -432.548856) (xy 428.568638 -432.489423) (xy 428.552741 -432.427509)
			(xy 428.54473 -432.364091) (xy 421.069637 -432.364091) (xy 421.041853 -432.402332) (xy 420.998096 -432.448929)
			(xy 420.948843 -432.489674) (xy 420.894872 -432.523925) (xy 420.837033 -432.551142) (xy 420.77624 -432.570895)
			(xy 420.71345 -432.582873) (xy 420.649654 -432.586887) (xy 420.585858 -432.582873) (xy 420.523068 -432.570895)
			(xy 420.462275 -432.551142) (xy 420.404436 -432.523925) (xy 420.350465 -432.489674) (xy 420.301212 -432.448929)
			(xy 420.257455 -432.402332) (xy 420.219882 -432.350617) (xy 420.189088 -432.294602) (xy 420.165556 -432.235169)
			(xy 420.149659 -432.173255) (xy 420.141648 -432.109837) (xy 419.711828 -432.109837) (xy 419.68202 -432.154891)
			(xy 419.644803 -432.196428) (xy 419.601935 -432.232103) (xy 419.554329 -432.261157) (xy 419.503 -432.282969)
			(xy 419.449043 -432.297075) (xy 419.393606 -432.303175) (xy 419.337872 -432.301138) (xy 419.283029 -432.291008)
			(xy 419.230245 -432.273001) (xy 419.180645 -432.2475) (xy 419.135287 -432.215049) (xy 419.095138 -432.17634)
			(xy 419.061052 -432.132197) (xy 419.033756 -432.083562) (xy 419.013833 -432.031471) (xy 419.001707 -431.977034)
			(xy 418.997636 -431.921412) (xy 416.943286 -431.921412) (xy 416.943286 -432.876198) (xy 421.395396 -432.876198)
			(xy 421.399467 -432.820576) (xy 421.411593 -432.766139) (xy 421.431516 -432.714048) (xy 421.458812 -432.665413)
			(xy 421.492898 -432.62127) (xy 421.533047 -432.582561) (xy 421.578405 -432.55011) (xy 421.628005 -432.524609)
			(xy 421.680789 -432.506602) (xy 421.735632 -432.496472) (xy 421.791366 -432.494435) (xy 421.846803 -432.500535)
			(xy 421.90076 -432.514641) (xy 421.952089 -432.536453) (xy 421.999695 -432.565507) (xy 422.042563 -432.601182)
			(xy 422.07978 -432.642719) (xy 422.110553 -432.689232) (xy 422.134225 -432.739729) (xy 422.150293 -432.793136)
			(xy 422.158413 -432.848312) (xy 422.158922 -432.876198) (xy 422.158413 -432.904084) (xy 422.150293 -432.95926)
			(xy 422.134225 -433.012667) (xy 422.110553 -433.063164) (xy 422.07978 -433.109677) (xy 422.042563 -433.151214)
			(xy 421.999695 -433.186889) (xy 421.952089 -433.215943) (xy 421.90076 -433.237755) (xy 421.846803 -433.251861)
			(xy 421.791366 -433.257961) (xy 421.735632 -433.255924) (xy 421.680789 -433.245794) (xy 421.628005 -433.227787)
			(xy 421.578405 -433.202286) (xy 421.533047 -433.169835) (xy 421.492898 -433.131126) (xy 421.458812 -433.086983)
			(xy 421.431516 -433.038348) (xy 421.411593 -432.986257) (xy 421.399467 -432.93182) (xy 421.395396 -432.876198)
			(xy 416.943286 -432.876198) (xy 416.943286 -433.504848) (xy 436.163466 -433.504848) (xy 436.163961 -433.472201)
			(xy 436.172325 -433.407443) (xy 436.188909 -433.344289) (xy 436.21344 -433.283778) (xy 436.245514 -433.226903)
			(xy 436.284604 -433.174602) (xy 436.330066 -433.127734) (xy 436.381154 -433.087071) (xy 436.40883 -433.069746)
			(xy 436.420416 -433.062125) (xy 436.439378 -433.041909) (xy 436.452216 -433.017344) (xy 436.457985 -432.990234)
			(xy 436.456262 -432.96257) (xy 436.447173 -432.936385) (xy 436.431387 -432.913603) (xy 436.421022 -432.904392)
			(xy 436.399706 -432.886214) (xy 436.36217 -432.844625) (xy 436.331124 -432.797992) (xy 436.307236 -432.747317)
			(xy 436.291022 -432.693692) (xy 436.28283 -432.638271) (xy 436.282338 -432.61026) (xy 436.282824 -432.583009)
			(xy 436.29058 -432.529061) (xy 436.305935 -432.476766) (xy 436.328577 -432.427189) (xy 436.358043 -432.381339)
			(xy 436.393734 -432.340148) (xy 436.434925 -432.304457) (xy 436.480775 -432.274991) (xy 436.530352 -432.252349)
			(xy 436.582647 -432.236994) (xy 436.636595 -432.229238) (xy 436.691097 -432.229238) (xy 436.745045 -432.236994)
			(xy 436.79734 -432.252349) (xy 436.846917 -432.274991) (xy 436.892767 -432.304457) (xy 436.933958 -432.340148)
			(xy 436.969649 -432.381339) (xy 436.999115 -432.427189) (xy 437.021757 -432.476766) (xy 437.037112 -432.529061)
			(xy 437.044868 -432.583009) (xy 437.045354 -432.61026) (xy 437.044869 -432.637701) (xy 437.037021 -432.692019)
			(xy 437.021467 -432.744651) (xy 436.99853 -432.794509) (xy 436.968681 -432.840565) (xy 436.932539 -432.881865)
			(xy 436.912004 -432.900074) (xy 436.901828 -432.909474) (xy 436.886455 -432.932503) (xy 436.877841 -432.958818)
			(xy 436.876622 -432.98648) (xy 436.882887 -433.013451) (xy 436.896173 -433.037744) (xy 436.915503 -433.057569)
			(xy 436.927244 -433.06492) (xy 436.955713 -433.082064) (xy 436.977956 -433.09921) (xy 439.32221 -433.09921)
			(xy 439.322696 -433.071959) (xy 439.330452 -433.018011) (xy 439.345807 -432.965716) (xy 439.368449 -432.916139)
			(xy 439.397915 -432.870289) (xy 439.433606 -432.829098) (xy 439.474797 -432.793407) (xy 439.520647 -432.763941)
			(xy 439.570224 -432.741299) (xy 439.622519 -432.725944) (xy 439.676467 -432.718188) (xy 439.730969 -432.718188)
			(xy 439.784917 -432.725944) (xy 439.837212 -432.741299) (xy 439.886789 -432.763941) (xy 439.932639 -432.793407)
			(xy 439.97383 -432.829098) (xy 440.009521 -432.870289) (xy 440.038987 -432.916139) (xy 440.061629 -432.965716)
			(xy 440.076984 -433.018011) (xy 440.08474 -433.071959) (xy 440.085226 -433.09921) (xy 440.084692 -433.127545)
			(xy 440.076267 -433.183585) (xy 440.059646 -433.237763) (xy 440.047888 -433.263548) (xy 440.043062 -433.274216)
			(xy 440.042808 -433.296568) (xy 440.086242 -433.38877) (xy 440.103768 -433.403248) (xy 440.114944 -433.406042)
			(xy 440.144584 -433.413895) (xy 440.201866 -433.435779) (xy 440.256099 -433.464396) (xy 440.306494 -433.49933)
			(xy 440.35232 -433.540073) (xy 440.392912 -433.586035) (xy 440.427678 -433.636546) (xy 440.456115 -433.690873)
			(xy 440.477808 -433.748227) (xy 440.492444 -433.807774) (xy 440.499808 -433.86865) (xy 440.500262 -433.89931)
			(xy 442.116462 -433.89931) (xy 442.120533 -433.843688) (xy 442.132659 -433.789251) (xy 442.152582 -433.73716)
			(xy 442.179878 -433.688525) (xy 442.213964 -433.644382) (xy 442.254113 -433.605673) (xy 442.299471 -433.573222)
			(xy 442.349071 -433.547721) (xy 442.401855 -433.529714) (xy 442.456698 -433.519584) (xy 442.512432 -433.517547)
			(xy 442.567869 -433.523647) (xy 442.621826 -433.537753) (xy 442.673155 -433.559565) (xy 442.720761 -433.588619)
			(xy 442.763629 -433.624294) (xy 442.800846 -433.665831) (xy 442.831619 -433.712344) (xy 442.855291 -433.762841)
			(xy 442.871359 -433.816248) (xy 442.879479 -433.871424) (xy 442.879988 -433.89931) (xy 442.879479 -433.927196)
			(xy 442.871359 -433.982372) (xy 442.855291 -434.035779) (xy 442.831619 -434.086276) (xy 442.800846 -434.132789)
			(xy 442.763629 -434.174326) (xy 442.720761 -434.210001) (xy 442.673155 -434.239055) (xy 442.621826 -434.260867)
			(xy 442.567869 -434.274973) (xy 442.512432 -434.281073) (xy 442.456698 -434.279036) (xy 442.401855 -434.268906)
			(xy 442.349071 -434.250899) (xy 442.299471 -434.225398) (xy 442.254113 -434.192947) (xy 442.213964 -434.154238)
			(xy 442.179878 -434.110095) (xy 442.152582 -434.06146) (xy 442.132659 -434.009369) (xy 442.120533 -433.954932)
			(xy 442.116462 -433.89931) (xy 440.500262 -433.89931) (xy 440.49976 -433.931271) (xy 440.491749 -433.994689)
			(xy 440.475852 -434.056603) (xy 440.45232 -434.116036) (xy 440.421526 -434.172051) (xy 440.383953 -434.223766)
			(xy 440.340196 -434.270363) (xy 440.290943 -434.311108) (xy 440.236972 -434.345359) (xy 440.179133 -434.372576)
			(xy 440.11834 -434.392329) (xy 440.05555 -434.404307) (xy 439.991754 -434.408321) (xy 439.927958 -434.404307)
			(xy 439.865168 -434.392329) (xy 439.804375 -434.372576) (xy 439.746536 -434.345359) (xy 439.692565 -434.311108)
			(xy 439.643312 -434.270363) (xy 439.599555 -434.223766) (xy 439.561982 -434.172051) (xy 439.531188 -434.116036)
			(xy 439.507656 -434.056603) (xy 439.491759 -433.994689) (xy 439.483748 -433.931271) (xy 439.483246 -433.89931)
			(xy 439.48375 -433.867023) (xy 439.491918 -433.802968) (xy 439.508138 -433.740465) (xy 439.532146 -433.680521)
			(xy 439.563557 -433.624102) (xy 439.582306 -433.597812) (xy 439.589164 -433.588414) (xy 439.593482 -433.566316)
			(xy 439.568082 -433.46751) (xy 439.553858 -433.450238) (xy 439.54319 -433.445412) (xy 439.51878 -433.433591)
			(xy 439.47331 -433.404026) (xy 439.432486 -433.36832) (xy 439.397128 -433.327193) (xy 439.367949 -433.281475)
			(xy 439.345538 -433.232085) (xy 439.330346 -433.18002) (xy 439.32268 -433.126328) (xy 439.32221 -433.09921)
			(xy 436.977956 -433.09921) (xy 437.008346 -433.122636) (xy 437.055248 -433.169718) (xy 437.095619 -433.222506)
			(xy 437.128772 -433.280102) (xy 437.154142 -433.341525) (xy 437.171297 -433.405729) (xy 437.179945 -433.47162)
			(xy 437.180482 -433.504848) (xy 437.17998 -433.536809) (xy 437.171969 -433.600227) (xy 437.156072 -433.662141)
			(xy 437.13254 -433.721574) (xy 437.101746 -433.777589) (xy 437.064173 -433.829304) (xy 437.020416 -433.875901)
			(xy 436.971163 -433.916646) (xy 436.917192 -433.950897) (xy 436.859353 -433.978114) (xy 436.79856 -433.997867)
			(xy 436.73577 -434.009845) (xy 436.671974 -434.013859) (xy 436.608178 -434.009845) (xy 436.545388 -433.997867)
			(xy 436.484595 -433.978114) (xy 436.426756 -433.950897) (xy 436.372785 -433.916646) (xy 436.323532 -433.875901)
			(xy 436.279775 -433.829304) (xy 436.242202 -433.777589) (xy 436.211408 -433.721574) (xy 436.187876 -433.662141)
			(xy 436.171979 -433.600227) (xy 436.163968 -433.536809) (xy 436.163466 -433.504848) (xy 416.943286 -433.504848)
			(xy 416.943286 -434.526647) (xy 417.32936 -434.526647) (xy 417.32936 -434.462725) (xy 417.337371 -434.399307)
			(xy 417.353268 -434.337393) (xy 417.3768 -434.27796) (xy 417.407594 -434.221945) (xy 417.445167 -434.17023)
			(xy 417.488924 -434.123633) (xy 417.538177 -434.082888) (xy 417.592148 -434.048637) (xy 417.649987 -434.02142)
			(xy 417.71078 -434.001667) (xy 417.77357 -433.989689) (xy 417.837366 -433.985676) (xy 417.853422 -433.986686)
			(xy 420.49522 -433.986686) (xy 420.499291 -433.931064) (xy 420.511417 -433.876627) (xy 420.53134 -433.824536)
			(xy 420.558636 -433.775901) (xy 420.592722 -433.731758) (xy 420.632871 -433.693049) (xy 420.678229 -433.660598)
			(xy 420.727829 -433.635097) (xy 420.780613 -433.61709) (xy 420.835456 -433.60696) (xy 420.89119 -433.604923)
			(xy 420.946627 -433.611023) (xy 421.000584 -433.625129) (xy 421.051913 -433.646941) (xy 421.099519 -433.675995)
			(xy 421.142387 -433.71167) (xy 421.179604 -433.753207) (xy 421.210377 -433.79972) (xy 421.234049 -433.850217)
			(xy 421.250117 -433.903624) (xy 421.258237 -433.9588) (xy 421.258746 -433.986686) (xy 421.258237 -434.014572)
			(xy 421.250117 -434.069748) (xy 421.234049 -434.123155) (xy 421.210377 -434.173652) (xy 421.179604 -434.220165)
			(xy 421.142387 -434.261702) (xy 421.099519 -434.297377) (xy 421.051913 -434.326431) (xy 421.000584 -434.348243)
			(xy 420.946627 -434.362349) (xy 420.89119 -434.368449) (xy 420.835456 -434.366412) (xy 420.780613 -434.356282)
			(xy 420.727829 -434.338275) (xy 420.678229 -434.312774) (xy 420.632871 -434.280323) (xy 420.592722 -434.241614)
			(xy 420.558636 -434.197471) (xy 420.53134 -434.148836) (xy 420.511417 -434.096745) (xy 420.499291 -434.042308)
			(xy 420.49522 -433.986686) (xy 417.853422 -433.986686) (xy 417.901162 -433.989689) (xy 417.963952 -434.001667)
			(xy 418.024745 -434.02142) (xy 418.082584 -434.048637) (xy 418.136555 -434.082888) (xy 418.185808 -434.123633)
			(xy 418.229565 -434.17023) (xy 418.267138 -434.221945) (xy 418.297932 -434.27796) (xy 418.321464 -434.337393)
			(xy 418.337361 -434.399307) (xy 418.345372 -434.462725) (xy 418.345874 -434.494686) (xy 418.345372 -434.526647)
			(xy 418.337361 -434.590065) (xy 418.321464 -434.651979) (xy 418.297932 -434.711412) (xy 418.267138 -434.767427)
			(xy 418.253073 -434.786786) (xy 423.289982 -434.786786) (xy 423.294053 -434.731164) (xy 423.306179 -434.676727)
			(xy 423.326102 -434.624636) (xy 423.353398 -434.576001) (xy 423.387484 -434.531858) (xy 423.427633 -434.493149)
			(xy 423.472991 -434.460698) (xy 423.522591 -434.435197) (xy 423.575375 -434.41719) (xy 423.630218 -434.40706)
			(xy 423.685952 -434.405023) (xy 423.741389 -434.411123) (xy 423.795346 -434.425229) (xy 423.846675 -434.447041)
			(xy 423.894281 -434.476095) (xy 423.937149 -434.51177) (xy 423.950479 -434.526647) (xy 426.21936 -434.526647)
			(xy 426.21936 -434.462725) (xy 426.227371 -434.399307) (xy 426.243268 -434.337393) (xy 426.2668 -434.27796)
			(xy 426.297594 -434.221945) (xy 426.335167 -434.17023) (xy 426.378924 -434.123633) (xy 426.428177 -434.082888)
			(xy 426.482148 -434.048637) (xy 426.539987 -434.02142) (xy 426.60078 -434.001667) (xy 426.66357 -433.989689)
			(xy 426.727366 -433.985676) (xy 426.743422 -433.986686) (xy 429.38522 -433.986686) (xy 429.389291 -433.931064)
			(xy 429.401417 -433.876627) (xy 429.42134 -433.824536) (xy 429.448636 -433.775901) (xy 429.482722 -433.731758)
			(xy 429.522871 -433.693049) (xy 429.568229 -433.660598) (xy 429.617829 -433.635097) (xy 429.670613 -433.61709)
			(xy 429.725456 -433.60696) (xy 429.78119 -433.604923) (xy 429.836627 -433.611023) (xy 429.890584 -433.625129)
			(xy 429.941913 -433.646941) (xy 429.989519 -433.675995) (xy 430.032387 -433.71167) (xy 430.069604 -433.753207)
			(xy 430.100377 -433.79972) (xy 430.124049 -433.850217) (xy 430.140117 -433.903624) (xy 430.148237 -433.9588)
			(xy 430.148746 -433.986686) (xy 430.148237 -434.014572) (xy 430.140117 -434.069748) (xy 430.124049 -434.123155)
			(xy 430.100377 -434.173652) (xy 430.069604 -434.220165) (xy 430.032387 -434.261702) (xy 429.989519 -434.297377)
			(xy 429.941913 -434.326431) (xy 429.890584 -434.348243) (xy 429.836627 -434.362349) (xy 429.78119 -434.368449)
			(xy 429.725456 -434.366412) (xy 429.670613 -434.356282) (xy 429.617829 -434.338275) (xy 429.568229 -434.312774)
			(xy 429.522871 -434.280323) (xy 429.482722 -434.241614) (xy 429.448636 -434.197471) (xy 429.42134 -434.148836)
			(xy 429.401417 -434.096745) (xy 429.389291 -434.042308) (xy 429.38522 -433.986686) (xy 426.743422 -433.986686)
			(xy 426.791162 -433.989689) (xy 426.853952 -434.001667) (xy 426.914745 -434.02142) (xy 426.972584 -434.048637)
			(xy 427.026555 -434.082888) (xy 427.075808 -434.123633) (xy 427.119565 -434.17023) (xy 427.157138 -434.221945)
			(xy 427.187932 -434.27796) (xy 427.211464 -434.337393) (xy 427.227361 -434.399307) (xy 427.235372 -434.462725)
			(xy 427.235874 -434.494686) (xy 427.235372 -434.526647) (xy 427.227361 -434.590065) (xy 427.211464 -434.651979)
			(xy 427.187932 -434.711412) (xy 427.157138 -434.767427) (xy 427.143073 -434.786786) (xy 432.179982 -434.786786)
			(xy 432.184053 -434.731164) (xy 432.196179 -434.676727) (xy 432.216102 -434.624636) (xy 432.243398 -434.576001)
			(xy 432.277484 -434.531858) (xy 432.317633 -434.493149) (xy 432.362991 -434.460698) (xy 432.412591 -434.435197)
			(xy 432.465375 -434.41719) (xy 432.520218 -434.40706) (xy 432.575952 -434.405023) (xy 432.631389 -434.411123)
			(xy 432.685346 -434.425229) (xy 432.736675 -434.447041) (xy 432.784281 -434.476095) (xy 432.827149 -434.51177)
			(xy 432.864366 -434.553307) (xy 432.895139 -434.59982) (xy 432.918811 -434.650317) (xy 432.934879 -434.703724)
			(xy 432.942999 -434.7589) (xy 432.943508 -434.786786) (xy 432.942999 -434.814672) (xy 432.934879 -434.869848)
			(xy 432.932664 -434.87721) (xy 436.66918 -434.87721) (xy 436.669682 -434.845249) (xy 436.677693 -434.781831)
			(xy 436.69359 -434.719917) (xy 436.717122 -434.660484) (xy 436.747916 -434.604469) (xy 436.785489 -434.552754)
			(xy 436.829246 -434.506157) (xy 436.878499 -434.465412) (xy 436.93247 -434.431161) (xy 436.990309 -434.403944)
			(xy 437.051102 -434.384191) (xy 437.113892 -434.372213) (xy 437.177688 -434.3682) (xy 437.241484 -434.372213)
			(xy 437.304274 -434.384191) (xy 437.365067 -434.403944) (xy 437.422906 -434.431161) (xy 437.476877 -434.465412)
			(xy 437.52613 -434.506157) (xy 437.569887 -434.552754) (xy 437.60746 -434.604469) (xy 437.638254 -434.660484)
			(xy 437.661786 -434.719917) (xy 437.677683 -434.781831) (xy 437.685694 -434.845249) (xy 437.686196 -434.87721)
			(xy 437.685615 -434.911023) (xy 437.676666 -434.978054) (xy 437.658914 -435.043309) (xy 437.632671 -435.105636)
			(xy 437.598401 -435.163936) (xy 437.577992 -435.1909) (xy 437.571286 -435.199282) (xy 441.486542 -435.199282)
			(xy 441.490613 -435.14366) (xy 441.502739 -435.089223) (xy 441.522662 -435.037132) (xy 441.549958 -434.988497)
			(xy 441.584044 -434.944354) (xy 441.624193 -434.905645) (xy 441.669551 -434.873194) (xy 441.719151 -434.847693)
			(xy 441.771935 -434.829686) (xy 441.826778 -434.819556) (xy 441.882512 -434.817519) (xy 441.937949 -434.823619)
			(xy 441.991906 -434.837725) (xy 442.043235 -434.859537) (xy 442.090841 -434.888591) (xy 442.133709 -434.924266)
			(xy 442.170926 -434.965803) (xy 442.201699 -435.012316) (xy 442.225371 -435.062813) (xy 442.241439 -435.11622)
			(xy 442.249559 -435.171396) (xy 442.250068 -435.199282) (xy 442.249559 -435.227168) (xy 442.241439 -435.282344)
			(xy 442.225371 -435.335751) (xy 442.201699 -435.386248) (xy 442.170926 -435.432761) (xy 442.133709 -435.474298)
			(xy 442.090841 -435.509973) (xy 442.043235 -435.539027) (xy 441.991906 -435.560839) (xy 441.937949 -435.574945)
			(xy 441.882512 -435.581045) (xy 441.826778 -435.579008) (xy 441.771935 -435.568878) (xy 441.719151 -435.550871)
			(xy 441.669551 -435.52537) (xy 441.624193 -435.492919) (xy 441.584044 -435.45421) (xy 441.549958 -435.410067)
			(xy 441.522662 -435.361432) (xy 441.502739 -435.309341) (xy 441.490613 -435.254904) (xy 441.486542 -435.199282)
			(xy 437.571286 -435.199282) (xy 437.57088 -435.19979) (xy 437.5658 -435.22138) (xy 437.585866 -435.319424)
			(xy 437.599074 -435.337204) (xy 437.60898 -435.342792) (xy 437.634315 -435.357254) (xy 437.680638 -435.392708)
			(xy 437.721021 -435.434804) (xy 437.754519 -435.482561) (xy 437.780352 -435.534863) (xy 437.797915 -435.59049)
			(xy 437.8068 -435.648143) (xy 437.807354 -435.67731) (xy 437.806868 -435.704561) (xy 437.799112 -435.758509)
			(xy 437.783757 -435.810804) (xy 437.761115 -435.860381) (xy 437.735311 -435.900533) (xy 442.625474 -435.900533)
			(xy 442.625474 -435.836611) (xy 442.633485 -435.773193) (xy 442.649382 -435.711279) (xy 442.672914 -435.651846)
			(xy 442.703708 -435.595831) (xy 442.741281 -435.544116) (xy 442.785038 -435.497519) (xy 442.834291 -435.456774)
			(xy 442.888262 -435.422523) (xy 442.946101 -435.395306) (xy 443.006894 -435.375553) (xy 443.069684 -435.363575)
			(xy 443.13348 -435.359562) (xy 443.197276 -435.363575) (xy 443.260066 -435.375553) (xy 443.320859 -435.395306)
			(xy 443.378698 -435.422523) (xy 443.432669 -435.456774) (xy 443.481922 -435.497519) (xy 443.525679 -435.544116)
			(xy 443.563252 -435.595831) (xy 443.594046 -435.651846) (xy 443.617578 -435.711279) (xy 443.633475 -435.773193)
			(xy 443.641486 -435.836611) (xy 443.641988 -435.868572) (xy 443.641486 -435.900533) (xy 443.633475 -435.963951)
			(xy 443.617578 -436.025865) (xy 443.594046 -436.085298) (xy 443.563252 -436.141313) (xy 443.525679 -436.193028)
			(xy 443.481922 -436.239625) (xy 443.432669 -436.28037) (xy 443.378698 -436.314621) (xy 443.320859 -436.341838)
			(xy 443.260066 -436.361591) (xy 443.197276 -436.373569) (xy 443.13348 -436.377583) (xy 443.069684 -436.373569)
			(xy 443.006894 -436.361591) (xy 442.946101 -436.341838) (xy 442.888262 -436.314621) (xy 442.834291 -436.28037)
			(xy 442.785038 -436.239625) (xy 442.741281 -436.193028) (xy 442.703708 -436.141313) (xy 442.672914 -436.085298)
			(xy 442.649382 -436.025865) (xy 442.633485 -435.963951) (xy 442.625474 -435.900533) (xy 437.735311 -435.900533)
			(xy 437.731649 -435.906231) (xy 437.695958 -435.947422) (xy 437.654767 -435.983113) (xy 437.608917 -436.012579)
			(xy 437.55934 -436.035221) (xy 437.507045 -436.050576) (xy 437.453097 -436.058332) (xy 437.398595 -436.058332)
			(xy 437.344647 -436.050576) (xy 437.292352 -436.035221) (xy 437.242775 -436.012579) (xy 437.196925 -435.983113)
			(xy 437.155734 -435.947422) (xy 437.120043 -435.906231) (xy 437.090577 -435.860381) (xy 437.067935 -435.810804)
			(xy 437.05258 -435.758509) (xy 437.044824 -435.704561) (xy 437.044338 -435.67731) (xy 437.044916 -435.647512)
			(xy 437.054189 -435.588641) (xy 437.072526 -435.531936) (xy 437.085486 -435.505098) (xy 437.090566 -435.494938)
			(xy 437.091328 -435.47284) (xy 437.052466 -435.380638) (xy 437.035956 -435.365652) (xy 437.025288 -435.36235)
			(xy 436.994709 -435.352215) (xy 436.93618 -435.3253) (xy 436.881519 -435.291207) (xy 436.831601 -435.250484)
			(xy 436.787227 -435.203782) (xy 436.749106 -435.15185) (xy 436.71785 -435.095519) (xy 436.693959 -435.035692)
			(xy 436.677815 -434.973326) (xy 436.669677 -434.909421) (xy 436.66918 -434.87721) (xy 432.932664 -434.87721)
			(xy 432.918811 -434.923255) (xy 432.895139 -434.973752) (xy 432.864366 -435.020265) (xy 432.827149 -435.061802)
			(xy 432.784281 -435.097477) (xy 432.736675 -435.126531) (xy 432.685346 -435.148343) (xy 432.631389 -435.162449)
			(xy 432.575952 -435.168549) (xy 432.520218 -435.166512) (xy 432.465375 -435.156382) (xy 432.412591 -435.138375)
			(xy 432.362991 -435.112874) (xy 432.317633 -435.080423) (xy 432.277484 -435.041714) (xy 432.243398 -434.997571)
			(xy 432.216102 -434.948936) (xy 432.196179 -434.896845) (xy 432.184053 -434.842408) (xy 432.179982 -434.786786)
			(xy 427.143073 -434.786786) (xy 427.119565 -434.819142) (xy 427.075808 -434.865739) (xy 427.026555 -434.906484)
			(xy 426.972584 -434.940735) (xy 426.914745 -434.967952) (xy 426.853952 -434.987705) (xy 426.791162 -434.999683)
			(xy 426.727366 -435.003697) (xy 426.66357 -434.999683) (xy 426.60078 -434.987705) (xy 426.539987 -434.967952)
			(xy 426.482148 -434.940735) (xy 426.428177 -434.906484) (xy 426.378924 -434.865739) (xy 426.335167 -434.819142)
			(xy 426.297594 -434.767427) (xy 426.2668 -434.711412) (xy 426.243268 -434.651979) (xy 426.227371 -434.590065)
			(xy 426.21936 -434.526647) (xy 423.950479 -434.526647) (xy 423.974366 -434.553307) (xy 424.005139 -434.59982)
			(xy 424.028811 -434.650317) (xy 424.044879 -434.703724) (xy 424.052999 -434.7589) (xy 424.053508 -434.786786)
			(xy 424.052999 -434.814672) (xy 424.044879 -434.869848) (xy 424.028811 -434.923255) (xy 424.005139 -434.973752)
			(xy 423.974366 -435.020265) (xy 423.937149 -435.061802) (xy 423.894281 -435.097477) (xy 423.846675 -435.126531)
			(xy 423.795346 -435.148343) (xy 423.741389 -435.162449) (xy 423.685952 -435.168549) (xy 423.630218 -435.166512)
			(xy 423.575375 -435.156382) (xy 423.522591 -435.138375) (xy 423.472991 -435.112874) (xy 423.427633 -435.080423)
			(xy 423.387484 -435.041714) (xy 423.353398 -434.997571) (xy 423.326102 -434.948936) (xy 423.306179 -434.896845)
			(xy 423.294053 -434.842408) (xy 423.289982 -434.786786) (xy 418.253073 -434.786786) (xy 418.229565 -434.819142)
			(xy 418.185808 -434.865739) (xy 418.136555 -434.906484) (xy 418.082584 -434.940735) (xy 418.024745 -434.967952)
			(xy 417.963952 -434.987705) (xy 417.901162 -434.999683) (xy 417.837366 -435.003697) (xy 417.77357 -434.999683)
			(xy 417.71078 -434.987705) (xy 417.649987 -434.967952) (xy 417.592148 -434.940735) (xy 417.538177 -434.906484)
			(xy 417.488924 -434.865739) (xy 417.445167 -434.819142) (xy 417.407594 -434.767427) (xy 417.3768 -434.711412)
			(xy 417.353268 -434.651979) (xy 417.337371 -434.590065) (xy 417.32936 -434.526647) (xy 416.943286 -434.526647)
			(xy 416.943286 -435.754207) (xy 417.328484 -435.754207) (xy 417.33369 -435.691339) (xy 417.346632 -435.629598)
			(xy 417.367112 -435.569932) (xy 417.394814 -435.513257) (xy 417.429314 -435.460443) (xy 417.470082 -435.412303)
			(xy 417.516492 -435.369575) (xy 417.56783 -435.332916) (xy 417.623308 -435.302888) (xy 417.682074 -435.279953)
			(xy 417.743226 -435.264463) (xy 417.805824 -435.256656) (xy 417.837366 -435.256178) (xy 417.867439 -435.256649)
			(xy 417.927164 -435.263764) (xy 417.985636 -435.277865) (xy 418.042039 -435.298756) (xy 418.069014 -435.312058)
			(xy 418.081722 -435.318004) (xy 418.109227 -435.323476) (xy 418.137183 -435.321256) (xy 418.163478 -435.311509)
			(xy 418.186128 -435.294973) (xy 418.203422 -435.272896) (xy 418.214054 -435.246946) (xy 418.21608 -435.233064)
			(xy 418.219764 -435.205465) (xy 418.233984 -435.151635) (xy 418.255874 -435.100443) (xy 418.284969 -435.052974)
			(xy 418.320653 -435.010236) (xy 418.362167 -434.973136) (xy 418.408631 -434.942462) (xy 418.459059 -434.918864)
			(xy 418.512381 -434.902843) (xy 418.567464 -434.89474) (xy 418.595302 -434.894228) (xy 418.622556 -434.894642)
			(xy 418.676508 -434.902399) (xy 418.728808 -434.917756) (xy 418.778389 -434.9404) (xy 418.824244 -434.969869)
			(xy 418.865438 -435.005564) (xy 418.901132 -435.046758) (xy 418.930601 -435.092612) (xy 418.953244 -435.142194)
			(xy 418.968601 -435.194494) (xy 418.976358 -435.248446) (xy 418.976358 -435.302954) (xy 418.968601 -435.356906)
			(xy 418.953244 -435.409206) (xy 418.930601 -435.458788) (xy 418.901132 -435.504642) (xy 418.865438 -435.545836)
			(xy 418.824244 -435.581531) (xy 418.778389 -435.611) (xy 418.728808 -435.633644) (xy 418.676508 -435.649001)
			(xy 418.622556 -435.656758) (xy 418.595302 -435.657244) (xy 418.565464 -435.656659) (xy 418.506518 -435.64735)
			(xy 418.477954 -435.638702) (xy 418.464464 -435.634837) (xy 418.436428 -435.633882) (xy 418.409188 -435.640582)
			(xy 418.384792 -435.654431) (xy 418.365078 -435.674387) (xy 418.351527 -435.69895) (xy 418.345161 -435.72627)
			(xy 418.345366 -435.740302) (xy 418.345874 -435.764686) (xy 418.345447 -435.796228) (xy 418.337646 -435.858827)
			(xy 418.322162 -435.91998) (xy 418.299232 -435.978749) (xy 418.26921 -436.03423) (xy 418.232555 -436.085571)
			(xy 418.231462 -436.086758) (xy 422.660062 -436.086758) (xy 422.664133 -436.031136) (xy 422.676259 -435.976699)
			(xy 422.696182 -435.924608) (xy 422.723478 -435.875973) (xy 422.757564 -435.83183) (xy 422.797713 -435.793121)
			(xy 422.843071 -435.76067) (xy 422.892671 -435.735169) (xy 422.945455 -435.717162) (xy 423.000298 -435.707032)
			(xy 423.056032 -435.704995) (xy 423.111469 -435.711095) (xy 423.165426 -435.725201) (xy 423.216755 -435.747013)
			(xy 423.245736 -435.7647) (xy 426.218375 -435.7647) (xy 426.222389 -435.700905) (xy 426.234366 -435.638116)
			(xy 426.254118 -435.577323) (xy 426.281333 -435.519485) (xy 426.315583 -435.465514) (xy 426.356326 -435.416261)
			(xy 426.402921 -435.372502) (xy 426.454633 -435.334928) (xy 426.510646 -435.304131) (xy 426.570077 -435.280597)
			(xy 426.631989 -435.264697) (xy 426.695405 -435.256682) (xy 426.727366 -435.256178) (xy 426.757439 -435.256649)
			(xy 426.817164 -435.263764) (xy 426.875636 -435.277865) (xy 426.932039 -435.298756) (xy 426.959014 -435.312058)
			(xy 426.97019 -435.317646) (xy 426.995082 -435.317392) (xy 427.09084 -435.266084) (xy 427.10481 -435.24551)
			(xy 427.10608 -435.233064) (xy 427.109764 -435.205465) (xy 427.123984 -435.151635) (xy 427.145874 -435.100443)
			(xy 427.174969 -435.052974) (xy 427.210653 -435.010236) (xy 427.252167 -434.973136) (xy 427.298631 -434.942462)
			(xy 427.349059 -434.918864) (xy 427.402381 -434.902843) (xy 427.457464 -434.89474) (xy 427.485302 -434.894228)
			(xy 427.512556 -434.894642) (xy 427.566508 -434.902399) (xy 427.618808 -434.917756) (xy 427.668389 -434.9404)
			(xy 427.714244 -434.969869) (xy 427.755438 -435.005564) (xy 427.791132 -435.046758) (xy 427.820601 -435.092612)
			(xy 427.843244 -435.142194) (xy 427.858601 -435.194494) (xy 427.866358 -435.248446) (xy 427.866358 -435.302954)
			(xy 427.858601 -435.356906) (xy 427.843244 -435.409206) (xy 427.820601 -435.458788) (xy 427.791132 -435.504642)
			(xy 427.755438 -435.545836) (xy 427.714244 -435.581531) (xy 427.668389 -435.611) (xy 427.618808 -435.633644)
			(xy 427.566508 -435.649001) (xy 427.512556 -435.656758) (xy 427.485302 -435.657244) (xy 427.455464 -435.656659)
			(xy 427.396518 -435.64735) (xy 427.367954 -435.638702) (xy 427.356016 -435.634892) (xy 427.331632 -435.638956)
			(xy 427.245018 -435.70525) (xy 427.234604 -435.727602) (xy 427.235366 -435.740302) (xy 427.235874 -435.764686)
			(xy 427.235816 -435.776068) (xy 427.234798 -435.79881) (xy 427.233842 -435.810152) (xy 427.232826 -435.821836)
			(xy 427.241208 -435.84368) (xy 427.317154 -435.914546) (xy 427.339506 -435.921404) (xy 427.35119 -435.919372)
			(xy 427.366263 -435.9171) (xy 427.396653 -435.914685) (xy 427.411896 -435.914546) (xy 427.439146 -435.915101)
			(xy 427.493091 -435.922857) (xy 427.545383 -435.93821) (xy 427.594957 -435.96085) (xy 427.640805 -435.990314)
			(xy 427.681994 -436.026004) (xy 427.717683 -436.067191) (xy 427.747148 -436.113039) (xy 427.769788 -436.162614)
			(xy 427.785143 -436.214905) (xy 427.792899 -436.26885) (xy 427.792899 -436.271924) (xy 430.190146 -436.271924)
			(xy 430.194217 -436.216302) (xy 430.206343 -436.161865) (xy 430.226266 -436.109774) (xy 430.253562 -436.061139)
			(xy 430.287648 -436.016996) (xy 430.327797 -435.978287) (xy 430.373155 -435.945836) (xy 430.422755 -435.920335)
			(xy 430.475539 -435.902328) (xy 430.530382 -435.892198) (xy 430.586116 -435.890161) (xy 430.641553 -435.896261)
			(xy 430.69551 -435.910367) (xy 430.746839 -435.932179) (xy 430.794445 -435.961233) (xy 430.837313 -435.996908)
			(xy 430.87453 -436.038445) (xy 430.905303 -436.084958) (xy 430.906147 -436.086758) (xy 431.550062 -436.086758)
			(xy 431.554133 -436.031136) (xy 431.566259 -435.976699) (xy 431.586182 -435.924608) (xy 431.613478 -435.875973)
			(xy 431.647564 -435.83183) (xy 431.687713 -435.793121) (xy 431.733071 -435.76067) (xy 431.782671 -435.735169)
			(xy 431.835455 -435.717162) (xy 431.890298 -435.707032) (xy 431.946032 -435.704995) (xy 432.001469 -435.711095)
			(xy 432.055426 -435.725201) (xy 432.106755 -435.747013) (xy 432.154361 -435.776067) (xy 432.197229 -435.811742)
			(xy 432.234446 -435.853279) (xy 432.265219 -435.899792) (xy 432.288891 -435.950289) (xy 432.304959 -436.003696)
			(xy 432.313079 -436.058872) (xy 432.313588 -436.086758) (xy 432.313079 -436.114644) (xy 432.304959 -436.16982)
			(xy 432.288891 -436.223227) (xy 432.265219 -436.273724) (xy 432.234446 -436.320237) (xy 432.197229 -436.361774)
			(xy 432.154361 -436.397449) (xy 432.106755 -436.426503) (xy 432.055426 -436.448315) (xy 432.001469 -436.462421)
			(xy 431.946032 -436.468521) (xy 431.890298 -436.466484) (xy 431.835455 -436.456354) (xy 431.782671 -436.438347)
			(xy 431.733071 -436.412846) (xy 431.687713 -436.380395) (xy 431.647564 -436.341686) (xy 431.613478 -436.297543)
			(xy 431.586182 -436.248908) (xy 431.566259 -436.196817) (xy 431.554133 -436.14238) (xy 431.550062 -436.086758)
			(xy 430.906147 -436.086758) (xy 430.928975 -436.135455) (xy 430.945043 -436.188862) (xy 430.953163 -436.244038)
			(xy 430.953672 -436.271924) (xy 430.953163 -436.29981) (xy 430.945043 -436.354986) (xy 430.928975 -436.408393)
			(xy 430.905303 -436.45889) (xy 430.87453 -436.505403) (xy 430.837313 -436.54694) (xy 430.794445 -436.582615)
			(xy 430.746839 -436.611669) (xy 430.69551 -436.633481) (xy 430.641553 -436.647587) (xy 430.586116 -436.653687)
			(xy 430.530382 -436.65165) (xy 430.475539 -436.64152) (xy 430.422755 -436.623513) (xy 430.373155 -436.598012)
			(xy 430.327797 -436.565561) (xy 430.287648 -436.526852) (xy 430.253562 -436.482709) (xy 430.226266 -436.434074)
			(xy 430.206343 -436.381983) (xy 430.194217 -436.327546) (xy 430.190146 -436.271924) (xy 427.792899 -436.271924)
			(xy 427.792899 -436.32335) (xy 427.785143 -436.377295) (xy 427.769788 -436.429586) (xy 427.747148 -436.479161)
			(xy 427.717683 -436.525009) (xy 427.681994 -436.566196) (xy 427.640805 -436.601886) (xy 427.594957 -436.63135)
			(xy 427.545383 -436.65399) (xy 427.493091 -436.669343) (xy 427.439146 -436.677099) (xy 427.411896 -436.677562)
			(xy 427.383645 -436.677047) (xy 427.327761 -436.668727) (xy 427.273714 -436.652254) (xy 427.222689 -436.627989)
			(xy 427.175801 -436.596463) (xy 427.134077 -436.558366) (xy 427.098429 -436.51453) (xy 427.069636 -436.465916)
			(xy 427.04833 -436.413586) (xy 427.034976 -436.358686) (xy 427.031912 -436.330598) (xy 427.030896 -436.318914)
			(xy 427.018704 -436.298848) (xy 426.931328 -436.242714) (xy 426.908214 -436.240174) (xy 426.897038 -436.243984)
			(xy 426.869721 -436.253246) (xy 426.813518 -436.266229) (xy 426.756207 -436.272778) (xy 426.727366 -436.273194)
			(xy 426.695405 -436.272718) (xy 426.631989 -436.264703) (xy 426.570077 -436.248803) (xy 426.510646 -436.225269)
			(xy 426.454633 -436.194472) (xy 426.402921 -436.156898) (xy 426.356326 -436.113139) (xy 426.315583 -436.063886)
			(xy 426.281333 -436.009915) (xy 426.254118 -435.952077) (xy 426.234366 -435.891284) (xy 426.222389 -435.828495)
			(xy 426.218375 -435.7647) (xy 423.245736 -435.7647) (xy 423.264361 -435.776067) (xy 423.307229 -435.811742)
			(xy 423.344446 -435.853279) (xy 423.375219 -435.899792) (xy 423.398891 -435.950289) (xy 423.414959 -436.003696)
			(xy 423.423079 -436.058872) (xy 423.423588 -436.086758) (xy 423.423079 -436.114644) (xy 423.414959 -436.16982)
			(xy 423.398891 -436.223227) (xy 423.375219 -436.273724) (xy 423.344446 -436.320237) (xy 423.307229 -436.361774)
			(xy 423.264361 -436.397449) (xy 423.216755 -436.426503) (xy 423.165426 -436.448315) (xy 423.111469 -436.462421)
			(xy 423.056032 -436.468521) (xy 423.000298 -436.466484) (xy 422.945455 -436.456354) (xy 422.892671 -436.438347)
			(xy 422.843071 -436.412846) (xy 422.797713 -436.380395) (xy 422.757564 -436.341686) (xy 422.723478 -436.297543)
			(xy 422.696182 -436.248908) (xy 422.676259 -436.196817) (xy 422.664133 -436.14238) (xy 422.660062 -436.086758)
			(xy 418.231462 -436.086758) (xy 418.189832 -436.131984) (xy 418.141695 -436.172757) (xy 418.088885 -436.207262)
			(xy 418.032213 -436.23497) (xy 417.972548 -436.255455) (xy 417.910808 -436.268403) (xy 417.847941 -436.273615)
			(xy 417.784911 -436.271011) (xy 417.722688 -436.26063) (xy 417.662226 -436.242633) (xy 417.604455 -436.217295)
			(xy 417.550262 -436.185006) (xy 417.500478 -436.146262) (xy 417.45587 -436.101658) (xy 417.417121 -436.051878)
			(xy 417.384827 -435.997688) (xy 417.359483 -435.939919) (xy 417.34148 -435.879459) (xy 417.331094 -435.817237)
			(xy 417.328484 -435.754207) (xy 416.943286 -435.754207) (xy 416.943286 -436.564786) (xy 418.217348 -436.564786)
			(xy 418.221419 -436.509164) (xy 418.233545 -436.454727) (xy 418.253468 -436.402636) (xy 418.280764 -436.354001)
			(xy 418.31485 -436.309858) (xy 418.354999 -436.271149) (xy 418.400357 -436.238698) (xy 418.449957 -436.213197)
			(xy 418.502741 -436.19519) (xy 418.557584 -436.18506) (xy 418.613318 -436.183023) (xy 418.668755 -436.189123)
			(xy 418.722712 -436.203229) (xy 418.774041 -436.225041) (xy 418.821647 -436.254095) (xy 418.864515 -436.28977)
			(xy 418.901732 -436.331307) (xy 418.932505 -436.37782) (xy 418.956177 -436.428317) (xy 418.972245 -436.481724)
			(xy 418.980365 -436.5369) (xy 418.980874 -436.564786) (xy 418.980365 -436.592672) (xy 418.972245 -436.647848)
			(xy 418.956177 -436.701255) (xy 418.932505 -436.751752) (xy 418.901732 -436.798265) (xy 418.864515 -436.839802)
			(xy 418.821647 -436.875477) (xy 418.774041 -436.904531) (xy 418.722712 -436.926343) (xy 418.668755 -436.940449)
			(xy 418.613318 -436.946549) (xy 418.557584 -436.944512) (xy 418.502741 -436.934382) (xy 418.449957 -436.916375)
			(xy 418.400357 -436.890874) (xy 418.354999 -436.858423) (xy 418.31485 -436.819714) (xy 418.280764 -436.775571)
			(xy 418.253468 -436.726936) (xy 418.233545 -436.674845) (xy 418.221419 -436.620408) (xy 418.217348 -436.564786)
			(xy 416.943286 -436.564786) (xy 416.943286 -438.374747) (xy 417.32936 -438.374747) (xy 417.32936 -438.310825)
			(xy 417.337371 -438.247407) (xy 417.353268 -438.185493) (xy 417.3768 -438.12606) (xy 417.407594 -438.070045)
			(xy 417.445167 -438.01833) (xy 417.488924 -437.971733) (xy 417.538177 -437.930988) (xy 417.592148 -437.896737)
			(xy 417.649987 -437.86952) (xy 417.71078 -437.849767) (xy 417.77357 -437.837789) (xy 417.837366 -437.833776)
			(xy 417.853422 -437.834786) (xy 420.49522 -437.834786) (xy 420.499291 -437.779164) (xy 420.511417 -437.724727)
			(xy 420.53134 -437.672636) (xy 420.558636 -437.624001) (xy 420.592722 -437.579858) (xy 420.632871 -437.541149)
			(xy 420.678229 -437.508698) (xy 420.727829 -437.483197) (xy 420.780613 -437.46519) (xy 420.835456 -437.45506)
			(xy 420.89119 -437.453023) (xy 420.946627 -437.459123) (xy 421.000584 -437.473229) (xy 421.051913 -437.495041)
			(xy 421.099519 -437.524095) (xy 421.142387 -437.55977) (xy 421.179604 -437.601307) (xy 421.210377 -437.64782)
			(xy 421.234049 -437.698317) (xy 421.250117 -437.751724) (xy 421.256136 -437.792622) (xy 426.43425 -437.792622)
			(xy 426.434752 -437.760661) (xy 426.442763 -437.697243) (xy 426.45866 -437.635329) (xy 426.482192 -437.575896)
			(xy 426.512986 -437.519881) (xy 426.550559 -437.468166) (xy 426.594316 -437.421569) (xy 426.643569 -437.380824)
			(xy 426.69754 -437.346573) (xy 426.755379 -437.319356) (xy 426.816172 -437.299603) (xy 426.878962 -437.287625)
			(xy 426.942758 -437.283612) (xy 427.006554 -437.287625) (xy 427.069344 -437.299603) (xy 427.072354 -437.300581)
			(xy 436.155586 -437.300581) (xy 436.155586 -437.236659) (xy 436.163597 -437.173241) (xy 436.179494 -437.111327)
			(xy 436.203026 -437.051894) (xy 436.23382 -436.995879) (xy 436.271393 -436.944164) (xy 436.31515 -436.897567)
			(xy 436.364403 -436.856822) (xy 436.418374 -436.822571) (xy 436.476213 -436.795354) (xy 436.537006 -436.775601)
			(xy 436.599796 -436.763623) (xy 436.663592 -436.75961) (xy 436.727388 -436.763623) (xy 436.790178 -436.775601)
			(xy 436.850971 -436.795354) (xy 436.90881 -436.822571) (xy 436.962781 -436.856822) (xy 437.012034 -436.897567)
			(xy 437.055791 -436.944164) (xy 437.058077 -436.94731) (xy 439.3217 -436.94731) (xy 439.325771 -436.891688)
			(xy 439.337897 -436.837251) (xy 439.35782 -436.78516) (xy 439.385116 -436.736525) (xy 439.419202 -436.692382)
			(xy 439.459351 -436.653673) (xy 439.504709 -436.621222) (xy 439.554309 -436.595721) (xy 439.607093 -436.577714)
			(xy 439.661936 -436.567584) (xy 439.71767 -436.565547) (xy 439.773107 -436.571647) (xy 439.827064 -436.585753)
			(xy 439.878393 -436.607565) (xy 439.925999 -436.636619) (xy 439.968867 -436.672294) (xy 440.006084 -436.713831)
			(xy 440.036857 -436.760344) (xy 440.060529 -436.810841) (xy 440.076597 -436.864248) (xy 440.084717 -436.919424)
			(xy 440.085226 -436.94731) (xy 440.084717 -436.975196) (xy 440.076597 -437.030372) (xy 440.060529 -437.083779)
			(xy 440.036857 -437.134276) (xy 440.006084 -437.180789) (xy 439.968867 -437.222326) (xy 439.925999 -437.258001)
			(xy 439.878393 -437.287055) (xy 439.827064 -437.308867) (xy 439.773107 -437.322973) (xy 439.71767 -437.329073)
			(xy 439.661936 -437.327036) (xy 439.607093 -437.316906) (xy 439.554309 -437.298899) (xy 439.504709 -437.273398)
			(xy 439.459351 -437.240947) (xy 439.419202 -437.202238) (xy 439.385116 -437.158095) (xy 439.35782 -437.10946)
			(xy 439.337897 -437.057369) (xy 439.325771 -437.002932) (xy 439.3217 -436.94731) (xy 437.058077 -436.94731)
			(xy 437.093364 -436.995879) (xy 437.124158 -437.051894) (xy 437.14769 -437.111327) (xy 437.163587 -437.173241)
			(xy 437.171598 -437.236659) (xy 437.1721 -437.26862) (xy 437.171598 -437.300581) (xy 437.163587 -437.363999)
			(xy 437.14769 -437.425913) (xy 437.124158 -437.485346) (xy 437.093364 -437.541361) (xy 437.055791 -437.593076)
			(xy 437.012034 -437.639673) (xy 436.962781 -437.680418) (xy 436.90881 -437.714669) (xy 436.850971 -437.741886)
			(xy 436.83397 -437.74741) (xy 442.116462 -437.74741) (xy 442.120533 -437.691788) (xy 442.132659 -437.637351)
			(xy 442.152582 -437.58526) (xy 442.179878 -437.536625) (xy 442.213964 -437.492482) (xy 442.254113 -437.453773)
			(xy 442.299471 -437.421322) (xy 442.349071 -437.395821) (xy 442.401855 -437.377814) (xy 442.456698 -437.367684)
			(xy 442.512432 -437.365647) (xy 442.567869 -437.371747) (xy 442.621826 -437.385853) (xy 442.673155 -437.407665)
			(xy 442.720761 -437.436719) (xy 442.763629 -437.472394) (xy 442.800846 -437.513931) (xy 442.831619 -437.560444)
			(xy 442.855291 -437.610941) (xy 442.871359 -437.664348) (xy 442.879479 -437.719524) (xy 442.879988 -437.74741)
			(xy 442.879479 -437.775296) (xy 442.871359 -437.830472) (xy 442.855291 -437.883879) (xy 442.831619 -437.934376)
			(xy 442.800846 -437.980889) (xy 442.763629 -438.022426) (xy 442.720761 -438.058101) (xy 442.673155 -438.087155)
			(xy 442.621826 -438.108967) (xy 442.567869 -438.123073) (xy 442.512432 -438.129173) (xy 442.456698 -438.127136)
			(xy 442.401855 -438.117006) (xy 442.349071 -438.098999) (xy 442.299471 -438.073498) (xy 442.254113 -438.041047)
			(xy 442.213964 -438.002338) (xy 442.179878 -437.958195) (xy 442.152582 -437.90956) (xy 442.132659 -437.857469)
			(xy 442.120533 -437.803032) (xy 442.116462 -437.74741) (xy 436.83397 -437.74741) (xy 436.790178 -437.761639)
			(xy 436.727388 -437.773617) (xy 436.663592 -437.777631) (xy 436.599796 -437.773617) (xy 436.537006 -437.761639)
			(xy 436.476213 -437.741886) (xy 436.418374 -437.714669) (xy 436.364403 -437.680418) (xy 436.31515 -437.639673)
			(xy 436.271393 -437.593076) (xy 436.23382 -437.541361) (xy 436.203026 -437.485346) (xy 436.179494 -437.425913)
			(xy 436.163597 -437.363999) (xy 436.155586 -437.300581) (xy 427.072354 -437.300581) (xy 427.130137 -437.319356)
			(xy 427.187976 -437.346573) (xy 427.241947 -437.380824) (xy 427.2912 -437.421569) (xy 427.334957 -437.468166)
			(xy 427.37253 -437.519881) (xy 427.403324 -437.575896) (xy 427.426856 -437.635329) (xy 427.442753 -437.697243)
			(xy 427.450764 -437.760661) (xy 427.451266 -437.792622) (xy 432.12334 -437.792622) (xy 432.127411 -437.737)
			(xy 432.139537 -437.682563) (xy 432.15946 -437.630472) (xy 432.186756 -437.581837) (xy 432.220842 -437.537694)
			(xy 432.260991 -437.498985) (xy 432.306349 -437.466534) (xy 432.355949 -437.441033) (xy 432.408733 -437.423026)
			(xy 432.463576 -437.412896) (xy 432.51931 -437.410859) (xy 432.574747 -437.416959) (xy 432.628704 -437.431065)
			(xy 432.680033 -437.452877) (xy 432.727639 -437.481931) (xy 432.770507 -437.517606) (xy 432.807724 -437.559143)
			(xy 432.838497 -437.605656) (xy 432.862169 -437.656153) (xy 432.878237 -437.70956) (xy 432.886357 -437.764736)
			(xy 432.886866 -437.792622) (xy 432.886357 -437.820508) (xy 432.878237 -437.875684) (xy 432.862169 -437.929091)
			(xy 432.838497 -437.979588) (xy 432.807724 -438.026101) (xy 432.770507 -438.067638) (xy 432.727639 -438.103313)
			(xy 432.680033 -438.132367) (xy 432.628704 -438.154179) (xy 432.574747 -438.168285) (xy 432.51931 -438.174385)
			(xy 432.463576 -438.172348) (xy 432.408733 -438.162218) (xy 432.355949 -438.144211) (xy 432.306349 -438.11871)
			(xy 432.260991 -438.086259) (xy 432.220842 -438.04755) (xy 432.186756 -438.003407) (xy 432.15946 -437.954772)
			(xy 432.139537 -437.902681) (xy 432.127411 -437.848244) (xy 432.12334 -437.792622) (xy 427.451266 -437.792622)
			(xy 427.45068 -437.826407) (xy 427.441729 -437.89338) (xy 427.423987 -437.958579) (xy 427.397768 -438.020854)
			(xy 427.363532 -438.079108) (xy 427.321884 -438.132315) (xy 427.273556 -438.179538) (xy 427.2194 -438.219945)
			(xy 427.190154 -438.236868) (xy 427.180502 -438.242202) (xy 427.167548 -438.259728) (xy 427.146974 -438.355994)
			(xy 427.151546 -438.37733) (xy 427.15815 -438.38622) (xy 427.175819 -438.411041) (xy 427.203906 -438.465103)
			(xy 427.22304 -438.522942) (xy 427.232734 -438.583089) (xy 427.233334 -438.61355) (xy 427.232848 -438.640801)
			(xy 427.225092 -438.694749) (xy 427.219206 -438.714796) (xy 436.172508 -438.714796) (xy 436.177715 -438.651931)
			(xy 436.190658 -438.590194) (xy 436.211138 -438.530531) (xy 436.23884 -438.47386) (xy 436.273339 -438.42105)
			(xy 436.314106 -438.372913) (xy 436.360513 -438.330188) (xy 436.411849 -438.293532) (xy 436.467325 -438.263506)
			(xy 436.526088 -438.240573) (xy 436.587237 -438.225085) (xy 436.649832 -438.217279) (xy 436.681372 -438.216802)
			(xy 436.709533 -438.217149) (xy 436.765511 -438.223357) (xy 436.820459 -438.235723) (xy 436.8737 -438.254093)
			(xy 436.899304 -438.265824) (xy 436.91048 -438.271158) (xy 436.934356 -438.270396) (xy 437.028336 -438.219342)
			(xy 437.041798 -438.19953) (xy 437.043576 -438.187084) (xy 437.047629 -438.159876) (xy 437.062466 -438.10691)
			(xy 437.084761 -438.056625) (xy 437.114051 -438.010066) (xy 437.149728 -437.9682) (xy 437.191051 -437.931896)
			(xy 437.237163 -437.901907) (xy 437.287106 -437.878856) (xy 437.339843 -437.863221) (xy 437.394279 -437.855328)
			(xy 437.421782 -437.854852) (xy 437.449033 -437.855394) (xy 437.50298 -437.863148) (xy 437.555275 -437.878501)
			(xy 437.604852 -437.90114) (xy 437.650702 -437.930604) (xy 437.691893 -437.966294) (xy 437.727585 -438.007483)
			(xy 437.757051 -438.053332) (xy 437.779693 -438.102909) (xy 437.795048 -438.155202) (xy 437.802805 -438.209149)
			(xy 437.802805 -438.263651) (xy 437.795048 -438.317598) (xy 437.779693 -438.369891) (xy 437.757051 -438.419468)
			(xy 437.727585 -438.465317) (xy 437.691893 -438.506506) (xy 437.650702 -438.542196) (xy 437.604852 -438.57166)
			(xy 437.555275 -438.594299) (xy 437.50298 -438.609652) (xy 437.449033 -438.617406) (xy 437.421782 -438.617868)
			(xy 437.395601 -438.617451) (xy 437.343727 -438.610307) (xy 437.318404 -438.603644) (xy 437.306466 -438.600342)
			(xy 437.283098 -438.604914) (xy 437.199024 -438.671208) (xy 437.189118 -438.693052) (xy 437.189372 -438.705498)
			(xy 437.18988 -438.72531) (xy 437.189422 -438.75685) (xy 437.181618 -438.819445) (xy 437.166132 -438.880595)
			(xy 437.143201 -438.939359) (xy 437.113178 -438.994836) (xy 437.076523 -439.046173) (xy 437.07541 -439.047382)
			(xy 441.486542 -439.047382) (xy 441.490613 -438.99176) (xy 441.502739 -438.937323) (xy 441.522662 -438.885232)
			(xy 441.549958 -438.836597) (xy 441.584044 -438.792454) (xy 441.624193 -438.753745) (xy 441.669551 -438.721294)
			(xy 441.719151 -438.695793) (xy 441.771935 -438.677786) (xy 441.826778 -438.667656) (xy 441.882512 -438.665619)
			(xy 441.937949 -438.671719) (xy 441.991906 -438.685825) (xy 442.043235 -438.707637) (xy 442.090841 -438.736691)
			(xy 442.133709 -438.772366) (xy 442.170926 -438.813903) (xy 442.201699 -438.860416) (xy 442.225371 -438.910913)
			(xy 442.241439 -438.96432) (xy 442.249559 -439.019496) (xy 442.250068 -439.047382) (xy 442.249559 -439.075268)
			(xy 442.241439 -439.130444) (xy 442.225371 -439.183851) (xy 442.201699 -439.234348) (xy 442.170926 -439.280861)
			(xy 442.133709 -439.322398) (xy 442.090841 -439.358073) (xy 442.043235 -439.387127) (xy 441.991906 -439.408939)
			(xy 441.937949 -439.423045) (xy 441.882512 -439.429145) (xy 441.826778 -439.427108) (xy 441.771935 -439.416978)
			(xy 441.719151 -439.398971) (xy 441.669551 -439.37347) (xy 441.624193 -439.341019) (xy 441.584044 -439.30231)
			(xy 441.549958 -439.258167) (xy 441.522662 -439.209532) (xy 441.502739 -439.157441) (xy 441.490613 -439.103004)
			(xy 441.486542 -439.047382) (xy 437.07541 -439.047382) (xy 437.0338 -439.092582) (xy 436.985664 -439.13335)
			(xy 436.932856 -439.167851) (xy 436.876186 -439.195555) (xy 436.816524 -439.216037) (xy 436.754786 -439.228982)
			(xy 436.691922 -439.234192) (xy 436.628896 -439.231585) (xy 436.566676 -439.221203) (xy 436.506219 -439.203205)
			(xy 436.448452 -439.177867) (xy 436.394262 -439.145578) (xy 436.344483 -439.106834) (xy 436.299878 -439.062231)
			(xy 436.261132 -439.012453) (xy 436.228842 -438.958264) (xy 436.203501 -438.900498) (xy 436.185501 -438.840041)
			(xy 436.175117 -438.777822) (xy 436.172508 -438.714796) (xy 427.219206 -438.714796) (xy 427.209737 -438.747044)
			(xy 427.187095 -438.796621) (xy 427.157629 -438.842471) (xy 427.121938 -438.883662) (xy 427.080747 -438.919353)
			(xy 427.034897 -438.948819) (xy 426.98532 -438.971461) (xy 426.933025 -438.986816) (xy 426.879077 -438.994572)
			(xy 426.824575 -438.994572) (xy 426.770627 -438.986816) (xy 426.718332 -438.971461) (xy 426.668755 -438.948819)
			(xy 426.622905 -438.919353) (xy 426.581714 -438.883662) (xy 426.546023 -438.842471) (xy 426.516557 -438.796621)
			(xy 426.493915 -438.747044) (xy 426.47856 -438.694749) (xy 426.470804 -438.640801) (xy 426.470318 -438.61355)
			(xy 426.470797 -438.586212) (xy 426.47858 -438.532094) (xy 426.494007 -438.479641) (xy 426.516764 -438.429926)
			(xy 426.546383 -438.383969) (xy 426.582259 -438.342711) (xy 426.602652 -438.324498) (xy 426.611034 -438.317386)
			(xy 426.620178 -438.297574) (xy 426.621194 -438.199276) (xy 426.612304 -438.17921) (xy 426.603922 -438.171844)
			(xy 426.581411 -438.151144) (xy 426.541035 -438.105209) (xy 426.506458 -438.054765) (xy 426.478176 -438.00054)
			(xy 426.4566 -437.943315) (xy 426.44204 -437.883916) (xy 426.434705 -437.823201) (xy 426.43425 -437.792622)
			(xy 421.256136 -437.792622) (xy 421.258237 -437.8069) (xy 421.258746 -437.834786) (xy 421.258237 -437.862672)
			(xy 421.250117 -437.917848) (xy 421.234049 -437.971255) (xy 421.210377 -438.021752) (xy 421.179604 -438.068265)
			(xy 421.142387 -438.109802) (xy 421.099519 -438.145477) (xy 421.051913 -438.174531) (xy 421.000584 -438.196343)
			(xy 420.946627 -438.210449) (xy 420.89119 -438.216549) (xy 420.835456 -438.214512) (xy 420.780613 -438.204382)
			(xy 420.727829 -438.186375) (xy 420.678229 -438.160874) (xy 420.632871 -438.128423) (xy 420.592722 -438.089714)
			(xy 420.558636 -438.045571) (xy 420.53134 -437.996936) (xy 420.511417 -437.944845) (xy 420.499291 -437.890408)
			(xy 420.49522 -437.834786) (xy 417.853422 -437.834786) (xy 417.901162 -437.837789) (xy 417.963952 -437.849767)
			(xy 418.024745 -437.86952) (xy 418.082584 -437.896737) (xy 418.136555 -437.930988) (xy 418.185808 -437.971733)
			(xy 418.229565 -438.01833) (xy 418.267138 -438.070045) (xy 418.297932 -438.12606) (xy 418.321464 -438.185493)
			(xy 418.337361 -438.247407) (xy 418.345372 -438.310825) (xy 418.345874 -438.342786) (xy 418.345372 -438.374747)
			(xy 418.337361 -438.438165) (xy 418.321464 -438.500079) (xy 418.297932 -438.559512) (xy 418.267138 -438.615527)
			(xy 418.253073 -438.634886) (xy 423.289982 -438.634886) (xy 423.294053 -438.579264) (xy 423.306179 -438.524827)
			(xy 423.326102 -438.472736) (xy 423.353398 -438.424101) (xy 423.387484 -438.379958) (xy 423.427633 -438.341249)
			(xy 423.472991 -438.308798) (xy 423.522591 -438.283297) (xy 423.575375 -438.26529) (xy 423.630218 -438.25516)
			(xy 423.685952 -438.253123) (xy 423.741389 -438.259223) (xy 423.795346 -438.273329) (xy 423.846675 -438.295141)
			(xy 423.894281 -438.324195) (xy 423.937149 -438.35987) (xy 423.974366 -438.401407) (xy 424.005139 -438.44792)
			(xy 424.028811 -438.498417) (xy 424.044879 -438.551824) (xy 424.052999 -438.607) (xy 424.053508 -438.634886)
			(xy 424.052999 -438.662772) (xy 424.044879 -438.717948) (xy 424.028811 -438.771355) (xy 424.005139 -438.821852)
			(xy 423.974366 -438.868365) (xy 423.937149 -438.909902) (xy 423.894281 -438.945577) (xy 423.846675 -438.974631)
			(xy 423.795346 -438.996443) (xy 423.741389 -439.010549) (xy 423.685952 -439.016649) (xy 423.630218 -439.014612)
			(xy 423.575375 -439.004482) (xy 423.522591 -438.986475) (xy 423.472991 -438.960974) (xy 423.427633 -438.928523)
			(xy 423.387484 -438.889814) (xy 423.353398 -438.845671) (xy 423.326102 -438.797036) (xy 423.306179 -438.744945)
			(xy 423.294053 -438.690508) (xy 423.289982 -438.634886) (xy 418.253073 -438.634886) (xy 418.229565 -438.667242)
			(xy 418.185808 -438.713839) (xy 418.136555 -438.754584) (xy 418.082584 -438.788835) (xy 418.024745 -438.816052)
			(xy 417.963952 -438.835805) (xy 417.901162 -438.847783) (xy 417.837366 -438.851797) (xy 417.77357 -438.847783)
			(xy 417.71078 -438.835805) (xy 417.649987 -438.816052) (xy 417.592148 -438.788835) (xy 417.538177 -438.754584)
			(xy 417.488924 -438.713839) (xy 417.445167 -438.667242) (xy 417.407594 -438.615527) (xy 417.3768 -438.559512)
			(xy 417.353268 -438.500079) (xy 417.337371 -438.438165) (xy 417.32936 -438.374747) (xy 416.943286 -438.374747)
			(xy 416.943286 -439.506106) (xy 416.94371 -439.516176) (xy 416.951424 -439.53478) (xy 416.958272 -439.542174)
			(xy 417.15817 -439.742072) (xy 417.165884 -439.749036) (xy 417.185209 -439.756626) (xy 417.20596 -439.755929)
			(xy 417.215574 -439.751978) (xy 417.316666 -439.70448) (xy 417.332668 -439.676794) (xy 417.331144 -439.660538)
			(xy 417.330078 -439.648629) (xy 417.328936 -439.624743) (xy 417.328858 -439.612786) (xy 417.329322 -439.582055)
			(xy 417.336732 -439.521041) (xy 417.351442 -439.461364) (xy 417.373237 -439.403896) (xy 417.4018 -439.349474)
			(xy 417.436714 -439.298891) (xy 417.477471 -439.252885) (xy 417.523475 -439.212127) (xy 417.574057 -439.17721)
			(xy 417.628478 -439.148645) (xy 417.685945 -439.126848) (xy 417.745621 -439.112136) (xy 417.806635 -439.104724)
			(xy 417.837366 -439.104278) (xy 417.867443 -439.104714) (xy 417.927176 -439.111807) (xy 417.985653 -439.125907)
			(xy 418.042054 -439.146819) (xy 418.069014 -439.160158) (xy 418.08019 -439.165746) (xy 418.105082 -439.165492)
			(xy 418.20084 -439.114184) (xy 418.21481 -439.09361) (xy 418.21608 -439.081164) (xy 418.219689 -439.053548)
			(xy 418.233884 -438.999694) (xy 418.25576 -438.948478) (xy 418.284852 -438.900988) (xy 418.320542 -438.858233)
			(xy 418.36207 -438.821125) (xy 418.408554 -438.79045) (xy 418.459005 -438.766863) (xy 418.51235 -438.750863)
			(xy 418.567455 -438.742792) (xy 418.595302 -438.742328) (xy 418.622551 -438.742814) (xy 418.676493 -438.75057)
			(xy 418.728782 -438.765924) (xy 418.778355 -438.788563) (xy 418.8242 -438.818027) (xy 418.865387 -438.853715)
			(xy 418.901074 -438.894901) (xy 418.930538 -438.940747) (xy 418.953177 -438.990319) (xy 418.96853 -439.042609)
			(xy 418.976286 -439.096551) (xy 418.976286 -439.151049) (xy 418.96853 -439.204991) (xy 418.966032 -439.213498)
			(xy 428.721264 -439.213498) (xy 428.725335 -439.157876) (xy 428.737461 -439.103439) (xy 428.757384 -439.051348)
			(xy 428.78468 -439.002713) (xy 428.818766 -438.95857) (xy 428.858915 -438.919861) (xy 428.904273 -438.88741)
			(xy 428.953873 -438.861909) (xy 429.006657 -438.843902) (xy 429.0615 -438.833772) (xy 429.117234 -438.831735)
			(xy 429.172671 -438.837835) (xy 429.226628 -438.851941) (xy 429.277957 -438.873753) (xy 429.325563 -438.902807)
			(xy 429.368431 -438.938482) (xy 429.405648 -438.980019) (xy 429.436421 -439.026532) (xy 429.460093 -439.077029)
			(xy 429.476161 -439.130436) (xy 429.484281 -439.185612) (xy 429.48479 -439.213498) (xy 429.484281 -439.241384)
			(xy 429.476161 -439.29656) (xy 429.460093 -439.349967) (xy 429.436421 -439.400464) (xy 429.405648 -439.446977)
			(xy 429.368431 -439.488514) (xy 429.325563 -439.524189) (xy 429.323562 -439.52541) (xy 437.043828 -439.52541)
			(xy 437.047899 -439.469788) (xy 437.060025 -439.415351) (xy 437.079948 -439.36326) (xy 437.107244 -439.314625)
			(xy 437.14133 -439.270482) (xy 437.181479 -439.231773) (xy 437.226837 -439.199322) (xy 437.276437 -439.173821)
			(xy 437.329221 -439.155814) (xy 437.384064 -439.145684) (xy 437.439798 -439.143647) (xy 437.495235 -439.149747)
			(xy 437.549192 -439.163853) (xy 437.600521 -439.185665) (xy 437.648127 -439.214719) (xy 437.690995 -439.250394)
			(xy 437.728212 -439.291931) (xy 437.758985 -439.338444) (xy 437.782657 -439.388941) (xy 437.798725 -439.442348)
			(xy 437.806845 -439.497524) (xy 437.807354 -439.52541) (xy 437.806845 -439.553296) (xy 437.798725 -439.608472)
			(xy 437.782657 -439.661879) (xy 437.758985 -439.712376) (xy 437.728212 -439.758889) (xy 437.690995 -439.800426)
			(xy 437.648127 -439.836101) (xy 437.600521 -439.865155) (xy 437.549192 -439.886967) (xy 437.495235 -439.901073)
			(xy 437.439798 -439.907173) (xy 437.384064 -439.905136) (xy 437.329221 -439.895006) (xy 437.276437 -439.876999)
			(xy 437.226837 -439.851498) (xy 437.181479 -439.819047) (xy 437.14133 -439.780338) (xy 437.107244 -439.736195)
			(xy 437.079948 -439.68756) (xy 437.060025 -439.635469) (xy 437.047899 -439.581032) (xy 437.043828 -439.52541)
			(xy 429.323562 -439.52541) (xy 429.277957 -439.553243) (xy 429.226628 -439.575055) (xy 429.172671 -439.589161)
			(xy 429.117234 -439.595261) (xy 429.0615 -439.593224) (xy 429.006657 -439.583094) (xy 428.953873 -439.565087)
			(xy 428.904273 -439.539586) (xy 428.858915 -439.507135) (xy 428.818766 -439.468426) (xy 428.78468 -439.424283)
			(xy 428.757384 -439.375648) (xy 428.737461 -439.323557) (xy 428.725335 -439.26912) (xy 428.721264 -439.213498)
			(xy 418.966032 -439.213498) (xy 418.953177 -439.257281) (xy 418.930538 -439.306853) (xy 418.901074 -439.352699)
			(xy 418.865387 -439.393885) (xy 418.8242 -439.429573) (xy 418.778355 -439.459037) (xy 418.728782 -439.481676)
			(xy 418.676493 -439.49703) (xy 418.622551 -439.504786) (xy 418.595302 -439.505344) (xy 418.565466 -439.504743)
			(xy 418.506524 -439.495425) (xy 418.477954 -439.486802) (xy 418.466016 -439.482992) (xy 418.441632 -439.487056)
			(xy 418.355018 -439.55335) (xy 418.344604 -439.575702) (xy 418.345366 -439.588402) (xy 418.345874 -439.612786)
			(xy 418.345429 -439.643518) (xy 418.338022 -439.704534) (xy 418.323313 -439.764212) (xy 418.301518 -439.821681)
			(xy 418.272955 -439.876105) (xy 418.238039 -439.926688) (xy 418.230801 -439.934858) (xy 422.660062 -439.934858)
			(xy 422.664133 -439.879236) (xy 422.676259 -439.824799) (xy 422.696182 -439.772708) (xy 422.723478 -439.724073)
			(xy 422.757564 -439.67993) (xy 422.797713 -439.641221) (xy 422.843071 -439.60877) (xy 422.892671 -439.583269)
			(xy 422.945455 -439.565262) (xy 423.000298 -439.555132) (xy 423.056032 -439.553095) (xy 423.111469 -439.559195)
			(xy 423.165426 -439.573301) (xy 423.216755 -439.595113) (xy 423.264361 -439.624167) (xy 423.307229 -439.659842)
			(xy 423.344446 -439.701379) (xy 423.375219 -439.747892) (xy 423.398891 -439.798389) (xy 423.414959 -439.851796)
			(xy 423.423079 -439.906972) (xy 423.423588 -439.934858) (xy 423.423079 -439.962744) (xy 423.414959 -440.01792)
			(xy 423.398891 -440.071327) (xy 423.375219 -440.121824) (xy 423.344446 -440.168337) (xy 423.307229 -440.209874)
			(xy 423.264361 -440.245549) (xy 423.216755 -440.274603) (xy 423.165426 -440.296415) (xy 423.111469 -440.310521)
			(xy 423.056032 -440.316621) (xy 423.000298 -440.314584) (xy 422.945455 -440.304454) (xy 422.892671 -440.286447)
			(xy 422.843071 -440.260946) (xy 422.797713 -440.228495) (xy 422.757564 -440.189786) (xy 422.723478 -440.145643)
			(xy 422.696182 -440.097008) (xy 422.676259 -440.044917) (xy 422.664133 -439.99048) (xy 422.660062 -439.934858)
			(xy 418.230801 -439.934858) (xy 418.19728 -439.972694) (xy 418.151273 -440.013451) (xy 418.100688 -440.048365)
			(xy 418.046263 -440.076926) (xy 417.988793 -440.098719) (xy 417.929114 -440.113425) (xy 417.868098 -440.12083)
			(xy 417.837366 -440.121294) (xy 417.82541 -440.12121) (xy 417.801524 -440.120066) (xy 417.789614 -440.119008)
			(xy 417.773358 -440.117484) (xy 417.745672 -440.133486) (xy 417.698174 -440.234578) (xy 417.694209 -440.244186)
			(xy 417.693535 -440.264939) (xy 417.701111 -440.284273) (xy 417.70808 -440.291982) (xy 418.075364 -440.659266)
			(xy 418.082764 -440.666106) (xy 418.101363 -440.673822) (xy 418.111432 -440.674252)
		)
		(stroke
			(width 0)
			(type solid)
		)
		(fill yes)
		(layer "In4.Cu")
		(net "P3V3_AUX")
	)
	(gr_poly
		(pts
			(xy 20.036536 -196.006466) (xy 20.052049 -196.005867) (xy 20.081622 -195.996476) (xy 20.107025 -195.978658)
			(xy 20.125925 -195.954049) (xy 20.136587 -195.924909) (xy 20.137882 -195.909438) (xy 20.139651 -195.881764)
			(xy 20.150187 -195.827323) (xy 20.16849 -195.77498) (xy 20.194176 -195.725836) (xy 20.226703 -195.680927)
			(xy 20.265386 -195.641197) (xy 20.309412 -195.607484) (xy 20.357853 -195.580497) (xy 20.40969 -195.560804)
			(xy 20.463831 -195.54882) (xy 20.519136 -195.544797) (xy 20.574441 -195.54882) (xy 20.628582 -195.560804)
			(xy 20.680419 -195.580497) (xy 20.72886 -195.607484) (xy 20.772886 -195.641197) (xy 20.811569 -195.680927)
			(xy 20.844096 -195.725836) (xy 20.869782 -195.77498) (xy 20.888085 -195.827323) (xy 20.898621 -195.881764)
			(xy 20.90039 -195.909438) (xy 20.901624 -195.924929) (xy 20.912246 -195.954117) (xy 20.93115 -195.978763)
			(xy 20.956587 -195.996588) (xy 20.986206 -196.005942) (xy 21.001736 -196.006466) (xy 22.331426 -196.006466)
			(xy 22.35454 -195.993766) (xy 22.361398 -195.98259) (xy 22.400514 -195.920106) (xy 22.405086 -195.911216)
			(xy 22.408134 -195.898008) (xy 22.408388 -195.893182) (xy 22.408388 -195.86194) (xy 22.403562 -195.85178)
			(xy 22.388386 -195.817873) (xy 22.366921 -195.746756) (xy 22.356019 -195.673276) (xy 22.355302 -195.636134)
			(xy 22.355302 -195.635372) (xy 22.355812 -195.602632) (xy 22.364221 -195.537695) (xy 22.380896 -195.474374)
			(xy 22.405562 -195.413718) (xy 22.437809 -195.35673) (xy 22.477105 -195.304353) (xy 22.499574 -195.280534)
			(xy 22.506686 -195.273422) (xy 22.514052 -195.255134) (xy 22.514052 -195.165472) (xy 22.506686 -195.147184)
			(xy 22.499574 -195.140072) (xy 22.47709 -195.116267) (xy 22.437792 -195.063887) (xy 22.405542 -195.006897)
			(xy 22.380875 -194.946238) (xy 22.364199 -194.882915) (xy 22.355789 -194.817975) (xy 22.355302 -194.785234)
			(xy 22.35582 -194.752315) (xy 22.364317 -194.687026) (xy 22.381172 -194.623382) (xy 22.406104 -194.562446)
			(xy 22.438695 -194.50524) (xy 22.4784 -194.452721) (xy 22.501098 -194.428872) (xy 22.50821 -194.42176)
			(xy 22.515576 -194.403472) (xy 22.515322 -194.321938) (xy 22.51481 -194.312036) (xy 22.507242 -194.293729)
			(xy 22.50059 -194.286378) (xy 22.500336 -194.286124) (xy 22.47773 -194.262797) (xy 22.438188 -194.211258)
			(xy 22.405713 -194.154999) (xy 22.380858 -194.094982) (xy 22.364051 -194.032235) (xy 22.355578 -193.96783)
			(xy 22.355048 -193.93535) (xy 22.355553 -193.902868) (xy 22.364027 -193.838459) (xy 22.380836 -193.775706)
			(xy 22.405692 -193.715686) (xy 22.438171 -193.659423) (xy 22.477716 -193.607881) (xy 22.523651 -193.561943)
			(xy 22.57519 -193.522393) (xy 22.63145 -193.48991) (xy 22.691469 -193.465049) (xy 22.754219 -193.448235)
			(xy 22.818628 -193.439756) (xy 22.85111 -193.439288) (xy 22.851872 -193.439288) (xy 22.883103 -193.439778)
			(xy 22.945066 -193.447658) (xy 23.005549 -193.463257) (xy 23.034752 -193.47434) (xy 23.03907 -193.476118)
			(xy 23.048722 -193.47815) (xy 23.06069 -193.479839) (xy 23.083892 -193.473196) (xy 23.093172 -193.46545)
			(xy 23.170388 -193.394076) (xy 23.178008 -193.365374) (xy 23.173436 -193.351404) (xy 23.160923 -193.310462)
			(xy 23.142984 -193.226746) (xy 23.137622 -193.184272) (xy 23.136352 -193.173858) (xy 23.125938 -193.15557)
			(xy 23.05939 -193.106294) (xy 23.052694 -193.101705) (xy 23.037277 -193.096649) (xy 23.029164 -193.096388)
			(xy 23.017734 -193.096388) (xy 23.013162 -193.09715) (xy 22.973089 -193.104252) (xy 22.892058 -193.111887)
			(xy 22.851364 -193.11239) (xy 22.85111 -193.11239) (xy 22.809354 -193.111894) (xy 22.726221 -193.103955)
			(xy 22.644218 -193.088151) (xy 22.564089 -193.064623) (xy 22.486559 -193.033584) (xy 22.412331 -192.995317)
			(xy 22.342077 -192.950167) (xy 22.276432 -192.898544) (xy 22.215992 -192.840914) (xy 22.161303 -192.7778)
			(xy 22.112862 -192.709773) (xy 22.071106 -192.63745) (xy 22.036414 -192.561485) (xy 22.0091 -192.482567)
			(xy 21.989411 -192.401409) (xy 21.977526 -192.318747) (xy 21.973553 -192.23533) (xy 21.977526 -192.151913)
			(xy 21.989411 -192.069251) (xy 22.0091 -191.988093) (xy 22.036414 -191.909175) (xy 22.071106 -191.83321)
			(xy 22.112862 -191.760887) (xy 22.161303 -191.69286) (xy 22.215992 -191.629746) (xy 22.276432 -191.572116)
			(xy 22.342077 -191.520493) (xy 22.412331 -191.475343) (xy 22.486559 -191.437076) (xy 22.564089 -191.406037)
			(xy 22.644218 -191.382509) (xy 22.726221 -191.366705) (xy 22.809354 -191.358766) (xy 22.85111 -191.358266)
			(xy 22.89281 -191.358761) (xy 22.975833 -191.36668) (xy 23.057729 -191.382446) (xy 23.137759 -191.405916)
			(xy 23.215198 -191.436878) (xy 23.289348 -191.475053) (xy 23.359539 -191.520095) (xy 23.392638 -191.545464)
			(xy 23.399242 -191.550544) (xy 23.41372 -191.555624) (xy 23.422053 -191.558168) (xy 23.439463 -191.558042)
			(xy 23.447756 -191.55537) (xy 23.46071 -191.550544) (xy 23.46706 -191.545464) (xy 23.500167 -191.520107)
			(xy 23.570361 -191.475073) (xy 23.644512 -191.436904) (xy 23.72195 -191.405942) (xy 23.801976 -191.382468)
			(xy 23.883869 -191.366693) (xy 23.966889 -191.358759) (xy 24.008588 -191.358266) (xy 24.008842 -191.358266)
			(xy 24.009096 -191.358266) (xy 24.052158 -191.358777) (xy 24.137867 -191.367218) (xy 24.222336 -191.38402)
			(xy 24.304751 -191.409021) (xy 24.384318 -191.441979) (xy 24.460272 -191.482578) (xy 24.531881 -191.530426)
			(xy 24.598455 -191.585064) (xy 24.659353 -191.645963) (xy 24.713988 -191.712538) (xy 24.761834 -191.784148)
			(xy 24.802431 -191.860103) (xy 24.835387 -191.939672) (xy 24.860386 -192.022088) (xy 24.877185 -192.106557)
			(xy 24.885624 -192.192266) (xy 24.88595 -192.218564) (xy 25.938241 -192.218564) (xy 25.942179 -192.164756)
			(xy 25.953909 -192.112095) (xy 25.973183 -192.061704) (xy 25.999588 -192.014655) (xy 26.032561 -191.971953)
			(xy 26.071401 -191.934506) (xy 26.11528 -191.903114) (xy 26.163261 -191.878445) (xy 26.214323 -191.861025)
			(xy 26.267377 -191.851225) (xy 26.321293 -191.849255) (xy 26.374921 -191.855156) (xy 26.427118 -191.868802)
			(xy 26.476772 -191.889903) (xy 26.522825 -191.918008) (xy 26.564295 -191.95252) (xy 26.600298 -191.992701)
			(xy 26.630067 -192.037697) (xy 26.652967 -192.086547) (xy 26.66851 -192.138211) (xy 26.676366 -192.191588)
			(xy 26.676858 -192.218564) (xy 27.726909 -192.218564) (xy 27.730847 -192.164756) (xy 27.742577 -192.112095)
			(xy 27.761851 -192.061704) (xy 27.788256 -192.014655) (xy 27.821229 -191.971953) (xy 27.860069 -191.934506)
			(xy 27.903948 -191.903114) (xy 27.951929 -191.878445) (xy 28.002991 -191.861025) (xy 28.056045 -191.851225)
			(xy 28.109961 -191.849255) (xy 28.163589 -191.855156) (xy 28.215786 -191.868802) (xy 28.26544 -191.889903)
			(xy 28.311493 -191.918008) (xy 28.352963 -191.95252) (xy 28.388966 -191.992701) (xy 28.418735 -192.037697)
			(xy 28.441635 -192.086547) (xy 28.457178 -192.138211) (xy 28.465034 -192.191588) (xy 28.465526 -192.218564)
			(xy 28.465034 -192.24554) (xy 28.457178 -192.298917) (xy 28.441635 -192.350581) (xy 28.418735 -192.399431)
			(xy 28.388966 -192.444427) (xy 28.352963 -192.484608) (xy 28.311493 -192.51912) (xy 28.26544 -192.547225)
			(xy 28.215786 -192.568326) (xy 28.163589 -192.581972) (xy 28.109961 -192.587873) (xy 28.056045 -192.585903)
			(xy 28.002991 -192.576103) (xy 27.951929 -192.558683) (xy 27.903948 -192.534014) (xy 27.860069 -192.502622)
			(xy 27.821229 -192.465175) (xy 27.788256 -192.422473) (xy 27.761851 -192.375424) (xy 27.742577 -192.325033)
			(xy 27.730847 -192.272372) (xy 27.726909 -192.218564) (xy 26.676858 -192.218564) (xy 26.676366 -192.24554)
			(xy 26.66851 -192.298917) (xy 26.652967 -192.350581) (xy 26.630067 -192.399431) (xy 26.600298 -192.444427)
			(xy 26.564295 -192.484608) (xy 26.522825 -192.51912) (xy 26.476772 -192.547225) (xy 26.427118 -192.568326)
			(xy 26.374921 -192.581972) (xy 26.321293 -192.587873) (xy 26.267377 -192.585903) (xy 26.214323 -192.576103)
			(xy 26.163261 -192.558683) (xy 26.11528 -192.534014) (xy 26.071401 -192.502622) (xy 26.032561 -192.465175)
			(xy 25.999588 -192.422473) (xy 25.973183 -192.375424) (xy 25.953909 -192.325033) (xy 25.942179 -192.272372)
			(xy 25.938241 -192.218564) (xy 24.88595 -192.218564) (xy 24.886158 -192.235328) (xy 24.886158 -192.235582)
			(xy 24.885679 -192.276675) (xy 24.877991 -192.3585) (xy 24.862681 -192.439246) (xy 24.839884 -192.518206)
			(xy 24.809799 -192.594687) (xy 24.79167 -192.631568) (xy 24.788876 -192.636902) (xy 24.786082 -192.648332)
			(xy 24.784826 -192.654237) (xy 24.784819 -192.666305) (xy 24.786082 -192.672208) (xy 24.788876 -192.683638)
			(xy 24.79167 -192.688972) (xy 24.809794 -192.725855) (xy 24.839878 -192.802336) (xy 24.862675 -192.881295)
			(xy 24.877987 -192.962041) (xy 24.885678 -193.043866) (xy 24.886158 -193.084958) (xy 24.886158 -193.085212)
			(xy 24.885905 -193.107564) (xy 25.938241 -193.107564) (xy 25.942179 -193.053756) (xy 25.953909 -193.001095)
			(xy 25.973183 -192.950704) (xy 25.999588 -192.903655) (xy 26.032561 -192.860953) (xy 26.071401 -192.823506)
			(xy 26.11528 -192.792114) (xy 26.163261 -192.767445) (xy 26.214323 -192.750025) (xy 26.267377 -192.740225)
			(xy 26.321293 -192.738255) (xy 26.374921 -192.744156) (xy 26.427118 -192.757802) (xy 26.476772 -192.778903)
			(xy 26.522825 -192.807008) (xy 26.564295 -192.84152) (xy 26.600298 -192.881701) (xy 26.630067 -192.926697)
			(xy 26.652967 -192.975547) (xy 26.66851 -193.027211) (xy 26.676366 -193.080588) (xy 26.676858 -193.107564)
			(xy 26.676366 -193.13454) (xy 26.66851 -193.187917) (xy 26.652967 -193.239581) (xy 26.630067 -193.288431)
			(xy 26.600298 -193.333427) (xy 26.564295 -193.373608) (xy 26.522825 -193.40812) (xy 26.476772 -193.436225)
			(xy 26.427118 -193.457326) (xy 26.374921 -193.470972) (xy 26.321293 -193.476873) (xy 26.267377 -193.474903)
			(xy 26.214323 -193.465103) (xy 26.163261 -193.447683) (xy 26.11528 -193.423014) (xy 26.071401 -193.391622)
			(xy 26.032561 -193.354175) (xy 25.999588 -193.311473) (xy 25.973183 -193.264424) (xy 25.953909 -193.214033)
			(xy 25.942179 -193.161372) (xy 25.938241 -193.107564) (xy 24.885905 -193.107564) (xy 24.885703 -193.125457)
			(xy 24.878327 -193.205607) (xy 24.863638 -193.284744) (xy 24.84176 -193.362203) (xy 24.812876 -193.437331)
			(xy 24.777231 -193.509497) (xy 24.735123 -193.578093) (xy 24.686907 -193.642542) (xy 24.632989 -193.702303)
			(xy 24.573822 -193.756871) (xy 24.509903 -193.805789) (xy 24.441772 -193.848645) (xy 24.406098 -193.867278)
			(xy 24.40559 -193.867532) (xy 24.399494 -193.870834) (xy 24.394668 -193.875152) (xy 24.39205 -193.877587)
			(xy 24.387461 -193.883069) (xy 24.385524 -193.886074) (xy 24.365458 -193.918332) (xy 24.365458 -193.933064)
			(xy 24.365458 -193.93535) (xy 24.364899 -193.964189) (xy 24.3598 -193.996564) (xy 27.726909 -193.996564)
			(xy 27.730847 -193.942756) (xy 27.742577 -193.890095) (xy 27.761851 -193.839704) (xy 27.788256 -193.792655)
			(xy 27.821229 -193.749953) (xy 27.860069 -193.712506) (xy 27.903948 -193.681114) (xy 27.951929 -193.656445)
			(xy 28.002991 -193.639025) (xy 28.056045 -193.629225) (xy 28.109961 -193.627255) (xy 28.163589 -193.633156)
			(xy 28.215786 -193.646802) (xy 28.26544 -193.667903) (xy 28.311493 -193.696008) (xy 28.352963 -193.73052)
			(xy 28.388966 -193.770701) (xy 28.418735 -193.815697) (xy 28.441635 -193.864547) (xy 28.457178 -193.916211)
			(xy 28.465034 -193.969588) (xy 28.465526 -193.996564) (xy 28.465034 -194.02354) (xy 28.457178 -194.076917)
			(xy 28.441635 -194.128581) (xy 28.418735 -194.177431) (xy 28.388966 -194.222427) (xy 28.352963 -194.262608)
			(xy 28.311493 -194.29712) (xy 28.26544 -194.325225) (xy 28.215786 -194.346326) (xy 28.163589 -194.359972)
			(xy 28.109961 -194.365873) (xy 28.056045 -194.363903) (xy 28.002991 -194.354103) (xy 27.951929 -194.336683)
			(xy 27.903948 -194.312014) (xy 27.860069 -194.280622) (xy 27.821229 -194.243175) (xy 27.788256 -194.200473)
			(xy 27.761851 -194.153424) (xy 27.742577 -194.103033) (xy 27.730847 -194.050372) (xy 27.726909 -193.996564)
			(xy 24.3598 -193.996564) (xy 24.355926 -194.021164) (xy 24.338206 -194.076052) (xy 24.312169 -194.127519)
			(xy 24.278448 -194.174313) (xy 24.237864 -194.215296) (xy 24.191402 -194.249473) (xy 24.166068 -194.263264)
			(xy 24.159718 -194.266312) (xy 24.149304 -194.276218) (xy 24.145748 -194.282314) (xy 24.142317 -194.288369)
			(xy 24.138586 -194.301773) (xy 24.138382 -194.30873) (xy 24.139144 -194.395344) (xy 24.139681 -194.405089)
			(xy 24.147129 -194.423109) (xy 24.153622 -194.430396) (xy 24.153876 -194.43065) (xy 24.16683 -194.443604)
			(xy 24.173688 -194.44716) (xy 24.196477 -194.459608) (xy 24.238767 -194.48974) (xy 24.276584 -194.525326)
			(xy 24.30923 -194.565708) (xy 24.336102 -194.610141) (xy 24.356704 -194.657806) (xy 24.370657 -194.707824)
			(xy 24.377703 -194.759271) (xy 24.378158 -194.785234) (xy 24.377672 -194.812503) (xy 24.36991 -194.866487)
			(xy 24.364309 -194.885564) (xy 25.938241 -194.885564) (xy 25.942179 -194.831756) (xy 25.953909 -194.779095)
			(xy 25.973183 -194.728704) (xy 25.999588 -194.681655) (xy 26.032561 -194.638953) (xy 26.071401 -194.601506)
			(xy 26.11528 -194.570114) (xy 26.163261 -194.545445) (xy 26.214323 -194.528025) (xy 26.267377 -194.518225)
			(xy 26.321293 -194.516255) (xy 26.374921 -194.522156) (xy 26.427118 -194.535802) (xy 26.476772 -194.556903)
			(xy 26.522825 -194.585008) (xy 26.564295 -194.61952) (xy 26.600298 -194.659701) (xy 26.630067 -194.704697)
			(xy 26.652967 -194.753547) (xy 26.66851 -194.805211) (xy 26.676366 -194.858588) (xy 26.676858 -194.885564)
			(xy 26.676366 -194.91254) (xy 26.675327 -194.9196) (xy 27.714192 -194.9196) (xy 27.718265 -194.863941)
			(xy 27.7304 -194.809468) (xy 27.750336 -194.757342) (xy 27.77765 -194.708674) (xy 27.811758 -194.664502)
			(xy 27.851935 -194.625767) (xy 27.897323 -194.593295) (xy 27.946955 -194.567777) (xy 27.999775 -194.549758)
			(xy 28.054654 -194.539621) (xy 28.110425 -194.537583) (xy 28.165899 -194.543686) (xy 28.219892 -194.557802)
			(xy 28.271255 -194.579629) (xy 28.318893 -194.608702) (xy 28.361789 -194.644401) (xy 28.399031 -194.685965)
			(xy 28.429825 -194.732509) (xy 28.453513 -194.78304) (xy 28.469591 -194.836482) (xy 28.477717 -194.891696)
			(xy 28.478226 -194.9196) (xy 28.477717 -194.947504) (xy 28.469591 -195.002718) (xy 28.453513 -195.05616)
			(xy 28.429825 -195.106691) (xy 28.399031 -195.153235) (xy 28.361789 -195.194799) (xy 28.318893 -195.230498)
			(xy 28.271255 -195.259571) (xy 28.219892 -195.281398) (xy 28.165899 -195.295514) (xy 28.110425 -195.301617)
			(xy 28.054654 -195.299579) (xy 27.999775 -195.289442) (xy 27.946955 -195.271423) (xy 27.897323 -195.245905)
			(xy 27.851935 -195.213433) (xy 27.811758 -195.174698) (xy 27.77765 -195.130526) (xy 27.750336 -195.081858)
			(xy 27.7304 -195.029732) (xy 27.718265 -194.975259) (xy 27.714192 -194.9196) (xy 26.675327 -194.9196)
			(xy 26.66851 -194.965917) (xy 26.652967 -195.017581) (xy 26.630067 -195.066431) (xy 26.600298 -195.111427)
			(xy 26.564295 -195.151608) (xy 26.522825 -195.18612) (xy 26.476772 -195.214225) (xy 26.427118 -195.235326)
			(xy 26.374921 -195.248972) (xy 26.321293 -195.254873) (xy 26.267377 -195.252903) (xy 26.214323 -195.243103)
			(xy 26.163261 -195.225683) (xy 26.11528 -195.201014) (xy 26.071401 -195.169622) (xy 26.032561 -195.132175)
			(xy 25.999588 -195.089473) (xy 25.973183 -195.042424) (xy 25.953909 -194.992033) (xy 25.942179 -194.939372)
			(xy 25.938241 -194.885564) (xy 24.364309 -194.885564) (xy 24.354545 -194.918817) (xy 24.331888 -194.968427)
			(xy 24.302402 -195.014308) (xy 24.266687 -195.055525) (xy 24.22547 -195.09124) (xy 24.179589 -195.120726)
			(xy 24.129979 -195.143383) (xy 24.077649 -195.158748) (xy 24.023665 -195.16651) (xy 23.969127 -195.16651)
			(xy 23.915143 -195.158748) (xy 23.862813 -195.143383) (xy 23.813203 -195.120726) (xy 23.767322 -195.09124)
			(xy 23.726105 -195.055525) (xy 23.69039 -195.014308) (xy 23.660904 -194.968427) (xy 23.638247 -194.918817)
			(xy 23.622882 -194.866487) (xy 23.61512 -194.812503) (xy 23.614634 -194.785234) (xy 23.615068 -194.759291)
			(xy 23.622094 -194.707884) (xy 23.636022 -194.657902) (xy 23.656594 -194.61027) (xy 23.683431 -194.565864)
			(xy 23.716037 -194.525504) (xy 23.753812 -194.489935) (xy 23.796059 -194.459813) (xy 23.81885 -194.447414)
			(xy 23.825708 -194.443858) (xy 23.838916 -194.43065) (xy 23.845535 -194.423349) (xy 23.853128 -194.405184)
			(xy 23.853648 -194.395344) (xy 23.85441 -194.30873) (xy 23.854025 -194.299398) (xy 23.847425 -194.281942)
			(xy 23.835043 -194.267979) (xy 23.826978 -194.263264) (xy 23.801595 -194.249528) (xy 23.755065 -194.215386)
			(xy 23.714418 -194.174416) (xy 23.680645 -194.127618) (xy 23.654569 -194.076133) (xy 23.636826 -194.021216)
			(xy 23.627849 -193.964206) (xy 23.627334 -193.93535) (xy 23.627588 -193.923158) (xy 23.627588 -193.922396)
			(xy 23.627588 -193.918586) (xy 23.627334 -193.912998) (xy 23.626565 -193.907203) (xy 23.622722 -193.896166)
			(xy 23.619714 -193.891154) (xy 23.612348 -193.879724) (xy 23.608792 -193.873628) (xy 23.589742 -193.855594)
			(xy 23.5839 -193.852546) (xy 23.564926 -193.8418) (xy 23.527952 -193.818676) (xy 23.509986 -193.806318)
			(xy 23.50389 -193.802254) (xy 23.478998 -193.793872) (xy 23.457408 -193.795904) (xy 23.447756 -193.801492)
			(xy 23.35784 -193.853054) (xy 23.344124 -193.879216) (xy 23.345394 -193.893948) (xy 23.347172 -193.93535)
			(xy 23.346698 -193.96624) (xy 23.339021 -194.027542) (xy 23.323794 -194.087417) (xy 23.30125 -194.144938)
			(xy 23.27174 -194.199215) (xy 23.23572 -194.249409) (xy 23.215092 -194.272408) (xy 23.21179 -194.275964)
			(xy 23.206202 -194.284854) (xy 23.202138 -194.291204) (xy 23.198074 -194.305682) (xy 23.200106 -194.382644)
			(xy 23.200355 -194.387619) (xy 23.202534 -194.397339) (xy 23.204424 -194.401948) (xy 23.208488 -194.411092)
			(xy 23.2156 -194.41795) (xy 23.216616 -194.418966) (xy 23.21687 -194.41922) (xy 23.241007 -194.443259)
			(xy 23.283286 -194.496675) (xy 23.318051 -194.555258) (xy 23.344681 -194.617961) (xy 23.362697 -194.683658)
			(xy 23.371778 -194.751173) (xy 23.372318 -194.785234) (xy 23.371807 -194.817974) (xy 23.363398 -194.882911)
			(xy 23.346723 -194.946231) (xy 23.322058 -195.006888) (xy 23.289811 -195.063876) (xy 23.250515 -195.116254)
			(xy 23.228046 -195.140072) (xy 23.220934 -195.147184) (xy 23.213568 -195.165472) (xy 23.213568 -195.255134)
			(xy 23.220934 -195.273422) (xy 23.228046 -195.280534) (xy 23.250529 -195.30434) (xy 23.289825 -195.35672)
			(xy 23.322073 -195.413711) (xy 23.346738 -195.474369) (xy 23.363413 -195.537692) (xy 23.371822 -195.602631)
			(xy 23.372318 -195.635372) (xy 23.372318 -195.636134) (xy 23.371863 -195.665363) (xy 23.365076 -195.723426)
			(xy 23.351688 -195.780331) (xy 23.331873 -195.835329) (xy 23.319232 -195.861686) (xy 23.319232 -195.86194)
			(xy 23.315757 -195.869771) (xy 23.313689 -195.886767) (xy 23.31731 -195.903501) (xy 23.321518 -195.910962)
			(xy 23.349712 -195.956174) (xy 23.350474 -195.957444) (xy 23.364444 -195.98132) (xy 23.369193 -195.988821)
			(xy 23.38282 -196.000185) (xy 23.399513 -196.006198) (xy 23.408386 -196.006466) (xy 27.58059 -196.006466)
			(xy 27.596107 -196.005874) (xy 27.625693 -195.99649) (xy 27.651108 -195.978674) (xy 27.670018 -195.954062)
			(xy 27.680686 -195.924915) (xy 27.681936 -195.909438) (xy 27.683705 -195.881764) (xy 27.694241 -195.827323)
			(xy 27.712544 -195.77498) (xy 27.73823 -195.725836) (xy 27.770757 -195.680927) (xy 27.80944 -195.641197)
			(xy 27.853466 -195.607484) (xy 27.901907 -195.580497) (xy 27.953744 -195.560804) (xy 28.007885 -195.54882)
			(xy 28.06319 -195.544797) (xy 28.118495 -195.54882) (xy 28.172636 -195.560804) (xy 28.224473 -195.580497)
			(xy 28.272914 -195.607484) (xy 28.31694 -195.641197) (xy 28.355623 -195.680927) (xy 28.38815 -195.725836)
			(xy 28.413836 -195.77498) (xy 28.432139 -195.827323) (xy 28.442675 -195.881764) (xy 28.444444 -195.909438)
			(xy 28.445677 -195.924932) (xy 28.456298 -195.954126) (xy 28.4752 -195.97878) (xy 28.500637 -195.996615)
			(xy 28.530257 -196.005982) (xy 28.54579 -196.006466) (xy 29.87548 -196.006466) (xy 29.898594 -195.993766)
			(xy 29.905452 -195.98259) (xy 29.944568 -195.920106) (xy 29.94914 -195.911216) (xy 29.952188 -195.898008)
			(xy 29.952442 -195.893182) (xy 29.952442 -195.86194) (xy 29.947616 -195.85178) (xy 29.932441 -195.817872)
			(xy 29.910978 -195.746756) (xy 29.900077 -195.673275) (xy 29.899356 -195.636134) (xy 29.899356 -195.635372)
			(xy 29.899866 -195.602633) (xy 29.908276 -195.537696) (xy 29.924952 -195.474377) (xy 29.94962 -195.413722)
			(xy 29.98187 -195.356736) (xy 30.021169 -195.304361) (xy 30.043628 -195.280534) (xy 30.05074 -195.273422)
			(xy 30.058106 -195.255134) (xy 30.058106 -195.165472) (xy 30.05074 -195.147184) (xy 30.043628 -195.140072)
			(xy 30.021146 -195.116266) (xy 29.981851 -195.063885) (xy 29.949604 -195.006894) (xy 29.92494 -194.946236)
			(xy 29.908265 -194.882914) (xy 29.899856 -194.817975) (xy 29.899356 -194.785234) (xy 29.899874 -194.752314)
			(xy 29.90837 -194.687025) (xy 29.925224 -194.62338) (xy 29.950155 -194.562443) (xy 29.982743 -194.505235)
			(xy 30.022446 -194.452713) (xy 30.045152 -194.428872) (xy 30.052264 -194.42176) (xy 30.05963 -194.403472)
			(xy 30.059376 -194.321938) (xy 30.058863 -194.312037) (xy 30.05129 -194.293734) (xy 30.044644 -194.286378)
			(xy 30.04439 -194.286124) (xy 30.021782 -194.262798) (xy 29.982236 -194.211261) (xy 29.949757 -194.155002)
			(xy 29.9249 -194.094985) (xy 29.90809 -194.032236) (xy 29.899616 -193.967831) (xy 29.899102 -193.93535)
			(xy 29.899607 -193.902867) (xy 29.908081 -193.838455) (xy 29.924889 -193.775701) (xy 29.949745 -193.715677)
			(xy 29.982223 -193.659412) (xy 30.021768 -193.607867) (xy 30.067702 -193.561925) (xy 30.11924 -193.522371)
			(xy 30.1755 -193.489883) (xy 30.235519 -193.465017) (xy 30.298271 -193.448197) (xy 30.362681 -193.439713)
			(xy 30.395164 -193.439288) (xy 30.395418 -193.439288) (xy 30.427376 -193.439787) (xy 30.490763 -193.447999)
			(xy 30.55257 -193.464287) (xy 30.582362 -193.475864) (xy 30.596078 -193.481452) (xy 30.62478 -193.476372)
			(xy 30.714188 -193.394076) (xy 30.721808 -193.365628) (xy 30.717236 -193.351404) (xy 30.704723 -193.310462)
			(xy 30.686784 -193.226746) (xy 30.681422 -193.184272) (xy 30.680152 -193.173604) (xy 30.669738 -193.15557)
			(xy 30.592776 -193.098928) (xy 30.572456 -193.094356) (xy 30.561788 -193.096388) (xy 30.520541 -193.103886)
			(xy 30.437084 -193.111903) (xy 30.395164 -193.11239) (xy 30.352103 -193.11186) (xy 30.266397 -193.103416)
			(xy 30.181931 -193.086612) (xy 30.099518 -193.06161) (xy 30.019953 -193.02865) (xy 29.944002 -192.988052)
			(xy 29.872395 -192.940204) (xy 29.805823 -192.885569) (xy 29.744926 -192.824671) (xy 29.690291 -192.758099)
			(xy 29.642444 -192.686491) (xy 29.601846 -192.61054) (xy 29.568888 -192.530974) (xy 29.543887 -192.448561)
			(xy 29.527083 -192.364095) (xy 29.518639 -192.278389) (xy 29.518102 -192.235328) (xy 29.518629 -192.192265)
			(xy 29.527068 -192.106554) (xy 29.543867 -192.022082) (xy 29.568865 -191.939664) (xy 29.601822 -191.860093)
			(xy 29.642418 -191.784136) (xy 29.690265 -191.712523) (xy 29.7449 -191.645945) (xy 29.805798 -191.585043)
			(xy 29.872372 -191.530403) (xy 29.943981 -191.482551) (xy 30.019936 -191.441949) (xy 30.099504 -191.408987)
			(xy 30.18192 -191.383983) (xy 30.26639 -191.367177) (xy 30.352101 -191.358732) (xy 30.395164 -191.358266)
			(xy 30.43558 -191.358744) (xy 30.516067 -191.366209) (xy 30.595526 -191.381041) (xy 30.673286 -191.403116)
			(xy 30.748687 -191.432246) (xy 30.82109 -191.468185) (xy 30.889883 -191.510628) (xy 30.922468 -191.534542)
			(xy 30.935422 -191.544194) (xy 30.942534 -191.549782) (xy 30.953202 -191.553592) (xy 30.958028 -191.55537)
			(xy 30.966264 -191.557759) (xy 30.983401 -191.557512) (xy 30.991556 -191.554862) (xy 31.005526 -191.549782)
			(xy 31.012638 -191.544194) (xy 31.025592 -191.534542) (xy 31.058163 -191.510605) (xy 31.126948 -191.468143)
			(xy 31.19935 -191.432193) (xy 31.274754 -191.403059) (xy 31.352519 -191.38099) (xy 31.431985 -191.366172)
			(xy 31.512478 -191.358731) (xy 31.552896 -191.358266) (xy 31.595958 -191.358777) (xy 31.681667 -191.367218)
			(xy 31.766136 -191.38402) (xy 31.848551 -191.409021) (xy 31.928118 -191.441979) (xy 32.004072 -191.482578)
			(xy 32.075681 -191.530426) (xy 32.142255 -191.585064) (xy 32.203153 -191.645963) (xy 32.257788 -191.712538)
			(xy 32.305634 -191.784148) (xy 32.346231 -191.860103) (xy 32.379187 -191.939672) (xy 32.404186 -192.022088)
			(xy 32.420985 -192.106557) (xy 32.429424 -192.192266) (xy 32.42975 -192.218564) (xy 33.443941 -192.218564)
			(xy 33.447879 -192.164756) (xy 33.459609 -192.112095) (xy 33.478883 -192.061704) (xy 33.505288 -192.014655)
			(xy 33.538261 -191.971953) (xy 33.577101 -191.934506) (xy 33.62098 -191.903114) (xy 33.668961 -191.878445)
			(xy 33.720023 -191.861025) (xy 33.773077 -191.851225) (xy 33.826993 -191.849255) (xy 33.880621 -191.855156)
			(xy 33.932818 -191.868802) (xy 33.982472 -191.889903) (xy 34.028525 -191.918008) (xy 34.069995 -191.95252)
			(xy 34.105998 -191.992701) (xy 34.135767 -192.037697) (xy 34.158667 -192.086547) (xy 34.17421 -192.138211)
			(xy 34.182066 -192.191588) (xy 34.182558 -192.218564) (xy 35.270709 -192.218564) (xy 35.274647 -192.164756)
			(xy 35.286377 -192.112095) (xy 35.305651 -192.061704) (xy 35.332056 -192.014655) (xy 35.365029 -191.971953)
			(xy 35.403869 -191.934506) (xy 35.447748 -191.903114) (xy 35.495729 -191.878445) (xy 35.546791 -191.861025)
			(xy 35.599845 -191.851225) (xy 35.653761 -191.849255) (xy 35.707389 -191.855156) (xy 35.759586 -191.868802)
			(xy 35.80924 -191.889903) (xy 35.855293 -191.918008) (xy 35.896763 -191.95252) (xy 35.932766 -191.992701)
			(xy 35.962535 -192.037697) (xy 35.985435 -192.086547) (xy 36.000978 -192.138211) (xy 36.008834 -192.191588)
			(xy 36.009326 -192.218564) (xy 36.008834 -192.24554) (xy 36.000978 -192.298917) (xy 35.985435 -192.350581)
			(xy 35.962535 -192.399431) (xy 35.932766 -192.444427) (xy 35.896763 -192.484608) (xy 35.855293 -192.51912)
			(xy 35.80924 -192.547225) (xy 35.759586 -192.568326) (xy 35.707389 -192.581972) (xy 35.653761 -192.587873)
			(xy 35.599845 -192.585903) (xy 35.546791 -192.576103) (xy 35.495729 -192.558683) (xy 35.447748 -192.534014)
			(xy 35.403869 -192.502622) (xy 35.365029 -192.465175) (xy 35.332056 -192.422473) (xy 35.305651 -192.375424)
			(xy 35.286377 -192.325033) (xy 35.274647 -192.272372) (xy 35.270709 -192.218564) (xy 34.182558 -192.218564)
			(xy 34.182066 -192.24554) (xy 34.17421 -192.298917) (xy 34.158667 -192.350581) (xy 34.135767 -192.399431)
			(xy 34.105998 -192.444427) (xy 34.069995 -192.484608) (xy 34.028525 -192.51912) (xy 33.982472 -192.547225)
			(xy 33.932818 -192.568326) (xy 33.880621 -192.581972) (xy 33.826993 -192.587873) (xy 33.773077 -192.585903)
			(xy 33.720023 -192.576103) (xy 33.668961 -192.558683) (xy 33.62098 -192.534014) (xy 33.577101 -192.502622)
			(xy 33.538261 -192.465175) (xy 33.505288 -192.422473) (xy 33.478883 -192.375424) (xy 33.459609 -192.325033)
			(xy 33.447879 -192.272372) (xy 33.443941 -192.218564) (xy 32.42975 -192.218564) (xy 32.429958 -192.235328)
			(xy 32.429958 -192.235582) (xy 32.429479 -192.276675) (xy 32.421791 -192.3585) (xy 32.406481 -192.439246)
			(xy 32.383684 -192.518206) (xy 32.353599 -192.594687) (xy 32.33547 -192.631568) (xy 32.332676 -192.636902)
			(xy 32.329882 -192.648332) (xy 32.328626 -192.654237) (xy 32.328619 -192.666305) (xy 32.329882 -192.672208)
			(xy 32.332676 -192.683638) (xy 32.33547 -192.688972) (xy 32.353594 -192.725855) (xy 32.383678 -192.802336)
			(xy 32.406475 -192.881295) (xy 32.421787 -192.962041) (xy 32.429478 -193.043866) (xy 32.429958 -193.084958)
			(xy 32.429958 -193.085212) (xy 32.429705 -193.107564) (xy 33.443941 -193.107564) (xy 33.447879 -193.053756)
			(xy 33.459609 -193.001095) (xy 33.478883 -192.950704) (xy 33.505288 -192.903655) (xy 33.538261 -192.860953)
			(xy 33.577101 -192.823506) (xy 33.62098 -192.792114) (xy 33.668961 -192.767445) (xy 33.720023 -192.750025)
			(xy 33.773077 -192.740225) (xy 33.826993 -192.738255) (xy 33.880621 -192.744156) (xy 33.932818 -192.757802)
			(xy 33.982472 -192.778903) (xy 34.028525 -192.807008) (xy 34.069995 -192.84152) (xy 34.105998 -192.881701)
			(xy 34.135767 -192.926697) (xy 34.158667 -192.975547) (xy 34.17421 -193.027211) (xy 34.182066 -193.080588)
			(xy 34.182558 -193.107564) (xy 34.182066 -193.13454) (xy 34.17421 -193.187917) (xy 34.158667 -193.239581)
			(xy 34.135767 -193.288431) (xy 34.105998 -193.333427) (xy 34.069995 -193.373608) (xy 34.028525 -193.40812)
			(xy 33.982472 -193.436225) (xy 33.932818 -193.457326) (xy 33.880621 -193.470972) (xy 33.826993 -193.476873)
			(xy 33.773077 -193.474903) (xy 33.720023 -193.465103) (xy 33.668961 -193.447683) (xy 33.62098 -193.423014)
			(xy 33.577101 -193.391622) (xy 33.538261 -193.354175) (xy 33.505288 -193.311473) (xy 33.478883 -193.264424)
			(xy 33.459609 -193.214033) (xy 33.447879 -193.161372) (xy 33.443941 -193.107564) (xy 32.429705 -193.107564)
			(xy 32.429503 -193.125457) (xy 32.422127 -193.205607) (xy 32.407438 -193.284744) (xy 32.38556 -193.362203)
			(xy 32.356676 -193.437331) (xy 32.321031 -193.509497) (xy 32.278923 -193.578093) (xy 32.230707 -193.642542)
			(xy 32.176789 -193.702303) (xy 32.117622 -193.756871) (xy 32.053703 -193.805789) (xy 31.985572 -193.848645)
			(xy 31.949898 -193.867278) (xy 31.94939 -193.867532) (xy 31.943294 -193.870834) (xy 31.938468 -193.875152)
			(xy 31.93585 -193.877587) (xy 31.931261 -193.883069) (xy 31.929324 -193.886074) (xy 31.909258 -193.918332)
			(xy 31.909258 -193.933064) (xy 31.909258 -193.93535) (xy 31.908699 -193.964189) (xy 31.9036 -193.996564)
			(xy 35.270709 -193.996564) (xy 35.274647 -193.942756) (xy 35.286377 -193.890095) (xy 35.305651 -193.839704)
			(xy 35.332056 -193.792655) (xy 35.365029 -193.749953) (xy 35.403869 -193.712506) (xy 35.447748 -193.681114)
			(xy 35.495729 -193.656445) (xy 35.546791 -193.639025) (xy 35.599845 -193.629225) (xy 35.653761 -193.627255)
			(xy 35.707389 -193.633156) (xy 35.759586 -193.646802) (xy 35.80924 -193.667903) (xy 35.855293 -193.696008)
			(xy 35.896763 -193.73052) (xy 35.932766 -193.770701) (xy 35.962535 -193.815697) (xy 35.985435 -193.864547)
			(xy 36.000978 -193.916211) (xy 36.008834 -193.969588) (xy 36.009326 -193.996564) (xy 36.008834 -194.02354)
			(xy 36.000978 -194.076917) (xy 35.985435 -194.128581) (xy 35.962535 -194.177431) (xy 35.932766 -194.222427)
			(xy 35.896763 -194.262608) (xy 35.855293 -194.29712) (xy 35.80924 -194.325225) (xy 35.759586 -194.346326)
			(xy 35.707389 -194.359972) (xy 35.653761 -194.365873) (xy 35.599845 -194.363903) (xy 35.546791 -194.354103)
			(xy 35.495729 -194.336683) (xy 35.447748 -194.312014) (xy 35.403869 -194.280622) (xy 35.365029 -194.243175)
			(xy 35.332056 -194.200473) (xy 35.305651 -194.153424) (xy 35.286377 -194.103033) (xy 35.274647 -194.050372)
			(xy 35.270709 -193.996564) (xy 31.9036 -193.996564) (xy 31.899726 -194.021164) (xy 31.882006 -194.076052)
			(xy 31.855969 -194.127519) (xy 31.822248 -194.174313) (xy 31.781664 -194.215296) (xy 31.735202 -194.249473)
			(xy 31.709868 -194.263264) (xy 31.703518 -194.266312) (xy 31.693104 -194.276218) (xy 31.689548 -194.282314)
			(xy 31.686117 -194.288369) (xy 31.682386 -194.301773) (xy 31.682182 -194.30873) (xy 31.682944 -194.395344)
			(xy 31.683481 -194.405089) (xy 31.690929 -194.423109) (xy 31.697422 -194.430396) (xy 31.697676 -194.43065)
			(xy 31.71063 -194.443604) (xy 31.717488 -194.44716) (xy 31.740277 -194.459608) (xy 31.782567 -194.48974)
			(xy 31.820384 -194.525326) (xy 31.85303 -194.565708) (xy 31.879902 -194.610141) (xy 31.900504 -194.657806)
			(xy 31.914457 -194.707824) (xy 31.921503 -194.759271) (xy 31.921958 -194.785234) (xy 31.921472 -194.812503)
			(xy 31.91371 -194.866487) (xy 31.908109 -194.885564) (xy 33.443941 -194.885564) (xy 33.447879 -194.831756)
			(xy 33.459609 -194.779095) (xy 33.478883 -194.728704) (xy 33.505288 -194.681655) (xy 33.538261 -194.638953)
			(xy 33.577101 -194.601506) (xy 33.62098 -194.570114) (xy 33.668961 -194.545445) (xy 33.720023 -194.528025)
			(xy 33.773077 -194.518225) (xy 33.826993 -194.516255) (xy 33.880621 -194.522156) (xy 33.932818 -194.535802)
			(xy 33.982472 -194.556903) (xy 34.028525 -194.585008) (xy 34.069995 -194.61952) (xy 34.105998 -194.659701)
			(xy 34.135767 -194.704697) (xy 34.158667 -194.753547) (xy 34.17421 -194.805211) (xy 34.182066 -194.858588)
			(xy 34.182558 -194.885564) (xy 34.182066 -194.91254) (xy 34.181027 -194.9196) (xy 35.258246 -194.9196)
			(xy 35.262319 -194.863941) (xy 35.274454 -194.809468) (xy 35.29439 -194.757342) (xy 35.321704 -194.708674)
			(xy 35.355812 -194.664502) (xy 35.395989 -194.625767) (xy 35.441377 -194.593295) (xy 35.491009 -194.567777)
			(xy 35.543829 -194.549758) (xy 35.598708 -194.539621) (xy 35.654479 -194.537583) (xy 35.709953 -194.543686)
			(xy 35.763946 -194.557802) (xy 35.815309 -194.579629) (xy 35.862947 -194.608702) (xy 35.905843 -194.644401)
			(xy 35.943085 -194.685965) (xy 35.973879 -194.732509) (xy 35.997567 -194.78304) (xy 36.013645 -194.836482)
			(xy 36.021771 -194.891696) (xy 36.02228 -194.9196) (xy 36.021771 -194.947504) (xy 36.013645 -195.002718)
			(xy 35.997567 -195.05616) (xy 35.973879 -195.106691) (xy 35.943085 -195.153235) (xy 35.905843 -195.194799)
			(xy 35.862947 -195.230498) (xy 35.815309 -195.259571) (xy 35.763946 -195.281398) (xy 35.709953 -195.295514)
			(xy 35.654479 -195.301617) (xy 35.598708 -195.299579) (xy 35.543829 -195.289442) (xy 35.491009 -195.271423)
			(xy 35.441377 -195.245905) (xy 35.395989 -195.213433) (xy 35.355812 -195.174698) (xy 35.321704 -195.130526)
			(xy 35.29439 -195.081858) (xy 35.274454 -195.029732) (xy 35.262319 -194.975259) (xy 35.258246 -194.9196)
			(xy 34.181027 -194.9196) (xy 34.17421 -194.965917) (xy 34.158667 -195.017581) (xy 34.135767 -195.066431)
			(xy 34.105998 -195.111427) (xy 34.069995 -195.151608) (xy 34.028525 -195.18612) (xy 33.982472 -195.214225)
			(xy 33.932818 -195.235326) (xy 33.880621 -195.248972) (xy 33.826993 -195.254873) (xy 33.773077 -195.252903)
			(xy 33.720023 -195.243103) (xy 33.668961 -195.225683) (xy 33.62098 -195.201014) (xy 33.577101 -195.169622)
			(xy 33.538261 -195.132175) (xy 33.505288 -195.089473) (xy 33.478883 -195.042424) (xy 33.459609 -194.992033)
			(xy 33.447879 -194.939372) (xy 33.443941 -194.885564) (xy 31.908109 -194.885564) (xy 31.898345 -194.918817)
			(xy 31.875688 -194.968427) (xy 31.846202 -195.014308) (xy 31.810487 -195.055525) (xy 31.76927 -195.09124)
			(xy 31.723389 -195.120726) (xy 31.673779 -195.143383) (xy 31.621449 -195.158748) (xy 31.567465 -195.16651)
			(xy 31.512927 -195.16651) (xy 31.458943 -195.158748) (xy 31.406613 -195.143383) (xy 31.357003 -195.120726)
			(xy 31.311122 -195.09124) (xy 31.269905 -195.055525) (xy 31.23419 -195.014308) (xy 31.204704 -194.968427)
			(xy 31.182047 -194.918817) (xy 31.166682 -194.866487) (xy 31.15892 -194.812503) (xy 31.158434 -194.785234)
			(xy 31.158868 -194.759291) (xy 31.165894 -194.707884) (xy 31.179822 -194.657902) (xy 31.200394 -194.61027)
			(xy 31.227231 -194.565864) (xy 31.259837 -194.525504) (xy 31.297612 -194.489935) (xy 31.339859 -194.459813)
			(xy 31.36265 -194.447414) (xy 31.369508 -194.443858) (xy 31.382716 -194.43065) (xy 31.389335 -194.423349)
			(xy 31.396928 -194.405184) (xy 31.397448 -194.395344) (xy 31.39821 -194.30873) (xy 31.397825 -194.299398)
			(xy 31.391225 -194.281942) (xy 31.378843 -194.267979) (xy 31.370778 -194.263264) (xy 31.345395 -194.249528)
			(xy 31.298865 -194.215386) (xy 31.258218 -194.174416) (xy 31.224445 -194.127618) (xy 31.198369 -194.076133)
			(xy 31.180626 -194.021216) (xy 31.171649 -193.964206) (xy 31.171134 -193.93535) (xy 31.171388 -193.923158)
			(xy 31.171388 -193.922396) (xy 31.171388 -193.918586) (xy 31.171388 -193.9036) (xy 31.154624 -193.877438)
			(xy 31.14675 -193.86804) (xy 31.133796 -193.855848) (xy 31.128208 -193.852546) (xy 31.109238 -193.841862)
			(xy 31.072264 -193.818863) (xy 31.054294 -193.806572) (xy 31.048452 -193.802508) (xy 31.033466 -193.797428)
			(xy 31.023101 -193.794452) (xy 31.001661 -193.796571) (xy 30.992064 -193.801492) (xy 30.914848 -193.845688)
			(xy 30.906636 -193.850835) (xy 30.89456 -193.865971) (xy 30.889003 -193.88452) (xy 30.889448 -193.894202)
			(xy 30.891226 -193.93535) (xy 30.890752 -193.96624) (xy 30.883075 -194.027542) (xy 30.867846 -194.087416)
			(xy 30.845301 -194.144935) (xy 30.815789 -194.199211) (xy 30.779766 -194.249402) (xy 30.759146 -194.272408)
			(xy 30.755844 -194.275964) (xy 30.750256 -194.284854) (xy 30.746192 -194.291204) (xy 30.742128 -194.305682)
			(xy 30.74416 -194.382644) (xy 30.744408 -194.38762) (xy 30.746586 -194.397339) (xy 30.748478 -194.401948)
			(xy 30.752542 -194.411092) (xy 30.759654 -194.41795) (xy 30.76067 -194.418966) (xy 30.760924 -194.41922)
			(xy 30.785063 -194.443258) (xy 30.827345 -194.496672) (xy 30.862114 -194.555256) (xy 30.888746 -194.617958)
			(xy 30.906764 -194.683656) (xy 30.915846 -194.751172) (xy 30.916372 -194.785234) (xy 30.915861 -194.817973)
			(xy 30.907451 -194.88291) (xy 30.890775 -194.94623) (xy 30.866108 -195.006885) (xy 30.833859 -195.063871)
			(xy 30.794561 -195.116247) (xy 30.7721 -195.140072) (xy 30.764988 -195.147184) (xy 30.757622 -195.165472)
			(xy 30.757622 -195.255134) (xy 30.764988 -195.273422) (xy 30.7721 -195.280534) (xy 30.794581 -195.304341)
			(xy 30.833873 -195.356722) (xy 30.866117 -195.413713) (xy 30.89078 -195.474372) (xy 30.907453 -195.537694)
			(xy 30.915861 -195.602632) (xy 30.916372 -195.635372) (xy 30.916372 -195.636134) (xy 30.915917 -195.665362)
			(xy 30.90913 -195.723426) (xy 30.89574 -195.78033) (xy 30.875924 -195.835327) (xy 30.863286 -195.861686)
			(xy 30.863286 -195.86194) (xy 30.859809 -195.86977) (xy 30.857738 -195.886767) (xy 30.861363 -195.903501)
			(xy 30.865572 -195.910962) (xy 30.893766 -195.956174) (xy 30.894528 -195.957444) (xy 30.908498 -195.98132)
			(xy 30.91325 -195.988815) (xy 30.926879 -196.000165) (xy 30.943571 -196.00616) (xy 30.95244 -196.006466)
			(xy 35.157664 -196.006466) (xy 35.171322 -196.005979) (xy 35.197641 -195.99865) (xy 35.22108 -195.984614)
			(xy 35.239965 -195.964872) (xy 35.252947 -195.940834) (xy 35.259101 -195.914216) (xy 35.25901 -195.900548)
			(xy 35.25901 -195.89877) (xy 35.25901 -195.898008) (xy 35.258756 -195.8848) (xy 35.259242 -195.857531)
			(xy 35.267004 -195.803547) (xy 35.282369 -195.751217) (xy 35.305026 -195.701607) (xy 35.334512 -195.655726)
			(xy 35.370227 -195.614509) (xy 35.411444 -195.578794) (xy 35.457325 -195.549308) (xy 35.506935 -195.526651)
			(xy 35.559265 -195.511286) (xy 35.613249 -195.503524) (xy 35.667787 -195.503524) (xy 35.721771 -195.511286)
			(xy 35.774101 -195.526651) (xy 35.823711 -195.549308) (xy 35.869592 -195.578794) (xy 35.910809 -195.614509)
			(xy 35.946524 -195.655726) (xy 35.97601 -195.701607) (xy 35.998667 -195.751217) (xy 36.014032 -195.803547)
			(xy 36.021794 -195.857531) (xy 36.02228 -195.8848) (xy 36.022026 -195.898008) (xy 36.022026 -195.89877)
			(xy 36.022026 -195.900548) (xy 36.021882 -195.914225) (xy 36.028005 -195.94087) (xy 36.040983 -195.964934)
			(xy 36.059885 -195.984689) (xy 36.083353 -195.998715) (xy 36.109702 -196.006008) (xy 36.123372 -196.006466)
			(xy 37.41928 -196.006466) (xy 37.442394 -195.993766) (xy 37.449252 -195.98259) (xy 37.488368 -195.920106)
			(xy 37.49294 -195.911216) (xy 37.495988 -195.898008) (xy 37.496242 -195.893182) (xy 37.496242 -195.86194)
			(xy 37.491416 -195.85178) (xy 37.476241 -195.817872) (xy 37.454778 -195.746756) (xy 37.443877 -195.673275)
			(xy 37.443156 -195.636134) (xy 37.443156 -195.635372) (xy 37.443666 -195.602633) (xy 37.452076 -195.537696)
			(xy 37.468752 -195.474377) (xy 37.49342 -195.413722) (xy 37.52567 -195.356736) (xy 37.564969 -195.304361)
			(xy 37.587428 -195.280534) (xy 37.59454 -195.273422) (xy 37.601906 -195.255134) (xy 37.601906 -195.165472)
			(xy 37.59454 -195.147184) (xy 37.587428 -195.140072) (xy 37.564946 -195.116266) (xy 37.525651 -195.063885)
			(xy 37.493404 -195.006894) (xy 37.46874 -194.946236) (xy 37.452065 -194.882914) (xy 37.443656 -194.817975)
			(xy 37.443156 -194.785234) (xy 37.443674 -194.752314) (xy 37.45217 -194.687025) (xy 37.469024 -194.62338)
			(xy 37.493955 -194.562443) (xy 37.526543 -194.505235) (xy 37.566246 -194.452713) (xy 37.588952 -194.428872)
			(xy 37.596064 -194.42176) (xy 37.60343 -194.403472) (xy 37.603176 -194.321938) (xy 37.602663 -194.312037)
			(xy 37.59509 -194.293734) (xy 37.588444 -194.286378) (xy 37.58819 -194.286124) (xy 37.565582 -194.262798)
			(xy 37.526036 -194.211261) (xy 37.493557 -194.155002) (xy 37.4687 -194.094985) (xy 37.45189 -194.032236)
			(xy 37.443416 -193.967831) (xy 37.442902 -193.93535) (xy 37.443407 -193.902867) (xy 37.451881 -193.838455)
			(xy 37.468689 -193.775701) (xy 37.493545 -193.715677) (xy 37.526023 -193.659412) (xy 37.565568 -193.607867)
			(xy 37.611502 -193.561925) (xy 37.66304 -193.522371) (xy 37.7193 -193.489883) (xy 37.779319 -193.465017)
			(xy 37.842071 -193.448197) (xy 37.906481 -193.439713) (xy 37.938964 -193.439288) (xy 37.939726 -193.439288)
			(xy 37.970957 -193.439775) (xy 38.032923 -193.447649) (xy 38.093408 -193.463244) (xy 38.122606 -193.47434)
			(xy 38.126924 -193.476118) (xy 38.136576 -193.47815) (xy 38.148548 -193.47985) (xy 38.171764 -193.473222)
			(xy 38.181026 -193.46545) (xy 38.258242 -193.394076) (xy 38.265862 -193.365374) (xy 38.26129 -193.351404)
			(xy 38.248778 -193.310462) (xy 38.23084 -193.226746) (xy 38.225476 -193.184272) (xy 38.224206 -193.173858)
			(xy 38.213792 -193.15557) (xy 38.147244 -193.106294) (xy 38.140546 -193.101711) (xy 38.12513 -193.096669)
			(xy 38.117018 -193.096388) (xy 38.105588 -193.096388) (xy 38.101016 -193.09715) (xy 38.060943 -193.10425)
			(xy 37.979912 -193.11188) (xy 37.939218 -193.11239) (xy 37.938964 -193.11239) (xy 37.897207 -193.111909)
			(xy 37.814072 -193.103971) (xy 37.732068 -193.088166) (xy 37.651937 -193.064638) (xy 37.574406 -193.033599)
			(xy 37.500176 -192.995331) (xy 37.42992 -192.950181) (xy 37.364274 -192.898556) (xy 37.303832 -192.840926)
			(xy 37.249142 -192.777811) (xy 37.2007 -192.709783) (xy 37.158943 -192.637458) (xy 37.12425 -192.561492)
			(xy 37.096936 -192.482571) (xy 37.077246 -192.401412) (xy 37.065361 -192.318749) (xy 37.061387 -192.23533)
			(xy 37.065361 -192.151911) (xy 37.077246 -192.069248) (xy 37.096936 -191.988089) (xy 37.12425 -191.909168)
			(xy 37.158943 -191.833202) (xy 37.2007 -191.760877) (xy 37.249142 -191.692849) (xy 37.303832 -191.629734)
			(xy 37.364274 -191.572104) (xy 37.42992 -191.520479) (xy 37.500176 -191.475329) (xy 37.574406 -191.437061)
			(xy 37.651937 -191.406022) (xy 37.732068 -191.382494) (xy 37.814072 -191.366689) (xy 37.897207 -191.358751)
			(xy 37.938964 -191.358266) (xy 37.939218 -191.358266) (xy 37.939472 -191.358266) (xy 37.981172 -191.358759)
			(xy 38.064195 -191.366677) (xy 38.146091 -191.382442) (xy 38.22612 -191.405914) (xy 38.303558 -191.43688)
			(xy 38.377705 -191.475059) (xy 38.447892 -191.520107) (xy 38.481 -191.545464) (xy 38.48735 -191.550544)
			(xy 38.50894 -191.558418) (xy 38.52672 -191.558418) (xy 38.535102 -191.55537) (xy 38.548818 -191.550544)
			(xy 38.555422 -191.545464) (xy 38.588524 -191.520099) (xy 38.658712 -191.475052) (xy 38.732861 -191.436874)
			(xy 38.8103 -191.40591) (xy 38.890329 -191.38244) (xy 38.972226 -191.366676) (xy 39.05525 -191.358761)
			(xy 39.09695 -191.358266) (xy 39.140009 -191.358796) (xy 39.225713 -191.367242) (xy 39.310176 -191.384048)
			(xy 39.392585 -191.409051) (xy 39.472146 -191.442011) (xy 39.548094 -191.482611) (xy 39.619697 -191.530459)
			(xy 39.686265 -191.585095) (xy 39.747157 -191.645993) (xy 39.801787 -191.712566) (xy 39.849629 -191.784173)
			(xy 39.890222 -191.860124) (xy 39.923175 -191.939689) (xy 39.948171 -192.0221) (xy 39.964969 -192.106565)
			(xy 39.973407 -192.192269) (xy 39.973776 -192.218564) (xy 41.026095 -192.218564) (xy 41.030033 -192.164756)
			(xy 41.041763 -192.112095) (xy 41.061037 -192.061704) (xy 41.087442 -192.014655) (xy 41.120415 -191.971953)
			(xy 41.159255 -191.934506) (xy 41.203134 -191.903114) (xy 41.251115 -191.878445) (xy 41.302177 -191.861025)
			(xy 41.355231 -191.851225) (xy 41.409147 -191.849255) (xy 41.462775 -191.855156) (xy 41.514972 -191.868802)
			(xy 41.564626 -191.889903) (xy 41.610679 -191.918008) (xy 41.652149 -191.95252) (xy 41.688152 -191.992701)
			(xy 41.717921 -192.037697) (xy 41.740821 -192.086547) (xy 41.756364 -192.138211) (xy 41.76422 -192.191588)
			(xy 41.764712 -192.218564) (xy 42.814763 -192.218564) (xy 42.818701 -192.164756) (xy 42.830431 -192.112095)
			(xy 42.849705 -192.061704) (xy 42.87611 -192.014655) (xy 42.909083 -191.971953) (xy 42.947923 -191.934506)
			(xy 42.991802 -191.903114) (xy 43.039783 -191.878445) (xy 43.090845 -191.861025) (xy 43.143899 -191.851225)
			(xy 43.197815 -191.849255) (xy 43.251443 -191.855156) (xy 43.30364 -191.868802) (xy 43.353294 -191.889903)
			(xy 43.399347 -191.918008) (xy 43.440817 -191.95252) (xy 43.47682 -191.992701) (xy 43.506589 -192.037697)
			(xy 43.529489 -192.086547) (xy 43.545032 -192.138211) (xy 43.552888 -192.191588) (xy 43.55338 -192.218564)
			(xy 43.552888 -192.24554) (xy 43.545032 -192.298917) (xy 43.529489 -192.350581) (xy 43.506589 -192.399431)
			(xy 43.47682 -192.444427) (xy 43.440817 -192.484608) (xy 43.399347 -192.51912) (xy 43.353294 -192.547225)
			(xy 43.30364 -192.568326) (xy 43.251443 -192.581972) (xy 43.197815 -192.587873) (xy 43.143899 -192.585903)
			(xy 43.090845 -192.576103) (xy 43.039783 -192.558683) (xy 42.991802 -192.534014) (xy 42.947923 -192.502622)
			(xy 42.909083 -192.465175) (xy 42.87611 -192.422473) (xy 42.849705 -192.375424) (xy 42.830431 -192.325033)
			(xy 42.818701 -192.272372) (xy 42.814763 -192.218564) (xy 41.764712 -192.218564) (xy 41.76422 -192.24554)
			(xy 41.756364 -192.298917) (xy 41.740821 -192.350581) (xy 41.717921 -192.399431) (xy 41.688152 -192.444427)
			(xy 41.652149 -192.484608) (xy 41.610679 -192.51912) (xy 41.564626 -192.547225) (xy 41.514972 -192.568326)
			(xy 41.462775 -192.581972) (xy 41.409147 -192.587873) (xy 41.355231 -192.585903) (xy 41.302177 -192.576103)
			(xy 41.251115 -192.558683) (xy 41.203134 -192.534014) (xy 41.159255 -192.502622) (xy 41.120415 -192.465175)
			(xy 41.087442 -192.422473) (xy 41.061037 -192.375424) (xy 41.041763 -192.325033) (xy 41.030033 -192.272372)
			(xy 41.026095 -192.218564) (xy 39.973776 -192.218564) (xy 39.974012 -192.235328) (xy 39.974012 -192.235582)
			(xy 39.973533 -192.276675) (xy 39.965845 -192.3585) (xy 39.950536 -192.439247) (xy 39.92774 -192.518208)
			(xy 39.897657 -192.594689) (xy 39.879524 -192.631568) (xy 39.87673 -192.636902) (xy 39.873936 -192.648332)
			(xy 39.87268 -192.654237) (xy 39.872673 -192.666305) (xy 39.873936 -192.672208) (xy 39.87673 -192.683638)
			(xy 39.879524 -192.688972) (xy 39.897647 -192.725855) (xy 39.927729 -192.802336) (xy 39.950525 -192.881296)
			(xy 39.965836 -192.962042) (xy 39.973527 -193.043866) (xy 39.974012 -193.084958) (xy 39.974012 -193.085212)
			(xy 39.973759 -193.107564) (xy 41.026095 -193.107564) (xy 41.030033 -193.053756) (xy 41.041763 -193.001095)
			(xy 41.061037 -192.950704) (xy 41.087442 -192.903655) (xy 41.120415 -192.860953) (xy 41.159255 -192.823506)
			(xy 41.203134 -192.792114) (xy 41.251115 -192.767445) (xy 41.302177 -192.750025) (xy 41.355231 -192.740225)
			(xy 41.409147 -192.738255) (xy 41.462775 -192.744156) (xy 41.514972 -192.757802) (xy 41.564626 -192.778903)
			(xy 41.610679 -192.807008) (xy 41.652149 -192.84152) (xy 41.688152 -192.881701) (xy 41.717921 -192.926697)
			(xy 41.740821 -192.975547) (xy 41.756364 -193.027211) (xy 41.76422 -193.080588) (xy 41.764712 -193.107564)
			(xy 41.76422 -193.13454) (xy 41.756364 -193.187917) (xy 41.740821 -193.239581) (xy 41.717921 -193.288431)
			(xy 41.688152 -193.333427) (xy 41.652149 -193.373608) (xy 41.610679 -193.40812) (xy 41.564626 -193.436225)
			(xy 41.514972 -193.457326) (xy 41.462775 -193.470972) (xy 41.409147 -193.476873) (xy 41.355231 -193.474903)
			(xy 41.302177 -193.465103) (xy 41.251115 -193.447683) (xy 41.203134 -193.423014) (xy 41.159255 -193.391622)
			(xy 41.120415 -193.354175) (xy 41.087442 -193.311473) (xy 41.061037 -193.264424) (xy 41.041763 -193.214033)
			(xy 41.030033 -193.161372) (xy 41.026095 -193.107564) (xy 39.973759 -193.107564) (xy 39.973557 -193.125457)
			(xy 39.966181 -193.205608) (xy 39.951493 -193.284747) (xy 39.929615 -193.362207) (xy 39.900733 -193.437336)
			(xy 39.865089 -193.509504) (xy 39.822982 -193.578102) (xy 39.774768 -193.642553) (xy 39.720851 -193.702316)
			(xy 39.661686 -193.756888) (xy 39.597769 -193.805809) (xy 39.529639 -193.848669) (xy 39.493952 -193.867278)
			(xy 39.493444 -193.867532) (xy 39.487348 -193.870834) (xy 39.482522 -193.875152) (xy 39.479902 -193.877586)
			(xy 39.475309 -193.883065) (xy 39.473378 -193.886074) (xy 39.453312 -193.918332) (xy 39.453312 -193.933064)
			(xy 39.453312 -193.93535) (xy 39.452753 -193.964188) (xy 39.447653 -193.996564) (xy 42.814763 -193.996564)
			(xy 42.818701 -193.942756) (xy 42.830431 -193.890095) (xy 42.849705 -193.839704) (xy 42.87611 -193.792655)
			(xy 42.909083 -193.749953) (xy 42.947923 -193.712506) (xy 42.991802 -193.681114) (xy 43.039783 -193.656445)
			(xy 43.090845 -193.639025) (xy 43.143899 -193.629225) (xy 43.197815 -193.627255) (xy 43.251443 -193.633156)
			(xy 43.30364 -193.646802) (xy 43.353294 -193.667903) (xy 43.399347 -193.696008) (xy 43.440817 -193.73052)
			(xy 43.47682 -193.770701) (xy 43.506589 -193.815697) (xy 43.529489 -193.864547) (xy 43.545032 -193.916211)
			(xy 43.552888 -193.969588) (xy 43.55338 -193.996564) (xy 43.552888 -194.02354) (xy 43.545032 -194.076917)
			(xy 43.529489 -194.128581) (xy 43.506589 -194.177431) (xy 43.47682 -194.222427) (xy 43.440817 -194.262608)
			(xy 43.399347 -194.29712) (xy 43.353294 -194.325225) (xy 43.30364 -194.346326) (xy 43.251443 -194.359972)
			(xy 43.197815 -194.365873) (xy 43.143899 -194.363903) (xy 43.090845 -194.354103) (xy 43.039783 -194.336683)
			(xy 42.991802 -194.312014) (xy 42.947923 -194.280622) (xy 42.909083 -194.243175) (xy 42.87611 -194.200473)
			(xy 42.849705 -194.153424) (xy 42.830431 -194.103033) (xy 42.818701 -194.050372) (xy 42.814763 -193.996564)
			(xy 39.447653 -193.996564) (xy 39.443779 -194.021162) (xy 39.426057 -194.076048) (xy 39.400019 -194.127512)
			(xy 39.366296 -194.174303) (xy 39.325709 -194.215282) (xy 39.279246 -194.249454) (xy 39.253922 -194.263264)
			(xy 39.247572 -194.266312) (xy 39.237158 -194.276218) (xy 39.233602 -194.282314) (xy 39.230173 -194.28837)
			(xy 39.226446 -194.301773) (xy 39.226236 -194.30873) (xy 39.226998 -194.395344) (xy 39.227534 -194.405089)
			(xy 39.234977 -194.423115) (xy 39.241476 -194.430396) (xy 39.24173 -194.43065) (xy 39.254684 -194.443604)
			(xy 39.261542 -194.44716) (xy 39.284333 -194.459606) (xy 39.326628 -194.489736) (xy 39.36445 -194.52532)
			(xy 39.397099 -194.565701) (xy 39.423975 -194.610135) (xy 39.44458 -194.657801) (xy 39.458535 -194.70782)
			(xy 39.465582 -194.759269) (xy 39.466012 -194.785234) (xy 39.465526 -194.812503) (xy 39.457764 -194.866487)
			(xy 39.452163 -194.885564) (xy 41.026095 -194.885564) (xy 41.030033 -194.831756) (xy 41.041763 -194.779095)
			(xy 41.061037 -194.728704) (xy 41.087442 -194.681655) (xy 41.120415 -194.638953) (xy 41.159255 -194.601506)
			(xy 41.203134 -194.570114) (xy 41.251115 -194.545445) (xy 41.302177 -194.528025) (xy 41.355231 -194.518225)
			(xy 41.409147 -194.516255) (xy 41.462775 -194.522156) (xy 41.514972 -194.535802) (xy 41.564626 -194.556903)
			(xy 41.610679 -194.585008) (xy 41.652149 -194.61952) (xy 41.688152 -194.659701) (xy 41.717921 -194.704697)
			(xy 41.740821 -194.753547) (xy 41.756364 -194.805211) (xy 41.76422 -194.858588) (xy 41.764712 -194.885564)
			(xy 41.76422 -194.91254) (xy 41.756364 -194.965917) (xy 41.749972 -194.987164) (xy 42.794426 -194.987164)
			(xy 42.798499 -194.931505) (xy 42.810634 -194.877032) (xy 42.83057 -194.824906) (xy 42.857884 -194.776238)
			(xy 42.891992 -194.732066) (xy 42.932169 -194.693331) (xy 42.977557 -194.660859) (xy 43.027189 -194.635341)
			(xy 43.080009 -194.617322) (xy 43.134888 -194.607185) (xy 43.190659 -194.605147) (xy 43.246133 -194.61125)
			(xy 43.300126 -194.625366) (xy 43.351489 -194.647193) (xy 43.399127 -194.676266) (xy 43.442023 -194.711965)
			(xy 43.479265 -194.753529) (xy 43.510059 -194.800073) (xy 43.533747 -194.850604) (xy 43.549825 -194.904046)
			(xy 43.557951 -194.95926) (xy 43.55846 -194.987164) (xy 43.557951 -195.015068) (xy 43.549825 -195.070282)
			(xy 43.533747 -195.123724) (xy 43.510059 -195.174255) (xy 43.479265 -195.220799) (xy 43.442023 -195.262363)
			(xy 43.399127 -195.298062) (xy 43.351489 -195.327135) (xy 43.300126 -195.348962) (xy 43.246133 -195.363078)
			(xy 43.190659 -195.369181) (xy 43.134888 -195.367143) (xy 43.080009 -195.357006) (xy 43.027189 -195.338987)
			(xy 42.977557 -195.313469) (xy 42.932169 -195.280997) (xy 42.891992 -195.242262) (xy 42.857884 -195.19809)
			(xy 42.83057 -195.149422) (xy 42.810634 -195.097296) (xy 42.798499 -195.042823) (xy 42.794426 -194.987164)
			(xy 41.749972 -194.987164) (xy 41.740821 -195.017581) (xy 41.717921 -195.066431) (xy 41.688152 -195.111427)
			(xy 41.652149 -195.151608) (xy 41.610679 -195.18612) (xy 41.564626 -195.214225) (xy 41.514972 -195.235326)
			(xy 41.462775 -195.248972) (xy 41.409147 -195.254873) (xy 41.355231 -195.252903) (xy 41.302177 -195.243103)
			(xy 41.251115 -195.225683) (xy 41.203134 -195.201014) (xy 41.159255 -195.169622) (xy 41.120415 -195.132175)
			(xy 41.087442 -195.089473) (xy 41.061037 -195.042424) (xy 41.041763 -194.992033) (xy 41.030033 -194.939372)
			(xy 41.026095 -194.885564) (xy 39.452163 -194.885564) (xy 39.442399 -194.918817) (xy 39.419742 -194.968427)
			(xy 39.390256 -195.014308) (xy 39.354541 -195.055525) (xy 39.313324 -195.09124) (xy 39.267443 -195.120726)
			(xy 39.217833 -195.143383) (xy 39.165503 -195.158748) (xy 39.111519 -195.16651) (xy 39.056981 -195.16651)
			(xy 39.002997 -195.158748) (xy 38.950667 -195.143383) (xy 38.901057 -195.120726) (xy 38.855176 -195.09124)
			(xy 38.813959 -195.055525) (xy 38.778244 -195.014308) (xy 38.748758 -194.968427) (xy 38.726101 -194.918817)
			(xy 38.710736 -194.866487) (xy 38.702974 -194.812503) (xy 38.702488 -194.785234) (xy 38.702922 -194.759292)
			(xy 38.709949 -194.707886) (xy 38.723878 -194.657907) (xy 38.744452 -194.610276) (xy 38.771291 -194.565873)
			(xy 38.8039 -194.525517) (xy 38.841677 -194.489952) (xy 38.883926 -194.459836) (xy 38.906704 -194.447414)
			(xy 38.913562 -194.443858) (xy 38.92677 -194.43065) (xy 38.933384 -194.423347) (xy 38.940968 -194.405182)
			(xy 38.941502 -194.395344) (xy 38.942264 -194.30873) (xy 38.94188 -194.299396) (xy 38.935284 -194.281934)
			(xy 38.922908 -194.267961) (xy 38.914832 -194.263264) (xy 38.889452 -194.249525) (xy 38.842927 -194.215381)
			(xy 38.802285 -194.17441) (xy 38.768516 -194.127612) (xy 38.742444 -194.076127) (xy 38.724703 -194.021212)
			(xy 38.715727 -193.964205) (xy 38.715188 -193.93535) (xy 38.715442 -193.923158) (xy 38.715442 -193.922396)
			(xy 38.715442 -193.918586) (xy 38.715188 -193.912998) (xy 38.71442 -193.907203) (xy 38.710581 -193.896163)
			(xy 38.707568 -193.891154) (xy 38.700202 -193.879724) (xy 38.696646 -193.873628) (xy 38.677596 -193.855594)
			(xy 38.671754 -193.852546) (xy 38.65278 -193.8418) (xy 38.615807 -193.818673) (xy 38.59784 -193.806318)
			(xy 38.591744 -193.802254) (xy 38.566852 -193.793872) (xy 38.545262 -193.795904) (xy 38.53561 -193.801492)
			(xy 38.445694 -193.853054) (xy 38.431978 -193.879216) (xy 38.433248 -193.893948) (xy 38.435026 -193.93535)
			(xy 38.434552 -193.96624) (xy 38.426875 -194.027542) (xy 38.411646 -194.087416) (xy 38.389101 -194.144935)
			(xy 38.359589 -194.199211) (xy 38.323566 -194.249402) (xy 38.302946 -194.272408) (xy 38.299644 -194.275964)
			(xy 38.294056 -194.284854) (xy 38.289992 -194.291204) (xy 38.285928 -194.305682) (xy 38.28796 -194.382644)
			(xy 38.288208 -194.38762) (xy 38.290386 -194.397339) (xy 38.292278 -194.401948) (xy 38.296342 -194.411092)
			(xy 38.303454 -194.41795) (xy 38.30447 -194.418966) (xy 38.304724 -194.41922) (xy 38.328863 -194.443258)
			(xy 38.371145 -194.496672) (xy 38.405914 -194.555256) (xy 38.432546 -194.617958) (xy 38.450564 -194.683656)
			(xy 38.459646 -194.751172) (xy 38.460172 -194.785234) (xy 38.459661 -194.817973) (xy 38.451251 -194.88291)
			(xy 38.434575 -194.94623) (xy 38.409908 -195.006885) (xy 38.377659 -195.063871) (xy 38.338361 -195.116247)
			(xy 38.3159 -195.140072) (xy 38.308788 -195.147184) (xy 38.301422 -195.165472) (xy 38.301422 -195.255134)
			(xy 38.308788 -195.273422) (xy 38.3159 -195.280534) (xy 38.338381 -195.304341) (xy 38.377673 -195.356722)
			(xy 38.409917 -195.413713) (xy 38.43458 -195.474372) (xy 38.451253 -195.537694) (xy 38.459661 -195.602632)
			(xy 38.460172 -195.635372) (xy 38.460172 -195.636134) (xy 38.459717 -195.665362) (xy 38.45293 -195.723426)
			(xy 38.43954 -195.78033) (xy 38.419724 -195.835327) (xy 38.407086 -195.861686) (xy 38.407086 -195.86194)
			(xy 38.403609 -195.86977) (xy 38.401538 -195.886767) (xy 38.405163 -195.903501) (xy 38.409372 -195.910962)
			(xy 38.437566 -195.956174) (xy 38.438328 -195.957444) (xy 38.452298 -195.98132) (xy 38.45705 -195.988815)
			(xy 38.470679 -196.000165) (xy 38.487371 -196.00616) (xy 38.49624 -196.006466) (xy 40.448992 -196.006466)
			(xy 40.458829 -196.005928) (xy 40.476991 -195.998343) (xy 40.484298 -195.991734) (xy 40.558466 -195.917566)
			(xy 40.581812 -195.894875) (xy 40.63272 -195.85429) (xy 40.687849 -195.819655) (xy 40.746507 -195.791405)
			(xy 40.807958 -195.769894) (xy 40.871428 -195.755394) (xy 40.936123 -195.748085) (xy 40.968676 -195.74764)
			(xy 41.20007 -195.74764) (xy 41.232622 -195.74811) (xy 41.297314 -195.755421) (xy 41.360783 -195.769921)
			(xy 41.422231 -195.791429) (xy 41.480889 -195.819674) (xy 41.536021 -195.854301) (xy 41.586933 -195.894878)
			(xy 41.61028 -195.917566) (xy 41.684194 -195.99148) (xy 41.691591 -195.998329) (xy 41.710189 -196.006069)
			(xy 41.720262 -196.006466) (xy 42.693336 -196.006466) (xy 42.706718 -196.006057) (xy 42.73256 -195.999089)
			(xy 42.755701 -195.985641) (xy 42.774549 -195.966638) (xy 42.787807 -195.943388) (xy 42.794564 -195.91749)
			(xy 42.794936 -195.904104) (xy 42.794936 -195.901564) (xy 42.795425 -195.874296) (xy 42.803191 -195.820316)
			(xy 42.818559 -195.767991) (xy 42.841217 -195.718385) (xy 42.870704 -195.672509) (xy 42.906419 -195.631295)
			(xy 42.947636 -195.595584) (xy 42.993515 -195.566101) (xy 43.043123 -195.543447) (xy 43.09545 -195.528083)
			(xy 43.14943 -195.520322) (xy 43.176698 -195.519802) (xy 43.203968 -195.520288) (xy 43.257954 -195.52805)
			(xy 43.310286 -195.543414) (xy 43.359899 -195.56607) (xy 43.405782 -195.595555) (xy 43.447003 -195.63127)
			(xy 43.482722 -195.672487) (xy 43.512212 -195.718368) (xy 43.534872 -195.767978) (xy 43.550242 -195.820309)
			(xy 43.558009 -195.874294) (xy 43.55846 -195.901564) (xy 43.55846 -195.904104) (xy 43.558759 -195.917499)
			(xy 43.565521 -195.943416) (xy 43.578789 -195.966683) (xy 43.59765 -195.9857) (xy 43.620807 -195.999159)
			(xy 43.646668 -196.006134) (xy 43.66006 -196.006466) (xy 44.963334 -196.006466) (xy 44.986448 -195.993766)
			(xy 44.993306 -195.98259) (xy 45.032422 -195.920106) (xy 45.036994 -195.911216) (xy 45.040042 -195.898008)
			(xy 45.040296 -195.893182) (xy 45.040296 -195.86194) (xy 45.03547 -195.85178) (xy 45.020294 -195.817873)
			(xy 44.998828 -195.746756) (xy 44.987926 -195.673276) (xy 44.98721 -195.636134) (xy 44.98721 -195.635372)
			(xy 44.98772 -195.602632) (xy 44.996129 -195.537695) (xy 45.012805 -195.474375) (xy 45.03747 -195.413719)
			(xy 45.069718 -195.356731) (xy 45.109015 -195.304354) (xy 45.131482 -195.280534) (xy 45.138594 -195.273422)
			(xy 45.14596 -195.255134) (xy 45.14596 -195.165472) (xy 45.138594 -195.147184) (xy 45.131482 -195.140072)
			(xy 45.108997 -195.116267) (xy 45.069699 -195.063888) (xy 45.037449 -195.006897) (xy 45.012781 -194.946239)
			(xy 44.996104 -194.882915) (xy 44.987694 -194.817975) (xy 44.98721 -194.785234) (xy 44.987728 -194.752315)
			(xy 44.996225 -194.687027) (xy 45.013081 -194.623382) (xy 45.038013 -194.562447) (xy 45.070604 -194.505241)
			(xy 45.110309 -194.452722) (xy 45.133006 -194.428872) (xy 45.140118 -194.42176) (xy 45.147484 -194.403472)
			(xy 45.14723 -194.321938) (xy 45.146718 -194.312036) (xy 45.139151 -194.293728) (xy 45.132498 -194.286378)
			(xy 45.132244 -194.286124) (xy 45.109638 -194.262797) (xy 45.070096 -194.211258) (xy 45.037619 -194.155)
			(xy 45.012765 -194.094983) (xy 44.995957 -194.032235) (xy 44.987484 -193.96783) (xy 44.986956 -193.93535)
			(xy 44.987461 -193.902868) (xy 44.995935 -193.838459) (xy 45.012744 -193.775707) (xy 45.037601 -193.715687)
			(xy 45.070079 -193.659425) (xy 45.109625 -193.607884) (xy 45.15556 -193.561946) (xy 45.207098 -193.522397)
			(xy 45.263358 -193.489915) (xy 45.323377 -193.465054) (xy 45.386128 -193.448241) (xy 45.450536 -193.439763)
			(xy 45.483018 -193.439288) (xy 45.48378 -193.439288) (xy 45.515012 -193.439772) (xy 45.576979 -193.447641)
			(xy 45.637467 -193.46323) (xy 45.66666 -193.47434) (xy 45.670978 -193.476118) (xy 45.68063 -193.47815)
			(xy 45.692605 -193.479861) (xy 45.715836 -193.473248) (xy 45.72508 -193.46545) (xy 45.802296 -193.394076)
			(xy 45.809916 -193.365374) (xy 45.805344 -193.351404) (xy 45.792831 -193.310462) (xy 45.774892 -193.226746)
			(xy 45.76953 -193.184272) (xy 45.76826 -193.173858) (xy 45.757846 -193.15557) (xy 45.691298 -193.106294)
			(xy 45.684602 -193.101704) (xy 45.669186 -193.096645) (xy 45.661072 -193.096388) (xy 45.649642 -193.096388)
			(xy 45.64507 -193.09715) (xy 45.604997 -193.104253) (xy 45.523966 -193.111888) (xy 45.483272 -193.11239)
			(xy 45.483018 -193.11239) (xy 45.441259 -193.111909) (xy 45.35812 -193.103972) (xy 45.276112 -193.088168)
			(xy 45.195978 -193.06464) (xy 45.118443 -193.033601) (xy 45.044209 -192.995332) (xy 44.973949 -192.95018)
			(xy 44.9083 -192.898554) (xy 44.847855 -192.840921) (xy 44.793163 -192.777804) (xy 44.744717 -192.709773)
			(xy 44.702958 -192.637446) (xy 44.668264 -192.561476) (xy 44.640947 -192.482552) (xy 44.621257 -192.40139)
			(xy 44.609371 -192.318723) (xy 44.605397 -192.2353) (xy 44.609371 -192.151877) (xy 44.621257 -192.06921)
			(xy 44.640947 -191.988048) (xy 44.668264 -191.909124) (xy 44.702958 -191.833154) (xy 44.744717 -191.760827)
			(xy 44.793163 -191.692796) (xy 44.847855 -191.629679) (xy 44.9083 -191.572046) (xy 44.973949 -191.52042)
			(xy 45.044209 -191.475268) (xy 45.118443 -191.436999) (xy 45.195978 -191.40596) (xy 45.276112 -191.382432)
			(xy 45.35812 -191.366628) (xy 45.441259 -191.358691) (xy 45.483018 -191.358266) (xy 45.524718 -191.358761)
			(xy 45.607741 -191.366681) (xy 45.689636 -191.382448) (xy 45.769665 -191.405918) (xy 45.847104 -191.436881)
			(xy 45.921254 -191.475056) (xy 45.991444 -191.520099) (xy 46.024546 -191.545464) (xy 46.03115 -191.550544)
			(xy 46.045628 -191.555624) (xy 46.053961 -191.558166) (xy 46.07137 -191.558038) (xy 46.079664 -191.55537)
			(xy 46.092618 -191.550544) (xy 46.098968 -191.545464) (xy 46.132075 -191.520107) (xy 46.20227 -191.475074)
			(xy 46.27642 -191.436905) (xy 46.353858 -191.405944) (xy 46.433885 -191.382471) (xy 46.515777 -191.366697)
			(xy 46.598797 -191.358764) (xy 46.640496 -191.358266) (xy 46.64075 -191.358266) (xy 46.641004 -191.358266)
			(xy 46.684066 -191.358777) (xy 46.769774 -191.367219) (xy 46.854242 -191.384022) (xy 46.936657 -191.409023)
			(xy 47.016224 -191.441982) (xy 47.092177 -191.482581) (xy 47.163785 -191.530429) (xy 47.230358 -191.585066)
			(xy 47.291255 -191.645966) (xy 47.34589 -191.712541) (xy 47.393736 -191.784151) (xy 47.434332 -191.860105)
			(xy 47.467288 -191.939674) (xy 47.492286 -192.022089) (xy 47.509085 -192.106558) (xy 47.517524 -192.192266)
			(xy 47.517855 -192.218564) (xy 48.570149 -192.218564) (xy 48.574087 -192.164756) (xy 48.585817 -192.112095)
			(xy 48.605091 -192.061704) (xy 48.631496 -192.014655) (xy 48.664469 -191.971953) (xy 48.703309 -191.934506)
			(xy 48.747188 -191.903114) (xy 48.795169 -191.878445) (xy 48.846231 -191.861025) (xy 48.899285 -191.851225)
			(xy 48.953201 -191.849255) (xy 49.006829 -191.855156) (xy 49.059026 -191.868802) (xy 49.10868 -191.889903)
			(xy 49.154733 -191.918008) (xy 49.196203 -191.95252) (xy 49.232206 -191.992701) (xy 49.261975 -192.037697)
			(xy 49.284875 -192.086547) (xy 49.300418 -192.138211) (xy 49.308274 -192.191588) (xy 49.308766 -192.218564)
			(xy 50.358817 -192.218564) (xy 50.362755 -192.164756) (xy 50.374485 -192.112095) (xy 50.393759 -192.061704)
			(xy 50.420164 -192.014655) (xy 50.453137 -191.971953) (xy 50.491977 -191.934506) (xy 50.535856 -191.903114)
			(xy 50.583837 -191.878445) (xy 50.634899 -191.861025) (xy 50.687953 -191.851225) (xy 50.741869 -191.849255)
			(xy 50.795497 -191.855156) (xy 50.847694 -191.868802) (xy 50.897348 -191.889903) (xy 50.943401 -191.918008)
			(xy 50.984871 -191.95252) (xy 51.020874 -191.992701) (xy 51.050643 -192.037697) (xy 51.073543 -192.086547)
			(xy 51.089086 -192.138211) (xy 51.096942 -192.191588) (xy 51.097434 -192.218564) (xy 51.096942 -192.24554)
			(xy 51.089086 -192.298917) (xy 51.073543 -192.350581) (xy 51.050643 -192.399431) (xy 51.020874 -192.444427)
			(xy 50.984871 -192.484608) (xy 50.943401 -192.51912) (xy 50.897348 -192.547225) (xy 50.847694 -192.568326)
			(xy 50.795497 -192.581972) (xy 50.741869 -192.587873) (xy 50.687953 -192.585903) (xy 50.634899 -192.576103)
			(xy 50.583837 -192.558683) (xy 50.535856 -192.534014) (xy 50.491977 -192.502622) (xy 50.453137 -192.465175)
			(xy 50.420164 -192.422473) (xy 50.393759 -192.375424) (xy 50.374485 -192.325033) (xy 50.362755 -192.272372)
			(xy 50.358817 -192.218564) (xy 49.308766 -192.218564) (xy 49.308274 -192.24554) (xy 49.300418 -192.298917)
			(xy 49.284875 -192.350581) (xy 49.261975 -192.399431) (xy 49.232206 -192.444427) (xy 49.196203 -192.484608)
			(xy 49.154733 -192.51912) (xy 49.10868 -192.547225) (xy 49.059026 -192.568326) (xy 49.006829 -192.581972)
			(xy 48.953201 -192.587873) (xy 48.899285 -192.585903) (xy 48.846231 -192.576103) (xy 48.795169 -192.558683)
			(xy 48.747188 -192.534014) (xy 48.703309 -192.502622) (xy 48.664469 -192.465175) (xy 48.631496 -192.422473)
			(xy 48.605091 -192.375424) (xy 48.585817 -192.325033) (xy 48.574087 -192.272372) (xy 48.570149 -192.218564)
			(xy 47.517855 -192.218564) (xy 47.518066 -192.235328) (xy 47.518066 -192.235582) (xy 47.517587 -192.276675)
			(xy 47.509899 -192.3585) (xy 47.494589 -192.439246) (xy 47.471792 -192.518207) (xy 47.441707 -192.594688)
			(xy 47.423578 -192.631568) (xy 47.420784 -192.636902) (xy 47.41799 -192.648332) (xy 47.416734 -192.654237)
			(xy 47.416727 -192.666305) (xy 47.41799 -192.672208) (xy 47.420784 -192.683638) (xy 47.423578 -192.688972)
			(xy 47.441702 -192.725855) (xy 47.471785 -192.802336) (xy 47.494583 -192.881295) (xy 47.509894 -192.962041)
			(xy 47.517586 -193.043866) (xy 47.518066 -193.084958) (xy 47.518066 -193.085212) (xy 47.517813 -193.107564)
			(xy 48.570149 -193.107564) (xy 48.574087 -193.053756) (xy 48.585817 -193.001095) (xy 48.605091 -192.950704)
			(xy 48.631496 -192.903655) (xy 48.664469 -192.860953) (xy 48.703309 -192.823506) (xy 48.747188 -192.792114)
			(xy 48.795169 -192.767445) (xy 48.846231 -192.750025) (xy 48.899285 -192.740225) (xy 48.953201 -192.738255)
			(xy 49.006829 -192.744156) (xy 49.059026 -192.757802) (xy 49.10868 -192.778903) (xy 49.154733 -192.807008)
			(xy 49.196203 -192.84152) (xy 49.232206 -192.881701) (xy 49.261975 -192.926697) (xy 49.284875 -192.975547)
			(xy 49.300418 -193.027211) (xy 49.308274 -193.080588) (xy 49.308766 -193.107564) (xy 49.308274 -193.13454)
			(xy 49.300418 -193.187917) (xy 49.284875 -193.239581) (xy 49.261975 -193.288431) (xy 49.232206 -193.333427)
			(xy 49.196203 -193.373608) (xy 49.154733 -193.40812) (xy 49.10868 -193.436225) (xy 49.059026 -193.457326)
			(xy 49.006829 -193.470972) (xy 48.953201 -193.476873) (xy 48.899285 -193.474903) (xy 48.846231 -193.465103)
			(xy 48.795169 -193.447683) (xy 48.747188 -193.423014) (xy 48.703309 -193.391622) (xy 48.664469 -193.354175)
			(xy 48.631496 -193.311473) (xy 48.605091 -193.264424) (xy 48.585817 -193.214033) (xy 48.574087 -193.161372)
			(xy 48.570149 -193.107564) (xy 47.517813 -193.107564) (xy 47.517611 -193.125457) (xy 47.510235 -193.205607)
			(xy 47.495546 -193.284745) (xy 47.473668 -193.362203) (xy 47.444785 -193.437332) (xy 47.409139 -193.509498)
			(xy 47.367032 -193.578094) (xy 47.318816 -193.642544) (xy 47.264898 -193.702305) (xy 47.205731 -193.756874)
			(xy 47.141813 -193.805792) (xy 47.073682 -193.848648) (xy 47.038006 -193.867278) (xy 47.037498 -193.867532)
			(xy 47.031402 -193.870834) (xy 47.026576 -193.875152) (xy 47.023958 -193.877587) (xy 47.019368 -193.883068)
			(xy 47.017432 -193.886074) (xy 46.997366 -193.918332) (xy 46.997366 -193.933064) (xy 46.997366 -193.93535)
			(xy 46.996807 -193.964189) (xy 46.991708 -193.996564) (xy 50.358817 -193.996564) (xy 50.362755 -193.942756)
			(xy 50.374485 -193.890095) (xy 50.393759 -193.839704) (xy 50.420164 -193.792655) (xy 50.453137 -193.749953)
			(xy 50.491977 -193.712506) (xy 50.535856 -193.681114) (xy 50.583837 -193.656445) (xy 50.634899 -193.639025)
			(xy 50.687953 -193.629225) (xy 50.741869 -193.627255) (xy 50.795497 -193.633156) (xy 50.847694 -193.646802)
			(xy 50.897348 -193.667903) (xy 50.943401 -193.696008) (xy 50.984871 -193.73052) (xy 51.020874 -193.770701)
			(xy 51.050643 -193.815697) (xy 51.073543 -193.864547) (xy 51.089086 -193.916211) (xy 51.096942 -193.969588)
			(xy 51.097434 -193.996564) (xy 51.096942 -194.02354) (xy 51.089086 -194.076917) (xy 51.073543 -194.128581)
			(xy 51.050643 -194.177431) (xy 51.020874 -194.222427) (xy 50.984871 -194.262608) (xy 50.943401 -194.29712)
			(xy 50.897348 -194.325225) (xy 50.847694 -194.346326) (xy 50.795497 -194.359972) (xy 50.741869 -194.365873)
			(xy 50.687953 -194.363903) (xy 50.634899 -194.354103) (xy 50.583837 -194.336683) (xy 50.535856 -194.312014)
			(xy 50.491977 -194.280622) (xy 50.453137 -194.243175) (xy 50.420164 -194.200473) (xy 50.393759 -194.153424)
			(xy 50.374485 -194.103033) (xy 50.362755 -194.050372) (xy 50.358817 -193.996564) (xy 46.991708 -193.996564)
			(xy 46.987834 -194.021165) (xy 46.970114 -194.076053) (xy 46.944077 -194.12752) (xy 46.910357 -194.174314)
			(xy 46.869773 -194.215298) (xy 46.823312 -194.249476) (xy 46.797976 -194.263264) (xy 46.791626 -194.266312)
			(xy 46.781212 -194.276218) (xy 46.777656 -194.282314) (xy 46.774224 -194.288369) (xy 46.770493 -194.301773)
			(xy 46.77029 -194.30873) (xy 46.771052 -194.395344) (xy 46.771587 -194.40509) (xy 46.779025 -194.42312)
			(xy 46.78553 -194.430396) (xy 46.785784 -194.43065) (xy 46.798738 -194.443604) (xy 46.805596 -194.44716)
			(xy 46.828385 -194.459609) (xy 46.870674 -194.489741) (xy 46.90849 -194.525327) (xy 46.941135 -194.565709)
			(xy 46.968007 -194.610142) (xy 46.988609 -194.657807) (xy 47.002561 -194.707824) (xy 47.009607 -194.759271)
			(xy 47.010066 -194.785234) (xy 47.00958 -194.812503) (xy 47.001818 -194.866487) (xy 46.996217 -194.885564)
			(xy 48.570149 -194.885564) (xy 48.574087 -194.831756) (xy 48.585817 -194.779095) (xy 48.605091 -194.728704)
			(xy 48.631496 -194.681655) (xy 48.664469 -194.638953) (xy 48.703309 -194.601506) (xy 48.747188 -194.570114)
			(xy 48.795169 -194.545445) (xy 48.846231 -194.528025) (xy 48.899285 -194.518225) (xy 48.953201 -194.516255)
			(xy 49.006829 -194.522156) (xy 49.059026 -194.535802) (xy 49.10868 -194.556903) (xy 49.154733 -194.585008)
			(xy 49.196203 -194.61952) (xy 49.232206 -194.659701) (xy 49.261975 -194.704697) (xy 49.284875 -194.753547)
			(xy 49.300418 -194.805211) (xy 49.308274 -194.858588) (xy 49.308766 -194.885564) (xy 49.308274 -194.91254)
			(xy 49.300418 -194.965917) (xy 49.284875 -195.017581) (xy 49.261975 -195.066431) (xy 49.232206 -195.111427)
			(xy 49.196203 -195.151608) (xy 49.154733 -195.18612) (xy 49.10868 -195.214225) (xy 49.059026 -195.235326)
			(xy 49.006829 -195.248972) (xy 48.953201 -195.254873) (xy 48.899285 -195.252903) (xy 48.846231 -195.243103)
			(xy 48.795169 -195.225683) (xy 48.747188 -195.201014) (xy 48.703309 -195.169622) (xy 48.664469 -195.132175)
			(xy 48.631496 -195.089473) (xy 48.605091 -195.042424) (xy 48.585817 -194.992033) (xy 48.574087 -194.939372)
			(xy 48.570149 -194.885564) (xy 46.996217 -194.885564) (xy 46.986453 -194.918817) (xy 46.963796 -194.968427)
			(xy 46.93431 -195.014308) (xy 46.898595 -195.055525) (xy 46.857378 -195.09124) (xy 46.811497 -195.120726)
			(xy 46.761887 -195.143383) (xy 46.709557 -195.158748) (xy 46.655573 -195.16651) (xy 46.601035 -195.16651)
			(xy 46.547051 -195.158748) (xy 46.494721 -195.143383) (xy 46.445111 -195.120726) (xy 46.39923 -195.09124)
			(xy 46.358013 -195.055525) (xy 46.322298 -195.014308) (xy 46.292812 -194.968427) (xy 46.270155 -194.918817)
			(xy 46.25479 -194.866487) (xy 46.247028 -194.812503) (xy 46.246542 -194.785234) (xy 46.246976 -194.759291)
			(xy 46.254002 -194.707884) (xy 46.26793 -194.657903) (xy 46.288502 -194.61027) (xy 46.315339 -194.565865)
			(xy 46.347946 -194.525506) (xy 46.385722 -194.489938) (xy 46.427969 -194.459816) (xy 46.450758 -194.447414)
			(xy 46.457616 -194.443858) (xy 46.470824 -194.43065) (xy 46.477442 -194.423349) (xy 46.485034 -194.405184)
			(xy 46.485556 -194.395344) (xy 46.486318 -194.30873) (xy 46.485933 -194.299398) (xy 46.479334 -194.281941)
			(xy 46.466952 -194.267976) (xy 46.458886 -194.263264) (xy 46.433503 -194.249528) (xy 46.386972 -194.215386)
			(xy 46.346324 -194.174417) (xy 46.31255 -194.127619) (xy 46.286473 -194.076134) (xy 46.26873 -194.021216)
			(xy 46.259752 -193.964206) (xy 46.259242 -193.93535) (xy 46.259496 -193.923158) (xy 46.259496 -193.922396)
			(xy 46.259496 -193.918586) (xy 46.259242 -193.912998) (xy 46.258473 -193.907203) (xy 46.254631 -193.896165)
			(xy 46.251622 -193.891154) (xy 46.244256 -193.879724) (xy 46.2407 -193.873628) (xy 46.22165 -193.855594)
			(xy 46.215808 -193.852546) (xy 46.196834 -193.841801) (xy 46.159859 -193.818676) (xy 46.141894 -193.806318)
			(xy 46.135798 -193.802254) (xy 46.110906 -193.793872) (xy 46.089316 -193.795904) (xy 46.079664 -193.801492)
			(xy 45.989748 -193.853054) (xy 45.976032 -193.879216) (xy 45.977302 -193.893948) (xy 45.97908 -193.93535)
			(xy 45.978606 -193.96624) (xy 45.97093 -194.027543) (xy 45.955702 -194.087417) (xy 45.933159 -194.144939)
			(xy 45.903649 -194.199216) (xy 45.867629 -194.24941) (xy 45.847 -194.272408) (xy 45.843698 -194.275964)
			(xy 45.83811 -194.284854) (xy 45.834046 -194.291204) (xy 45.829982 -194.305682) (xy 45.832014 -194.382644)
			(xy 45.832263 -194.387619) (xy 45.834442 -194.397338) (xy 45.836332 -194.401948) (xy 45.840396 -194.411092)
			(xy 45.847508 -194.41795) (xy 45.848524 -194.418966) (xy 45.848778 -194.41922) (xy 45.872915 -194.443259)
			(xy 45.915193 -194.496675) (xy 45.949958 -194.555259) (xy 45.976587 -194.617961) (xy 45.994603 -194.683658)
			(xy 46.003684 -194.751173) (xy 46.004226 -194.785234) (xy 46.003715 -194.817974) (xy 45.995306 -194.882911)
			(xy 45.978631 -194.946232) (xy 45.953966 -195.006888) (xy 45.92172 -195.063877) (xy 45.882425 -195.116255)
			(xy 45.859954 -195.140072) (xy 45.852842 -195.147184) (xy 45.845476 -195.165472) (xy 45.845476 -195.255134)
			(xy 45.852842 -195.273422) (xy 45.859954 -195.280534) (xy 45.882437 -195.30434) (xy 45.921732 -195.35672)
			(xy 45.938986 -195.387214) (xy 49.821592 -195.387214) (xy 49.822137 -195.359947) (xy 49.829896 -195.305968)
			(xy 49.845257 -195.253642) (xy 49.867908 -195.204035) (xy 49.897388 -195.158157) (xy 49.933097 -195.11694)
			(xy 49.974308 -195.081224) (xy 50.020183 -195.051737) (xy 50.069786 -195.029078) (xy 50.122109 -195.013709)
			(xy 50.176087 -195.005942) (xy 50.203354 -195.005452) (xy 50.236374 -195.006976) (xy 50.250179 -195.007763)
			(xy 50.277349 -195.002672) (xy 50.302164 -194.990493) (xy 50.322811 -194.972113) (xy 50.337783 -194.948877)
			(xy 50.345987 -194.922479) (xy 50.346864 -194.908678) (xy 50.348092 -194.88193) (xy 50.357065 -194.829144)
			(xy 50.373328 -194.778131) (xy 50.396564 -194.729892) (xy 50.426316 -194.685376) (xy 50.461998 -194.645456)
			(xy 50.502912 -194.610917) (xy 50.548252 -194.582436) (xy 50.597129 -194.560574) (xy 50.648582 -194.54576)
			(xy 50.7016 -194.538285) (xy 50.728372 -194.537838) (xy 50.755642 -194.538328) (xy 50.809628 -194.546086)
			(xy 50.86196 -194.561449) (xy 50.911574 -194.584103) (xy 50.957457 -194.613588) (xy 50.998678 -194.649302)
			(xy 51.034396 -194.69052) (xy 51.063884 -194.736402) (xy 51.086542 -194.786013) (xy 51.101908 -194.838344)
			(xy 51.10967 -194.89233) (xy 51.110134 -194.9196) (xy 51.109698 -194.946872) (xy 51.101936 -195.000862)
			(xy 51.086568 -195.053197) (xy 51.063908 -195.102812) (xy 51.034418 -195.148697) (xy 50.998698 -195.189917)
			(xy 50.957474 -195.225635) (xy 50.911587 -195.255122) (xy 50.86197 -195.277778) (xy 50.809634 -195.293142)
			(xy 50.755644 -195.3009) (xy 50.728372 -195.301362) (xy 50.695352 -195.299838) (xy 50.681546 -195.299062)
			(xy 50.654376 -195.304147) (xy 50.62956 -195.316323) (xy 50.608911 -195.334701) (xy 50.593939 -195.357937)
			(xy 50.585738 -195.384335) (xy 50.584862 -195.398136) (xy 50.58362 -195.424882) (xy 50.574647 -195.477667)
			(xy 50.558383 -195.528678) (xy 50.535148 -195.576915) (xy 50.505397 -195.62143) (xy 50.469716 -195.66135)
			(xy 50.428804 -195.695889) (xy 50.383466 -195.72437) (xy 50.334592 -195.746233) (xy 50.283142 -195.761049)
			(xy 50.230125 -195.768528) (xy 50.203354 -195.768976) (xy 50.176084 -195.768518) (xy 50.1221 -195.760751)
			(xy 50.069771 -195.74538) (xy 50.020162 -195.72272) (xy 49.974282 -195.69323) (xy 49.933065 -195.657512)
			(xy 49.89735 -195.616293) (xy 49.867865 -195.57041) (xy 49.845208 -195.520799) (xy 49.829842 -195.468468)
			(xy 49.822079 -195.414484) (xy 49.821592 -195.387214) (xy 45.938986 -195.387214) (xy 45.953979 -195.413711)
			(xy 45.978644 -195.474369) (xy 45.995319 -195.537692) (xy 46.003728 -195.602631) (xy 46.004226 -195.635372)
			(xy 46.004226 -195.636134) (xy 46.003771 -195.665363) (xy 45.996984 -195.723426) (xy 45.983596 -195.780331)
			(xy 45.963782 -195.835329) (xy 45.95114 -195.861686) (xy 45.95114 -195.86194) (xy 45.947665 -195.86977)
			(xy 45.945596 -195.886767) (xy 45.949218 -195.903501) (xy 45.953426 -195.910962) (xy 45.98162 -195.956174)
			(xy 45.982382 -195.957444) (xy 45.996352 -195.98132) (xy 46.001102 -195.98882) (xy 46.014729 -196.000182)
			(xy 46.031422 -196.006192) (xy 46.040294 -196.006466) (xy 52.507388 -196.006466) (xy 52.530502 -195.993766)
			(xy 52.53736 -195.98259) (xy 52.576476 -195.920106) (xy 52.581048 -195.911216) (xy 52.584096 -195.898008)
			(xy 52.58435 -195.893182) (xy 52.58435 -195.86194) (xy 52.579524 -195.85178) (xy 52.564349 -195.817872)
			(xy 52.542885 -195.746756) (xy 52.531984 -195.673275) (xy 52.531264 -195.636134) (xy 52.531264 -195.635372)
			(xy 52.531774 -195.602633) (xy 52.540184 -195.537696) (xy 52.556861 -195.474377) (xy 52.581528 -195.413722)
			(xy 52.613779 -195.356737) (xy 52.653078 -195.304363) (xy 52.675536 -195.280534) (xy 52.682648 -195.273422)
			(xy 52.690014 -195.255134) (xy 52.690014 -195.165472) (xy 52.682648 -195.147184) (xy 52.675536 -195.140072)
			(xy 52.653053 -195.116266) (xy 52.613758 -195.063886) (xy 52.581511 -195.006895) (xy 52.556846 -194.946236)
			(xy 52.540171 -194.882914) (xy 52.531761 -194.817975) (xy 52.531264 -194.785234) (xy 52.531782 -194.752314)
			(xy 52.540278 -194.687026) (xy 52.557133 -194.62338) (xy 52.582063 -194.562444) (xy 52.614652 -194.505236)
			(xy 52.654355 -194.452714) (xy 52.67706 -194.428872) (xy 52.684172 -194.42176) (xy 52.691538 -194.403472)
			(xy 52.691284 -194.321938) (xy 52.690771 -194.312037) (xy 52.683199 -194.293734) (xy 52.676552 -194.286378)
			(xy 52.676298 -194.286124) (xy 52.65369 -194.262798) (xy 52.614143 -194.211261) (xy 52.581663 -194.155003)
			(xy 52.556806 -194.094985) (xy 52.539996 -194.032237) (xy 52.531522 -193.967831) (xy 52.53101 -193.93535)
			(xy 52.531515 -193.902867) (xy 52.539989 -193.838456) (xy 52.556797 -193.775702) (xy 52.581653 -193.715679)
			(xy 52.614132 -193.659414) (xy 52.653676 -193.607869) (xy 52.699611 -193.561928) (xy 52.751149 -193.522375)
			(xy 52.807409 -193.489888) (xy 52.867428 -193.465022) (xy 52.930179 -193.448204) (xy 52.994589 -193.43972)
			(xy 53.027072 -193.439288) (xy 53.027834 -193.439288) (xy 53.059065 -193.439776) (xy 53.12103 -193.447651)
			(xy 53.181515 -193.463246) (xy 53.210714 -193.47434) (xy 53.215032 -193.476118) (xy 53.224684 -193.47815)
			(xy 53.236655 -193.479848) (xy 53.259869 -193.473217) (xy 53.269134 -193.46545) (xy 53.34635 -193.394076)
			(xy 53.35397 -193.365374) (xy 53.349398 -193.351404) (xy 53.336886 -193.310462) (xy 53.318947 -193.226746)
			(xy 53.313584 -193.184272) (xy 53.312314 -193.173858) (xy 53.3019 -193.15557) (xy 53.235352 -193.106294)
			(xy 53.228654 -193.10171) (xy 53.213238 -193.096666) (xy 53.205126 -193.096388) (xy 53.193696 -193.096388)
			(xy 53.189124 -193.09715) (xy 53.149051 -193.10425) (xy 53.06802 -193.111882) (xy 53.027326 -193.11239)
			(xy 53.027072 -193.11239) (xy 52.985316 -193.111892) (xy 52.902181 -193.103951) (xy 52.820178 -193.088144)
			(xy 52.740048 -193.064614) (xy 52.662518 -193.033573) (xy 52.58829 -192.995304) (xy 52.518035 -192.950152)
			(xy 52.452391 -192.898526) (xy 52.391951 -192.840895) (xy 52.337262 -192.777779) (xy 52.288821 -192.709751)
			(xy 52.247065 -192.637426) (xy 52.212373 -192.56146) (xy 52.18506 -192.48254) (xy 52.165371 -192.401381)
			(xy 52.153486 -192.318718) (xy 52.149512 -192.2353) (xy 52.153486 -192.151882) (xy 52.165371 -192.069219)
			(xy 52.18506 -191.98806) (xy 52.212373 -191.90914) (xy 52.247065 -191.833174) (xy 52.288821 -191.760849)
			(xy 52.337262 -191.692821) (xy 52.391951 -191.629705) (xy 52.452391 -191.572074) (xy 52.518035 -191.520448)
			(xy 52.58829 -191.475296) (xy 52.662518 -191.437027) (xy 52.740048 -191.405986) (xy 52.820178 -191.382456)
			(xy 52.902181 -191.366649) (xy 52.985316 -191.358708) (xy 53.027072 -191.358266) (xy 53.027326 -191.358266)
			(xy 53.02758 -191.358266) (xy 53.06928 -191.35876) (xy 53.152302 -191.366678) (xy 53.234198 -191.382444)
			(xy 53.314226 -191.405916) (xy 53.391664 -191.436882) (xy 53.465811 -191.475062) (xy 53.535997 -191.520111)
			(xy 53.569108 -191.545464) (xy 53.575458 -191.550544) (xy 53.597048 -191.558418) (xy 53.614828 -191.558418)
			(xy 53.62321 -191.55537) (xy 53.636926 -191.550544) (xy 53.64353 -191.545464) (xy 53.676632 -191.520099)
			(xy 53.74682 -191.475053) (xy 53.820969 -191.436875) (xy 53.898408 -191.405912) (xy 53.978438 -191.382443)
			(xy 54.060334 -191.36668) (xy 54.143358 -191.358765) (xy 54.185058 -191.358266) (xy 54.228121 -191.358775)
			(xy 54.313833 -191.367213) (xy 54.398304 -191.384012) (xy 54.480723 -191.409011) (xy 54.560294 -191.441968)
			(xy 54.636251 -191.482565) (xy 54.707863 -191.530413) (xy 54.77444 -191.58505) (xy 54.835341 -191.64595)
			(xy 54.889979 -191.712526) (xy 54.937828 -191.784137) (xy 54.978426 -191.860094) (xy 55.011385 -191.939664)
			(xy 55.036384 -192.022082) (xy 55.053185 -192.106553) (xy 55.061624 -192.192265) (xy 55.061927 -192.218564)
			(xy 56.114203 -192.218564) (xy 56.118141 -192.164756) (xy 56.129871 -192.112095) (xy 56.149145 -192.061704)
			(xy 56.17555 -192.014655) (xy 56.208523 -191.971953) (xy 56.247363 -191.934506) (xy 56.291242 -191.903114)
			(xy 56.339223 -191.878445) (xy 56.390285 -191.861025) (xy 56.443339 -191.851225) (xy 56.497255 -191.849255)
			(xy 56.550883 -191.855156) (xy 56.60308 -191.868802) (xy 56.652734 -191.889903) (xy 56.698787 -191.918008)
			(xy 56.740257 -191.95252) (xy 56.77626 -191.992701) (xy 56.806029 -192.037697) (xy 56.828929 -192.086547)
			(xy 56.844472 -192.138211) (xy 56.852328 -192.191588) (xy 56.85282 -192.218564) (xy 56.852328 -192.24554)
			(xy 56.844472 -192.298917) (xy 56.828929 -192.350581) (xy 56.806029 -192.399431) (xy 56.77626 -192.444427)
			(xy 56.740257 -192.484608) (xy 56.698787 -192.51912) (xy 56.652734 -192.547225) (xy 56.60308 -192.568326)
			(xy 56.550883 -192.581972) (xy 56.497255 -192.587873) (xy 56.443339 -192.585903) (xy 56.390285 -192.576103)
			(xy 56.339223 -192.558683) (xy 56.291242 -192.534014) (xy 56.247363 -192.502622) (xy 56.208523 -192.465175)
			(xy 56.17555 -192.422473) (xy 56.149145 -192.375424) (xy 56.129871 -192.325033) (xy 56.118141 -192.272372)
			(xy 56.114203 -192.218564) (xy 55.061927 -192.218564) (xy 55.06212 -192.235328) (xy 55.06212 -192.235582)
			(xy 55.061641 -192.276675) (xy 55.053952 -192.358499) (xy 55.038642 -192.439246) (xy 55.015844 -192.518206)
			(xy 54.985758 -192.594686) (xy 54.967632 -192.631568) (xy 54.964838 -192.636902) (xy 54.962044 -192.648332)
			(xy 54.960787 -192.654237) (xy 54.960781 -192.666305) (xy 54.962044 -192.672208) (xy 54.964838 -192.683638)
			(xy 54.967632 -192.688972) (xy 54.985755 -192.725855) (xy 55.015837 -192.802336) (xy 55.038632 -192.881296)
			(xy 55.053943 -192.962042) (xy 55.061634 -193.043866) (xy 55.06212 -193.084958) (xy 55.06212 -193.085212)
			(xy 55.061867 -193.107564) (xy 56.114203 -193.107564) (xy 56.118141 -193.053756) (xy 56.129871 -193.001095)
			(xy 56.149145 -192.950704) (xy 56.17555 -192.903655) (xy 56.208523 -192.860953) (xy 56.247363 -192.823506)
			(xy 56.291242 -192.792114) (xy 56.339223 -192.767445) (xy 56.390285 -192.750025) (xy 56.443339 -192.740225)
			(xy 56.497255 -192.738255) (xy 56.550883 -192.744156) (xy 56.60308 -192.757802) (xy 56.652734 -192.778903)
			(xy 56.698787 -192.807008) (xy 56.740257 -192.84152) (xy 56.77626 -192.881701) (xy 56.806029 -192.926697)
			(xy 56.828929 -192.975547) (xy 56.844472 -193.027211) (xy 56.852328 -193.080588) (xy 56.85282 -193.107564)
			(xy 56.852328 -193.13454) (xy 56.844472 -193.187917) (xy 56.828929 -193.239581) (xy 56.806029 -193.288431)
			(xy 56.77626 -193.333427) (xy 56.740257 -193.373608) (xy 56.698787 -193.40812) (xy 56.652734 -193.436225)
			(xy 56.60308 -193.457326) (xy 56.550883 -193.470972) (xy 56.497255 -193.476873) (xy 56.443339 -193.474903)
			(xy 56.390285 -193.465103) (xy 56.339223 -193.447683) (xy 56.291242 -193.423014) (xy 56.247363 -193.391622)
			(xy 56.208523 -193.354175) (xy 56.17555 -193.311473) (xy 56.149145 -193.264424) (xy 56.129871 -193.214033)
			(xy 56.118141 -193.161372) (xy 56.114203 -193.107564) (xy 55.061867 -193.107564) (xy 55.061665 -193.125456)
			(xy 55.054288 -193.205606) (xy 55.039599 -193.284743) (xy 55.017721 -193.3622) (xy 54.988836 -193.437327)
			(xy 54.95319 -193.509492) (xy 54.911081 -193.578087) (xy 54.862864 -193.642534) (xy 54.808945 -193.702293)
			(xy 54.749777 -193.756859) (xy 54.685857 -193.805775) (xy 54.617725 -193.848628) (xy 54.58206 -193.867278)
			(xy 54.581552 -193.867532) (xy 54.575456 -193.870834) (xy 54.57063 -193.875152) (xy 54.56801 -193.877585)
			(xy 54.563416 -193.883064) (xy 54.561486 -193.886074) (xy 54.54142 -193.918332) (xy 54.54142 -193.933064)
			(xy 54.54142 -193.93535) (xy 54.540861 -193.964188) (xy 54.531887 -194.021162) (xy 54.514166 -194.076049)
			(xy 54.488127 -194.127514) (xy 54.454405 -194.174305) (xy 54.413819 -194.215285) (xy 54.367356 -194.249457)
			(xy 54.34203 -194.263264) (xy 54.33568 -194.266566) (xy 54.32552 -194.275964) (xy 54.32171 -194.282314)
			(xy 54.318255 -194.288428) (xy 54.314528 -194.301963) (xy 54.314344 -194.308984) (xy 54.315106 -194.395598)
			(xy 54.31567 -194.405525) (xy 54.323368 -194.423836) (xy 54.330092 -194.431158) (xy 54.342792 -194.443858)
			(xy 54.34965 -194.447414) (xy 54.372418 -194.459854) (xy 54.414669 -194.489966) (xy 54.452448 -194.525527)
			(xy 54.485059 -194.56588) (xy 54.5119 -194.610281) (xy 54.532475 -194.65791) (xy 54.546405 -194.707888)
			(xy 54.553433 -194.759292) (xy 54.553866 -194.785234) (xy 54.5534 -194.812484) (xy 54.545639 -194.866429)
			(xy 54.540019 -194.885564) (xy 56.114203 -194.885564) (xy 56.118141 -194.831756) (xy 56.129871 -194.779095)
			(xy 56.149145 -194.728704) (xy 56.17555 -194.681655) (xy 56.208523 -194.638953) (xy 56.247363 -194.601506)
			(xy 56.291242 -194.570114) (xy 56.339223 -194.545445) (xy 56.390285 -194.528025) (xy 56.443339 -194.518225)
			(xy 56.497255 -194.516255) (xy 56.550883 -194.522156) (xy 56.60308 -194.535802) (xy 56.652734 -194.556903)
			(xy 56.698787 -194.585008) (xy 56.740257 -194.61952) (xy 56.77626 -194.659701) (xy 56.806029 -194.704697)
			(xy 56.828929 -194.753547) (xy 56.844472 -194.805211) (xy 56.852328 -194.858588) (xy 56.85282 -194.885564)
			(xy 56.852328 -194.91254) (xy 56.844472 -194.965917) (xy 56.828929 -195.017581) (xy 56.806029 -195.066431)
			(xy 56.77626 -195.111427) (xy 56.740257 -195.151608) (xy 56.698787 -195.18612) (xy 56.652734 -195.214225)
			(xy 56.60308 -195.235326) (xy 56.550883 -195.248972) (xy 56.497255 -195.254873) (xy 56.443339 -195.252903)
			(xy 56.390285 -195.243103) (xy 56.339223 -195.225683) (xy 56.291242 -195.201014) (xy 56.247363 -195.169622)
			(xy 56.208523 -195.132175) (xy 56.17555 -195.089473) (xy 56.149145 -195.042424) (xy 56.129871 -194.992033)
			(xy 56.118141 -194.939372) (xy 56.114203 -194.885564) (xy 54.540019 -194.885564) (xy 54.53028 -194.918721)
			(xy 54.507635 -194.968294) (xy 54.478165 -195.01414) (xy 54.442471 -195.055325) (xy 54.401279 -195.091011)
			(xy 54.355427 -195.120471) (xy 54.305849 -195.143106) (xy 54.253555 -195.158455) (xy 54.199608 -195.166206)
			(xy 54.172358 -195.166742) (xy 54.170834 -195.166742) (xy 54.148264 -195.166397) (xy 54.103442 -195.161053)
			(xy 54.081426 -195.156074) (xy 54.078378 -195.155312) (xy 54.066186 -195.153788) (xy 54.059328 -195.153788)
			(xy 54.058058 -195.153788) (xy 54.044342 -195.154296) (xy 54.044088 -195.154296) (xy 54.017725 -195.153825)
			(xy 53.965537 -195.146321) (xy 53.914948 -195.131466) (xy 53.866987 -195.109563) (xy 53.822632 -195.081058)
			(xy 53.782784 -195.046531) (xy 53.748255 -195.006686) (xy 53.719748 -194.962332) (xy 53.697842 -194.914373)
			(xy 53.682984 -194.863784) (xy 53.675476 -194.811597) (xy 53.675026 -194.785234) (xy 53.675477 -194.759101)
			(xy 53.682844 -194.707355) (xy 53.697436 -194.657167) (xy 53.718961 -194.609538) (xy 53.746988 -194.565421)
			(xy 53.780957 -194.525698) (xy 53.82019 -194.491164) (xy 53.863901 -194.462508) (xy 53.911217 -194.440304)
			(xy 53.961192 -194.424995) (xy 53.986938 -194.42049) (xy 54.005734 -194.417442) (xy 54.029864 -194.389502)
			(xy 54.030372 -194.294252) (xy 54.01564 -194.269868) (xy 54.00294 -194.263264) (xy 53.977559 -194.249526)
			(xy 53.931034 -194.215381) (xy 53.890391 -194.174411) (xy 53.856621 -194.127613) (xy 53.830548 -194.076128)
			(xy 53.812807 -194.021213) (xy 53.803831 -193.964205) (xy 53.803296 -193.93535) (xy 53.80355 -193.923158)
			(xy 53.80355 -193.922396) (xy 53.80355 -193.918586) (xy 53.803296 -193.912998) (xy 53.802528 -193.907202)
			(xy 53.79869 -193.896163) (xy 53.795676 -193.891154) (xy 53.78831 -193.879724) (xy 53.784754 -193.873628)
			(xy 53.765704 -193.855594) (xy 53.759862 -193.852546) (xy 53.740888 -193.8418) (xy 53.703915 -193.818674)
			(xy 53.685948 -193.806318) (xy 53.679852 -193.802254) (xy 53.65496 -193.793872) (xy 53.63337 -193.795904)
			(xy 53.623718 -193.801492) (xy 53.533802 -193.853054) (xy 53.520086 -193.879216) (xy 53.521356 -193.893948)
			(xy 53.523134 -193.93535) (xy 53.52266 -193.96624) (xy 53.514983 -194.027542) (xy 53.499754 -194.087416)
			(xy 53.47721 -194.144936) (xy 53.447698 -194.199212) (xy 53.411675 -194.249403) (xy 53.391054 -194.272408)
			(xy 53.387752 -194.275964) (xy 53.382164 -194.284854) (xy 53.3781 -194.291204) (xy 53.374036 -194.305682)
			(xy 53.376068 -194.382644) (xy 53.376317 -194.38762) (xy 53.378494 -194.397339) (xy 53.380386 -194.401948)
			(xy 53.38445 -194.411092) (xy 53.391562 -194.41795) (xy 53.392578 -194.418966) (xy 53.392832 -194.41922)
			(xy 53.416971 -194.443258) (xy 53.459252 -194.496673) (xy 53.49402 -194.555256) (xy 53.520652 -194.617959)
			(xy 53.53867 -194.683656) (xy 53.547752 -194.751172) (xy 53.54828 -194.785234) (xy 53.547769 -194.817973)
			(xy 53.539359 -194.88291) (xy 53.522683 -194.94623) (xy 53.498017 -195.006885) (xy 53.465768 -195.063872)
			(xy 53.426471 -195.116248) (xy 53.404008 -195.140072) (xy 53.396896 -195.147184) (xy 53.38953 -195.165472)
			(xy 53.38953 -195.255134) (xy 53.396896 -195.273422) (xy 53.404008 -195.280534) (xy 53.426493 -195.304339)
			(xy 53.465792 -195.356718) (xy 53.498041 -195.413708) (xy 53.522709 -195.474367) (xy 53.539385 -195.537691)
			(xy 53.547795 -195.602631) (xy 53.54828 -195.635372) (xy 53.54828 -195.636134) (xy 53.547825 -195.665363)
			(xy 53.541038 -195.723426) (xy 53.527648 -195.78033) (xy 53.507832 -195.835327) (xy 53.495194 -195.861686)
			(xy 53.495194 -195.86194) (xy 53.491716 -195.86977) (xy 53.489645 -195.886767) (xy 53.493271 -195.903501)
			(xy 53.49748 -195.910962) (xy 53.525674 -195.956174) (xy 53.526436 -195.957444) (xy 53.540406 -195.98132)
			(xy 53.545158 -195.988814) (xy 53.558787 -196.000162) (xy 53.575479 -196.006154) (xy 53.584348 -196.006466)
			(xy 57.393332 -196.006466) (xy 57.403399 -196.006036) (xy 57.421992 -195.99831) (xy 57.4294 -195.99148)
			(xy 57.868312 -195.552568) (xy 57.874916 -195.525644) (xy 57.870852 -195.511928) (xy 57.863045 -195.484649)
			(xy 57.854629 -195.428537) (xy 57.854088 -195.400168) (xy 57.854543 -195.373576) (xy 57.861915 -195.320906)
			(xy 57.876525 -195.269769) (xy 57.898091 -195.221154) (xy 57.926196 -195.176003) (xy 57.960294 -195.135189)
			(xy 57.999727 -195.099502) (xy 58.021474 -195.084192) (xy 58.031449 -195.07671) (xy 58.043169 -195.054734)
			(xy 58.043826 -195.042282) (xy 58.043826 -194.88912) (xy 58.043186 -194.876564) (xy 58.031326 -194.854433)
			(xy 58.02122 -194.846956) (xy 57.999143 -194.831709) (xy 57.959088 -194.796013) (xy 57.924426 -194.755061)
			(xy 57.89584 -194.709658) (xy 57.873892 -194.660701) (xy 57.859015 -194.609152) (xy 57.851503 -194.556028)
			(xy 57.85104 -194.529202) (xy 57.851495 -194.502375) (xy 57.859007 -194.44925) (xy 57.873884 -194.3977)
			(xy 57.895832 -194.348741) (xy 57.924419 -194.303337) (xy 57.959081 -194.262383) (xy 57.999137 -194.226686)
			(xy 58.02122 -194.211448) (xy 58.031277 -194.20393) (xy 58.043117 -194.181821) (xy 58.043826 -194.169284)
			(xy 58.043826 -194.134486) (xy 58.03519 -194.115182) (xy 58.026808 -194.107816) (xy 58.007747 -194.090223)
			(xy 57.974254 -194.050614) (xy 57.946635 -194.006707) (xy 57.925432 -193.959366) (xy 57.911065 -193.909524)
			(xy 57.903815 -193.858162) (xy 57.903364 -193.832226) (xy 57.903801 -193.80629) (xy 57.911056 -193.754927)
			(xy 57.925426 -193.705084) (xy 57.946629 -193.657743) (xy 57.974248 -193.613834) (xy 58.007739 -193.574221)
			(xy 58.026808 -193.556636) (xy 58.034435 -193.549073) (xy 58.043249 -193.529514) (xy 58.043826 -193.51879)
			(xy 58.043826 -193.485008) (xy 58.0517 -193.466466) (xy 58.058812 -193.459354) (xy 58.058812 -192.55613)
			(xy 58.058635 -192.55047) (xy 58.056078 -192.53944) (xy 58.053732 -192.534286) (xy 58.042556 -192.510664)
			(xy 58.035952 -192.502028) (xy 58.031888 -192.498472) (xy 58.01211 -192.480853) (xy 57.977309 -192.440924)
			(xy 57.948571 -192.396431) (xy 57.926485 -192.348288) (xy 57.911506 -192.297484) (xy 57.90394 -192.24506)
			(xy 57.903944 -192.192093) (xy 57.911516 -192.13967) (xy 57.926502 -192.088868) (xy 57.948593 -192.040728)
			(xy 57.977337 -191.996239) (xy 58.012144 -191.956314) (xy 58.031888 -191.938656) (xy 58.035952 -191.9351)
			(xy 58.042556 -191.926464) (xy 58.058812 -191.892428) (xy 58.058812 -191.880744) (xy 58.058812 -191.674242)
			(xy 58.058429 -191.665389) (xy 58.052413 -191.648735) (xy 58.041113 -191.635102) (xy 58.033666 -191.6303)
			(xy 58.023506 -191.622426) (xy 57.902602 -191.501522) (xy 57.89549 -191.494156) (xy 57.876694 -191.486536)
			(xy 56.096916 -191.486536) (xy 56.096408 -191.486028) (xy 56.096154 -191.486028) (xy 55.461916 -190.85179)
			(xy 53.233574 -188.623194) (xy 53.230018 -188.619638) (xy 53.206904 -188.596524) (xy 53.142388 -188.531754)
			(xy 53.135575 -188.524411) (xy 53.127845 -188.505947) (xy 53.127402 -188.49594) (xy 53.127402 -188.37656)
			(xy 53.127402 -188.375544) (xy 53.127148 -188.3664) (xy 53.127148 -188.144658) (xy 53.126716 -188.134592)
			(xy 53.118985 -188.116004) (xy 53.112162 -188.10859) (xy 52.758086 -187.754514) (xy 52.730908 -187.74791)
			(xy 52.716938 -187.752482) (xy 52.679151 -187.763856) (xy 52.601198 -187.776104) (xy 52.561744 -187.776866)
			(xy 52.560982 -187.776866) (xy 52.530252 -187.776419) (xy 52.469239 -187.769009) (xy 52.409565 -187.754297)
			(xy 52.352098 -187.7325) (xy 52.297679 -187.703935) (xy 52.247099 -187.669019) (xy 52.201097 -187.62826)
			(xy 52.160344 -187.582253) (xy 52.125434 -187.53167) (xy 52.096875 -187.477247) (xy 52.075085 -187.419778)
			(xy 52.060381 -187.360102) (xy 52.052977 -187.299089) (xy 52.052474 -187.268358) (xy 52.052474 -187.267596)
			(xy 52.053258 -187.228144) (xy 52.065503 -187.150193) (xy 52.076858 -187.112402) (xy 52.08143 -187.098432)
			(xy 52.074826 -187.071254) (xy 51.830986 -186.827414) (xy 51.823874 -186.820048) (xy 51.805078 -186.812428)
			(xy 51.787298 -186.812428) (xy 51.774852 -186.813952) (xy 51.683158 -186.837066) (xy 51.663854 -186.855354)
			(xy 51.660044 -186.868562) (xy 51.646594 -186.911871) (xy 51.612836 -186.996048) (xy 51.571529 -187.07679)
			(xy 51.523019 -187.15342) (xy 51.467711 -187.225298) (xy 51.406068 -187.291823) (xy 51.338606 -187.352438)
			(xy 51.265888 -187.406637) (xy 51.188523 -187.453966) (xy 51.107158 -187.49403) (xy 51.022473 -187.526493)
			(xy 50.935176 -187.551085) (xy 50.845999 -187.567598) (xy 50.755685 -187.575896) (xy 50.710338 -187.57646)
			(xy 48.957738 -187.57646) (xy 48.911951 -187.575949) (xy 48.820766 -187.567503) (xy 48.73075 -187.550679)
			(xy 48.64267 -187.525621) (xy 48.557278 -187.492543) (xy 48.475302 -187.451727) (xy 48.397442 -187.403521)
			(xy 48.324362 -187.348337) (xy 48.256686 -187.286645) (xy 48.194991 -187.218971) (xy 48.139804 -187.145894)
			(xy 48.091594 -187.068036) (xy 48.050775 -186.986063) (xy 48.017693 -186.900672) (xy 47.992631 -186.812593)
			(xy 47.975803 -186.722578) (xy 47.967353 -186.631393) (xy 47.966884 -186.585606) (xy 47.966884 -186.585098)
			(xy 47.967341 -186.542504) (xy 47.974656 -186.457629) (xy 47.989232 -186.373697) (xy 48.010961 -186.291326)
			(xy 48.039684 -186.211125) (xy 48.075186 -186.133687) (xy 48.117207 -186.059583) (xy 48.165437 -185.989361)
			(xy 48.219517 -185.92354) (xy 48.27905 -185.862606) (xy 48.343595 -185.807009) (xy 48.377856 -185.781696)
			(xy 48.391318 -185.772044) (xy 48.401478 -185.740802) (xy 48.36668 -185.633106) (xy 48.362865 -185.623109)
			(xy 48.348599 -185.607197) (xy 48.329103 -185.598441) (xy 48.31842 -185.5978) (xy 43.808142 -185.5978)
			(xy 43.798077 -185.597366) (xy 43.779487 -185.589637) (xy 43.772074 -185.582814) (xy 43.354498 -185.165238)
			(xy 43.352974 -185.163968) (xy 43.31843 -185.132218) (xy 35.792664 -177.606452) (xy 35.760914 -177.571908)
			(xy 35.759644 -177.570384) (xy 32.941006 -174.751746) (xy 32.934167 -174.744345) (xy 32.926452 -174.725747)
			(xy 32.92602 -174.715678) (xy 32.92602 -170.79214) (xy 32.925587 -170.782074) (xy 32.917859 -170.763484)
			(xy 32.911034 -170.756072) (xy 32.386016 -170.231054) (xy 32.363821 -170.208261) (xy 32.324144 -170.158528)
			(xy 32.290286 -170.104664) (xy 32.262673 -170.047347) (xy 32.241653 -169.987298) (xy 32.227488 -169.925274)
			(xy 32.220359 -169.862053) (xy 32.2199 -169.830242) (xy 32.2199 -161.473642) (xy 32.219466 -161.463577)
			(xy 32.211737 -161.444987) (xy 32.204914 -161.437574) (xy 31.645606 -160.878266) (xy 31.638494 -160.8709)
			(xy 31.619698 -160.86328) (xy 26.985722 -160.86328) (xy 26.975659 -160.862842) (xy 26.957077 -160.855106)
			(xy 26.949654 -160.848294) (xy 23.297896 -157.196536) (xy 23.29106 -157.189134) (xy 23.283349 -157.170536)
			(xy 23.28291 -157.160468) (xy 23.28291 -154.309064) (xy 23.27529 -154.290268) (xy 23.267924 -154.283156)
			(xy 22.868128 -153.88336) (xy 22.861016 -153.875994) (xy 22.84222 -153.868374) (xy 21.7678 -153.868374)
			(xy 21.738082 -153.897076) (xy 21.737574 -153.91765) (xy 21.736138 -153.947319) (xy 21.725215 -154.005702)
			(xy 21.705369 -154.061684) (xy 21.677081 -154.113912) (xy 21.641035 -154.16112) (xy 21.619972 -154.182064)
			(xy 21.612352 -154.18943) (xy 21.604224 -154.208734) (xy 21.606002 -154.304746) (xy 21.614638 -154.323796)
			(xy 21.622766 -154.330908) (xy 21.642448 -154.349094) (xy 21.67703 -154.390027) (xy 21.70555 -154.435393)
			(xy 21.727448 -154.484301) (xy 21.742292 -154.53579) (xy 21.749792 -154.588849) (xy 21.750274 -154.615642)
			(xy 21.749788 -154.642893) (xy 21.742032 -154.696841) (xy 21.726677 -154.749136) (xy 21.704035 -154.798713)
			(xy 21.674569 -154.844563) (xy 21.638878 -154.885754) (xy 21.597687 -154.921445) (xy 21.551837 -154.950911)
			(xy 21.50226 -154.973553) (xy 21.449965 -154.988908) (xy 21.396017 -154.996664) (xy 21.341515 -154.996664)
			(xy 21.287567 -154.988908) (xy 21.235272 -154.973553) (xy 21.185695 -154.950911) (xy 21.139845 -154.921445)
			(xy 21.098654 -154.885754) (xy 21.062963 -154.844563) (xy 21.033497 -154.798713) (xy 21.010855 -154.749136)
			(xy 20.9955 -154.696841) (xy 20.987744 -154.642893) (xy 20.987258 -154.615642) (xy 20.987674 -154.589941)
			(xy 20.994567 -154.539002) (xy 21.008232 -154.489449) (xy 21.028423 -154.442178) (xy 21.054775 -154.398044)
			(xy 21.086811 -154.357846) (xy 21.105114 -154.339798) (xy 21.112734 -154.332432) (xy 21.120862 -154.313128)
			(xy 21.119084 -154.217116) (xy 21.110448 -154.198066) (xy 21.10232 -154.190954) (xy 21.083333 -154.173425)
			(xy 21.049784 -154.134119) (xy 21.021847 -154.090645) (xy 21.000031 -154.043799) (xy 20.984737 -153.994438)
			(xy 20.976244 -153.943465) (xy 20.975066 -153.91765) (xy 20.974558 -153.897076) (xy 20.94484 -153.868374)
			(xy 19.681952 -153.868374) (xy 19.663156 -153.875994) (xy 19.656044 -153.88336) (xy 19.265392 -154.274012)
			(xy 19.25871 -154.281423) (xy 19.251134 -154.299859) (xy 19.25066 -154.309826) (xy 19.25066 -163.304982)
			(xy 19.250298 -163.329951) (xy 19.245717 -163.37968) (xy 19.241516 -163.404296) (xy 19.240754 -163.408868)
			(xy 19.240754 -163.586668) (xy 19.240317 -163.596732) (xy 19.23258 -163.615314) (xy 19.225768 -163.622736)
			(xy 14.052804 -168.7957) (xy 14.045438 -168.802812) (xy 14.037818 -168.821608) (xy 14.037818 -174.31639)
			(xy 28.33065 -174.31639) (xy 28.334721 -174.260768) (xy 28.346847 -174.206331) (xy 28.36677 -174.15424)
			(xy 28.394066 -174.105605) (xy 28.428152 -174.061462) (xy 28.468301 -174.022753) (xy 28.513659 -173.990302)
			(xy 28.563259 -173.964801) (xy 28.616043 -173.946794) (xy 28.670886 -173.936664) (xy 28.72662 -173.934627)
			(xy 28.782057 -173.940727) (xy 28.836014 -173.954833) (xy 28.887343 -173.976645) (xy 28.934949 -174.005699)
			(xy 28.977817 -174.041374) (xy 29.015034 -174.082911) (xy 29.045807 -174.129424) (xy 29.069479 -174.179921)
			(xy 29.085547 -174.233328) (xy 29.093667 -174.288504) (xy 29.094176 -174.31639) (xy 29.093667 -174.344276)
			(xy 29.085547 -174.399452) (xy 29.069479 -174.452859) (xy 29.045807 -174.503356) (xy 29.015034 -174.549869)
			(xy 28.977817 -174.591406) (xy 28.934949 -174.627081) (xy 28.887343 -174.656135) (xy 28.836014 -174.677947)
			(xy 28.782057 -174.692053) (xy 28.72662 -174.698153) (xy 28.670886 -174.696116) (xy 28.616043 -174.685986)
			(xy 28.563259 -174.667979) (xy 28.513659 -174.642478) (xy 28.468301 -174.610027) (xy 28.428152 -174.571318)
			(xy 28.394066 -174.527175) (xy 28.36677 -174.47854) (xy 28.346847 -174.426449) (xy 28.334721 -174.372012)
			(xy 28.33065 -174.31639) (xy 14.037818 -174.31639) (xy 14.037818 -182.948912) (xy 21.441384 -182.948912)
			(xy 21.441384 -182.894408) (xy 21.44914 -182.84046) (xy 21.464496 -182.788165) (xy 21.487137 -182.738587)
			(xy 21.516604 -182.692736) (xy 21.552296 -182.651546) (xy 21.593486 -182.615854) (xy 21.639337 -182.586387)
			(xy 21.688915 -182.563746) (xy 21.74121 -182.54839) (xy 21.795158 -182.540634) (xy 21.82241 -182.540148)
			(xy 21.849781 -182.540597) (xy 21.903961 -182.548417) (xy 21.956465 -182.563909) (xy 22.006212 -182.586755)
			(xy 22.052177 -182.616484) (xy 22.073108 -182.634128) (xy 22.073362 -182.634382) (xy 22.080457 -182.639956)
			(xy 22.097367 -182.646211) (xy 22.106382 -182.646574) (xy 22.173438 -182.646574) (xy 22.182457 -182.646241)
			(xy 22.199374 -182.639977) (xy 22.206458 -182.634382) (xy 22.206966 -182.633874) (xy 22.22789 -182.61628)
			(xy 22.273828 -182.586643) (xy 22.323526 -182.563867) (xy 22.375967 -182.54842) (xy 22.430076 -182.540617)
			(xy 22.45741 -182.540148) (xy 22.484661 -182.540642) (xy 22.538608 -182.548398) (xy 22.590902 -182.563753)
			(xy 22.640479 -182.586394) (xy 22.686329 -182.61586) (xy 22.727519 -182.651551) (xy 22.76321 -182.692741)
			(xy 22.792676 -182.738591) (xy 22.815317 -182.788168) (xy 22.830672 -182.840462) (xy 22.838428 -182.894409)
			(xy 22.838428 -182.948911) (xy 22.830672 -183.002858) (xy 22.815317 -183.055152) (xy 22.792676 -183.104729)
			(xy 22.76321 -183.150579) (xy 22.727519 -183.191769) (xy 22.686329 -183.22746) (xy 22.640479 -183.256926)
			(xy 22.590902 -183.279567) (xy 22.538608 -183.294922) (xy 22.484661 -183.302678) (xy 22.45741 -183.303164)
			(xy 22.43004 -183.302701) (xy 22.37586 -183.294884) (xy 22.323357 -183.279394) (xy 22.27361 -183.256552)
			(xy 22.227643 -183.226826) (xy 22.206712 -183.209184) (xy 22.206458 -183.20893) (xy 22.199365 -183.203353)
			(xy 22.182453 -183.197103) (xy 22.173438 -183.196738) (xy 22.106382 -183.196738) (xy 22.097363 -183.197078)
			(xy 22.080446 -183.203336) (xy 22.073362 -183.20893) (xy 22.072854 -183.209438) (xy 22.051924 -183.227024)
			(xy 22.005987 -183.256662) (xy 21.956291 -183.279439) (xy 21.903851 -183.294889) (xy 21.849744 -183.302694)
			(xy 21.82241 -183.303164) (xy 21.795158 -183.302686) (xy 21.74121 -183.29493) (xy 21.688915 -183.279574)
			(xy 21.639337 -183.256933) (xy 21.593486 -183.227466) (xy 21.552296 -183.191774) (xy 21.516604 -183.150584)
			(xy 21.487137 -183.104733) (xy 21.464496 -183.055155) (xy 21.44914 -183.00286) (xy 21.441384 -182.948912)
			(xy 14.037818 -182.948912) (xy 14.037818 -183.50992) (xy 28.061412 -183.50992) (xy 28.061834 -183.471632)
			(xy 28.068459 -183.395341) (xy 28.08161 -183.319901) (xy 28.10119 -183.245869) (xy 28.113736 -183.209692)
			(xy 28.116366 -183.201251) (xy 28.116373 -183.183586) (xy 28.113736 -183.175148) (xy 28.101158 -183.138981)
			(xy 28.081567 -183.064949) (xy 28.068422 -182.989505) (xy 28.061819 -182.91321) (xy 28.061412 -182.87492)
			(xy 28.061834 -182.836632) (xy 28.068459 -182.760341) (xy 28.08161 -182.684901) (xy 28.10119 -182.610869)
			(xy 28.113736 -182.574692) (xy 28.116366 -182.566251) (xy 28.116373 -182.548586) (xy 28.113736 -182.540148)
			(xy 28.101158 -182.503981) (xy 28.081567 -182.429949) (xy 28.068422 -182.354505) (xy 28.061819 -182.27821)
			(xy 28.061412 -182.23992) (xy 28.061834 -182.201632) (xy 28.068459 -182.125341) (xy 28.08161 -182.049901)
			(xy 28.10119 -181.975869) (xy 28.113736 -181.939692) (xy 28.116366 -181.931251) (xy 28.116373 -181.913586)
			(xy 28.113736 -181.905148) (xy 28.101158 -181.868981) (xy 28.081567 -181.794949) (xy 28.068422 -181.719505)
			(xy 28.061819 -181.64321) (xy 28.061412 -181.60492) (xy 28.061871 -181.563817) (xy 28.069455 -181.48196)
			(xy 28.084559 -181.401153) (xy 28.107055 -181.322084) (xy 28.13675 -181.245428) (xy 28.173392 -181.171839)
			(xy 28.216668 -181.101945) (xy 28.266209 -181.036343) (xy 28.321591 -180.975591) (xy 28.382343 -180.920209)
			(xy 28.447945 -180.870668) (xy 28.517839 -180.827392) (xy 28.591428 -180.79075) (xy 28.668084 -180.761055)
			(xy 28.747153 -180.738559) (xy 28.82796 -180.723455) (xy 28.909817 -180.715871) (xy 28.95092 -180.715412)
			(xy 28.989208 -180.715851) (xy 29.065498 -180.722471) (xy 29.140938 -180.735617) (xy 29.21497 -180.755193)
			(xy 29.251148 -180.767736) (xy 29.259586 -180.770378) (xy 29.277254 -180.770378) (xy 29.285692 -180.767736)
			(xy 29.321865 -180.755175) (xy 29.395895 -180.735579) (xy 29.471337 -180.722429) (xy 29.54763 -180.715822)
			(xy 29.58592 -180.715412) (xy 29.624208 -180.715851) (xy 29.700498 -180.722471) (xy 29.775938 -180.735617)
			(xy 29.84997 -180.755193) (xy 29.886148 -180.767736) (xy 29.894586 -180.770378) (xy 29.912254 -180.770378)
			(xy 29.920692 -180.767736) (xy 29.956865 -180.755175) (xy 30.030895 -180.735579) (xy 30.106337 -180.722429)
			(xy 30.18263 -180.715822) (xy 30.22092 -180.715412) (xy 30.259208 -180.715851) (xy 30.335498 -180.722471)
			(xy 30.410938 -180.735617) (xy 30.48497 -180.755193) (xy 30.521148 -180.767736) (xy 30.529586 -180.770378)
			(xy 30.547254 -180.770378) (xy 30.555692 -180.767736) (xy 30.591865 -180.755175) (xy 30.665895 -180.735579)
			(xy 30.741337 -180.722429) (xy 30.81763 -180.715822) (xy 30.85592 -180.715412) (xy 30.894208 -180.715851)
			(xy 30.970498 -180.722471) (xy 31.045938 -180.735617) (xy 31.11997 -180.755193) (xy 31.156148 -180.767736)
			(xy 31.164586 -180.770378) (xy 31.182254 -180.770378) (xy 31.190692 -180.767736) (xy 31.226865 -180.755175)
			(xy 31.300895 -180.735579) (xy 31.376337 -180.722429) (xy 31.45263 -180.715822) (xy 31.49092 -180.715412)
			(xy 31.532023 -180.715848) (xy 31.613879 -180.723435) (xy 31.694686 -180.738542) (xy 31.773754 -180.761041)
			(xy 31.850409 -180.790739) (xy 31.923997 -180.827383) (xy 31.99389 -180.870661) (xy 32.059491 -180.920203)
			(xy 32.120241 -180.975587) (xy 32.175622 -181.03634) (xy 32.225162 -181.101943) (xy 32.268436 -181.171838)
			(xy 32.305077 -181.245427) (xy 32.334772 -181.322084) (xy 32.357267 -181.401153) (xy 32.372371 -181.48196)
			(xy 32.379954 -181.563817) (xy 32.380428 -181.60492) (xy 32.379986 -181.643208) (xy 32.373367 -181.719498)
			(xy 32.360221 -181.794938) (xy 32.340647 -181.86897) (xy 32.328104 -181.905148) (xy 32.325452 -181.913583)
			(xy 32.325459 -181.931254) (xy 32.328104 -181.939692) (xy 32.340667 -181.975864) (xy 32.360261 -182.049895)
			(xy 32.373411 -182.125337) (xy 32.380018 -182.20163) (xy 32.380428 -182.23992) (xy 32.379986 -182.278208)
			(xy 32.373367 -182.354498) (xy 32.360221 -182.429938) (xy 32.340647 -182.50397) (xy 32.328104 -182.540148)
			(xy 32.325452 -182.548583) (xy 32.325459 -182.566254) (xy 32.328104 -182.574692) (xy 32.340667 -182.610864)
			(xy 32.360261 -182.684895) (xy 32.373411 -182.760337) (xy 32.380018 -182.83663) (xy 32.380428 -182.87492)
			(xy 32.379986 -182.913208) (xy 32.373367 -182.989498) (xy 32.360221 -183.064938) (xy 32.340647 -183.13897)
			(xy 32.328104 -183.175148) (xy 32.325452 -183.183583) (xy 32.325459 -183.201254) (xy 32.328104 -183.209692)
			(xy 32.340667 -183.245864) (xy 32.360261 -183.319895) (xy 32.373411 -183.395337) (xy 32.380018 -183.47163)
			(xy 32.380428 -183.50992) (xy 32.379952 -183.551022) (xy 32.372366 -183.632876) (xy 32.35726 -183.71368)
			(xy 32.334762 -183.792746) (xy 32.305065 -183.8694) (xy 32.268423 -183.942986) (xy 32.225148 -184.012877)
			(xy 32.175608 -184.078477) (xy 32.120227 -184.139227) (xy 32.059477 -184.194608) (xy 31.993877 -184.244148)
			(xy 31.923986 -184.287423) (xy 31.8504 -184.324065) (xy 31.773746 -184.353762) (xy 31.69468 -184.37626)
			(xy 31.613876 -184.391366) (xy 31.532022 -184.398952) (xy 31.49092 -184.399428) (xy 31.452632 -184.399004)
			(xy 31.376341 -184.392379) (xy 31.300901 -184.379229) (xy 31.226869 -184.359649) (xy 31.190692 -184.347104)
			(xy 31.182254 -184.344462) (xy 31.164586 -184.344462) (xy 31.156148 -184.347104) (xy 31.119981 -184.359684)
			(xy 31.045949 -184.379274) (xy 30.970505 -184.392419) (xy 30.89421 -184.399021) (xy 30.85592 -184.399428)
			(xy 30.817632 -184.399004) (xy 30.741341 -184.392379) (xy 30.665901 -184.379229) (xy 30.591869 -184.359649)
			(xy 30.555692 -184.347104) (xy 30.547254 -184.344462) (xy 30.529586 -184.344462) (xy 30.521148 -184.347104)
			(xy 30.484981 -184.359684) (xy 30.410949 -184.379274) (xy 30.335505 -184.392419) (xy 30.25921 -184.399021)
			(xy 30.22092 -184.399428) (xy 30.182632 -184.399004) (xy 30.106341 -184.392379) (xy 30.030901 -184.379229)
			(xy 29.956869 -184.359649) (xy 29.920692 -184.347104) (xy 29.912254 -184.344462) (xy 29.894586 -184.344462)
			(xy 29.886148 -184.347104) (xy 29.849981 -184.359684) (xy 29.775949 -184.379274) (xy 29.700505 -184.392419)
			(xy 29.62421 -184.399021) (xy 29.58592 -184.399428) (xy 29.547632 -184.399004) (xy 29.471341 -184.392379)
			(xy 29.395901 -184.379229) (xy 29.321869 -184.359649) (xy 29.285692 -184.347104) (xy 29.277254 -184.344462)
			(xy 29.259586 -184.344462) (xy 29.251148 -184.347104) (xy 29.214981 -184.359684) (xy 29.140949 -184.379274)
			(xy 29.065505 -184.392419) (xy 28.98921 -184.399021) (xy 28.95092 -184.399428) (xy 28.909818 -184.398914)
			(xy 28.827966 -184.391331) (xy 28.747162 -184.376228) (xy 28.668096 -184.353734) (xy 28.591444 -184.324041)
			(xy 28.517857 -184.287401) (xy 28.447966 -184.244129) (xy 28.382365 -184.194592) (xy 28.321615 -184.139213)
			(xy 28.266234 -184.078465) (xy 28.216694 -184.012867) (xy 28.173418 -183.942977) (xy 28.136775 -183.869393)
			(xy 28.107078 -183.792742) (xy 28.084581 -183.713677) (xy 28.069474 -183.632874) (xy 28.061888 -183.551022)
			(xy 28.061412 -183.50992) (xy 14.037818 -183.50992) (xy 14.037818 -186.58535) (xy 17.790174 -186.58535)
			(xy 17.794166 -186.496463) (xy 17.80611 -186.408292) (xy 17.825909 -186.321547) (xy 17.853404 -186.236926)
			(xy 17.888374 -186.15511) (xy 17.930537 -186.076757) (xy 17.979553 -186.0025) (xy 18.035029 -185.932936)
			(xy 18.096517 -185.868624) (xy 18.163522 -185.810083) (xy 18.235505 -185.757784) (xy 18.311887 -185.712148)
			(xy 18.392051 -185.673542) (xy 18.475354 -185.642278) (xy 18.561124 -185.618607) (xy 18.64867 -185.602719)
			(xy 18.737288 -185.594743) (xy 18.781776 -185.594244) (xy 20.534376 -185.594244) (xy 20.578865 -185.594724)
			(xy 20.667485 -185.6027) (xy 20.755034 -185.618587) (xy 20.840806 -185.642259) (xy 20.92411 -185.673523)
			(xy 21.004277 -185.712129) (xy 21.080661 -185.757766) (xy 21.152646 -185.810066) (xy 21.219653 -185.868608)
			(xy 21.281143 -185.932921) (xy 21.33662 -186.002487) (xy 21.385638 -186.076746) (xy 21.427802 -186.155099)
			(xy 21.462773 -186.236917) (xy 21.490269 -186.321541) (xy 21.510068 -186.408288) (xy 21.522012 -186.496461)
			(xy 21.526004 -186.58535) (xy 25.334225 -186.58535) (xy 25.338216 -186.496463) (xy 25.35016 -186.408292)
			(xy 25.369959 -186.321546) (xy 25.397454 -186.236925) (xy 25.432424 -186.155108) (xy 25.474587 -186.076756)
			(xy 25.523604 -186.002499) (xy 25.57908 -185.932934) (xy 25.640568 -185.868623) (xy 25.707574 -185.810082)
			(xy 25.779558 -185.757783) (xy 25.855939 -185.712147) (xy 25.936104 -185.673541) (xy 26.019407 -185.642277)
			(xy 26.105177 -185.618606) (xy 26.192724 -185.602719) (xy 26.281342 -185.594743) (xy 26.32583 -185.594244)
			(xy 28.07843 -185.594244) (xy 28.122918 -185.594739) (xy 28.211537 -185.602715) (xy 28.299084 -185.618602)
			(xy 28.384854 -185.642273) (xy 28.468157 -185.673538) (xy 28.548323 -185.712143) (xy 28.624705 -185.757779)
			(xy 28.696688 -185.810078) (xy 28.763694 -185.86862) (xy 28.825183 -185.932932) (xy 28.880659 -186.002497)
			(xy 28.929676 -186.076754) (xy 28.971839 -186.155107) (xy 29.006809 -186.236923) (xy 29.034305 -186.321545)
			(xy 29.054104 -186.408291) (xy 29.066048 -186.496463) (xy 29.07004 -186.58535) (xy 32.878025 -186.58535)
			(xy 32.882016 -186.496463) (xy 32.89396 -186.408292) (xy 32.913759 -186.321546) (xy 32.941254 -186.236925)
			(xy 32.976224 -186.155108) (xy 33.018387 -186.076756) (xy 33.067404 -186.002499) (xy 33.12288 -185.932934)
			(xy 33.184368 -185.868623) (xy 33.251374 -185.810082) (xy 33.323358 -185.757783) (xy 33.399739 -185.712147)
			(xy 33.479904 -185.673541) (xy 33.563207 -185.642277) (xy 33.648977 -185.618606) (xy 33.736524 -185.602719)
			(xy 33.825142 -185.594743) (xy 33.86963 -185.594244) (xy 35.62223 -185.594244) (xy 35.666718 -185.594739)
			(xy 35.755337 -185.602715) (xy 35.842884 -185.618602) (xy 35.928654 -185.642273) (xy 36.011957 -185.673538)
			(xy 36.092123 -185.712143) (xy 36.168505 -185.757779) (xy 36.240488 -185.810078) (xy 36.307494 -185.86862)
			(xy 36.368983 -185.932932) (xy 36.424459 -186.002497) (xy 36.473476 -186.076754) (xy 36.515639 -186.155107)
			(xy 36.550609 -186.236923) (xy 36.578105 -186.321545) (xy 36.597904 -186.408291) (xy 36.609848 -186.496463)
			(xy 36.61384 -186.58535) (xy 40.42206 -186.58535) (xy 40.426052 -186.496462) (xy 40.437996 -186.408289)
			(xy 40.457795 -186.321542) (xy 40.485291 -186.236919) (xy 40.520262 -186.155101) (xy 40.562426 -186.076748)
			(xy 40.611444 -186.002489) (xy 40.66692 -185.932923) (xy 40.72841 -185.868611) (xy 40.795417 -185.810069)
			(xy 40.867402 -185.757769) (xy 40.943785 -185.712133) (xy 41.023951 -185.673527) (xy 41.107256 -185.642262)
			(xy 41.193027 -185.618591) (xy 41.280575 -185.602704) (xy 41.369195 -185.594728) (xy 41.413684 -185.594244)
			(xy 43.166284 -185.594244) (xy 43.210772 -185.594739) (xy 43.299391 -185.602715) (xy 43.386937 -185.618603)
			(xy 43.472707 -185.642274) (xy 43.55601 -185.673539) (xy 43.636175 -185.712144) (xy 43.712557 -185.757781)
			(xy 43.78454 -185.81008) (xy 43.851546 -185.868621) (xy 43.913034 -185.932933) (xy 43.96851 -186.002498)
			(xy 44.017527 -186.076755) (xy 44.05969 -186.155108) (xy 44.09466 -186.236924) (xy 44.122155 -186.321546)
			(xy 44.141954 -186.408292) (xy 44.153898 -186.496463) (xy 44.15789 -186.58535) (xy 44.153898 -186.674237)
			(xy 44.141954 -186.762408) (xy 44.122155 -186.849154) (xy 44.09466 -186.933776) (xy 44.05969 -187.015592)
			(xy 44.017527 -187.093945) (xy 43.96851 -187.168202) (xy 43.913034 -187.237767) (xy 43.851546 -187.302079)
			(xy 43.78454 -187.36062) (xy 43.712557 -187.412919) (xy 43.636175 -187.458556) (xy 43.55601 -187.497161)
			(xy 43.472707 -187.528426) (xy 43.386937 -187.552097) (xy 43.299391 -187.567985) (xy 43.210772 -187.575961)
			(xy 43.166284 -187.57646) (xy 41.413684 -187.57646) (xy 41.369195 -187.575972) (xy 41.280575 -187.567996)
			(xy 41.193027 -187.552109) (xy 41.107256 -187.528438) (xy 41.023951 -187.497173) (xy 40.943785 -187.458567)
			(xy 40.867402 -187.412931) (xy 40.795417 -187.360631) (xy 40.72841 -187.302089) (xy 40.66692 -187.237777)
			(xy 40.611444 -187.168211) (xy 40.562426 -187.093952) (xy 40.520262 -187.015599) (xy 40.485291 -186.933781)
			(xy 40.457795 -186.849158) (xy 40.437996 -186.762411) (xy 40.426052 -186.674238) (xy 40.42206 -186.58535)
			(xy 36.61384 -186.58535) (xy 36.609848 -186.674237) (xy 36.597904 -186.762409) (xy 36.578105 -186.849155)
			(xy 36.550609 -186.933777) (xy 36.515639 -187.015593) (xy 36.473476 -187.093946) (xy 36.424459 -187.168203)
			(xy 36.368983 -187.237768) (xy 36.307494 -187.30208) (xy 36.240488 -187.360622) (xy 36.168505 -187.412921)
			(xy 36.092123 -187.458557) (xy 36.011957 -187.497162) (xy 35.928654 -187.528427) (xy 35.842884 -187.552098)
			(xy 35.755337 -187.567985) (xy 35.666718 -187.575961) (xy 35.62223 -187.57646) (xy 33.86963 -187.57646)
			(xy 33.825142 -187.575957) (xy 33.736524 -187.567981) (xy 33.648977 -187.552094) (xy 33.563207 -187.528423)
			(xy 33.479904 -187.497159) (xy 33.399739 -187.458553) (xy 33.323358 -187.412917) (xy 33.251374 -187.360618)
			(xy 33.184368 -187.302077) (xy 33.12288 -187.237766) (xy 33.067404 -187.168201) (xy 33.018387 -187.093944)
			(xy 32.976224 -187.015592) (xy 32.941254 -186.933775) (xy 32.913759 -186.849154) (xy 32.89396 -186.762408)
			(xy 32.882016 -186.674237) (xy 32.878025 -186.58535) (xy 29.07004 -186.58535) (xy 29.066048 -186.674237)
			(xy 29.054104 -186.762409) (xy 29.034305 -186.849155) (xy 29.006809 -186.933777) (xy 28.971839 -187.015593)
			(xy 28.929676 -187.093946) (xy 28.880659 -187.168203) (xy 28.825183 -187.237768) (xy 28.763694 -187.30208)
			(xy 28.696688 -187.360622) (xy 28.624705 -187.412921) (xy 28.548323 -187.458557) (xy 28.468157 -187.497162)
			(xy 28.384854 -187.528427) (xy 28.299084 -187.552098) (xy 28.211537 -187.567985) (xy 28.122918 -187.575961)
			(xy 28.07843 -187.57646) (xy 26.32583 -187.57646) (xy 26.281342 -187.575957) (xy 26.192724 -187.567981)
			(xy 26.105177 -187.552094) (xy 26.019407 -187.528423) (xy 25.936104 -187.497159) (xy 25.855939 -187.458553)
			(xy 25.779558 -187.412917) (xy 25.707574 -187.360618) (xy 25.640568 -187.302077) (xy 25.57908 -187.237766)
			(xy 25.523604 -187.168201) (xy 25.474587 -187.093944) (xy 25.432424 -187.015592) (xy 25.397454 -186.933775)
			(xy 25.369959 -186.849154) (xy 25.35016 -186.762408) (xy 25.338216 -186.674237) (xy 25.334225 -186.58535)
			(xy 21.526004 -186.58535) (xy 21.522012 -186.674239) (xy 21.510068 -186.762412) (xy 21.490269 -186.849159)
			(xy 21.462773 -186.933783) (xy 21.427802 -187.015601) (xy 21.385638 -187.093954) (xy 21.33662 -187.168213)
			(xy 21.281143 -187.237779) (xy 21.219653 -187.302092) (xy 21.152646 -187.360634) (xy 21.080661 -187.412934)
			(xy 21.004277 -187.458571) (xy 20.92411 -187.497177) (xy 20.840806 -187.528441) (xy 20.755034 -187.552113)
			(xy 20.667485 -187.568) (xy 20.578865 -187.575976) (xy 20.534376 -187.57646) (xy 18.781776 -187.57646)
			(xy 18.737288 -187.575957) (xy 18.64867 -187.567981) (xy 18.561124 -187.552093) (xy 18.475354 -187.528422)
			(xy 18.392051 -187.497158) (xy 18.311887 -187.458552) (xy 18.235505 -187.412916) (xy 18.163522 -187.360617)
			(xy 18.096517 -187.302076) (xy 18.035029 -187.237764) (xy 17.979553 -187.1682) (xy 17.930537 -187.093943)
			(xy 17.888374 -187.01559) (xy 17.853404 -186.933774) (xy 17.825909 -186.849153) (xy 17.80611 -186.762408)
			(xy 17.794166 -186.674237) (xy 17.790174 -186.58535) (xy 14.037818 -186.58535) (xy 14.037818 -193.085212)
			(xy 15.588234 -193.085212) (xy 15.588742 -193.043487) (xy 15.596712 -192.960419) (xy 15.612533 -192.878483)
			(xy 15.636063 -192.798419) (xy 15.667089 -192.720951) (xy 15.68577 -192.683638) (xy 15.690774 -192.672482)
			(xy 15.690761 -192.648066) (xy 15.68577 -192.636902) (xy 15.667085 -192.59959) (xy 15.63604 -192.522128)
			(xy 15.612502 -192.442064) (xy 15.596683 -192.360125) (xy 15.588726 -192.277054) (xy 15.588234 -192.235328)
			(xy 15.588731 -192.193584) (xy 15.596667 -192.110474) (xy 15.612467 -192.028496) (xy 15.635988 -191.94839)
			(xy 15.667017 -191.870882) (xy 15.705274 -191.796676) (xy 15.75041 -191.726441) (xy 15.802019 -191.660815)
			(xy 15.859632 -191.600393) (xy 15.922728 -191.54572) (xy 15.990735 -191.497292) (xy 16.063038 -191.455548)
			(xy 16.138981 -191.420866) (xy 16.217877 -191.39356) (xy 16.299011 -191.373877) (xy 16.381649 -191.361996)
			(xy 16.465042 -191.358023) (xy 16.548435 -191.361996) (xy 16.631073 -191.373877) (xy 16.712207 -191.39356)
			(xy 16.791103 -191.420866) (xy 16.867046 -191.455548) (xy 16.939349 -191.497292) (xy 17.007356 -191.54572)
			(xy 17.070452 -191.600393) (xy 17.128065 -191.660815) (xy 17.179674 -191.726441) (xy 17.22481 -191.796676)
			(xy 17.263067 -191.870882) (xy 17.294096 -191.94839) (xy 17.317617 -192.028496) (xy 17.333417 -192.110474)
			(xy 17.341353 -192.193584) (xy 17.34165 -192.218564) (xy 18.394187 -192.218564) (xy 18.398125 -192.164756)
			(xy 18.409855 -192.112095) (xy 18.429129 -192.061704) (xy 18.455534 -192.014655) (xy 18.488507 -191.971953)
			(xy 18.527347 -191.934506) (xy 18.571226 -191.903114) (xy 18.619207 -191.878445) (xy 18.670269 -191.861025)
			(xy 18.723323 -191.851225) (xy 18.777239 -191.849255) (xy 18.830867 -191.855156) (xy 18.883064 -191.868802)
			(xy 18.932718 -191.889903) (xy 18.978771 -191.918008) (xy 19.020241 -191.95252) (xy 19.056244 -191.992701)
			(xy 19.086013 -192.037697) (xy 19.108913 -192.086547) (xy 19.124456 -192.138211) (xy 19.132312 -192.191588)
			(xy 19.132804 -192.218564) (xy 20.182855 -192.218564) (xy 20.186793 -192.164756) (xy 20.198523 -192.112095)
			(xy 20.217797 -192.061704) (xy 20.244202 -192.014655) (xy 20.277175 -191.971953) (xy 20.316015 -191.934506)
			(xy 20.359894 -191.903114) (xy 20.407875 -191.878445) (xy 20.458937 -191.861025) (xy 20.511991 -191.851225)
			(xy 20.565907 -191.849255) (xy 20.619535 -191.855156) (xy 20.671732 -191.868802) (xy 20.721386 -191.889903)
			(xy 20.767439 -191.918008) (xy 20.808909 -191.95252) (xy 20.844912 -191.992701) (xy 20.874681 -192.037697)
			(xy 20.897581 -192.086547) (xy 20.913124 -192.138211) (xy 20.92098 -192.191588) (xy 20.921472 -192.218564)
			(xy 20.92098 -192.24554) (xy 20.913124 -192.298917) (xy 20.897581 -192.350581) (xy 20.874681 -192.399431)
			(xy 20.844912 -192.444427) (xy 20.808909 -192.484608) (xy 20.767439 -192.51912) (xy 20.721386 -192.547225)
			(xy 20.671732 -192.568326) (xy 20.619535 -192.581972) (xy 20.565907 -192.587873) (xy 20.511991 -192.585903)
			(xy 20.458937 -192.576103) (xy 20.407875 -192.558683) (xy 20.359894 -192.534014) (xy 20.316015 -192.502622)
			(xy 20.277175 -192.465175) (xy 20.244202 -192.422473) (xy 20.217797 -192.375424) (xy 20.198523 -192.325033)
			(xy 20.186793 -192.272372) (xy 20.182855 -192.218564) (xy 19.132804 -192.218564) (xy 19.132312 -192.24554)
			(xy 19.124456 -192.298917) (xy 19.108913 -192.350581) (xy 19.086013 -192.399431) (xy 19.056244 -192.444427)
			(xy 19.020241 -192.484608) (xy 18.978771 -192.51912) (xy 18.932718 -192.547225) (xy 18.883064 -192.568326)
			(xy 18.830867 -192.581972) (xy 18.777239 -192.587873) (xy 18.723323 -192.585903) (xy 18.670269 -192.576103)
			(xy 18.619207 -192.558683) (xy 18.571226 -192.534014) (xy 18.527347 -192.502622) (xy 18.488507 -192.465175)
			(xy 18.455534 -192.422473) (xy 18.429129 -192.375424) (xy 18.409855 -192.325033) (xy 18.398125 -192.272372)
			(xy 18.394187 -192.218564) (xy 17.34165 -192.218564) (xy 17.34185 -192.235328) (xy 17.341308 -192.277052)
			(xy 17.333345 -192.360119) (xy 17.31753 -192.442055) (xy 17.294008 -192.522119) (xy 17.262991 -192.599588)
			(xy 17.244314 -192.636902) (xy 17.239351 -192.648072) (xy 17.239338 -192.672475) (xy 17.244314 -192.683638)
			(xy 17.263013 -192.720943) (xy 17.294055 -192.798408) (xy 17.31759 -192.878473) (xy 17.333406 -192.960413)
			(xy 17.341359 -193.043486) (xy 17.34185 -193.085212) (xy 17.341584 -193.107564) (xy 18.394187 -193.107564)
			(xy 18.398125 -193.053756) (xy 18.409855 -193.001095) (xy 18.429129 -192.950704) (xy 18.455534 -192.903655)
			(xy 18.488507 -192.860953) (xy 18.527347 -192.823506) (xy 18.571226 -192.792114) (xy 18.619207 -192.767445)
			(xy 18.670269 -192.750025) (xy 18.723323 -192.740225) (xy 18.777239 -192.738255) (xy 18.830867 -192.744156)
			(xy 18.883064 -192.757802) (xy 18.932718 -192.778903) (xy 18.978771 -192.807008) (xy 19.020241 -192.84152)
			(xy 19.056244 -192.881701) (xy 19.086013 -192.926697) (xy 19.108913 -192.975547) (xy 19.124456 -193.027211)
			(xy 19.132312 -193.080588) (xy 19.132804 -193.107564) (xy 19.132312 -193.13454) (xy 19.124456 -193.187917)
			(xy 19.108913 -193.239581) (xy 19.086013 -193.288431) (xy 19.056244 -193.333427) (xy 19.020241 -193.373608)
			(xy 18.978771 -193.40812) (xy 18.932718 -193.436225) (xy 18.883064 -193.457326) (xy 18.830867 -193.470972)
			(xy 18.777239 -193.476873) (xy 18.723323 -193.474903) (xy 18.670269 -193.465103) (xy 18.619207 -193.447683)
			(xy 18.571226 -193.423014) (xy 18.527347 -193.391622) (xy 18.488507 -193.354175) (xy 18.455534 -193.311473)
			(xy 18.429129 -193.264424) (xy 18.409855 -193.214033) (xy 18.398125 -193.161372) (xy 18.394187 -193.107564)
			(xy 17.341584 -193.107564) (xy 17.341353 -193.126956) (xy 17.333417 -193.210066) (xy 17.317617 -193.292044)
			(xy 17.294096 -193.37215) (xy 17.263067 -193.449658) (xy 17.22481 -193.523865) (xy 17.179674 -193.594099)
			(xy 17.128065 -193.659725) (xy 17.070452 -193.720147) (xy 17.007356 -193.77482) (xy 16.939349 -193.823248)
			(xy 16.867046 -193.864992) (xy 16.791103 -193.899674) (xy 16.712207 -193.92698) (xy 16.631073 -193.946663)
			(xy 16.548435 -193.958544) (xy 16.465042 -193.962517) (xy 16.381649 -193.958544) (xy 16.299011 -193.946663)
			(xy 16.217877 -193.92698) (xy 16.138981 -193.899674) (xy 16.063038 -193.864992) (xy 15.990735 -193.823248)
			(xy 15.922728 -193.77482) (xy 15.859632 -193.720147) (xy 15.802019 -193.659725) (xy 15.75041 -193.594099)
			(xy 15.705274 -193.523865) (xy 15.667017 -193.449658) (xy 15.635988 -193.37215) (xy 15.612467 -193.292044)
			(xy 15.596667 -193.210066) (xy 15.588731 -193.126956) (xy 15.588234 -193.085212) (xy 14.037818 -193.085212)
			(xy 14.037818 -193.342006) (xy 14.038243 -193.352075) (xy 14.045961 -193.370677) (xy 14.052804 -193.378074)
			(xy 14.671294 -193.996564) (xy 20.182855 -193.996564) (xy 20.186793 -193.942756) (xy 20.198523 -193.890095)
			(xy 20.217797 -193.839704) (xy 20.244202 -193.792655) (xy 20.277175 -193.749953) (xy 20.316015 -193.712506)
			(xy 20.359894 -193.681114) (xy 20.407875 -193.656445) (xy 20.458937 -193.639025) (xy 20.511991 -193.629225)
			(xy 20.565907 -193.627255) (xy 20.619535 -193.633156) (xy 20.671732 -193.646802) (xy 20.721386 -193.667903)
			(xy 20.767439 -193.696008) (xy 20.808909 -193.73052) (xy 20.844912 -193.770701) (xy 20.874681 -193.815697)
			(xy 20.897581 -193.864547) (xy 20.913124 -193.916211) (xy 20.92098 -193.969588) (xy 20.921472 -193.996564)
			(xy 20.92098 -194.02354) (xy 20.913124 -194.076917) (xy 20.897581 -194.128581) (xy 20.874681 -194.177431)
			(xy 20.844912 -194.222427) (xy 20.808909 -194.262608) (xy 20.767439 -194.29712) (xy 20.721386 -194.325225)
			(xy 20.671732 -194.346326) (xy 20.619535 -194.359972) (xy 20.565907 -194.365873) (xy 20.511991 -194.363903)
			(xy 20.458937 -194.354103) (xy 20.407875 -194.336683) (xy 20.359894 -194.312014) (xy 20.316015 -194.280622)
			(xy 20.277175 -194.243175) (xy 20.244202 -194.200473) (xy 20.217797 -194.153424) (xy 20.198523 -194.103033)
			(xy 20.186793 -194.050372) (xy 20.182855 -193.996564) (xy 14.671294 -193.996564) (xy 15.494508 -194.819778)
			(xy 15.501906 -194.826625) (xy 15.520504 -194.83436) (xy 15.530576 -194.834764) (xy 15.546324 -194.834764)
			(xy 15.552928 -194.832986) (xy 15.577116 -194.82694) (xy 15.626551 -194.820446) (xy 15.65148 -194.820032)
			(xy 15.678733 -194.820494) (xy 15.732684 -194.828249) (xy 15.784982 -194.843604) (xy 15.834562 -194.866245)
			(xy 15.880415 -194.895714) (xy 15.90798 -194.9196) (xy 20.170138 -194.9196) (xy 20.174211 -194.863941)
			(xy 20.186346 -194.809468) (xy 20.206282 -194.757342) (xy 20.233596 -194.708674) (xy 20.267704 -194.664502)
			(xy 20.307881 -194.625767) (xy 20.353269 -194.593295) (xy 20.402901 -194.567777) (xy 20.455721 -194.549758)
			(xy 20.5106 -194.539621) (xy 20.566371 -194.537583) (xy 20.621845 -194.543686) (xy 20.675838 -194.557802)
			(xy 20.727201 -194.579629) (xy 20.774839 -194.608702) (xy 20.817735 -194.644401) (xy 20.854977 -194.685965)
			(xy 20.885771 -194.732509) (xy 20.909459 -194.78304) (xy 20.925537 -194.836482) (xy 20.933663 -194.891696)
			(xy 20.934172 -194.9196) (xy 20.933663 -194.947504) (xy 20.925537 -195.002718) (xy 20.909459 -195.05616)
			(xy 20.885771 -195.106691) (xy 20.854977 -195.153235) (xy 20.817735 -195.194799) (xy 20.774839 -195.230498)
			(xy 20.727201 -195.259571) (xy 20.675838 -195.281398) (xy 20.621845 -195.295514) (xy 20.566371 -195.301617)
			(xy 20.5106 -195.299579) (xy 20.455721 -195.289442) (xy 20.402901 -195.271423) (xy 20.353269 -195.245905)
			(xy 20.307881 -195.213433) (xy 20.267704 -195.174698) (xy 20.233596 -195.130526) (xy 20.206282 -195.081858)
			(xy 20.186346 -195.029732) (xy 20.174211 -194.975259) (xy 20.170138 -194.9196) (xy 15.90798 -194.9196)
			(xy 15.921606 -194.931408) (xy 15.957298 -194.972602) (xy 15.986764 -195.018456) (xy 16.009403 -195.068037)
			(xy 16.024755 -195.120336) (xy 16.032507 -195.174287) (xy 16.032988 -195.20154) (xy 16.032549 -195.228121)
			(xy 16.025151 -195.280767) (xy 16.018256 -195.306442) (xy 16.018256 -195.306696) (xy 16.016105 -195.315474)
			(xy 16.017468 -195.333483) (xy 16.025038 -195.34988) (xy 16.03121 -195.35648) (xy 16.66621 -195.99148)
			(xy 16.673608 -195.998327) (xy 16.692206 -196.006061) (xy 16.702278 -196.006466)
		)
		(stroke
			(width 0)
			(type solid)
		)
		(fill yes)
		(layer "In4.Cu")
		(net "P3V3")
	)
	(gr_poly
		(pts
			(xy 302.961548 -401.160488) (xy 302.971614 -401.160056) (xy 302.990205 -401.152328) (xy 302.997616 -401.145502)
			(xy 303.431702 -400.711416) (xy 303.438535 -400.704013) (xy 303.446238 -400.685415) (xy 303.446688 -400.675348)
			(xy 303.446688 -399.657824) (xy 303.444656 -399.650712) (xy 303.423578 -399.578538) (xy 303.387181 -399.432635)
			(xy 303.357423 -399.285234) (xy 303.334363 -399.136638) (xy 303.325784 -399.06194) (xy 303.325784 -399.061432)
			(xy 303.320255 -399.006737) (xy 303.314412 -398.896948) (xy 303.3141 -398.841976) (xy 303.3141 -398.837404)
			(xy 303.289888 -398.830615) (xy 303.24393 -398.810216) (xy 303.201941 -398.782552) (xy 303.165061 -398.748375)
			(xy 303.134287 -398.70861) (xy 303.110455 -398.664335) (xy 303.09421 -398.616749) (xy 303.085993 -398.567143)
			(xy 303.0855 -398.542002) (xy 303.085565 -398.530529) (xy 303.087217 -398.507645) (xy 303.088802 -398.496282)
			(xy 303.089718 -398.487961) (xy 303.086725 -398.471502) (xy 303.08296 -398.464024) (xy 303.063113 -398.427317)
			(xy 303.028954 -398.351175) (xy 303.001335 -398.272425) (xy 302.980452 -398.191627) (xy 302.966453 -398.109356)
			(xy 302.959438 -398.026199) (xy 302.959008 -397.984472) (xy 302.959008 -397.868648) (xy 302.959508 -397.824281)
			(xy 302.967361 -397.735896) (xy 302.982986 -397.648548) (xy 303.006258 -397.562921) (xy 303.036997 -397.479681)
			(xy 303.074963 -397.39948) (xy 303.119859 -397.322942) (xy 303.171336 -397.250666) (xy 303.1998 -397.21663)
			(xy 303.205694 -397.209128) (xy 303.211953 -397.191119) (xy 303.211992 -397.181578) (xy 303.211484 -397.156432)
			(xy 303.211887 -397.125903) (xy 303.218329 -397.065186) (xy 303.231126 -397.005484) (xy 303.250133 -396.94746)
			(xy 303.262284 -396.91945) (xy 303.266765 -396.907783) (xy 303.265047 -396.882878) (xy 303.258982 -396.871952)
			(xy 303.244637 -396.847606) (xy 303.224162 -396.794945) (xy 303.213704 -396.73942) (xy 303.213008 -396.71117)
			(xy 303.213008 -396.710662) (xy 303.213508 -396.685264) (xy 303.221908 -396.635168) (xy 303.238486 -396.587153)
			(xy 303.262784 -396.542547) (xy 303.294133 -396.502578) (xy 303.312576 -396.48511) (xy 303.320374 -396.477378)
			(xy 303.329041 -396.457228) (xy 303.32934 -396.446248) (xy 303.327054 -396.36954) (xy 303.326312 -396.35856)
			(xy 303.316703 -396.338788) (xy 303.308512 -396.33144) (xy 303.28995 -396.315638) (xy 303.257222 -396.279512)
			(xy 303.230149 -396.238975) (xy 303.209315 -396.194905) (xy 303.195172 -396.148255) (xy 303.188026 -396.100035)
			(xy 303.187608 -396.075662) (xy 303.188047 -396.051546) (xy 303.195053 -396.003826) (xy 303.20891 -395.957628)
			(xy 303.229326 -395.91393) (xy 303.242218 -395.893544) (xy 303.24806 -395.884908) (xy 303.251616 -395.864588)
			(xy 303.23282 -395.782546) (xy 303.230105 -395.772615) (xy 303.218048 -395.755952) (xy 303.209452 -395.750288)
			(xy 303.18865 -395.737433) (xy 303.150733 -395.706554) (xy 303.117782 -395.670423) (xy 303.090518 -395.62983)
			(xy 303.069536 -395.58566) (xy 303.055296 -395.53888) (xy 303.048107 -395.490512) (xy 303.047654 -395.466062)
			(xy 303.048247 -395.438771) (xy 303.05727 -395.384939) (xy 303.074998 -395.333315) (xy 303.100952 -395.285297)
			(xy 303.134429 -395.242186) (xy 303.15408 -395.223238) (xy 303.161463 -395.215719) (xy 303.169881 -395.196426)
			(xy 303.170336 -395.1859) (xy 303.170336 -395.111224) (xy 303.169815 -395.10071) (xy 303.161427 -395.081424)
			(xy 303.15408 -395.073886) (xy 303.134355 -395.055002) (xy 303.10082 -395.011907) (xy 303.07484 -394.963879)
			(xy 303.057123 -394.912228) (xy 303.048154 -394.858365) (xy 303.047654 -394.831062) (xy 303.047654 -394.830808)
			(xy 303.0481 -394.807179) (xy 303.054867 -394.760407) (xy 303.068206 -394.715069) (xy 303.077626 -394.693394)
			(xy 303.081475 -394.684055) (xy 303.082263 -394.663887) (xy 303.07915 -394.654278) (xy 303.050448 -394.577316)
			(xy 303.036732 -394.562584) (xy 303.027334 -394.55852) (xy 303.002966 -394.546826) (xy 302.958084 -394.516714)
			(xy 302.918698 -394.479703) (xy 302.885857 -394.436777) (xy 302.860437 -394.389081) (xy 302.843114 -394.337886)
			(xy 302.834349 -394.284554) (xy 302.833786 -394.25753) (xy 302.834296 -394.231543) (xy 302.842426 -394.180208)
			(xy 302.858487 -394.130778) (xy 302.882083 -394.084468) (xy 302.912633 -394.04242) (xy 302.949384 -394.005669)
			(xy 302.991432 -393.975119) (xy 303.037742 -393.951523) (xy 303.087172 -393.935462) (xy 303.138507 -393.927332)
			(xy 303.190481 -393.927332) (xy 303.241816 -393.935462) (xy 303.291246 -393.951523) (xy 303.337556 -393.975119)
			(xy 303.379604 -394.005669) (xy 303.416355 -394.04242) (xy 303.446905 -394.084468) (xy 303.470501 -394.130778)
			(xy 303.486562 -394.180208) (xy 303.494692 -394.231543) (xy 303.495202 -394.25753) (xy 303.495202 -394.257784)
			(xy 303.494756 -394.281413) (xy 303.487992 -394.328186) (xy 303.474656 -394.373525) (xy 303.46523 -394.395198)
			(xy 303.461376 -394.404536) (xy 303.460585 -394.424707) (xy 303.463706 -394.434314) (xy 303.492408 -394.511276)
			(xy 303.506124 -394.526008) (xy 303.515522 -394.530072) (xy 303.539893 -394.541764) (xy 303.584781 -394.571872)
			(xy 303.624173 -394.608882) (xy 303.657019 -394.651807) (xy 303.682445 -394.699504) (xy 303.699772 -394.750702)
			(xy 303.708539 -394.804037) (xy 303.70907 -394.831062) (xy 303.708483 -394.858356) (xy 303.699472 -394.912195)
			(xy 303.681753 -394.963828) (xy 303.655807 -395.011856) (xy 303.622336 -395.054979) (xy 303.602644 -395.073886)
			(xy 303.595274 -395.081411) (xy 303.586878 -395.100702) (xy 303.586388 -395.111224) (xy 303.586388 -395.1859)
			(xy 303.586915 -395.196412) (xy 303.595311 -395.215687) (xy 303.602644 -395.223238) (xy 303.622367 -395.242124)
			(xy 303.655896 -395.28522) (xy 303.681871 -395.333248) (xy 303.699582 -395.384899) (xy 303.708547 -395.43876)
			(xy 303.70907 -395.466062) (xy 303.708637 -395.490179) (xy 303.70164 -395.537904) (xy 303.687791 -395.584108)
			(xy 303.667381 -395.627812) (xy 303.65446 -395.64818) (xy 303.648618 -395.656816) (xy 303.645062 -395.677136)
			(xy 303.663858 -395.759178) (xy 303.666575 -395.769108) (xy 303.678633 -395.785768) (xy 303.687226 -395.791436)
			(xy 303.708028 -395.804291) (xy 303.745945 -395.835169) (xy 303.778895 -395.8713) (xy 303.806158 -395.911893)
			(xy 303.827139 -395.956063) (xy 303.841377 -396.002844) (xy 303.848563 -396.051212) (xy 303.849024 -396.075662)
			(xy 303.848515 -396.101796) (xy 303.840258 -396.15341) (xy 303.823976 -396.203078) (xy 303.812448 -396.226538)
			(xy 303.808823 -396.234399) (xy 303.806526 -396.251547) (xy 303.810048 -396.268485) (xy 303.814226 -396.276068)
			(xy 303.859692 -396.350236) (xy 303.864488 -396.357452) (xy 303.87791 -396.368391) (xy 303.894215 -396.374217)
			(xy 303.902872 -396.37462) (xy 304.333656 -396.37462) (xy 304.342313 -396.374234) (xy 304.358616 -396.368391)
			(xy 304.372046 -396.357457) (xy 304.376836 -396.350236) (xy 304.422302 -396.276068) (xy 304.426514 -396.268495)
			(xy 304.43007 -396.251547) (xy 304.427751 -396.234387) (xy 304.42408 -396.226538) (xy 304.412581 -396.203066)
			(xy 304.396308 -396.1534) (xy 304.38804 -396.101794) (xy 304.387504 -396.075662) (xy 304.387943 -396.051546)
			(xy 304.394948 -396.003826) (xy 304.408806 -395.957628) (xy 304.429222 -395.91393) (xy 304.442114 -395.893544)
			(xy 304.447956 -395.884908) (xy 304.451512 -395.864588) (xy 304.432716 -395.782546) (xy 304.430001 -395.772615)
			(xy 304.417943 -395.755953) (xy 304.409348 -395.750288) (xy 304.388546 -395.737432) (xy 304.350629 -395.706554)
			(xy 304.317679 -395.670423) (xy 304.290416 -395.629829) (xy 304.269434 -395.58566) (xy 304.255194 -395.53888)
			(xy 304.248005 -395.490512) (xy 304.24755 -395.466062) (xy 304.248143 -395.438771) (xy 304.257165 -395.384939)
			(xy 304.274894 -395.333315) (xy 304.300847 -395.285297) (xy 304.334324 -395.242185) (xy 304.353976 -395.223238)
			(xy 304.36136 -395.215719) (xy 304.369778 -395.196427) (xy 304.370232 -395.1859) (xy 304.370232 -395.111224)
			(xy 304.369711 -395.10071) (xy 304.361322 -395.081425) (xy 304.353976 -395.073886) (xy 304.334251 -395.055002)
			(xy 304.300717 -395.011907) (xy 304.274737 -394.963879) (xy 304.25702 -394.912228) (xy 304.248051 -394.858365)
			(xy 304.24755 -394.831062) (xy 304.247804 -394.81887) (xy 304.248058 -394.809218) (xy 304.241962 -394.791438)
			(xy 304.183542 -394.724128) (xy 304.16627 -394.715238) (xy 304.156872 -394.714222) (xy 304.129958 -394.710872)
			(xy 304.077657 -394.696529) (xy 304.028398 -394.673841) (xy 303.983502 -394.643419) (xy 303.944174 -394.606076)
			(xy 303.911468 -394.562816) (xy 303.886261 -394.514797) (xy 303.86923 -394.463309) (xy 303.864518 -394.4366)
			(xy 303.862994 -394.427202) (xy 303.590198 -393.95527) (xy 303.582832 -393.949428) (xy 303.564054 -393.933624)
			(xy 303.530921 -393.897418) (xy 303.503501 -393.856713) (xy 303.482397 -393.812403) (xy 303.46807 -393.765462)
			(xy 303.460836 -393.71692) (xy 303.460404 -393.69238) (xy 303.460915 -393.666394) (xy 303.469048 -393.615063)
			(xy 303.485111 -393.565636) (xy 303.508708 -393.51933) (xy 303.539259 -393.477285) (xy 303.57601 -393.440538)
			(xy 303.618057 -393.409991) (xy 303.664365 -393.386399) (xy 303.713794 -393.370341) (xy 303.765126 -393.362213)
			(xy 303.791112 -393.361672) (xy 303.817127 -393.36215) (xy 303.868517 -393.370286) (xy 303.917998 -393.38637)
			(xy 303.96435 -393.410006) (xy 304.006427 -393.440609) (xy 304.043192 -393.477426) (xy 304.073737 -393.519546)
			(xy 304.097307 -393.565931) (xy 304.113322 -393.615435) (xy 304.117756 -393.641072) (xy 304.11928 -393.65047)
			(xy 304.392076 -394.122402) (xy 304.399442 -394.128244) (xy 304.418223 -394.144046) (xy 304.451361 -394.180251)
			(xy 304.478787 -394.220955) (xy 304.499897 -394.265265) (xy 304.514228 -394.312207) (xy 304.521467 -394.360751)
			(xy 304.52187 -394.385292) (xy 304.521616 -394.397484) (xy 304.521362 -394.407136) (xy 304.527458 -394.424916)
			(xy 304.585878 -394.492226) (xy 304.60315 -394.501116) (xy 304.612548 -394.502132) (xy 304.639319 -394.505455)
			(xy 304.691354 -394.519673) (xy 304.740392 -394.542146) (xy 304.785133 -394.572279) (xy 304.824391 -394.609273)
			(xy 304.857126 -394.652147) (xy 304.88247 -394.699765) (xy 304.899751 -394.750865) (xy 304.90851 -394.804091)
			(xy 304.908966 -394.831062) (xy 304.908379 -394.858356) (xy 304.899368 -394.912195) (xy 304.881649 -394.963828)
			(xy 304.855703 -395.011856) (xy 304.822231 -395.054978) (xy 304.80254 -395.073886) (xy 304.795171 -395.081411)
			(xy 304.786776 -395.100702) (xy 304.786284 -395.111224) (xy 304.786284 -395.1859) (xy 304.786811 -395.196412)
			(xy 304.795207 -395.215688) (xy 304.80254 -395.223238) (xy 304.822263 -395.242123) (xy 304.855792 -395.285219)
			(xy 304.881768 -395.333248) (xy 304.899479 -395.384898) (xy 304.908444 -395.43876) (xy 304.908966 -395.466062)
			(xy 304.908533 -395.490179) (xy 304.901536 -395.537904) (xy 304.887687 -395.584108) (xy 304.867277 -395.627811)
			(xy 304.854356 -395.64818) (xy 304.848514 -395.656816) (xy 304.844958 -395.677136) (xy 304.863754 -395.759178)
			(xy 304.866471 -395.769108) (xy 304.878529 -395.785769) (xy 304.887122 -395.791436) (xy 304.907924 -395.804291)
			(xy 304.945842 -395.835168) (xy 304.978792 -395.871299) (xy 305.006056 -395.911893) (xy 305.027036 -395.956063)
			(xy 305.041275 -396.002843) (xy 305.048461 -396.051212) (xy 305.04892 -396.075662) (xy 305.048411 -396.101796)
			(xy 305.040154 -396.153409) (xy 305.023871 -396.203078) (xy 305.012344 -396.226538) (xy 305.008719 -396.2344)
			(xy 305.006423 -396.251547) (xy 305.009945 -396.268485) (xy 305.014122 -396.276068) (xy 305.059588 -396.350236)
			(xy 305.064384 -396.357453) (xy 305.077806 -396.368392) (xy 305.094111 -396.37422) (xy 305.102768 -396.37462)
			(xy 305.533806 -396.37462) (xy 305.542459 -396.374226) (xy 305.558749 -396.368372) (xy 305.572167 -396.357434)
			(xy 305.576986 -396.350236) (xy 305.622452 -396.276068) (xy 305.626661 -396.268494) (xy 305.630213 -396.251547)
			(xy 305.627896 -396.234388) (xy 305.62423 -396.226538) (xy 305.61273 -396.203067) (xy 305.596454 -396.153401)
			(xy 305.588185 -396.101794) (xy 305.587654 -396.075662) (xy 305.588093 -396.051546) (xy 305.5951 -396.003827)
			(xy 305.608959 -395.957629) (xy 305.629377 -395.913933) (xy 305.642264 -395.893544) (xy 305.648106 -395.884908)
			(xy 305.651662 -395.864588) (xy 305.632866 -395.782546) (xy 305.630154 -395.772612) (xy 305.618103 -395.75594)
			(xy 305.609498 -395.750288) (xy 305.588694 -395.737434) (xy 305.550772 -395.706559) (xy 305.517816 -395.670429)
			(xy 305.490548 -395.629835) (xy 305.469563 -395.585665) (xy 305.45532 -395.538883) (xy 305.448131 -395.490513)
			(xy 305.4477 -395.466062) (xy 305.448293 -395.438772) (xy 305.457317 -395.38494) (xy 305.475047 -395.333318)
			(xy 305.501003 -395.285302) (xy 305.534484 -395.242194) (xy 305.554126 -395.223238) (xy 305.561503 -395.215716)
			(xy 305.569913 -395.196424) (xy 305.570382 -395.1859) (xy 305.570382 -395.111224) (xy 305.569859 -395.100711)
			(xy 305.561465 -395.081432) (xy 305.554126 -395.073886) (xy 305.534403 -395.055) (xy 305.500874 -395.011904)
			(xy 305.474898 -394.963875) (xy 305.457185 -394.912225) (xy 305.448217 -394.858364) (xy 305.4477 -394.831062)
			(xy 305.447954 -394.81887) (xy 305.448208 -394.809218) (xy 305.442112 -394.791438) (xy 305.390042 -394.731494)
			(xy 305.383412 -394.724492) (xy 305.366309 -394.715621) (xy 305.356768 -394.714222) (xy 305.329854 -394.710872)
			(xy 305.277553 -394.696528) (xy 305.228295 -394.67384) (xy 305.1834 -394.643417) (xy 305.144072 -394.606075)
			(xy 305.111367 -394.562815) (xy 305.08616 -394.514796) (xy 305.069129 -394.463308) (xy 305.064414 -394.4366)
			(xy 305.06289 -394.427202) (xy 304.790094 -393.95527) (xy 304.782728 -393.949428) (xy 304.76395 -393.933624)
			(xy 304.730817 -393.897417) (xy 304.703398 -393.856712) (xy 304.682294 -393.812403) (xy 304.667967 -393.765462)
			(xy 304.660734 -393.716919) (xy 304.6603 -393.69238) (xy 304.660811 -393.666394) (xy 304.668944 -393.615062)
			(xy 304.685007 -393.565635) (xy 304.708604 -393.519329) (xy 304.739154 -393.477284) (xy 304.775906 -393.440536)
			(xy 304.817953 -393.409989) (xy 304.864261 -393.386396) (xy 304.91369 -393.370338) (xy 304.965022 -393.362209)
			(xy 304.991008 -393.361672) (xy 305.017023 -393.36215) (xy 305.068414 -393.370285) (xy 305.117895 -393.386369)
			(xy 305.164247 -393.410004) (xy 305.206325 -393.440608) (xy 305.243091 -393.477424) (xy 305.273636 -393.519545)
			(xy 305.297207 -393.56593) (xy 305.313222 -393.615434) (xy 305.317652 -393.641072) (xy 305.319176 -393.65047)
			(xy 305.591972 -394.122402) (xy 305.599338 -394.128244) (xy 305.618119 -394.144046) (xy 305.651258 -394.180251)
			(xy 305.678684 -394.220955) (xy 305.699794 -394.265264) (xy 305.714126 -394.312207) (xy 305.721364 -394.360751)
			(xy 305.721766 -394.385292) (xy 305.721512 -394.397484) (xy 305.721258 -394.407136) (xy 305.727354 -394.424916)
			(xy 305.779424 -394.48486) (xy 305.786055 -394.49186) (xy 305.803157 -394.500734) (xy 305.812698 -394.502132)
			(xy 305.839466 -394.505458) (xy 305.891495 -394.519682) (xy 305.940526 -394.542159) (xy 305.98526 -394.572294)
			(xy 306.024512 -394.609288) (xy 306.057241 -394.652161) (xy 306.08258 -394.699776) (xy 306.099858 -394.750871)
			(xy 306.108616 -394.804093) (xy 306.109116 -394.831062) (xy 306.108529 -394.858355) (xy 306.099517 -394.912194)
			(xy 306.081796 -394.963825) (xy 306.055847 -395.01185) (xy 306.022372 -395.054969) (xy 306.00269 -395.073886)
			(xy 305.995314 -395.081408) (xy 305.986911 -395.1007) (xy 305.986434 -395.111224) (xy 305.986434 -395.1859)
			(xy 305.986962 -395.19641) (xy 305.995364 -395.215681) (xy 306.00269 -395.223238) (xy 306.02241 -395.242125)
			(xy 306.055935 -395.285222) (xy 306.081906 -395.333251) (xy 306.099615 -395.384901) (xy 306.108578 -395.438761)
			(xy 306.109116 -395.466062) (xy 306.108683 -395.49018) (xy 306.101687 -395.537905) (xy 306.087839 -395.584109)
			(xy 306.067432 -395.627815) (xy 306.054506 -395.64818) (xy 306.048664 -395.656816) (xy 306.045108 -395.677136)
			(xy 306.063904 -395.759178) (xy 306.066624 -395.769105) (xy 306.078688 -395.785756) (xy 306.087272 -395.791436)
			(xy 306.108072 -395.804293) (xy 306.145984 -395.835173) (xy 306.17893 -395.871305) (xy 306.206189 -395.911899)
			(xy 306.227166 -395.956068) (xy 306.241402 -396.002847) (xy 306.248587 -396.051213) (xy 306.24907 -396.075662)
			(xy 306.248561 -396.101797) (xy 306.240305 -396.15341) (xy 306.224025 -396.20308) (xy 306.212494 -396.226538)
			(xy 306.208867 -396.234399) (xy 306.206568 -396.251547) (xy 306.210093 -396.268486) (xy 306.214272 -396.276068)
			(xy 306.259738 -396.350236) (xy 306.264531 -396.357458) (xy 306.277951 -396.368411) (xy 306.294258 -396.374254)
			(xy 306.302918 -396.37462) (xy 306.733702 -396.37462) (xy 306.742355 -396.374226) (xy 306.758647 -396.368373)
			(xy 306.772065 -396.357436) (xy 306.776882 -396.350236) (xy 306.822348 -396.276068) (xy 306.826557 -396.268494)
			(xy 306.830109 -396.251547) (xy 306.827792 -396.234388) (xy 306.824126 -396.226538) (xy 306.812626 -396.203067)
			(xy 306.79635 -396.153401) (xy 306.788081 -396.101794) (xy 306.78755 -396.075662) (xy 306.787989 -396.051546)
			(xy 306.794995 -396.003826) (xy 306.808855 -395.957629) (xy 306.829273 -395.913933) (xy 306.84216 -395.893544)
			(xy 306.848002 -395.884908) (xy 306.851558 -395.864588) (xy 306.832762 -395.782546) (xy 306.83005 -395.772613)
			(xy 306.817998 -395.755941) (xy 306.809394 -395.750288) (xy 306.78859 -395.737434) (xy 306.750668 -395.706558)
			(xy 306.717713 -395.670429) (xy 306.690446 -395.629835) (xy 306.669461 -395.585665) (xy 306.655218 -395.538883)
			(xy 306.648028 -395.490513) (xy 306.647596 -395.466062) (xy 306.648189 -395.438772) (xy 306.657213 -395.38494)
			(xy 306.674942 -395.333318) (xy 306.700899 -395.285302) (xy 306.734379 -395.242194) (xy 306.754022 -395.223238)
			(xy 306.7614 -395.215716) (xy 306.769811 -395.196425) (xy 306.770278 -395.1859) (xy 306.770278 -395.111224)
			(xy 306.769755 -395.100711) (xy 306.76136 -395.081432) (xy 306.754022 -395.073886) (xy 306.7343 -395.055)
			(xy 306.700771 -395.011904) (xy 306.674795 -394.963875) (xy 306.657082 -394.912225) (xy 306.648114 -394.858364)
			(xy 306.647596 -394.831062) (xy 306.64785 -394.81887) (xy 306.648104 -394.809218) (xy 306.642008 -394.791438)
			(xy 306.589938 -394.731494) (xy 306.583308 -394.724493) (xy 306.566205 -394.715622) (xy 306.556664 -394.714222)
			(xy 306.529717 -394.710854) (xy 306.477355 -394.696465) (xy 306.428044 -394.673724) (xy 306.383106 -394.643238)
			(xy 306.343746 -394.605827) (xy 306.31102 -394.562493) (xy 306.285806 -394.514399) (xy 306.26878 -394.462835)
			(xy 306.264056 -394.436092) (xy 306.262786 -394.426694) (xy 305.990244 -393.95527) (xy 305.982878 -393.949428)
			(xy 305.964102 -393.933623) (xy 305.930975 -393.897414) (xy 305.90356 -393.856708) (xy 305.882458 -393.812399)
			(xy 305.868135 -393.765459) (xy 305.860902 -393.716919) (xy 305.86045 -393.69238) (xy 305.860961 -393.666393)
			(xy 305.869094 -393.615058) (xy 305.885156 -393.565628) (xy 305.908752 -393.519318) (xy 305.939302 -393.477269)
			(xy 305.976052 -393.440516) (xy 306.018099 -393.409964) (xy 306.064407 -393.386364) (xy 306.113837 -393.370299)
			(xy 306.165171 -393.362163) (xy 306.191158 -393.361672) (xy 306.217171 -393.362154) (xy 306.268555 -393.370295)
			(xy 306.318031 -393.386384) (xy 306.364376 -393.410022) (xy 306.406447 -393.440627) (xy 306.443206 -393.477443)
			(xy 306.473746 -393.519561) (xy 306.497313 -393.565943) (xy 306.513324 -393.615444) (xy 306.517802 -393.641072)
			(xy 306.519326 -393.65047) (xy 306.792376 -394.12291) (xy 306.799488 -394.128752) (xy 306.81822 -394.144532)
			(xy 306.85127 -394.180676) (xy 306.878623 -394.221302) (xy 306.899681 -394.265521) (xy 306.913981 -394.312364)
			(xy 306.921211 -394.360804) (xy 306.921662 -394.385292) (xy 306.921408 -394.397484) (xy 306.921154 -394.407136)
			(xy 306.92725 -394.424916) (xy 306.97932 -394.48486) (xy 306.985951 -394.491861) (xy 307.003053 -394.500736)
			(xy 307.012594 -394.502132) (xy 307.039362 -394.505458) (xy 307.091391 -394.519681) (xy 307.140423 -394.542158)
			(xy 307.185158 -394.572293) (xy 307.22441 -394.609287) (xy 307.25714 -394.65216) (xy 307.282479 -394.699775)
			(xy 307.299757 -394.750871) (xy 307.308515 -394.804093) (xy 307.309012 -394.831062) (xy 307.308425 -394.858355)
			(xy 307.299412 -394.912193) (xy 307.281692 -394.963824) (xy 307.255742 -395.011849) (xy 307.222267 -395.054968)
			(xy 307.202586 -395.073886) (xy 307.195211 -395.081409) (xy 307.186808 -395.1007) (xy 307.18633 -395.111224)
			(xy 307.18633 -395.1859) (xy 307.186858 -395.196411) (xy 307.195259 -395.215682) (xy 307.202586 -395.223238)
			(xy 307.222307 -395.242125) (xy 307.255831 -395.285222) (xy 307.281803 -395.333251) (xy 307.299512 -395.384901)
			(xy 307.308476 -395.438761) (xy 307.309012 -395.466062) (xy 307.308579 -395.49018) (xy 307.301583 -395.537905)
			(xy 307.287735 -395.584109) (xy 307.267328 -395.627815) (xy 307.254402 -395.64818) (xy 307.24856 -395.656816)
			(xy 307.245004 -395.677136) (xy 307.2638 -395.759178) (xy 307.266519 -395.769105) (xy 307.278583 -395.785757)
			(xy 307.287168 -395.791436) (xy 307.307968 -395.804293) (xy 307.345881 -395.835173) (xy 307.378827 -395.871305)
			(xy 307.406086 -395.911899) (xy 307.427063 -395.956068) (xy 307.4413 -396.002847) (xy 307.448484 -396.051213)
			(xy 307.448966 -396.075662) (xy 307.448457 -396.101797) (xy 307.440201 -396.15341) (xy 307.42392 -396.20308)
			(xy 307.41239 -396.226538) (xy 307.408763 -396.234399) (xy 307.406464 -396.251547) (xy 307.409989 -396.268486)
			(xy 307.414168 -396.276068) (xy 307.459634 -396.350236) (xy 307.464427 -396.357459) (xy 307.477847 -396.368413)
			(xy 307.494154 -396.374257) (xy 307.502814 -396.37462) (xy 307.933598 -396.37462) (xy 307.942252 -396.374227)
			(xy 307.958544 -396.368375) (xy 307.971963 -396.357438) (xy 307.976778 -396.350236) (xy 308.022244 -396.276068)
			(xy 308.026453 -396.268494) (xy 308.030006 -396.251547) (xy 308.027688 -396.234388) (xy 308.024022 -396.226538)
			(xy 308.012522 -396.203067) (xy 307.996246 -396.153401) (xy 307.987978 -396.101794) (xy 307.987446 -396.075662)
			(xy 307.987885 -396.051546) (xy 307.994891 -396.003826) (xy 308.00875 -395.957629) (xy 308.029168 -395.913933)
			(xy 308.042056 -395.893544) (xy 308.047898 -395.884908) (xy 308.051454 -395.864588) (xy 308.032658 -395.782546)
			(xy 308.029946 -395.772613) (xy 308.017893 -395.755942) (xy 308.00929 -395.750288) (xy 307.988486 -395.737434)
			(xy 307.950565 -395.706558) (xy 307.91761 -395.670428) (xy 307.890343 -395.629834) (xy 307.869359 -395.585664)
			(xy 307.855116 -395.538883) (xy 307.847926 -395.490513) (xy 307.847492 -395.466062) (xy 307.848085 -395.438772)
			(xy 307.857108 -395.38494) (xy 307.874838 -395.333317) (xy 307.900794 -395.285301) (xy 307.934274 -395.242193)
			(xy 307.953918 -395.223238) (xy 307.961296 -395.215716) (xy 307.969708 -395.196425) (xy 307.970174 -395.1859)
			(xy 307.970174 -395.111224) (xy 307.969651 -395.100711) (xy 307.961256 -395.081433) (xy 307.953918 -395.073886)
			(xy 307.934196 -395.055) (xy 307.900667 -395.011903) (xy 307.874692 -394.963875) (xy 307.856979 -394.912225)
			(xy 307.848012 -394.858364) (xy 307.847492 -394.831062) (xy 307.847746 -394.81887) (xy 307.848 -394.809218)
			(xy 307.841904 -394.791438) (xy 307.783484 -394.724128) (xy 307.766212 -394.715238) (xy 307.756814 -394.714222)
			(xy 307.729898 -394.710875) (xy 307.677591 -394.696537) (xy 307.628327 -394.673853) (xy 307.583426 -394.643432)
			(xy 307.544092 -394.60609) (xy 307.511381 -394.562828) (xy 307.48617 -394.514808) (xy 307.469136 -394.463316)
			(xy 307.46446 -394.4366) (xy 307.462936 -394.427202) (xy 307.19014 -393.95527) (xy 307.182774 -393.949428)
			(xy 307.163999 -393.933623) (xy 307.130871 -393.897414) (xy 307.103456 -393.856708) (xy 307.082356 -393.812399)
			(xy 307.068032 -393.765459) (xy 307.0608 -393.716918) (xy 307.060346 -393.69238) (xy 307.060857 -393.666393)
			(xy 307.06899 -393.615058) (xy 307.085052 -393.565627) (xy 307.108648 -393.519317) (xy 307.139197 -393.477268)
			(xy 307.175948 -393.440514) (xy 307.217995 -393.409962) (xy 307.264303 -393.386362) (xy 307.313732 -393.370296)
			(xy 307.365067 -393.362159) (xy 307.391054 -393.361672) (xy 307.417067 -393.362154) (xy 307.468452 -393.370294)
			(xy 307.517928 -393.386382) (xy 307.564274 -393.41002) (xy 307.606346 -393.440625) (xy 307.643105 -393.477441)
			(xy 307.673645 -393.51956) (xy 307.697212 -393.565942) (xy 307.713224 -393.615443) (xy 307.717698 -393.641072)
			(xy 307.719222 -393.65047) (xy 307.992018 -394.122402) (xy 307.999384 -394.128244) (xy 308.018163 -394.144048)
			(xy 308.051297 -394.180254) (xy 308.078719 -394.220959) (xy 308.099826 -394.265268) (xy 308.114156 -394.312209)
			(xy 308.121393 -394.360752) (xy 308.121812 -394.385292) (xy 308.121558 -394.397484) (xy 308.121304 -394.407136)
			(xy 308.1274 -394.424916) (xy 308.18582 -394.492226) (xy 308.203092 -394.501116) (xy 308.21249 -394.502132)
			(xy 308.239259 -394.505458) (xy 308.291288 -394.51968) (xy 308.34032 -394.542157) (xy 308.385056 -394.572291)
			(xy 308.424309 -394.609286) (xy 308.457039 -394.652158) (xy 308.482379 -394.699774) (xy 308.499657 -394.75087)
			(xy 308.508415 -394.804093) (xy 308.508908 -394.831062) (xy 308.508321 -394.858355) (xy 308.499308 -394.912193)
			(xy 308.481587 -394.963824) (xy 308.455638 -395.011849) (xy 308.422162 -395.054967) (xy 308.402482 -395.073886)
			(xy 308.395107 -395.081409) (xy 308.386705 -395.100701) (xy 308.386226 -395.111224) (xy 308.386226 -395.1859)
			(xy 308.386754 -395.196411) (xy 308.395155 -395.215682) (xy 308.402482 -395.223238) (xy 308.422203 -395.242125)
			(xy 308.455728 -395.285222) (xy 308.4817 -395.333251) (xy 308.499409 -395.3849) (xy 308.508373 -395.438761)
			(xy 308.508908 -395.466062) (xy 308.508475 -395.49018) (xy 308.501479 -395.537905) (xy 308.487631 -395.584109)
			(xy 308.467223 -395.627814) (xy 308.454298 -395.64818) (xy 308.448456 -395.656816) (xy 308.4449 -395.677136)
			(xy 308.463696 -395.759178) (xy 308.466415 -395.769105) (xy 308.478478 -395.785758) (xy 308.487064 -395.791436)
			(xy 308.507864 -395.804293) (xy 308.545777 -395.835172) (xy 308.578724 -395.871304) (xy 308.605983 -395.911898)
			(xy 308.626961 -395.956067) (xy 308.641198 -396.002846) (xy 308.648382 -396.051213) (xy 308.648862 -396.075662)
			(xy 308.648353 -396.101797) (xy 308.640097 -396.15341) (xy 308.623816 -396.203079) (xy 308.612286 -396.226538)
			(xy 308.608659 -396.234399) (xy 308.606361 -396.251547) (xy 308.609885 -396.268486) (xy 308.614064 -396.276068)
			(xy 308.65953 -396.350236) (xy 308.664323 -396.357459) (xy 308.677742 -396.368414) (xy 308.69405 -396.37426)
			(xy 308.70271 -396.37462) (xy 309.133748 -396.37462) (xy 309.142406 -396.374235) (xy 309.158711 -396.368394)
			(xy 309.172143 -396.357461) (xy 309.176928 -396.350236) (xy 309.222394 -396.276068) (xy 309.226607 -396.268495)
			(xy 309.230163 -396.251547) (xy 309.227843 -396.234387) (xy 309.224172 -396.226538) (xy 309.212673 -396.203066)
			(xy 309.196401 -396.1534) (xy 309.188133 -396.101794) (xy 309.187596 -396.075662) (xy 309.188035 -396.051546)
			(xy 309.19504 -396.003826) (xy 309.208898 -395.957627) (xy 309.229313 -395.913929) (xy 309.242206 -395.893544)
			(xy 309.248048 -395.884908) (xy 309.251604 -395.864588) (xy 309.232808 -395.782546) (xy 309.230093 -395.772616)
			(xy 309.218034 -395.755955) (xy 309.20944 -395.750288) (xy 309.188639 -395.737432) (xy 309.150723 -395.706553)
			(xy 309.117773 -395.670422) (xy 309.09051 -395.629828) (xy 309.069529 -395.585659) (xy 309.055289 -395.53888)
			(xy 309.048101 -395.490512) (xy 309.047642 -395.466062) (xy 309.048235 -395.438771) (xy 309.057257 -395.384938)
			(xy 309.074985 -395.333314) (xy 309.100938 -395.285296) (xy 309.134415 -395.242183) (xy 309.154068 -395.223238)
			(xy 309.161452 -395.215719) (xy 309.169872 -395.196427) (xy 309.170324 -395.1859) (xy 309.170324 -395.111224)
			(xy 309.169802 -395.10071) (xy 309.161413 -395.081426) (xy 309.154068 -395.073886) (xy 309.134343 -395.055001)
			(xy 309.10081 -395.011906) (xy 309.074831 -394.963878) (xy 309.057115 -394.912227) (xy 309.048146 -394.858364)
			(xy 309.047642 -394.831062) (xy 309.047896 -394.81887) (xy 309.04815 -394.809218) (xy 309.042054 -394.791438)
			(xy 308.989984 -394.731494) (xy 308.983357 -394.724487) (xy 308.966255 -394.715601) (xy 308.95671 -394.714222)
			(xy 308.929794 -394.710875) (xy 308.877488 -394.696536) (xy 308.828224 -394.673852) (xy 308.783323 -394.64343)
			(xy 308.74399 -394.606088) (xy 308.71128 -394.562827) (xy 308.686069 -394.514807) (xy 308.669035 -394.463316)
			(xy 308.664356 -394.4366) (xy 308.662832 -394.427202) (xy 308.390036 -393.95527) (xy 308.38267 -393.949428)
			(xy 308.363895 -393.933623) (xy 308.330768 -393.897413) (xy 308.303353 -393.856708) (xy 308.282253 -393.812399)
			(xy 308.267929 -393.765459) (xy 308.260697 -393.716918) (xy 308.260242 -393.69238) (xy 308.260727 -393.666393)
			(xy 308.268861 -393.61506) (xy 308.284925 -393.565631) (xy 308.308525 -393.519325) (xy 308.339078 -393.47728)
			(xy 308.375833 -393.440533) (xy 308.417884 -393.409988) (xy 308.464196 -393.386399) (xy 308.513628 -393.370344)
			(xy 308.564963 -393.362221) (xy 308.59095 -393.361672) (xy 308.616963 -393.362153) (xy 308.668349 -393.370294)
			(xy 308.717825 -393.386381) (xy 308.764171 -393.410019) (xy 308.806244 -393.440624) (xy 308.843004 -393.47744)
			(xy 308.873544 -393.519559) (xy 308.897112 -393.565941) (xy 308.913124 -393.615442) (xy 308.917594 -393.641072)
			(xy 308.919118 -393.65047) (xy 309.191914 -394.122402) (xy 309.19928 -394.128244) (xy 309.218059 -394.144047)
			(xy 309.251194 -394.180254) (xy 309.278616 -394.220958) (xy 309.299724 -394.265267) (xy 309.314053 -394.312209)
			(xy 309.321291 -394.360752) (xy 309.321708 -394.385292) (xy 309.321454 -394.397484) (xy 309.3212 -394.407136)
			(xy 309.327296 -394.424916) (xy 309.379366 -394.48486) (xy 309.385999 -394.491855) (xy 309.403103 -394.500714)
			(xy 309.41264 -394.502132) (xy 309.439411 -394.505454) (xy 309.491447 -394.519671) (xy 309.540486 -394.542144)
			(xy 309.585229 -394.572277) (xy 309.624488 -394.60927) (xy 309.657224 -394.652145) (xy 309.682568 -394.699763)
			(xy 309.69985 -394.750863) (xy 309.708609 -394.804091) (xy 309.709058 -394.831062) (xy 309.708471 -394.858355)
			(xy 309.69946 -394.912195) (xy 309.681741 -394.963827) (xy 309.655794 -395.011855) (xy 309.622322 -395.054977)
			(xy 309.602632 -395.073886) (xy 309.595252 -395.081406) (xy 309.58684 -395.100699) (xy 309.586376 -395.111224)
			(xy 309.586376 -395.1859) (xy 309.586903 -395.196412) (xy 309.595298 -395.215689) (xy 309.602632 -395.223238)
			(xy 309.622355 -395.242123) (xy 309.655886 -395.285219) (xy 309.681861 -395.333247) (xy 309.699574 -395.384898)
			(xy 309.708539 -395.43876) (xy 309.709058 -395.466062) (xy 309.708625 -395.490179) (xy 309.701628 -395.537904)
			(xy 309.687778 -395.584107) (xy 309.667368 -395.627811) (xy 309.654448 -395.64818) (xy 309.648606 -395.656816)
			(xy 309.64505 -395.677136) (xy 309.663846 -395.759178) (xy 309.666562 -395.769108) (xy 309.678619 -395.785771)
			(xy 309.687214 -395.791436) (xy 309.708017 -395.804291) (xy 309.745935 -395.835168) (xy 309.778886 -395.871298)
			(xy 309.806151 -395.911892) (xy 309.827131 -395.956062) (xy 309.841371 -396.002843) (xy 309.848557 -396.051212)
			(xy 309.849012 -396.075662) (xy 309.848503 -396.101796) (xy 309.840246 -396.153409) (xy 309.823963 -396.203078)
			(xy 309.812436 -396.226538) (xy 309.808812 -396.2344) (xy 309.806516 -396.251547) (xy 309.810037 -396.268485)
			(xy 309.814214 -396.276068) (xy 309.85968 -396.350236) (xy 309.864475 -396.357454) (xy 309.877897 -396.368395)
			(xy 309.894203 -396.374225) (xy 309.90286 -396.37462) (xy 310.333644 -396.37462) (xy 310.342302 -396.374235)
			(xy 310.358608 -396.368395) (xy 310.372042 -396.357463) (xy 310.376824 -396.350236) (xy 310.42229 -396.276068)
			(xy 310.426503 -396.268495) (xy 310.43006 -396.251547) (xy 310.42774 -396.234386) (xy 310.424068 -396.226538)
			(xy 310.41257 -396.203066) (xy 310.396297 -396.1534) (xy 310.388029 -396.101794) (xy 310.387492 -396.075662)
			(xy 310.387931 -396.051546) (xy 310.394936 -396.003826) (xy 310.408793 -395.957627) (xy 310.429209 -395.913929)
			(xy 310.442102 -395.893544) (xy 310.447944 -395.884908) (xy 310.4515 -395.864588) (xy 310.432704 -395.782546)
			(xy 310.429989 -395.772616) (xy 310.417929 -395.755956) (xy 310.409336 -395.750288) (xy 310.388535 -395.737432)
			(xy 310.350619 -395.706553) (xy 310.31767 -395.670422) (xy 310.290408 -395.629828) (xy 310.269427 -395.585659)
			(xy 310.255187 -395.538879) (xy 310.247999 -395.490512) (xy 310.247538 -395.466062) (xy 310.248131 -395.438771)
			(xy 310.257153 -395.384938) (xy 310.274881 -395.333314) (xy 310.300834 -395.285295) (xy 310.33431 -395.242183)
			(xy 310.353964 -395.223238) (xy 310.361349 -395.215719) (xy 310.36977 -395.196427) (xy 310.37022 -395.1859)
			(xy 310.37022 -395.111224) (xy 310.369698 -395.10071) (xy 310.361308 -395.081427) (xy 310.353964 -395.073886)
			(xy 310.334239 -395.055001) (xy 310.300706 -395.011906) (xy 310.274727 -394.963878) (xy 310.257012 -394.912227)
			(xy 310.248043 -394.858364) (xy 310.247538 -394.831062) (xy 310.247792 -394.81887) (xy 310.248046 -394.809218)
			(xy 310.24195 -394.791438) (xy 310.18353 -394.724128) (xy 310.166258 -394.715238) (xy 310.15686 -394.714222)
			(xy 310.129947 -394.710871) (xy 310.077647 -394.696526) (xy 310.02839 -394.673838) (xy 309.983496 -394.643415)
			(xy 309.944169 -394.606072) (xy 309.911464 -394.562812) (xy 309.886259 -394.514794) (xy 309.869228 -394.463307)
			(xy 309.864506 -394.4366) (xy 309.862982 -394.427202) (xy 309.590186 -393.95527) (xy 309.58282 -393.949428)
			(xy 309.564042 -393.933624) (xy 309.530911 -393.897417) (xy 309.503492 -393.856712) (xy 309.482388 -393.812403)
			(xy 309.468062 -393.765462) (xy 309.460829 -393.716919) (xy 309.460392 -393.69238) (xy 309.460903 -393.666394)
			(xy 309.469036 -393.615062) (xy 309.485099 -393.565634) (xy 309.508696 -393.519327) (xy 309.539246 -393.477282)
			(xy 309.575997 -393.440533) (xy 309.618044 -393.409985) (xy 309.664352 -393.386391) (xy 309.713781 -393.370331)
			(xy 309.765114 -393.362201) (xy 309.7911 -393.361672) (xy 309.817111 -393.362157) (xy 309.868491 -393.370304)
			(xy 309.917961 -393.386396) (xy 309.9643 -393.410037) (xy 310.006366 -393.440642) (xy 310.04312 -393.477458)
			(xy 310.073655 -393.519575) (xy 310.097217 -393.565955) (xy 310.113226 -393.615452) (xy 310.117744 -393.641072)
			(xy 310.119268 -393.65047) (xy 310.392064 -394.122402) (xy 310.39943 -394.128244) (xy 310.418207 -394.144049)
			(xy 310.451337 -394.180257) (xy 310.478755 -394.220962) (xy 310.499859 -394.265271) (xy 310.514186 -394.312211)
			(xy 310.521423 -394.360753) (xy 310.521858 -394.385292) (xy 310.521604 -394.397484) (xy 310.52135 -394.407136)
			(xy 310.527446 -394.424916) (xy 310.585866 -394.492226) (xy 310.603138 -394.501116) (xy 310.612536 -394.502132)
			(xy 310.639302 -394.505461) (xy 310.691326 -394.519689) (xy 310.740352 -394.542169) (xy 310.785081 -394.572305)
			(xy 310.824328 -394.609299) (xy 310.857052 -394.652171) (xy 310.882388 -394.699784) (xy 310.899663 -394.750877)
			(xy 310.90842 -394.804095) (xy 310.908954 -394.831062) (xy 310.908367 -394.858355) (xy 310.899355 -394.912195)
			(xy 310.881636 -394.963827) (xy 310.855689 -395.011854) (xy 310.822217 -395.054976) (xy 310.802528 -395.073886)
			(xy 310.795148 -395.081406) (xy 310.786738 -395.100699) (xy 310.786272 -395.111224) (xy 310.786272 -395.1859)
			(xy 310.786799 -395.196412) (xy 310.795193 -395.215689) (xy 310.802528 -395.223238) (xy 310.822252 -395.242123)
			(xy 310.855782 -395.285219) (xy 310.881758 -395.333247) (xy 310.899471 -395.384898) (xy 310.908436 -395.43876)
			(xy 310.908954 -395.466062) (xy 310.908521 -395.490179) (xy 310.901524 -395.537904) (xy 310.887674 -395.584107)
			(xy 310.867263 -395.627811) (xy 310.854344 -395.64818) (xy 310.848502 -395.656816) (xy 310.844946 -395.677136)
			(xy 310.863742 -395.759178) (xy 310.866458 -395.769108) (xy 310.878514 -395.785772) (xy 310.88711 -395.791436)
			(xy 310.907913 -395.80429) (xy 310.945832 -395.835167) (xy 310.978783 -395.871298) (xy 311.006048 -395.911892)
			(xy 311.027029 -395.956062) (xy 311.041268 -396.002843) (xy 311.048455 -396.051212) (xy 311.048908 -396.075662)
			(xy 311.048399 -396.101796) (xy 311.040141 -396.153409) (xy 311.023858 -396.203078) (xy 311.012332 -396.226538)
			(xy 311.008708 -396.2344) (xy 311.006412 -396.251547) (xy 311.009933 -396.268485) (xy 311.01411 -396.276068)
			(xy 311.059576 -396.350236) (xy 311.064371 -396.357454) (xy 311.077793 -396.368397) (xy 311.094099 -396.374228)
			(xy 311.102756 -396.37462) (xy 311.533794 -396.37462) (xy 311.542448 -396.374228) (xy 311.558741 -396.368376)
			(xy 311.572162 -396.35744) (xy 311.576974 -396.350236) (xy 311.62244 -396.276068) (xy 311.626649 -396.268494)
			(xy 311.630203 -396.251547) (xy 311.627885 -396.234388) (xy 311.624218 -396.226538) (xy 311.612718 -396.203067)
			(xy 311.596443 -396.153401) (xy 311.588174 -396.101794) (xy 311.587642 -396.075662) (xy 311.588081 -396.051546)
			(xy 311.595087 -396.003826) (xy 311.608946 -395.957629) (xy 311.629364 -395.913932) (xy 311.642252 -395.893544)
			(xy 311.648094 -395.884908) (xy 311.65165 -395.864588) (xy 311.632854 -395.782546) (xy 311.630141 -395.772613)
			(xy 311.618089 -395.755943) (xy 311.609486 -395.750288) (xy 311.588682 -395.737434) (xy 311.550761 -395.706557)
			(xy 311.517808 -395.670428) (xy 311.490541 -395.629834) (xy 311.469556 -395.585664) (xy 311.455314 -395.538883)
			(xy 311.448124 -395.490513) (xy 311.447688 -395.466062) (xy 311.448281 -395.438771) (xy 311.457304 -395.38494)
			(xy 311.475034 -395.333317) (xy 311.50099 -395.285301) (xy 311.534469 -395.242192) (xy 311.554114 -395.223238)
			(xy 311.561493 -395.215717) (xy 311.569905 -395.196425) (xy 311.57037 -395.1859) (xy 311.57037 -395.111224)
			(xy 311.569847 -395.100711) (xy 311.561451 -395.081433) (xy 311.554114 -395.073886) (xy 311.534392 -395.055)
			(xy 311.500864 -395.011903) (xy 311.474889 -394.963875) (xy 311.457176 -394.912225) (xy 311.448209 -394.858364)
			(xy 311.447688 -394.831062) (xy 311.447942 -394.81887) (xy 311.448196 -394.809218) (xy 311.4421 -394.791438)
			(xy 311.39003 -394.731494) (xy 311.3834 -394.724494) (xy 311.366296 -394.715626) (xy 311.356756 -394.714222)
			(xy 311.329843 -394.710871) (xy 311.277544 -394.696526) (xy 311.228287 -394.673837) (xy 311.183393 -394.643414)
			(xy 311.144067 -394.606071) (xy 311.111363 -394.562811) (xy 311.086158 -394.514793) (xy 311.069127 -394.463306)
			(xy 311.064402 -394.4366) (xy 311.062878 -394.427202) (xy 310.790082 -393.95527) (xy 310.782716 -393.949428)
			(xy 310.763938 -393.933624) (xy 310.730807 -393.897416) (xy 310.703389 -393.856711) (xy 310.682285 -393.812402)
			(xy 310.66796 -393.765461) (xy 310.660726 -393.716919) (xy 310.660288 -393.69238) (xy 310.660799 -393.666394)
			(xy 310.668932 -393.615061) (xy 310.684995 -393.565633) (xy 310.708592 -393.519326) (xy 310.739142 -393.477281)
			(xy 310.775893 -393.440531) (xy 310.81794 -393.409983) (xy 310.864248 -393.386389) (xy 310.913677 -393.370328)
			(xy 310.96501 -393.362198) (xy 310.990996 -393.361672) (xy 311.017007 -393.362157) (xy 311.068387 -393.370303)
			(xy 311.117858 -393.386395) (xy 311.164198 -393.410035) (xy 311.206264 -393.440641) (xy 311.243018 -393.477457)
			(xy 311.273554 -393.519574) (xy 311.297117 -393.565954) (xy 311.313126 -393.615451) (xy 311.31764 -393.641072)
			(xy 311.319164 -393.65047) (xy 311.59196 -394.122402) (xy 311.599326 -394.128244) (xy 311.618103 -394.144049)
			(xy 311.651233 -394.180257) (xy 311.678652 -394.220962) (xy 311.699756 -394.265271) (xy 311.714084 -394.312211)
			(xy 311.72132 -394.360753) (xy 311.721754 -394.385292) (xy 311.7215 -394.397484) (xy 311.721246 -394.407136)
			(xy 311.727342 -394.424916) (xy 311.779412 -394.48486) (xy 311.786042 -394.491862) (xy 311.803144 -394.500739)
			(xy 311.812686 -394.502132) (xy 311.839455 -394.505457) (xy 311.891485 -394.51968) (xy 311.940518 -394.542156)
			(xy 311.985254 -394.57229) (xy 312.024507 -394.609284) (xy 312.057238 -394.652157) (xy 312.082578 -394.699773)
			(xy 312.099856 -394.75087) (xy 312.108614 -394.804093) (xy 312.109104 -394.831062) (xy 312.108517 -394.858355)
			(xy 312.099504 -394.912193) (xy 312.081783 -394.963824) (xy 312.055833 -395.011849) (xy 312.022358 -395.054966)
			(xy 312.002678 -395.073886) (xy 311.995304 -395.081409) (xy 311.986902 -395.100701) (xy 311.986422 -395.111224)
			(xy 311.986422 -395.1859) (xy 311.98695 -395.196411) (xy 311.99535 -395.215683) (xy 312.002678 -395.223238)
			(xy 312.022399 -395.242125) (xy 312.055925 -395.285222) (xy 312.081897 -395.333251) (xy 312.099606 -395.3849)
			(xy 312.10857 -395.438761) (xy 312.109104 -395.466062) (xy 312.108671 -395.49018) (xy 312.101675 -395.537905)
			(xy 312.087827 -395.584109) (xy 312.067419 -395.627814) (xy 312.054494 -395.64818) (xy 312.048652 -395.656816)
			(xy 312.045096 -395.677136) (xy 312.063892 -395.759178) (xy 312.066611 -395.769106) (xy 312.078674 -395.785759)
			(xy 312.08726 -395.791436) (xy 312.10806 -395.804292) (xy 312.145974 -395.835172) (xy 312.178921 -395.871304)
			(xy 312.206181 -395.911898) (xy 312.227158 -395.956067) (xy 312.241395 -396.002846) (xy 312.24858 -396.051213)
			(xy 312.249058 -396.075662) (xy 312.248549 -396.101797) (xy 312.240293 -396.15341) (xy 312.224012 -396.203079)
			(xy 312.212482 -396.226538) (xy 312.208855 -396.234399) (xy 312.206557 -396.251547) (xy 312.210082 -396.268486)
			(xy 312.21426 -396.276068) (xy 312.259726 -396.350236) (xy 312.264519 -396.35746) (xy 312.277938 -396.368416)
			(xy 312.294245 -396.374262) (xy 312.302906 -396.37462) (xy 312.73369 -396.37462) (xy 312.742344 -396.374228)
			(xy 312.758639 -396.368378) (xy 312.77206 -396.357442) (xy 312.77687 -396.350236) (xy 312.822336 -396.276068)
			(xy 312.826546 -396.268495) (xy 312.830099 -396.251547) (xy 312.827781 -396.234388) (xy 312.824114 -396.226538)
			(xy 312.812614 -396.203067) (xy 312.796339 -396.1534) (xy 312.78807 -396.101794) (xy 312.787538 -396.075662)
			(xy 312.787977 -396.051546) (xy 312.794983 -396.003826) (xy 312.808842 -395.957629) (xy 312.82926 -395.913932)
			(xy 312.842148 -395.893544) (xy 312.84799 -395.884908) (xy 312.851546 -395.864588) (xy 312.83275 -395.782546)
			(xy 312.830037 -395.772613) (xy 312.817984 -395.755944) (xy 312.809382 -395.750288) (xy 312.788578 -395.737434)
			(xy 312.750658 -395.706557) (xy 312.717705 -395.670427) (xy 312.690438 -395.629833) (xy 312.669454 -395.585663)
			(xy 312.655212 -395.538882) (xy 312.648022 -395.490513) (xy 312.647584 -395.466062) (xy 312.648177 -395.438771)
			(xy 312.6572 -395.38494) (xy 312.67493 -395.333317) (xy 312.700885 -395.285301) (xy 312.734365 -395.242191)
			(xy 312.75401 -395.223238) (xy 312.761389 -395.215717) (xy 312.769802 -395.196425) (xy 312.770266 -395.1859)
			(xy 312.770266 -395.111224) (xy 312.769742 -395.100711) (xy 312.761347 -395.081434) (xy 312.75401 -395.073886)
			(xy 312.734288 -395.055) (xy 312.700761 -395.011903) (xy 312.674786 -394.963874) (xy 312.657073 -394.912225)
			(xy 312.648106 -394.858363) (xy 312.647584 -394.831062) (xy 312.647838 -394.81887) (xy 312.648092 -394.809218)
			(xy 312.641996 -394.791438) (xy 312.589926 -394.731494) (xy 312.583296 -394.724494) (xy 312.566191 -394.715628)
			(xy 312.556652 -394.714222) (xy 312.529705 -394.710853) (xy 312.477345 -394.696463) (xy 312.428035 -394.67372)
			(xy 312.383099 -394.643234) (xy 312.343741 -394.605823) (xy 312.311016 -394.56249) (xy 312.285803 -394.514396)
			(xy 312.268778 -394.462833) (xy 312.264044 -394.436092) (xy 312.262774 -394.426694) (xy 311.990232 -393.95527)
			(xy 311.982866 -393.949428) (xy 311.964086 -393.933625) (xy 311.93095 -393.89742) (xy 311.903527 -393.856715)
			(xy 311.88242 -393.812406) (xy 311.868092 -393.765464) (xy 311.860858 -393.71692) (xy 311.860438 -393.69238)
			(xy 311.860923 -393.666393) (xy 311.869057 -393.61506) (xy 311.885121 -393.565631) (xy 311.908721 -393.519324)
			(xy 311.939274 -393.477279) (xy 311.976029 -393.440531) (xy 312.01808 -393.409986) (xy 312.064392 -393.386396)
			(xy 312.113824 -393.370341) (xy 312.165159 -393.362217) (xy 312.191146 -393.361672) (xy 312.217159 -393.362153)
			(xy 312.268545 -393.370293) (xy 312.318022 -393.38638) (xy 312.364369 -393.410018) (xy 312.406442 -393.440622)
			(xy 312.443203 -393.477438) (xy 312.473744 -393.519557) (xy 312.497311 -393.56594) (xy 312.513324 -393.615441)
			(xy 312.51779 -393.641072) (xy 312.519314 -393.65047) (xy 312.792364 -394.12291) (xy 312.799476 -394.128752)
			(xy 312.818208 -394.144531) (xy 312.85126 -394.180675) (xy 312.878614 -394.221301) (xy 312.899672 -394.26552)
			(xy 312.913973 -394.312363) (xy 312.921203 -394.360803) (xy 312.92165 -394.385292) (xy 312.921396 -394.397484)
			(xy 312.921142 -394.407136) (xy 312.927238 -394.424916) (xy 312.979308 -394.48486) (xy 312.985938 -394.491863)
			(xy 313.00304 -394.500741) (xy 313.012582 -394.502132) (xy 313.039351 -394.505457) (xy 313.091382 -394.519679)
			(xy 313.140415 -394.542155) (xy 313.185151 -394.572289) (xy 313.224405 -394.609283) (xy 313.257136 -394.652156)
			(xy 313.282477 -394.699772) (xy 313.299755 -394.750869) (xy 313.308514 -394.804092) (xy 313.309 -394.831062)
			(xy 313.308413 -394.858355) (xy 313.2994 -394.912193) (xy 313.281679 -394.963824) (xy 313.255729 -395.011848)
			(xy 313.222253 -395.054966) (xy 313.202574 -395.073886) (xy 313.1952 -395.081409) (xy 313.186799 -395.100701)
			(xy 313.186318 -395.111224) (xy 313.186318 -395.1859) (xy 313.186846 -395.196411) (xy 313.195246 -395.215683)
			(xy 313.202574 -395.223238) (xy 313.222295 -395.242124) (xy 313.255821 -395.285221) (xy 313.281794 -395.33325)
			(xy 313.299503 -395.3849) (xy 313.308467 -395.438761) (xy 313.309 -395.466062) (xy 313.308567 -395.49018)
			(xy 313.301571 -395.537905) (xy 313.287723 -395.584109) (xy 313.267314 -395.627814) (xy 313.25439 -395.64818)
			(xy 313.248548 -395.656816) (xy 313.244992 -395.677136) (xy 313.263788 -395.759178) (xy 313.266507 -395.769106)
			(xy 313.278569 -395.78576) (xy 313.287156 -395.791436) (xy 313.307957 -395.804292) (xy 313.34587 -395.835172)
			(xy 313.378818 -395.871303) (xy 313.406078 -395.911897) (xy 313.427056 -395.956066) (xy 313.441293 -396.002846)
			(xy 313.448478 -396.051213) (xy 313.448954 -396.075662) (xy 313.448445 -396.101797) (xy 313.440189 -396.15341)
			(xy 313.423908 -396.203079) (xy 313.412378 -396.226538) (xy 313.408751 -396.234399) (xy 313.406453 -396.251547)
			(xy 313.409977 -396.268486) (xy 313.414156 -396.276068) (xy 313.459622 -396.350236) (xy 313.464414 -396.35746)
			(xy 313.477834 -396.368417) (xy 313.494141 -396.374265) (xy 313.502802 -396.37462) (xy 313.933586 -396.37462)
			(xy 313.942241 -396.374229) (xy 313.958536 -396.368379) (xy 313.971959 -396.357444) (xy 313.976766 -396.350236)
			(xy 314.022232 -396.276068) (xy 314.026442 -396.268495) (xy 314.029996 -396.251547) (xy 314.027678 -396.234388)
			(xy 314.02401 -396.226538) (xy 314.01251 -396.203067) (xy 313.996235 -396.1534) (xy 313.987967 -396.101794)
			(xy 313.987434 -396.075662) (xy 313.987873 -396.051546) (xy 313.994879 -396.003826) (xy 314.008738 -395.957629)
			(xy 314.029155 -395.913932) (xy 314.042044 -395.893544) (xy 314.047886 -395.884908) (xy 314.051442 -395.864588)
			(xy 314.032646 -395.782546) (xy 314.029933 -395.772613) (xy 314.017879 -395.755945) (xy 314.009278 -395.750288)
			(xy 313.988475 -395.737434) (xy 313.950555 -395.706557) (xy 313.917602 -395.670427) (xy 313.890335 -395.629833)
			(xy 313.869352 -395.585663) (xy 313.85511 -395.538882) (xy 313.84792 -395.490513) (xy 313.84748 -395.466062)
			(xy 313.848073 -395.438771) (xy 313.857096 -395.38494) (xy 313.874825 -395.333317) (xy 313.900781 -395.2853)
			(xy 313.93426 -395.242191) (xy 313.953906 -395.223238) (xy 313.961286 -395.215717) (xy 313.969699 -395.196425)
			(xy 313.970162 -395.1859) (xy 313.970162 -395.111224) (xy 313.969638 -395.100712) (xy 313.961242 -395.081434)
			(xy 313.953906 -395.073886) (xy 313.934184 -395.055) (xy 313.900657 -395.011903) (xy 313.874683 -394.963874)
			(xy 313.856971 -394.912224) (xy 313.848003 -394.858363) (xy 313.84748 -394.831062) (xy 313.847734 -394.81887)
			(xy 313.847988 -394.809218) (xy 313.841892 -394.791438) (xy 313.783472 -394.724128) (xy 313.7662 -394.715238)
			(xy 313.756802 -394.714222) (xy 313.729886 -394.710874) (xy 313.677581 -394.696534) (xy 313.628319 -394.673849)
			(xy 313.583419 -394.643428) (xy 313.544087 -394.606086) (xy 313.511377 -394.562825) (xy 313.486168 -394.514805)
			(xy 313.469134 -394.463314) (xy 313.464448 -394.4366) (xy 313.462924 -394.427202) (xy 313.190128 -393.95527)
			(xy 313.182762 -393.949428) (xy 313.163982 -393.933625) (xy 313.130847 -393.89742) (xy 313.103424 -393.856715)
			(xy 313.082318 -393.812406) (xy 313.06799 -393.765464) (xy 313.060755 -393.71692) (xy 313.060334 -393.69238)
			(xy 313.060819 -393.666393) (xy 313.068953 -393.615059) (xy 313.085017 -393.56563) (xy 313.108617 -393.519323)
			(xy 313.13917 -393.477277) (xy 313.175925 -393.44053) (xy 313.217976 -393.409984) (xy 313.264287 -393.386393)
			(xy 313.31372 -393.370338) (xy 313.365055 -393.362214) (xy 313.391042 -393.361672) (xy 313.417056 -393.362153)
			(xy 313.468442 -393.370292) (xy 313.517919 -393.386379) (xy 313.564267 -393.410016) (xy 313.60634 -393.440621)
			(xy 313.643101 -393.477437) (xy 313.673643 -393.519556) (xy 313.697211 -393.565939) (xy 313.713223 -393.61544)
			(xy 313.717686 -393.641072) (xy 313.71921 -393.65047) (xy 313.992006 -394.122402) (xy 313.999372 -394.128244)
			(xy 314.018152 -394.144047) (xy 314.051287 -394.180253) (xy 314.07871 -394.220958) (xy 314.099818 -394.265267)
			(xy 314.114148 -394.312208) (xy 314.121386 -394.360752) (xy 314.1218 -394.385292) (xy 314.121546 -394.397484)
			(xy 314.121292 -394.407136) (xy 314.127388 -394.424916) (xy 314.185808 -394.492226) (xy 314.20308 -394.501116)
			(xy 314.212478 -394.502132) (xy 314.239247 -394.505457) (xy 314.291278 -394.519678) (xy 314.340312 -394.542154)
			(xy 314.385049 -394.572288) (xy 314.424304 -394.609282) (xy 314.457035 -394.652155) (xy 314.482376 -394.699771)
			(xy 314.499655 -394.750869) (xy 314.508413 -394.804092) (xy 314.508896 -394.831062) (xy 314.508309 -394.858355)
			(xy 314.499296 -394.912193) (xy 314.481575 -394.963823) (xy 314.455624 -395.011848) (xy 314.422148 -395.054965)
			(xy 314.40247 -395.073886) (xy 314.395097 -395.08141) (xy 314.386697 -395.100701) (xy 314.386214 -395.111224)
			(xy 314.386214 -395.1859) (xy 314.386741 -395.196411) (xy 314.395141 -395.215684) (xy 314.40247 -395.223238)
			(xy 314.422191 -395.242124) (xy 314.455718 -395.285221) (xy 314.481691 -395.33325) (xy 314.499401 -395.3849)
			(xy 314.508365 -395.438761) (xy 314.508896 -395.466062) (xy 314.508463 -395.49018) (xy 314.501467 -395.537905)
			(xy 314.487618 -395.584109) (xy 314.46721 -395.627813) (xy 314.454286 -395.64818) (xy 314.448444 -395.656816)
			(xy 314.444888 -395.677136) (xy 314.463684 -395.759178) (xy 314.466403 -395.769106) (xy 314.478464 -395.785761)
			(xy 314.487052 -395.791436) (xy 314.507853 -395.804292) (xy 314.545767 -395.835171) (xy 314.578715 -395.871303)
			(xy 314.605975 -395.911897) (xy 314.626954 -395.956066) (xy 314.641191 -396.002845) (xy 314.648376 -396.051213)
			(xy 314.64885 -396.075662) (xy 314.648341 -396.101797) (xy 314.640085 -396.15341) (xy 314.623803 -396.203079)
			(xy 314.612274 -396.226538) (xy 314.608647 -396.234399) (xy 314.60635 -396.251547) (xy 314.609873 -396.268486)
			(xy 314.614052 -396.276068) (xy 314.659518 -396.350236) (xy 314.66431 -396.35746) (xy 314.677729 -396.368419)
			(xy 314.694037 -396.374268) (xy 314.702698 -396.37462) (xy 315.133736 -396.37462) (xy 315.142386 -396.374221)
			(xy 315.15867 -396.368361) (xy 315.172079 -396.357421) (xy 315.176916 -396.350236) (xy 315.222382 -396.276068)
			(xy 315.226596 -396.268496) (xy 315.230153 -396.251548) (xy 315.227832 -396.234386) (xy 315.22416 -396.226538)
			(xy 315.212662 -396.203066) (xy 315.19639 -396.1534) (xy 315.188122 -396.101794) (xy 315.187584 -396.075662)
			(xy 315.188023 -396.051546) (xy 315.195028 -396.003825) (xy 315.208885 -395.957627) (xy 315.2293 -395.913928)
			(xy 315.242194 -395.893544) (xy 315.248036 -395.884908) (xy 315.251592 -395.864588) (xy 315.232796 -395.782546)
			(xy 315.23008 -395.772616) (xy 315.21802 -395.755958) (xy 315.209428 -395.750288) (xy 315.188627 -395.737432)
			(xy 315.150713 -395.706552) (xy 315.117764 -395.670421) (xy 315.090502 -395.629827) (xy 315.069522 -395.585658)
			(xy 315.055283 -395.538879) (xy 315.048095 -395.490511) (xy 315.04763 -395.466062) (xy 315.048223 -395.438771)
			(xy 315.057245 -395.384938) (xy 315.074972 -395.333313) (xy 315.100925 -395.285294) (xy 315.134401 -395.242181)
			(xy 315.154056 -395.223238) (xy 315.16143 -395.215714) (xy 315.169835 -395.196423) (xy 315.170312 -395.1859)
			(xy 315.170312 -395.111224) (xy 315.16979 -395.10071) (xy 315.161399 -395.081428) (xy 315.154056 -395.073886)
			(xy 315.134332 -395.055001) (xy 315.1008 -395.011906) (xy 315.074821 -394.963877) (xy 315.057106 -394.912227)
			(xy 315.048137 -394.858364) (xy 315.04763 -394.831062) (xy 315.047884 -394.81887) (xy 315.048138 -394.809218)
			(xy 315.042042 -394.791438) (xy 314.989972 -394.731494) (xy 314.983344 -394.724488) (xy 314.966242 -394.715607)
			(xy 314.956698 -394.714222) (xy 314.929783 -394.710874) (xy 314.877478 -394.696534) (xy 314.828216 -394.673848)
			(xy 314.783317 -394.643427) (xy 314.743985 -394.606085) (xy 314.711276 -394.562823) (xy 314.686067 -394.514804)
			(xy 314.669033 -394.463313) (xy 314.664344 -394.4366) (xy 314.66282 -394.427202) (xy 314.390024 -393.95527)
			(xy 314.382658 -393.949428) (xy 314.363878 -393.933625) (xy 314.330743 -393.897419) (xy 314.303321 -393.856715)
			(xy 314.282215 -393.812405) (xy 314.267887 -393.765464) (xy 314.260653 -393.71692) (xy 314.26023 -393.69238)
			(xy 314.260715 -393.666393) (xy 314.268849 -393.615059) (xy 314.284913 -393.56563) (xy 314.308513 -393.519322)
			(xy 314.339066 -393.477276) (xy 314.37582 -393.440528) (xy 314.417871 -393.409982) (xy 314.464183 -393.386391)
			(xy 314.513615 -393.370335) (xy 314.564951 -393.36221) (xy 314.590938 -393.361672) (xy 314.616952 -393.362152)
			(xy 314.668339 -393.370291) (xy 314.717817 -393.386378) (xy 314.764165 -393.410015) (xy 314.806239 -393.440619)
			(xy 314.843 -393.477435) (xy 314.873542 -393.519555) (xy 314.89711 -393.565938) (xy 314.913123 -393.61544)
			(xy 314.917582 -393.641072) (xy 314.919106 -393.65047) (xy 315.191902 -394.122402) (xy 315.199268 -394.128244)
			(xy 315.218048 -394.144047) (xy 315.251184 -394.180253) (xy 315.278607 -394.220957) (xy 315.299715 -394.265267)
			(xy 315.314046 -394.312208) (xy 315.321283 -394.360752) (xy 315.321696 -394.385292) (xy 315.321442 -394.397484)
			(xy 315.321188 -394.407136) (xy 315.327284 -394.424916) (xy 315.379354 -394.48486) (xy 315.385986 -394.491857)
			(xy 315.40309 -394.50072) (xy 315.412628 -394.502132) (xy 315.439395 -394.50546) (xy 315.491419 -394.519687)
			(xy 315.540446 -394.542167) (xy 315.585176 -394.572303) (xy 315.624424 -394.609297) (xy 315.65715 -394.652169)
			(xy 315.682486 -394.699782) (xy 315.699762 -394.750875) (xy 315.708519 -394.804095) (xy 315.709046 -394.831062)
			(xy 315.708459 -394.858355) (xy 315.699447 -394.912194) (xy 315.681728 -394.963827) (xy 315.65578 -395.011853)
			(xy 315.622307 -395.054974) (xy 315.60262 -395.073886) (xy 315.595241 -395.081407) (xy 315.586832 -395.100699)
			(xy 315.586364 -395.111224) (xy 315.586364 -395.1859) (xy 315.58689 -395.196412) (xy 315.595284 -395.215691)
			(xy 315.60262 -395.223238) (xy 315.622344 -395.242123) (xy 315.655875 -395.285218) (xy 315.681852 -395.333247)
			(xy 315.699565 -395.384897) (xy 315.708531 -395.43876) (xy 315.709046 -395.466062) (xy 315.708613 -395.490179)
			(xy 315.701616 -395.537904) (xy 315.687765 -395.584107) (xy 315.667355 -395.62781) (xy 315.654436 -395.64818)
			(xy 315.648594 -395.656816) (xy 315.645038 -395.677136) (xy 315.663834 -395.759178) (xy 315.66655 -395.769109)
			(xy 315.678605 -395.785774) (xy 315.687202 -395.791436) (xy 315.708005 -395.80429) (xy 315.745925 -395.835167)
			(xy 315.778877 -395.871297) (xy 315.806143 -395.911891) (xy 315.827124 -395.956061) (xy 315.841364 -396.002842)
			(xy 315.848551 -396.051212) (xy 315.849 -396.075662) (xy 315.848491 -396.101796) (xy 315.840233 -396.153409)
			(xy 315.82395 -396.203077) (xy 315.812424 -396.226538) (xy 315.8088 -396.2344) (xy 315.806505 -396.251547)
			(xy 315.810025 -396.268485) (xy 315.814202 -396.276068) (xy 315.859668 -396.350236) (xy 315.864463 -396.357455)
			(xy 315.877884 -396.3684) (xy 315.89419 -396.374233) (xy 315.902848 -396.37462) (xy 316.333632 -396.37462)
			(xy 316.342283 -396.374222) (xy 316.358567 -396.368362) (xy 316.371977 -396.357423) (xy 316.376812 -396.350236)
			(xy 316.422278 -396.276068) (xy 316.426491 -396.268496) (xy 316.430049 -396.251547) (xy 316.427728 -396.234386)
			(xy 316.424056 -396.226538) (xy 316.412558 -396.203066) (xy 316.396286 -396.1534) (xy 316.388019 -396.101794)
			(xy 316.38748 -396.075662) (xy 316.387919 -396.051546) (xy 316.394924 -396.003825) (xy 316.408781 -395.957627)
			(xy 316.429195 -395.913928) (xy 316.44209 -395.893544) (xy 316.447932 -395.884908) (xy 316.451488 -395.864588)
			(xy 316.432692 -395.782546) (xy 316.429976 -395.772616) (xy 316.417915 -395.755959) (xy 316.409324 -395.750288)
			(xy 316.388523 -395.737431) (xy 316.350609 -395.706552) (xy 316.317661 -395.67042) (xy 316.2904 -395.629826)
			(xy 316.26942 -395.585658) (xy 316.255181 -395.538878) (xy 316.247993 -395.490511) (xy 316.247526 -395.466062)
			(xy 316.248119 -395.438771) (xy 316.257141 -395.384938) (xy 316.274868 -395.333313) (xy 316.300821 -395.285294)
			(xy 316.334296 -395.24218) (xy 316.353952 -395.223238) (xy 316.361326 -395.215715) (xy 316.369732 -395.196423)
			(xy 316.370208 -395.1859) (xy 316.370208 -395.111224) (xy 316.369686 -395.10071) (xy 316.361295 -395.081428)
			(xy 316.353952 -395.073886) (xy 316.334228 -395.055001) (xy 316.300696 -395.011905) (xy 316.274718 -394.963877)
			(xy 316.257003 -394.912227) (xy 316.248035 -394.858364) (xy 316.247526 -394.831062) (xy 316.24778 -394.81887)
			(xy 316.248034 -394.809218) (xy 316.241938 -394.791438) (xy 316.183518 -394.724128) (xy 316.166246 -394.715238)
			(xy 316.156848 -394.714222) (xy 316.129935 -394.71087) (xy 316.077637 -394.696524) (xy 316.028381 -394.673835)
			(xy 315.983489 -394.643411) (xy 315.944164 -394.606068) (xy 315.911461 -394.562809) (xy 315.886256 -394.514791)
			(xy 315.869226 -394.463304) (xy 315.864494 -394.4366) (xy 315.86297 -394.427202) (xy 315.590174 -393.95527)
			(xy 315.582808 -393.949428) (xy 315.564031 -393.933624) (xy 315.5309 -393.897416) (xy 315.503483 -393.856711)
			(xy 315.48238 -393.812402) (xy 315.468054 -393.765461) (xy 315.460821 -393.716919) (xy 315.46038 -393.69238)
			(xy 315.460891 -393.666394) (xy 315.469024 -393.615061) (xy 315.485087 -393.565632) (xy 315.508683 -393.519325)
			(xy 315.539233 -393.477278) (xy 315.575984 -393.440528) (xy 315.618031 -393.409979) (xy 315.664339 -393.386384)
			(xy 315.713769 -393.370322) (xy 315.765101 -393.36219) (xy 315.791088 -393.361672) (xy 315.817099 -393.362156)
			(xy 315.86848 -393.370301) (xy 315.917952 -393.386392) (xy 315.964293 -393.410032) (xy 316.006361 -393.440638)
			(xy 316.043116 -393.477454) (xy 316.073652 -393.519571) (xy 316.097216 -393.565951) (xy 316.113226 -393.615449)
			(xy 316.117732 -393.641072) (xy 316.119256 -393.65047) (xy 316.392052 -394.122402) (xy 316.399418 -394.128244)
			(xy 316.418195 -394.144049) (xy 316.451326 -394.180257) (xy 316.478745 -394.220962) (xy 316.49985 -394.26527)
			(xy 316.514178 -394.312211) (xy 316.521415 -394.360753) (xy 316.521846 -394.385292) (xy 316.521592 -394.397484)
			(xy 316.521338 -394.407136) (xy 316.527434 -394.424916) (xy 316.585854 -394.492226) (xy 316.603126 -394.501116)
			(xy 316.612524 -394.502132) (xy 316.639291 -394.50546) (xy 316.691316 -394.519687) (xy 316.740343 -394.542166)
			(xy 316.785074 -394.572302) (xy 316.824323 -394.609296) (xy 316.857049 -394.652168) (xy 316.882386 -394.699781)
			(xy 316.899661 -394.750875) (xy 316.908418 -394.804094) (xy 316.908942 -394.831062) (xy 316.908355 -394.858355)
			(xy 316.899343 -394.912194) (xy 316.881623 -394.963826) (xy 316.855676 -395.011853) (xy 316.822203 -395.054974)
			(xy 316.802516 -395.073886) (xy 316.795138 -395.081407) (xy 316.786729 -395.100699) (xy 316.78626 -395.111224)
			(xy 316.78626 -395.1859) (xy 316.786786 -395.196412) (xy 316.795179 -395.215691) (xy 316.802516 -395.223238)
			(xy 316.82224 -395.242123) (xy 316.855772 -395.285218) (xy 316.881749 -395.333246) (xy 316.899462 -395.384897)
			(xy 316.908428 -395.43876) (xy 316.908942 -395.466062) (xy 316.908509 -395.49018) (xy 316.901514 -395.537905)
			(xy 316.887667 -395.58411) (xy 316.867261 -395.627817) (xy 316.854332 -395.64818) (xy 316.84849 -395.656816)
			(xy 316.844934 -395.677136) (xy 316.86373 -395.759178) (xy 316.866445 -395.769109) (xy 316.8785 -395.785775)
			(xy 316.887098 -395.791436) (xy 316.907902 -395.80429) (xy 316.945822 -395.835166) (xy 316.978775 -395.871296)
			(xy 317.00604 -395.91189) (xy 317.027022 -395.95606) (xy 317.041262 -396.002842) (xy 317.048449 -396.051211)
			(xy 317.048896 -396.075662) (xy 317.048387 -396.101796) (xy 317.040129 -396.153409) (xy 317.023846 -396.203077)
			(xy 317.01232 -396.226538) (xy 317.008697 -396.2344) (xy 317.006401 -396.251547) (xy 317.009922 -396.268485)
			(xy 317.014098 -396.276068) (xy 317.059564 -396.350236) (xy 317.064359 -396.357455) (xy 317.07778 -396.368401)
			(xy 317.094086 -396.374236) (xy 317.102744 -396.37462) (xy 317.533782 -396.37462) (xy 317.542437 -396.37423)
			(xy 317.558733 -396.368381) (xy 317.572157 -396.357445) (xy 317.576962 -396.350236) (xy 317.622428 -396.276068)
			(xy 317.626638 -396.268495) (xy 317.630192 -396.251547) (xy 317.627874 -396.234388) (xy 317.624206 -396.226538)
			(xy 317.612706 -396.203067) (xy 317.596432 -396.1534) (xy 317.588163 -396.101794) (xy 317.58763 -396.075662)
			(xy 317.588069 -396.051546) (xy 317.595075 -396.003826) (xy 317.608933 -395.957628) (xy 317.629351 -395.913931)
			(xy 317.64224 -395.893544) (xy 317.648082 -395.884908) (xy 317.651638 -395.864588) (xy 317.632842 -395.782546)
			(xy 317.630129 -395.772614) (xy 317.618074 -395.755946) (xy 317.609474 -395.750288) (xy 317.588671 -395.737433)
			(xy 317.550751 -395.706556) (xy 317.517799 -395.670426) (xy 317.490533 -395.629833) (xy 317.469549 -395.585663)
			(xy 317.455308 -395.538882) (xy 317.448118 -395.490513) (xy 317.447676 -395.466062) (xy 317.448269 -395.438771)
			(xy 317.457292 -395.38494) (xy 317.475021 -395.333316) (xy 317.500977 -395.2853) (xy 317.534455 -395.24219)
			(xy 317.554102 -395.223238) (xy 317.561482 -395.215717) (xy 317.569897 -395.196425) (xy 317.570358 -395.1859)
			(xy 317.570358 -395.111224) (xy 317.569834 -395.100712) (xy 317.561438 -395.081435) (xy 317.554102 -395.073886)
			(xy 317.534381 -395.054999) (xy 317.500854 -395.011902) (xy 317.47488 -394.963874) (xy 317.457168 -394.912224)
			(xy 317.448201 -394.858363) (xy 317.447676 -394.831062) (xy 317.44793 -394.81887) (xy 317.448184 -394.809218)
			(xy 317.442088 -394.791438) (xy 317.390018 -394.731494) (xy 317.383393 -394.724482) (xy 317.366293 -394.715585)
			(xy 317.356744 -394.714222) (xy 317.329831 -394.71087) (xy 317.277534 -394.696523) (xy 317.228279 -394.673834)
			(xy 317.183387 -394.64341) (xy 317.144062 -394.606067) (xy 317.111359 -394.562807) (xy 317.086155 -394.51479)
			(xy 317.069125 -394.463304) (xy 317.06439 -394.4366) (xy 317.062866 -394.427202) (xy 316.79007 -393.95527)
			(xy 316.782704 -393.949428) (xy 316.763927 -393.933624) (xy 316.730797 -393.897416) (xy 316.70338 -393.85671)
			(xy 316.682277 -393.812401) (xy 316.667952 -393.765461) (xy 316.660719 -393.716919) (xy 316.660276 -393.69238)
			(xy 316.660787 -393.666393) (xy 316.66892 -393.61506) (xy 316.684983 -393.565631) (xy 316.708579 -393.519324)
			(xy 316.739129 -393.477277) (xy 316.77588 -393.440526) (xy 316.817927 -393.409977) (xy 316.864235 -393.386381)
			(xy 316.913664 -393.370319) (xy 316.964997 -393.362187) (xy 316.990984 -393.361672) (xy 317.016996 -393.362156)
			(xy 317.068377 -393.3703) (xy 317.117849 -393.386391) (xy 317.164191 -393.410031) (xy 317.206259 -393.440636)
			(xy 317.243015 -393.477452) (xy 317.273551 -393.51957) (xy 317.297115 -393.56595) (xy 317.313125 -393.615449)
			(xy 317.317628 -393.641072) (xy 317.319152 -393.65047) (xy 317.591948 -394.122402) (xy 317.599314 -394.128244)
			(xy 317.618091 -394.144048) (xy 317.651223 -394.180256) (xy 317.678642 -394.220961) (xy 317.699748 -394.26527)
			(xy 317.714076 -394.31221) (xy 317.721312 -394.360753) (xy 317.721742 -394.385292) (xy 317.721488 -394.397484)
			(xy 317.721234 -394.407136) (xy 317.72733 -394.424916) (xy 317.7794 -394.48486) (xy 317.78603 -394.491864)
			(xy 317.803131 -394.500745) (xy 317.812674 -394.502132) (xy 317.839444 -394.505456) (xy 317.891475 -394.519677)
			(xy 317.940509 -394.542153) (xy 317.985247 -394.572287) (xy 318.024502 -394.609281) (xy 318.057234 -394.652154)
			(xy 318.082575 -394.699771) (xy 318.099854 -394.750868) (xy 318.108613 -394.804092) (xy 318.109092 -394.831062)
			(xy 318.108505 -394.858355) (xy 318.099492 -394.912193) (xy 318.08177 -394.963823) (xy 318.05582 -395.011847)
			(xy 318.022343 -395.054964) (xy 318.002666 -395.073886) (xy 317.995293 -395.08141) (xy 317.986894 -395.100701)
			(xy 317.98641 -395.111224) (xy 317.98641 -395.1859) (xy 317.986937 -395.196411) (xy 317.995336 -395.215685)
			(xy 318.002666 -395.223238) (xy 318.022388 -395.242124) (xy 318.055914 -395.285221) (xy 318.081887 -395.33325)
			(xy 318.099598 -395.3849) (xy 318.108562 -395.438761) (xy 318.109092 -395.466062) (xy 318.108659 -395.49018)
			(xy 318.101663 -395.537904) (xy 318.087814 -395.584109) (xy 318.067405 -395.627813) (xy 318.054482 -395.64818)
			(xy 318.04864 -395.656816) (xy 318.045084 -395.677136) (xy 318.06388 -395.759178) (xy 318.066598 -395.769106)
			(xy 318.07866 -395.785762) (xy 318.087248 -395.791436) (xy 318.108049 -395.804292) (xy 318.145964 -395.835171)
			(xy 318.178912 -395.871302) (xy 318.206173 -395.911896) (xy 318.227151 -395.956066) (xy 318.241389 -396.002845)
			(xy 318.248574 -396.051213) (xy 318.249046 -396.075662) (xy 318.248537 -396.101797) (xy 318.24028 -396.15341)
			(xy 318.223999 -396.203079) (xy 318.21247 -396.226538) (xy 318.208844 -396.234399) (xy 318.206546 -396.251547)
			(xy 318.21007 -396.268486) (xy 318.214248 -396.276068) (xy 318.259714 -396.350236) (xy 318.264511 -396.35745)
			(xy 318.277934 -396.368383) (xy 318.294239 -396.374202) (xy 318.302894 -396.37462) (xy 318.733678 -396.37462)
			(xy 318.742333 -396.37423) (xy 318.758631 -396.368382) (xy 318.772055 -396.357447) (xy 318.776858 -396.350236)
			(xy 318.822324 -396.276068) (xy 318.826535 -396.268495) (xy 318.830089 -396.251547) (xy 318.82777 -396.234387)
			(xy 318.824102 -396.226538) (xy 318.812602 -396.203067) (xy 318.796328 -396.1534) (xy 318.78806 -396.101794)
			(xy 318.787526 -396.075662) (xy 318.787965 -396.051546) (xy 318.794971 -396.003826) (xy 318.808829 -395.957628)
			(xy 318.829246 -395.913931) (xy 318.842136 -395.893544) (xy 318.847978 -395.884908) (xy 318.851534 -395.864588)
			(xy 318.832738 -395.782546) (xy 318.830025 -395.772614) (xy 318.81797 -395.755947) (xy 318.80937 -395.750288)
			(xy 318.788567 -395.737433) (xy 318.750648 -395.706556) (xy 318.717696 -395.670426) (xy 318.69043 -395.629832)
			(xy 318.669447 -395.585662) (xy 318.655205 -395.538882) (xy 318.648016 -395.490512) (xy 318.647572 -395.466062)
			(xy 318.648165 -395.438771) (xy 318.657188 -395.384939) (xy 318.674917 -395.333316) (xy 318.700872 -395.285299)
			(xy 318.73435 -395.242189) (xy 318.753998 -395.223238) (xy 318.761379 -395.215718) (xy 318.769794 -395.196426)
			(xy 318.770254 -395.1859) (xy 318.770254 -395.111224) (xy 318.76973 -395.100712) (xy 318.761333 -395.081435)
			(xy 318.753998 -395.073886) (xy 318.734277 -395.054999) (xy 318.70075 -395.011902) (xy 318.674777 -394.963873)
			(xy 318.657065 -394.912224) (xy 318.648098 -394.858363) (xy 318.647572 -394.831062) (xy 318.647826 -394.81887)
			(xy 318.64808 -394.809218) (xy 318.641984 -394.791438) (xy 318.589914 -394.731494) (xy 318.583289 -394.724482)
			(xy 318.566188 -394.715587) (xy 318.55664 -394.714222) (xy 318.529689 -394.710859) (xy 318.477318 -394.69648)
			(xy 318.427996 -394.673744) (xy 318.383048 -394.643262) (xy 318.343678 -394.605851) (xy 318.310944 -394.562516)
			(xy 318.285722 -394.514418) (xy 318.268691 -394.462848) (xy 318.264032 -394.436092) (xy 318.262762 -394.426694)
			(xy 317.99022 -393.95527) (xy 317.982854 -393.949428) (xy 317.964075 -393.933625) (xy 317.93094 -393.897419)
			(xy 317.903518 -393.856715) (xy 317.882412 -393.812405) (xy 317.868085 -393.765463) (xy 317.86085 -393.71692)
			(xy 317.860426 -393.69238) (xy 317.860911 -393.666393) (xy 317.869045 -393.615059) (xy 317.885109 -393.565629)
			(xy 317.908708 -393.519321) (xy 317.939262 -393.477275) (xy 317.976016 -393.440526) (xy 318.018067 -393.40998)
			(xy 318.064379 -393.386388) (xy 318.113811 -393.370332) (xy 318.165147 -393.362206) (xy 318.191134 -393.361672)
			(xy 318.217148 -393.362152) (xy 318.268535 -393.37029) (xy 318.318014 -393.386377) (xy 318.364362 -393.410013)
			(xy 318.406437 -393.440618) (xy 318.443199 -393.477434) (xy 318.473741 -393.519553) (xy 318.49731 -393.565937)
			(xy 318.513323 -393.615439) (xy 318.517778 -393.641072) (xy 318.519302 -393.65047) (xy 318.792352 -394.12291)
			(xy 318.799464 -394.128752) (xy 318.818192 -394.144534) (xy 318.851235 -394.180681) (xy 318.878582 -394.221309)
			(xy 318.899634 -394.265527) (xy 318.913931 -394.312367) (xy 318.921159 -394.360805) (xy 318.921638 -394.385292)
			(xy 318.921384 -394.397484) (xy 318.92113 -394.407136) (xy 318.927226 -394.424916) (xy 318.979296 -394.48486)
			(xy 318.985925 -394.491864) (xy 319.003027 -394.500747) (xy 319.01257 -394.502132) (xy 319.03934 -394.505456)
			(xy 319.091372 -394.519677) (xy 319.140407 -394.542152) (xy 319.185145 -394.572285) (xy 319.2244 -394.609279)
			(xy 319.257133 -394.652153) (xy 319.282475 -394.69977) (xy 319.299754 -394.750868) (xy 319.308513 -394.804092)
			(xy 319.308988 -394.831062) (xy 319.308401 -394.858356) (xy 319.29939 -394.912196) (xy 319.281672 -394.963829)
			(xy 319.255727 -395.011858) (xy 319.222257 -395.054982) (xy 319.202562 -395.073886) (xy 319.19519 -395.08141)
			(xy 319.186791 -395.100701) (xy 319.186306 -395.111224) (xy 319.186306 -395.1859) (xy 319.186833 -395.196411)
			(xy 319.195232 -395.215685) (xy 319.202562 -395.223238) (xy 319.222284 -395.242124) (xy 319.255811 -395.285221)
			(xy 319.281784 -395.333249) (xy 319.299495 -395.384899) (xy 319.308459 -395.438761) (xy 319.308988 -395.466062)
			(xy 319.308555 -395.49018) (xy 319.301559 -395.537904) (xy 319.28771 -395.584108) (xy 319.267301 -395.627813)
			(xy 319.254378 -395.64818) (xy 319.248536 -395.656816) (xy 319.24498 -395.677136) (xy 319.263776 -395.759178)
			(xy 319.266494 -395.769107) (xy 319.278555 -395.785764) (xy 319.287144 -395.791436) (xy 319.307945 -395.804292)
			(xy 319.34586 -395.835171) (xy 319.378809 -395.871302) (xy 319.40607 -395.911896) (xy 319.427049 -395.956065)
			(xy 319.441287 -396.002845) (xy 319.448472 -396.051213) (xy 319.448942 -396.075662) (xy 319.448433 -396.101796)
			(xy 319.440176 -396.15341) (xy 319.423895 -396.203079) (xy 319.412366 -396.226538) (xy 319.40874 -396.234399)
			(xy 319.406442 -396.251547) (xy 319.409966 -396.268486) (xy 319.414144 -396.276068) (xy 319.45961 -396.350236)
			(xy 319.464406 -396.35745) (xy 319.477829 -396.368384) (xy 319.494135 -396.374205) (xy 319.50279 -396.37462)
			(xy 319.933828 -396.37462) (xy 319.942479 -396.374222) (xy 319.958764 -396.368364) (xy 319.972175 -396.357425)
			(xy 319.977008 -396.350236) (xy 320.022474 -396.276068) (xy 320.026688 -396.268496) (xy 320.030246 -396.251547)
			(xy 320.027925 -396.234386) (xy 320.024252 -396.226538) (xy 320.012754 -396.203066) (xy 319.996482 -396.1534)
			(xy 319.988215 -396.101794) (xy 319.987676 -396.075662) (xy 319.988115 -396.051546) (xy 319.99512 -396.003825)
			(xy 320.008976 -395.957627) (xy 320.029391 -395.913928) (xy 320.042286 -395.893544) (xy 320.048128 -395.884908)
			(xy 320.051684 -395.864588) (xy 320.032888 -395.782546) (xy 320.030172 -395.772617) (xy 320.01811 -395.75596)
			(xy 320.00952 -395.750288) (xy 319.988714 -395.737435) (xy 319.95079 -395.706561) (xy 319.917833 -395.670432)
			(xy 319.890563 -395.629838) (xy 319.869576 -395.585667) (xy 319.855332 -395.538885) (xy 319.848142 -395.490514)
			(xy 319.847722 -395.466062) (xy 319.848315 -395.438771) (xy 319.857337 -395.384938) (xy 319.875064 -395.333313)
			(xy 319.901016 -395.285293) (xy 319.934491 -395.24218) (xy 319.954148 -395.223238) (xy 319.961523 -395.215715)
			(xy 319.969929 -395.196424) (xy 319.970404 -395.1859) (xy 319.970404 -395.111224) (xy 319.969882 -395.10071)
			(xy 319.96149 -395.081429) (xy 319.954148 -395.073886) (xy 319.934424 -395.055001) (xy 319.900893 -395.011905)
			(xy 319.874915 -394.963877) (xy 319.8572 -394.912226) (xy 319.848232 -394.858364) (xy 319.847722 -394.831062)
			(xy 319.847976 -394.81887) (xy 319.84823 -394.809218) (xy 319.842134 -394.791438) (xy 319.790064 -394.731494)
			(xy 319.783436 -394.724489) (xy 319.766333 -394.71561) (xy 319.75679 -394.714222) (xy 319.729875 -394.710873)
			(xy 319.677572 -394.696532) (xy 319.62831 -394.673846) (xy 319.583412 -394.643424) (xy 319.544082 -394.606082)
			(xy 319.511374 -394.562821) (xy 319.486165 -394.514802) (xy 319.469132 -394.463312) (xy 319.464436 -394.4366)
			(xy 319.462912 -394.427202) (xy 319.190116 -393.95527) (xy 319.18275 -393.949428) (xy 319.163971 -393.933625)
			(xy 319.130836 -393.897419) (xy 319.103415 -393.856714) (xy 319.082309 -393.812405) (xy 319.067982 -393.765463)
			(xy 319.060748 -393.71692) (xy 319.060322 -393.69238) (xy 319.060807 -393.666393) (xy 319.068941 -393.615058)
			(xy 319.085005 -393.565628) (xy 319.108604 -393.51932) (xy 319.139157 -393.477274) (xy 319.175912 -393.440525)
			(xy 319.217963 -393.409978) (xy 319.264275 -393.386386) (xy 319.313707 -393.370329) (xy 319.365043 -393.362203)
			(xy 319.39103 -393.361672) (xy 319.417044 -393.362152) (xy 319.468432 -393.37029) (xy 319.517911 -393.386375)
			(xy 319.56426 -393.410012) (xy 319.606335 -393.440616) (xy 319.643098 -393.477432) (xy 319.67364 -393.519552)
			(xy 319.697209 -393.565936) (xy 319.713223 -393.615438) (xy 319.717674 -393.641072) (xy 319.719198 -393.65047)
			(xy 319.991994 -394.122402) (xy 319.99936 -394.128244) (xy 320.01814 -394.144047) (xy 320.051277 -394.180253)
			(xy 320.078701 -394.220957) (xy 320.09981 -394.265266) (xy 320.11414 -394.312208) (xy 320.121378 -394.360752)
			(xy 320.121788 -394.385292) (xy 320.121534 -394.397484) (xy 320.12128 -394.407136) (xy 320.127376 -394.424916)
			(xy 320.179446 -394.48486) (xy 320.186078 -394.491858) (xy 320.203181 -394.500724) (xy 320.21272 -394.502132)
			(xy 320.239487 -394.50546) (xy 320.291513 -394.519686) (xy 320.340541 -394.542165) (xy 320.385272 -394.5723)
			(xy 320.424521 -394.609295) (xy 320.457248 -394.652167) (xy 320.482585 -394.69978) (xy 320.499861 -394.750874)
			(xy 320.508618 -394.804094) (xy 320.509138 -394.831062) (xy 320.508551 -394.858355) (xy 320.499539 -394.912194)
			(xy 320.481819 -394.963826) (xy 320.455871 -395.011852) (xy 320.422398 -395.054973) (xy 320.402712 -395.073886)
			(xy 320.395334 -395.081407) (xy 320.386926 -395.100699) (xy 320.386456 -395.111224) (xy 320.386456 -395.1859)
			(xy 320.386982 -395.196412) (xy 320.395375 -395.215692) (xy 320.402712 -395.223238) (xy 320.422431 -395.242126)
			(xy 320.455953 -395.285224) (xy 320.481923 -395.333253) (xy 320.499631 -395.384902) (xy 320.508593 -395.438762)
			(xy 320.509138 -395.466062) (xy 320.508705 -395.49018) (xy 320.50171 -395.537905) (xy 320.487863 -395.58411)
			(xy 320.467456 -395.627816) (xy 320.454528 -395.64818) (xy 320.448686 -395.656816) (xy 320.44513 -395.677136)
			(xy 320.463926 -395.759178) (xy 320.466641 -395.769109) (xy 320.478695 -395.785776) (xy 320.487294 -395.791436)
			(xy 320.508098 -395.80429) (xy 320.546018 -395.835166) (xy 320.578972 -395.871296) (xy 320.606237 -395.91189)
			(xy 320.62722 -395.95606) (xy 320.64146 -396.002842) (xy 320.648646 -396.051211) (xy 320.649092 -396.075662)
			(xy 320.648583 -396.101796) (xy 320.640325 -396.153409) (xy 320.624041 -396.203077) (xy 320.612516 -396.226538)
			(xy 320.608893 -396.2344) (xy 320.606598 -396.251547) (xy 320.610118 -396.268485) (xy 320.614294 -396.276068)
			(xy 320.65976 -396.350236) (xy 320.664554 -396.357456) (xy 320.677975 -396.368403) (xy 320.694282 -396.374239)
			(xy 320.70294 -396.37462) (xy 321.133724 -396.37462) (xy 321.142375 -396.374223) (xy 321.158662 -396.368365)
			(xy 321.172074 -396.357426) (xy 321.176904 -396.350236) (xy 321.22237 -396.276068) (xy 321.226584 -396.268496)
			(xy 321.230142 -396.251547) (xy 321.227821 -396.234386) (xy 321.224148 -396.226538) (xy 321.21265 -396.203066)
			(xy 321.196378 -396.1534) (xy 321.188111 -396.101793) (xy 321.187572 -396.075662) (xy 321.188011 -396.051546)
			(xy 321.195016 -396.003825) (xy 321.208872 -395.957626) (xy 321.229286 -395.913928) (xy 321.242182 -395.893544)
			(xy 321.248024 -395.884908) (xy 321.25158 -395.864588) (xy 321.232784 -395.782546) (xy 321.230068 -395.772617)
			(xy 321.218006 -395.755961) (xy 321.209416 -395.750288) (xy 321.188611 -395.737435) (xy 321.150687 -395.70656)
			(xy 321.11773 -395.670431) (xy 321.09046 -395.629838) (xy 321.069474 -395.585667) (xy 321.05523 -395.538885)
			(xy 321.04804 -395.490514) (xy 321.047618 -395.466062) (xy 321.048211 -395.438771) (xy 321.057233 -395.384938)
			(xy 321.07496 -395.333313) (xy 321.100912 -395.285293) (xy 321.134386 -395.242179) (xy 321.154044 -395.223238)
			(xy 321.161419 -395.215715) (xy 321.169827 -395.196424) (xy 321.1703 -395.1859) (xy 321.1703 -395.111224)
			(xy 321.169778 -395.100711) (xy 321.161386 -395.081429) (xy 321.154044 -395.073886) (xy 321.13432 -395.055001)
			(xy 321.100789 -395.011905) (xy 321.074812 -394.963876) (xy 321.057098 -394.912226) (xy 321.048129 -394.858364)
			(xy 321.047618 -394.831062) (xy 321.047872 -394.81887) (xy 321.048126 -394.809218) (xy 321.04203 -394.791438)
			(xy 320.98996 -394.731494) (xy 320.983331 -394.72449) (xy 320.966229 -394.715612) (xy 320.956686 -394.714222)
			(xy 320.929738 -394.710855) (xy 320.877373 -394.69647) (xy 320.828059 -394.67373) (xy 320.783118 -394.643245)
			(xy 320.743755 -394.605834) (xy 320.711027 -394.5625) (xy 320.685811 -394.514405) (xy 320.668783 -394.462839)
			(xy 320.664078 -394.436092) (xy 320.662808 -394.426694) (xy 320.390266 -393.95527) (xy 320.3829 -393.949428)
			(xy 320.364123 -393.933623) (xy 320.330993 -393.897415) (xy 320.303576 -393.85671) (xy 320.282474 -393.812401)
			(xy 320.268149 -393.765461) (xy 320.260916 -393.716919) (xy 320.260472 -393.69238) (xy 320.260983 -393.666393)
			(xy 320.269116 -393.61506) (xy 320.285178 -393.565631) (xy 320.308775 -393.519323) (xy 320.339325 -393.477276)
			(xy 320.376076 -393.440525) (xy 320.418123 -393.409975) (xy 320.464431 -393.386378) (xy 320.51386 -393.370316)
			(xy 320.565193 -393.362183) (xy 320.59118 -393.361672) (xy 320.617192 -393.362156) (xy 320.668574 -393.3703)
			(xy 320.718046 -393.38639) (xy 320.764389 -393.41003) (xy 320.806457 -393.440635) (xy 320.843213 -393.477451)
			(xy 320.873751 -393.519569) (xy 320.897315 -393.565949) (xy 320.913325 -393.615448) (xy 320.917824 -393.641072)
			(xy 320.919348 -393.65047) (xy 320.94357 -393.69238) (xy 321.460368 -393.69238) (xy 321.460883 -393.666393)
			(xy 321.469016 -393.615061) (xy 321.485078 -393.565632) (xy 321.508674 -393.519324) (xy 321.539224 -393.477277)
			(xy 321.575974 -393.440526) (xy 321.61802 -393.409976) (xy 321.664328 -393.38638) (xy 321.713757 -393.370317)
			(xy 321.765089 -393.362183) (xy 321.791076 -393.361672) (xy 321.817085 -393.362163) (xy 321.868461 -393.370319)
			(xy 321.917927 -393.386416) (xy 321.964263 -393.410059) (xy 322.006326 -393.440663) (xy 322.04308 -393.477476)
			(xy 322.073618 -393.519588) (xy 322.097186 -393.565961) (xy 322.113205 -393.615453) (xy 322.11772 -393.641072)
			(xy 322.119244 -393.65047) (xy 322.39204 -394.122402) (xy 322.399406 -394.128244) (xy 322.418189 -394.14404)
			(xy 322.451306 -394.180258) (xy 322.478715 -394.220968) (xy 322.499815 -394.265277) (xy 322.514144 -394.312215)
			(xy 322.521389 -394.360754) (xy 322.521834 -394.385292) (xy 322.52158 -394.396976) (xy 322.52167 -394.406688)
			(xy 322.528196 -394.424965) (xy 322.53428 -394.432536) (xy 322.586858 -394.491972) (xy 322.60413 -394.500862)
			(xy 322.613782 -394.501624) (xy 322.638122 -394.504238) (xy 322.685672 -394.515879) (xy 322.730989 -394.534397)
			(xy 322.773084 -394.559389) (xy 322.811038 -394.59031) (xy 322.844023 -394.626483) (xy 322.87132 -394.667121)
			(xy 322.892333 -394.711337) (xy 322.906603 -394.758165) (xy 322.91382 -394.806585) (xy 322.914264 -394.831062)
			(xy 322.913754 -394.857049) (xy 322.905624 -394.908384) (xy 322.889563 -394.957814) (xy 322.865967 -395.004124)
			(xy 322.835417 -395.046172) (xy 322.798666 -395.082923) (xy 322.756618 -395.113473) (xy 322.710308 -395.137069)
			(xy 322.660878 -395.15313) (xy 322.609543 -395.16126) (xy 322.557569 -395.16126) (xy 322.506234 -395.15313)
			(xy 322.456804 -395.137069) (xy 322.410494 -395.113473) (xy 322.368446 -395.082923) (xy 322.331695 -395.046172)
			(xy 322.301145 -395.004124) (xy 322.277549 -394.957814) (xy 322.261488 -394.908384) (xy 322.253358 -394.857049)
			(xy 322.252848 -394.831062) (xy 322.253102 -394.819378) (xy 322.253017 -394.809666) (xy 322.246485 -394.79139)
			(xy 322.240402 -394.783818) (xy 322.187824 -394.724382) (xy 322.170552 -394.715492) (xy 322.1609 -394.71473)
			(xy 322.136717 -394.712055) (xy 322.089453 -394.700515) (xy 322.044386 -394.682182) (xy 322.002488 -394.657451)
			(xy 321.964661 -394.626853) (xy 321.93172 -394.591049) (xy 321.904374 -394.550808) (xy 321.883212 -394.506998)
			(xy 321.868691 -394.460563) (xy 321.864482 -394.4366) (xy 321.862958 -394.427202) (xy 321.590162 -393.95527)
			(xy 321.582796 -393.949428) (xy 321.564048 -393.933592) (xy 321.530929 -393.897382) (xy 321.503515 -393.856681)
			(xy 321.482409 -393.81238) (xy 321.468072 -393.765449) (xy 321.460818 -393.716916) (xy 321.460368 -393.69238)
			(xy 320.94357 -393.69238) (xy 321.192398 -394.12291) (xy 321.19951 -394.128752) (xy 321.218241 -394.144532)
			(xy 321.251289 -394.180677) (xy 321.27864 -394.221304) (xy 321.299696 -394.265523) (xy 321.313995 -394.312365)
			(xy 321.321225 -394.360804) (xy 321.321684 -394.385292) (xy 321.32143 -394.397484) (xy 321.321176 -394.407136)
			(xy 321.327272 -394.424916) (xy 321.379342 -394.48486) (xy 321.385974 -394.491858) (xy 321.403077 -394.500725)
			(xy 321.412616 -394.502132) (xy 321.439383 -394.505459) (xy 321.491409 -394.519685) (xy 321.540438 -394.542164)
			(xy 321.58517 -394.572299) (xy 321.624419 -394.609293) (xy 321.657146 -394.652165) (xy 321.682484 -394.69978)
			(xy 321.69976 -394.750874) (xy 321.708518 -394.804094) (xy 321.709034 -394.831062) (xy 321.708447 -394.858355)
			(xy 321.699435 -394.912194) (xy 321.681715 -394.963826) (xy 321.655767 -395.011852) (xy 321.622293 -395.054972)
			(xy 321.602608 -395.073886) (xy 321.595231 -395.081408) (xy 321.586824 -395.1007) (xy 321.586352 -395.111224)
			(xy 321.586352 -395.1859) (xy 321.586878 -395.196413) (xy 321.59527 -395.215692) (xy 321.602608 -395.223238)
			(xy 321.622327 -395.242125) (xy 321.65585 -395.285223) (xy 321.68182 -395.333252) (xy 321.699528 -395.384902)
			(xy 321.708491 -395.438761) (xy 321.709034 -395.466062) (xy 321.708601 -395.49018) (xy 321.701606 -395.537905)
			(xy 321.687758 -395.58411) (xy 321.667352 -395.627816) (xy 321.654424 -395.64818) (xy 321.648582 -395.656816)
			(xy 321.645026 -395.677136) (xy 321.663822 -395.759178) (xy 321.666537 -395.76911) (xy 321.67859 -395.785777)
			(xy 321.68719 -395.791436) (xy 321.707994 -395.80429) (xy 321.745915 -395.835165) (xy 321.778869 -395.871295)
			(xy 321.806135 -395.911889) (xy 321.827117 -395.95606) (xy 321.841358 -396.002841) (xy 321.848544 -396.051211)
			(xy 321.848988 -396.075662) (xy 321.848506 -396.10136) (xy 321.84057 -396.152138) (xy 321.824883 -396.20108)
			(xy 321.801821 -396.247011) (xy 321.787266 -396.268194) (xy 321.782414 -396.275698) (xy 321.777669 -396.292913)
			(xy 321.77908 -396.310714) (xy 321.78244 -396.318994) (xy 321.800728 -396.358618) (xy 321.82562 -396.37462)
			(xy 321.836542 -396.37462) (xy 322.133214 -396.671292) (xy 323.495924 -396.671292) (xy 323.496434 -396.645305)
			(xy 323.504564 -396.59397) (xy 323.520625 -396.54454) (xy 323.544221 -396.49823) (xy 323.574771 -396.456182)
			(xy 323.611522 -396.419431) (xy 323.65357 -396.388881) (xy 323.69988 -396.365285) (xy 323.74931 -396.349224)
			(xy 323.800645 -396.341094) (xy 323.852619 -396.341094) (xy 323.903954 -396.349224) (xy 323.953384 -396.365285)
			(xy 323.999694 -396.388881) (xy 324.041742 -396.419431) (xy 324.078493 -396.456182) (xy 324.109043 -396.49823)
			(xy 324.132639 -396.54454) (xy 324.1487 -396.59397) (xy 324.15683 -396.645305) (xy 324.15734 -396.671292)
			(xy 324.156802 -396.698914) (xy 324.147617 -396.753389) (xy 324.129517 -396.805584) (xy 324.103004 -396.85405)
			(xy 324.068815 -396.897443) (xy 324.027897 -396.934559) (xy 324.00494 -396.94993) (xy 323.99351 -396.957042)
			(xy 323.981064 -396.980918) (xy 323.98462 -397.094964) (xy 323.998336 -397.11757) (xy 324.010274 -397.124174)
			(xy 324.031988 -397.136777) (xy 324.071646 -397.167565) (xy 324.106191 -397.203996) (xy 324.13483 -397.245233)
			(xy 324.156903 -397.290326) (xy 324.171903 -397.338239) (xy 324.179485 -397.387869) (xy 324.179946 -397.412972)
			(xy 324.179461 -397.437379) (xy 324.172277 -397.485661) (xy 324.158076 -397.532363) (xy 324.137166 -397.576471)
			(xy 324.110001 -397.617028) (xy 324.077171 -397.653152) (xy 324.039389 -397.684059) (xy 324.018656 -397.696944)
			(xy 324.006972 -397.703802) (xy 323.994018 -397.726916) (xy 323.994018 -397.828008) (xy 323.994418 -397.836665)
			(xy 324.000242 -397.852973) (xy 324.011184 -397.866394) (xy 324.018402 -397.871188) (xy 324.018402 -397.871442)
			(xy 324.01891 -397.871442) (xy 324.03957 -397.884374) (xy 324.077257 -397.915278) (xy 324.109999 -397.951378)
			(xy 324.137089 -397.991894) (xy 324.157938 -398.035947) (xy 324.172095 -398.082583) (xy 324.179255 -398.130791)
			(xy 324.179692 -398.15516) (xy 324.179264 -398.178933) (xy 324.172466 -398.225991) (xy 324.15899 -398.271588)
			(xy 324.139115 -398.314781) (xy 324.113251 -398.354678) (xy 324.097904 -398.372838) (xy 324.092217 -398.379957)
			(xy 324.085835 -398.397008) (xy 324.085458 -398.406112) (xy 324.085458 -398.437608) (xy 324.085837 -398.446711)
			(xy 324.09222 -398.463761) (xy 324.097904 -398.470882) (xy 324.113249 -398.489044) (xy 324.139104 -398.528945)
			(xy 324.158979 -398.572138) (xy 324.172462 -398.617732) (xy 324.179277 -398.664787) (xy 324.179692 -398.68856)
			(xy 324.179182 -398.714547) (xy 324.171052 -398.765882) (xy 324.154991 -398.815312) (xy 324.131395 -398.861622)
			(xy 324.100845 -398.90367) (xy 324.064094 -398.940421) (xy 324.022046 -398.970971) (xy 323.975736 -398.994567)
			(xy 323.926306 -399.010628) (xy 323.874971 -399.018758) (xy 323.822997 -399.018758) (xy 323.771662 -399.010628)
			(xy 323.722232 -398.994567) (xy 323.675922 -398.970971) (xy 323.633874 -398.940421) (xy 323.597123 -398.90367)
			(xy 323.566573 -398.861622) (xy 323.542977 -398.815312) (xy 323.526916 -398.765882) (xy 323.518786 -398.714547)
			(xy 323.518276 -398.68856) (xy 323.518699 -398.664786) (xy 323.525496 -398.617727) (xy 323.538972 -398.57213)
			(xy 323.558849 -398.528937) (xy 323.584715 -398.489041) (xy 323.600064 -398.470882) (xy 323.605739 -398.463755)
			(xy 323.612129 -398.44671) (xy 323.61251 -398.437608) (xy 323.61251 -398.406112) (xy 323.612106 -398.397012)
			(xy 323.605738 -398.379962) (xy 323.600064 -398.372838) (xy 323.584724 -398.354673) (xy 323.558869 -398.314772)
			(xy 323.538994 -398.27158) (xy 323.525509 -398.225987) (xy 323.518692 -398.178933) (xy 323.518276 -398.15516)
			(xy 323.518697 -398.130751) (xy 323.525891 -398.082466) (xy 323.540103 -398.035761) (xy 323.561023 -397.991653)
			(xy 323.588198 -397.951097) (xy 323.621038 -397.914975) (xy 323.658829 -397.884071) (xy 323.679566 -397.871188)
			(xy 323.69125 -397.86433) (xy 323.704204 -397.841216) (xy 323.704204 -397.740124) (xy 323.703841 -397.731464)
			(xy 323.697998 -397.715156) (xy 323.687043 -397.701736) (xy 323.67982 -397.696944) (xy 323.67982 -397.69669)
			(xy 323.679312 -397.69669) (xy 323.658604 -397.683833) (xy 323.620921 -397.652914) (xy 323.588184 -397.616799)
			(xy 323.561102 -397.576271) (xy 323.54026 -397.532207) (xy 323.526112 -397.485561) (xy 323.518962 -397.437344)
			(xy 323.51853 -397.412972) (xy 323.519085 -397.38535) (xy 323.528262 -397.330875) (xy 323.546356 -397.278679)
			(xy 323.572865 -397.230211) (xy 323.607054 -397.186818) (xy 323.647972 -397.149703) (xy 323.67093 -397.134334)
			(xy 323.68236 -397.127222) (xy 323.694806 -397.103346) (xy 323.69125 -396.9893) (xy 323.677534 -396.966694)
			(xy 323.665596 -396.96009) (xy 323.643903 -396.947453) (xy 323.604247 -396.916669) (xy 323.569702 -396.880243)
			(xy 323.541062 -396.839012) (xy 323.518985 -396.793925) (xy 323.503979 -396.746018) (xy 323.49639 -396.696393)
			(xy 323.495924 -396.671292) (xy 322.133214 -396.671292) (xy 323.097652 -397.63573) (xy 323.104499 -397.643128)
			(xy 323.11223 -397.661726) (xy 323.112638 -397.671798) (xy 323.112638 -399.358358) (xy 323.115432 -399.364962)
			(xy 323.503798 -399.753328) (xy 323.511193 -399.760183) (xy 323.529792 -399.767929) (xy 323.539866 -399.768314)
			(xy 323.903848 -399.768314) (xy 323.913915 -399.767883) (xy 323.932508 -399.760158) (xy 323.939916 -399.753328)
			(xy 324.49008 -399.203164) (xy 324.496923 -399.195765) (xy 324.504648 -399.177166) (xy 324.505066 -399.167096)
			(xy 324.505066 -397.577564) (xy 324.504604 -397.567687) (xy 324.497164 -397.549387) (xy 324.490588 -397.542004)
			(xy 324.472016 -397.522456) (xy 324.44 -397.479073) (xy 324.41441 -397.431614) (xy 324.395757 -397.381025)
			(xy 324.384413 -397.328314) (xy 324.380604 -397.27453) (xy 324.384405 -397.220746) (xy 324.395741 -397.168033)
			(xy 324.414385 -397.117441) (xy 324.439968 -397.069978) (xy 324.471978 -397.026589) (xy 324.490588 -397.00708)
			(xy 324.497172 -396.999699) (xy 324.504629 -396.9814) (xy 324.505066 -396.97152) (xy 324.505066 -395.23289)
			(xy 324.481952 -395.20495) (xy 324.463918 -395.201394) (xy 324.438141 -395.195967) (xy 324.388285 -395.178961)
			(xy 324.341243 -395.155256) (xy 324.297911 -395.125302) (xy 324.259113 -395.089671) (xy 324.225588 -395.049039)
			(xy 324.197973 -395.004181) (xy 324.176795 -394.955949) (xy 324.162455 -394.905261) (xy 324.155227 -394.853083)
			(xy 324.1548 -394.826744) (xy 324.1548 -394.826236) (xy 324.155066 -394.806272) (xy 324.159271 -394.766567)
			(xy 324.163182 -394.746988) (xy 324.16623 -394.733526) (xy 324.157594 -394.707364) (xy 324.080124 -394.639546)
			(xy 324.073037 -394.633893) (xy 324.05608 -394.627517) (xy 324.037963 -394.627402) (xy 324.029324 -394.630148)
			(xy 323.997931 -394.640775) (xy 323.932665 -394.652269) (xy 323.89953 -394.653008) (xy 323.872276 -394.652547)
			(xy 323.818322 -394.644793) (xy 323.76602 -394.62944) (xy 323.716436 -394.606799) (xy 323.670579 -394.577332)
			(xy 323.629383 -394.541638) (xy 323.593686 -394.500445) (xy 323.564215 -394.45459) (xy 323.541571 -394.405008)
			(xy 323.526213 -394.352708) (xy 323.518455 -394.298754) (xy 323.518022 -394.2715) (xy 323.518462 -394.245518)
			(xy 323.525517 -394.194035) (xy 323.539498 -394.143988) (xy 323.560144 -394.096301) (xy 323.587074 -394.05186)
			(xy 323.619789 -394.011487) (xy 323.638418 -393.99337) (xy 323.647035 -393.984441) (xy 323.655139 -393.961016)
			(xy 323.653912 -393.948666) (xy 323.639688 -393.853416) (xy 323.62521 -393.833604) (xy 323.61378 -393.828016)
			(xy 323.590401 -393.815936) (xy 323.54747 -393.785507) (xy 323.509898 -393.748663) (xy 323.478635 -393.706336)
			(xy 323.454468 -393.659592) (xy 323.438007 -393.609611) (xy 323.429668 -393.557655) (xy 323.429122 -393.531344)
			(xy 323.429122 -393.53109) (xy 323.429565 -393.506217) (xy 323.43701 -393.457031) (xy 323.451745 -393.409517)
			(xy 323.473437 -393.36475) (xy 323.501596 -393.32374) (xy 323.518276 -393.305284) (xy 323.524626 -393.298426)
			(xy 323.531738 -393.281408) (xy 323.534024 -393.195048) (xy 323.527928 -393.177522) (xy 323.521832 -393.17041)
			(xy 323.50709 -393.152405) (xy 323.482272 -393.113041) (xy 323.463216 -393.070588) (xy 323.450298 -393.025883)
			(xy 323.443771 -392.979809) (xy 323.443346 -392.956542) (xy 323.443852 -392.930551) (xy 323.451977 -392.879209)
			(xy 323.468034 -392.82977) (xy 323.491627 -392.783451) (xy 323.522175 -392.741394) (xy 323.558927 -392.704632)
			(xy 323.600976 -392.674073) (xy 323.647289 -392.650468) (xy 323.696723 -392.634398) (xy 323.748063 -392.626259)
			(xy 323.774054 -392.625834) (xy 323.774308 -392.625834) (xy 323.797746 -392.626239) (xy 323.844151 -392.632864)
			(xy 323.866764 -392.639042) (xy 323.880226 -392.642852) (xy 323.906388 -392.636502) (xy 323.989954 -392.555222)
			(xy 323.997066 -392.52906) (xy 323.99351 -392.515598) (xy 323.987579 -392.491651) (xy 323.981207 -392.442729)
			(xy 323.98081 -392.418062) (xy 323.981299 -392.390813) (xy 323.98906 -392.33687) (xy 324.004418 -392.284581)
			(xy 324.027062 -392.23501) (xy 324.05653 -392.189166) (xy 324.092221 -392.147982) (xy 324.133411 -392.112296)
			(xy 324.179259 -392.082835) (xy 324.228834 -392.060199) (xy 324.281125 -392.044848) (xy 324.335069 -392.037095)
			(xy 324.362318 -392.036554) (xy 324.39483 -392.037824) (xy 324.405498 -392.03884) (xy 324.425818 -392.031982)
			(xy 324.488556 -391.97407) (xy 324.495944 -391.966543) (xy 324.504446 -391.947263) (xy 324.505066 -391.936732)
			(xy 324.505066 -391.754614) (xy 324.504626 -391.744551) (xy 324.496886 -391.725973) (xy 324.49008 -391.718546)
			(xy 323.475858 -390.704324) (xy 323.468458 -390.697481) (xy 323.44986 -390.689758) (xy 323.43979 -390.689338)
			(xy 301.465234 -390.689338) (xy 301.45517 -390.689774) (xy 301.436586 -390.697509) (xy 301.429166 -390.704324)
			(xy 300.99 -391.14349) (xy 300.983152 -391.150888) (xy 300.975414 -391.169486) (xy 300.975014 -391.179558)
			(xy 300.975014 -391.316035) (xy 302.138082 -391.316035) (xy 302.138082 -391.264061) (xy 302.146212 -391.212726)
			(xy 302.162273 -391.163296) (xy 302.185869 -391.116986) (xy 302.216419 -391.074938) (xy 302.25317 -391.038187)
			(xy 302.295218 -391.007637) (xy 302.341528 -390.984041) (xy 302.390958 -390.96798) (xy 302.442293 -390.95985)
			(xy 302.494267 -390.95985) (xy 302.545602 -390.96798) (xy 302.595032 -390.984041) (xy 302.641342 -391.007637)
			(xy 302.68339 -391.038187) (xy 302.720141 -391.074938) (xy 302.750691 -391.116986) (xy 302.774287 -391.163296)
			(xy 302.790348 -391.212726) (xy 302.79798 -391.260917) (xy 303.48606 -391.260917) (xy 303.48606 -391.208943)
			(xy 303.49419 -391.157608) (xy 303.510251 -391.108178) (xy 303.533847 -391.061868) (xy 303.564397 -391.01982)
			(xy 303.601148 -390.983069) (xy 303.643196 -390.952519) (xy 303.689506 -390.928923) (xy 303.738936 -390.912862)
			(xy 303.790271 -390.904732) (xy 303.842245 -390.904732) (xy 303.89358 -390.912862) (xy 303.94301 -390.928923)
			(xy 303.98932 -390.952519) (xy 304.031368 -390.983069) (xy 304.068119 -391.01982) (xy 304.098669 -391.061868)
			(xy 304.122265 -391.108178) (xy 304.138326 -391.157608) (xy 304.146456 -391.208943) (xy 304.146966 -391.23493)
			(xy 304.146456 -391.260917) (xy 304.68621 -391.260917) (xy 304.68621 -391.208943) (xy 304.69434 -391.157608)
			(xy 304.710401 -391.108178) (xy 304.733997 -391.061868) (xy 304.764547 -391.01982) (xy 304.801298 -390.983069)
			(xy 304.843346 -390.952519) (xy 304.889656 -390.928923) (xy 304.939086 -390.912862) (xy 304.990421 -390.904732)
			(xy 305.042395 -390.904732) (xy 305.09373 -390.912862) (xy 305.14316 -390.928923) (xy 305.18947 -390.952519)
			(xy 305.231518 -390.983069) (xy 305.268269 -391.01982) (xy 305.298819 -391.061868) (xy 305.322415 -391.108178)
			(xy 305.338476 -391.157608) (xy 305.346606 -391.208943) (xy 305.347116 -391.23493) (xy 305.346606 -391.260917)
			(xy 305.886106 -391.260917) (xy 305.886106 -391.208943) (xy 305.894236 -391.157608) (xy 305.910297 -391.108178)
			(xy 305.933893 -391.061868) (xy 305.964443 -391.01982) (xy 306.001194 -390.983069) (xy 306.043242 -390.952519)
			(xy 306.089552 -390.928923) (xy 306.138982 -390.912862) (xy 306.190317 -390.904732) (xy 306.242291 -390.904732)
			(xy 306.293626 -390.912862) (xy 306.343056 -390.928923) (xy 306.389366 -390.952519) (xy 306.431414 -390.983069)
			(xy 306.468165 -391.01982) (xy 306.498715 -391.061868) (xy 306.522311 -391.108178) (xy 306.538372 -391.157608)
			(xy 306.546502 -391.208943) (xy 306.547012 -391.23493) (xy 306.546502 -391.260917) (xy 307.086002 -391.260917)
			(xy 307.086002 -391.208943) (xy 307.094132 -391.157608) (xy 307.110193 -391.108178) (xy 307.133789 -391.061868)
			(xy 307.164339 -391.01982) (xy 307.20109 -390.983069) (xy 307.243138 -390.952519) (xy 307.289448 -390.928923)
			(xy 307.338878 -390.912862) (xy 307.390213 -390.904732) (xy 307.442187 -390.904732) (xy 307.493522 -390.912862)
			(xy 307.542952 -390.928923) (xy 307.589262 -390.952519) (xy 307.63131 -390.983069) (xy 307.668061 -391.01982)
			(xy 307.698611 -391.061868) (xy 307.722207 -391.108178) (xy 307.738268 -391.157608) (xy 307.746398 -391.208943)
			(xy 307.746908 -391.23493) (xy 307.746398 -391.260917) (xy 308.286152 -391.260917) (xy 308.286152 -391.208943)
			(xy 308.294282 -391.157608) (xy 308.310343 -391.108178) (xy 308.333939 -391.061868) (xy 308.364489 -391.01982)
			(xy 308.40124 -390.983069) (xy 308.443288 -390.952519) (xy 308.489598 -390.928923) (xy 308.539028 -390.912862)
			(xy 308.590363 -390.904732) (xy 308.642337 -390.904732) (xy 308.693672 -390.912862) (xy 308.743102 -390.928923)
			(xy 308.789412 -390.952519) (xy 308.83146 -390.983069) (xy 308.868211 -391.01982) (xy 308.898761 -391.061868)
			(xy 308.922357 -391.108178) (xy 308.938418 -391.157608) (xy 308.946548 -391.208943) (xy 308.947058 -391.23493)
			(xy 308.946548 -391.260917) (xy 309.486048 -391.260917) (xy 309.486048 -391.208943) (xy 309.494178 -391.157608)
			(xy 309.510239 -391.108178) (xy 309.533835 -391.061868) (xy 309.564385 -391.01982) (xy 309.601136 -390.983069)
			(xy 309.643184 -390.952519) (xy 309.689494 -390.928923) (xy 309.738924 -390.912862) (xy 309.790259 -390.904732)
			(xy 309.842233 -390.904732) (xy 309.893568 -390.912862) (xy 309.942998 -390.928923) (xy 309.989308 -390.952519)
			(xy 310.031356 -390.983069) (xy 310.068107 -391.01982) (xy 310.098657 -391.061868) (xy 310.122253 -391.108178)
			(xy 310.138314 -391.157608) (xy 310.146444 -391.208943) (xy 310.146954 -391.23493) (xy 310.146444 -391.260917)
			(xy 310.686198 -391.260917) (xy 310.686198 -391.208943) (xy 310.694328 -391.157608) (xy 310.710389 -391.108178)
			(xy 310.733985 -391.061868) (xy 310.764535 -391.01982) (xy 310.801286 -390.983069) (xy 310.843334 -390.952519)
			(xy 310.889644 -390.928923) (xy 310.939074 -390.912862) (xy 310.990409 -390.904732) (xy 311.042383 -390.904732)
			(xy 311.093718 -390.912862) (xy 311.143148 -390.928923) (xy 311.189458 -390.952519) (xy 311.231506 -390.983069)
			(xy 311.268257 -391.01982) (xy 311.298807 -391.061868) (xy 311.322403 -391.108178) (xy 311.338464 -391.157608)
			(xy 311.346594 -391.208943) (xy 311.347104 -391.23493) (xy 311.346594 -391.260917) (xy 311.886094 -391.260917)
			(xy 311.886094 -391.208943) (xy 311.894224 -391.157608) (xy 311.910285 -391.108178) (xy 311.933881 -391.061868)
			(xy 311.964431 -391.01982) (xy 312.001182 -390.983069) (xy 312.04323 -390.952519) (xy 312.08954 -390.928923)
			(xy 312.13897 -390.912862) (xy 312.190305 -390.904732) (xy 312.242279 -390.904732) (xy 312.293614 -390.912862)
			(xy 312.343044 -390.928923) (xy 312.389354 -390.952519) (xy 312.431402 -390.983069) (xy 312.468153 -391.01982)
			(xy 312.498703 -391.061868) (xy 312.522299 -391.108178) (xy 312.53836 -391.157608) (xy 312.54649 -391.208943)
			(xy 312.547 -391.23493) (xy 312.54649 -391.260917) (xy 313.08599 -391.260917) (xy 313.08599 -391.208943)
			(xy 313.09412 -391.157608) (xy 313.110181 -391.108178) (xy 313.133777 -391.061868) (xy 313.164327 -391.01982)
			(xy 313.201078 -390.983069) (xy 313.243126 -390.952519) (xy 313.289436 -390.928923) (xy 313.338866 -390.912862)
			(xy 313.390201 -390.904732) (xy 313.442175 -390.904732) (xy 313.49351 -390.912862) (xy 313.54294 -390.928923)
			(xy 313.58925 -390.952519) (xy 313.631298 -390.983069) (xy 313.668049 -391.01982) (xy 313.698599 -391.061868)
			(xy 313.722195 -391.108178) (xy 313.738256 -391.157608) (xy 313.746386 -391.208943) (xy 313.746896 -391.23493)
			(xy 313.746386 -391.260917) (xy 314.28614 -391.260917) (xy 314.28614 -391.208943) (xy 314.29427 -391.157608)
			(xy 314.310331 -391.108178) (xy 314.333927 -391.061868) (xy 314.364477 -391.01982) (xy 314.401228 -390.983069)
			(xy 314.443276 -390.952519) (xy 314.489586 -390.928923) (xy 314.539016 -390.912862) (xy 314.590351 -390.904732)
			(xy 314.642325 -390.904732) (xy 314.69366 -390.912862) (xy 314.74309 -390.928923) (xy 314.7894 -390.952519)
			(xy 314.831448 -390.983069) (xy 314.868199 -391.01982) (xy 314.898749 -391.061868) (xy 314.922345 -391.108178)
			(xy 314.938406 -391.157608) (xy 314.946536 -391.208943) (xy 314.947046 -391.23493) (xy 314.946536 -391.260917)
			(xy 315.486036 -391.260917) (xy 315.486036 -391.208943) (xy 315.494166 -391.157608) (xy 315.510227 -391.108178)
			(xy 315.533823 -391.061868) (xy 315.564373 -391.01982) (xy 315.601124 -390.983069) (xy 315.643172 -390.952519)
			(xy 315.689482 -390.928923) (xy 315.738912 -390.912862) (xy 315.790247 -390.904732) (xy 315.842221 -390.904732)
			(xy 315.893556 -390.912862) (xy 315.942986 -390.928923) (xy 315.989296 -390.952519) (xy 316.031344 -390.983069)
			(xy 316.068095 -391.01982) (xy 316.098645 -391.061868) (xy 316.122241 -391.108178) (xy 316.138302 -391.157608)
			(xy 316.146432 -391.208943) (xy 316.146942 -391.23493) (xy 316.146432 -391.260917) (xy 316.686186 -391.260917)
			(xy 316.686186 -391.208943) (xy 316.694316 -391.157608) (xy 316.710377 -391.108178) (xy 316.733973 -391.061868)
			(xy 316.764523 -391.01982) (xy 316.801274 -390.983069) (xy 316.843322 -390.952519) (xy 316.889632 -390.928923)
			(xy 316.939062 -390.912862) (xy 316.990397 -390.904732) (xy 317.042371 -390.904732) (xy 317.093706 -390.912862)
			(xy 317.143136 -390.928923) (xy 317.189446 -390.952519) (xy 317.231494 -390.983069) (xy 317.268245 -391.01982)
			(xy 317.298795 -391.061868) (xy 317.322391 -391.108178) (xy 317.338452 -391.157608) (xy 317.346582 -391.208943)
			(xy 317.347092 -391.23493) (xy 317.346582 -391.260917) (xy 317.886082 -391.260917) (xy 317.886082 -391.208943)
			(xy 317.894212 -391.157608) (xy 317.910273 -391.108178) (xy 317.933869 -391.061868) (xy 317.964419 -391.01982)
			(xy 318.00117 -390.983069) (xy 318.043218 -390.952519) (xy 318.089528 -390.928923) (xy 318.138958 -390.912862)
			(xy 318.190293 -390.904732) (xy 318.242267 -390.904732) (xy 318.293602 -390.912862) (xy 318.343032 -390.928923)
			(xy 318.389342 -390.952519) (xy 318.43139 -390.983069) (xy 318.468141 -391.01982) (xy 318.498691 -391.061868)
			(xy 318.522287 -391.108178) (xy 318.538348 -391.157608) (xy 318.546478 -391.208943) (xy 318.546988 -391.23493)
			(xy 318.546478 -391.260917) (xy 319.085978 -391.260917) (xy 319.085978 -391.208943) (xy 319.094108 -391.157608)
			(xy 319.110169 -391.108178) (xy 319.133765 -391.061868) (xy 319.164315 -391.01982) (xy 319.201066 -390.983069)
			(xy 319.243114 -390.952519) (xy 319.289424 -390.928923) (xy 319.338854 -390.912862) (xy 319.390189 -390.904732)
			(xy 319.442163 -390.904732) (xy 319.493498 -390.912862) (xy 319.542928 -390.928923) (xy 319.589238 -390.952519)
			(xy 319.631286 -390.983069) (xy 319.668037 -391.01982) (xy 319.698587 -391.061868) (xy 319.722183 -391.108178)
			(xy 319.738244 -391.157608) (xy 319.746374 -391.208943) (xy 319.746884 -391.23493) (xy 319.746374 -391.260917)
			(xy 320.286128 -391.260917) (xy 320.286128 -391.208943) (xy 320.294258 -391.157608) (xy 320.310319 -391.108178)
			(xy 320.333915 -391.061868) (xy 320.364465 -391.01982) (xy 320.401216 -390.983069) (xy 320.443264 -390.952519)
			(xy 320.489574 -390.928923) (xy 320.539004 -390.912862) (xy 320.590339 -390.904732) (xy 320.642313 -390.904732)
			(xy 320.693648 -390.912862) (xy 320.743078 -390.928923) (xy 320.789388 -390.952519) (xy 320.831436 -390.983069)
			(xy 320.868187 -391.01982) (xy 320.898737 -391.061868) (xy 320.922333 -391.108178) (xy 320.938394 -391.157608)
			(xy 320.946524 -391.208943) (xy 320.947034 -391.23493) (xy 320.946524 -391.260917) (xy 321.486024 -391.260917)
			(xy 321.486024 -391.208943) (xy 321.494154 -391.157608) (xy 321.510215 -391.108178) (xy 321.533811 -391.061868)
			(xy 321.564361 -391.01982) (xy 321.601112 -390.983069) (xy 321.64316 -390.952519) (xy 321.68947 -390.928923)
			(xy 321.7389 -390.912862) (xy 321.790235 -390.904732) (xy 321.842209 -390.904732) (xy 321.893544 -390.912862)
			(xy 321.942974 -390.928923) (xy 321.989284 -390.952519) (xy 322.031332 -390.983069) (xy 322.068083 -391.01982)
			(xy 322.098633 -391.061868) (xy 322.122229 -391.108178) (xy 322.13829 -391.157608) (xy 322.14642 -391.208943)
			(xy 322.14693 -391.23493) (xy 322.14642 -391.260917) (xy 322.13829 -391.312252) (xy 322.122229 -391.361682)
			(xy 322.098633 -391.407992) (xy 322.068083 -391.45004) (xy 322.031332 -391.486791) (xy 321.989284 -391.517341)
			(xy 321.942974 -391.540937) (xy 321.893544 -391.556998) (xy 321.842209 -391.565128) (xy 321.790235 -391.565128)
			(xy 321.7389 -391.556998) (xy 321.68947 -391.540937) (xy 321.64316 -391.517341) (xy 321.601112 -391.486791)
			(xy 321.564361 -391.45004) (xy 321.533811 -391.407992) (xy 321.510215 -391.361682) (xy 321.494154 -391.312252)
			(xy 321.486024 -391.260917) (xy 320.946524 -391.260917) (xy 320.938394 -391.312252) (xy 320.922333 -391.361682)
			(xy 320.898737 -391.407992) (xy 320.868187 -391.45004) (xy 320.831436 -391.486791) (xy 320.789388 -391.517341)
			(xy 320.743078 -391.540937) (xy 320.693648 -391.556998) (xy 320.642313 -391.565128) (xy 320.590339 -391.565128)
			(xy 320.539004 -391.556998) (xy 320.489574 -391.540937) (xy 320.443264 -391.517341) (xy 320.401216 -391.486791)
			(xy 320.364465 -391.45004) (xy 320.333915 -391.407992) (xy 320.310319 -391.361682) (xy 320.294258 -391.312252)
			(xy 320.286128 -391.260917) (xy 319.746374 -391.260917) (xy 319.738244 -391.312252) (xy 319.722183 -391.361682)
			(xy 319.698587 -391.407992) (xy 319.668037 -391.45004) (xy 319.631286 -391.486791) (xy 319.589238 -391.517341)
			(xy 319.542928 -391.540937) (xy 319.493498 -391.556998) (xy 319.442163 -391.565128) (xy 319.390189 -391.565128)
			(xy 319.338854 -391.556998) (xy 319.289424 -391.540937) (xy 319.243114 -391.517341) (xy 319.201066 -391.486791)
			(xy 319.164315 -391.45004) (xy 319.133765 -391.407992) (xy 319.110169 -391.361682) (xy 319.094108 -391.312252)
			(xy 319.085978 -391.260917) (xy 318.546478 -391.260917) (xy 318.538348 -391.312252) (xy 318.522287 -391.361682)
			(xy 318.498691 -391.407992) (xy 318.468141 -391.45004) (xy 318.43139 -391.486791) (xy 318.389342 -391.517341)
			(xy 318.343032 -391.540937) (xy 318.293602 -391.556998) (xy 318.242267 -391.565128) (xy 318.190293 -391.565128)
			(xy 318.138958 -391.556998) (xy 318.089528 -391.540937) (xy 318.043218 -391.517341) (xy 318.00117 -391.486791)
			(xy 317.964419 -391.45004) (xy 317.933869 -391.407992) (xy 317.910273 -391.361682) (xy 317.894212 -391.312252)
			(xy 317.886082 -391.260917) (xy 317.346582 -391.260917) (xy 317.338452 -391.312252) (xy 317.322391 -391.361682)
			(xy 317.298795 -391.407992) (xy 317.268245 -391.45004) (xy 317.231494 -391.486791) (xy 317.189446 -391.517341)
			(xy 317.143136 -391.540937) (xy 317.093706 -391.556998) (xy 317.042371 -391.565128) (xy 316.990397 -391.565128)
			(xy 316.939062 -391.556998) (xy 316.889632 -391.540937) (xy 316.843322 -391.517341) (xy 316.801274 -391.486791)
			(xy 316.764523 -391.45004) (xy 316.733973 -391.407992) (xy 316.710377 -391.361682) (xy 316.694316 -391.312252)
			(xy 316.686186 -391.260917) (xy 316.146432 -391.260917) (xy 316.138302 -391.312252) (xy 316.122241 -391.361682)
			(xy 316.098645 -391.407992) (xy 316.068095 -391.45004) (xy 316.031344 -391.486791) (xy 315.989296 -391.517341)
			(xy 315.942986 -391.540937) (xy 315.893556 -391.556998) (xy 315.842221 -391.565128) (xy 315.790247 -391.565128)
			(xy 315.738912 -391.556998) (xy 315.689482 -391.540937) (xy 315.643172 -391.517341) (xy 315.601124 -391.486791)
			(xy 315.564373 -391.45004) (xy 315.533823 -391.407992) (xy 315.510227 -391.361682) (xy 315.494166 -391.312252)
			(xy 315.486036 -391.260917) (xy 314.946536 -391.260917) (xy 314.938406 -391.312252) (xy 314.922345 -391.361682)
			(xy 314.898749 -391.407992) (xy 314.868199 -391.45004) (xy 314.831448 -391.486791) (xy 314.7894 -391.517341)
			(xy 314.74309 -391.540937) (xy 314.69366 -391.556998) (xy 314.642325 -391.565128) (xy 314.590351 -391.565128)
			(xy 314.539016 -391.556998) (xy 314.489586 -391.540937) (xy 314.443276 -391.517341) (xy 314.401228 -391.486791)
			(xy 314.364477 -391.45004) (xy 314.333927 -391.407992) (xy 314.310331 -391.361682) (xy 314.29427 -391.312252)
			(xy 314.28614 -391.260917) (xy 313.746386 -391.260917) (xy 313.738256 -391.312252) (xy 313.722195 -391.361682)
			(xy 313.698599 -391.407992) (xy 313.668049 -391.45004) (xy 313.631298 -391.486791) (xy 313.58925 -391.517341)
			(xy 313.54294 -391.540937) (xy 313.49351 -391.556998) (xy 313.442175 -391.565128) (xy 313.390201 -391.565128)
			(xy 313.338866 -391.556998) (xy 313.289436 -391.540937) (xy 313.243126 -391.517341) (xy 313.201078 -391.486791)
			(xy 313.164327 -391.45004) (xy 313.133777 -391.407992) (xy 313.110181 -391.361682) (xy 313.09412 -391.312252)
			(xy 313.08599 -391.260917) (xy 312.54649 -391.260917) (xy 312.53836 -391.312252) (xy 312.522299 -391.361682)
			(xy 312.498703 -391.407992) (xy 312.468153 -391.45004) (xy 312.431402 -391.486791) (xy 312.389354 -391.517341)
			(xy 312.343044 -391.540937) (xy 312.293614 -391.556998) (xy 312.242279 -391.565128) (xy 312.190305 -391.565128)
			(xy 312.13897 -391.556998) (xy 312.08954 -391.540937) (xy 312.04323 -391.517341) (xy 312.001182 -391.486791)
			(xy 311.964431 -391.45004) (xy 311.933881 -391.407992) (xy 311.910285 -391.361682) (xy 311.894224 -391.312252)
			(xy 311.886094 -391.260917) (xy 311.346594 -391.260917) (xy 311.338464 -391.312252) (xy 311.322403 -391.361682)
			(xy 311.298807 -391.407992) (xy 311.268257 -391.45004) (xy 311.231506 -391.486791) (xy 311.189458 -391.517341)
			(xy 311.143148 -391.540937) (xy 311.093718 -391.556998) (xy 311.042383 -391.565128) (xy 310.990409 -391.565128)
			(xy 310.939074 -391.556998) (xy 310.889644 -391.540937) (xy 310.843334 -391.517341) (xy 310.801286 -391.486791)
			(xy 310.764535 -391.45004) (xy 310.733985 -391.407992) (xy 310.710389 -391.361682) (xy 310.694328 -391.312252)
			(xy 310.686198 -391.260917) (xy 310.146444 -391.260917) (xy 310.138314 -391.312252) (xy 310.122253 -391.361682)
			(xy 310.098657 -391.407992) (xy 310.068107 -391.45004) (xy 310.031356 -391.486791) (xy 309.989308 -391.517341)
			(xy 309.942998 -391.540937) (xy 309.893568 -391.556998) (xy 309.842233 -391.565128) (xy 309.790259 -391.565128)
			(xy 309.738924 -391.556998) (xy 309.689494 -391.540937) (xy 309.643184 -391.517341) (xy 309.601136 -391.486791)
			(xy 309.564385 -391.45004) (xy 309.533835 -391.407992) (xy 309.510239 -391.361682) (xy 309.494178 -391.312252)
			(xy 309.486048 -391.260917) (xy 308.946548 -391.260917) (xy 308.938418 -391.312252) (xy 308.922357 -391.361682)
			(xy 308.898761 -391.407992) (xy 308.868211 -391.45004) (xy 308.83146 -391.486791) (xy 308.789412 -391.517341)
			(xy 308.743102 -391.540937) (xy 308.693672 -391.556998) (xy 308.642337 -391.565128) (xy 308.590363 -391.565128)
			(xy 308.539028 -391.556998) (xy 308.489598 -391.540937) (xy 308.443288 -391.517341) (xy 308.40124 -391.486791)
			(xy 308.364489 -391.45004) (xy 308.333939 -391.407992) (xy 308.310343 -391.361682) (xy 308.294282 -391.312252)
			(xy 308.286152 -391.260917) (xy 307.746398 -391.260917) (xy 307.738268 -391.312252) (xy 307.722207 -391.361682)
			(xy 307.698611 -391.407992) (xy 307.668061 -391.45004) (xy 307.63131 -391.486791) (xy 307.589262 -391.517341)
			(xy 307.542952 -391.540937) (xy 307.493522 -391.556998) (xy 307.442187 -391.565128) (xy 307.390213 -391.565128)
			(xy 307.338878 -391.556998) (xy 307.289448 -391.540937) (xy 307.243138 -391.517341) (xy 307.20109 -391.486791)
			(xy 307.164339 -391.45004) (xy 307.133789 -391.407992) (xy 307.110193 -391.361682) (xy 307.094132 -391.312252)
			(xy 307.086002 -391.260917) (xy 306.546502 -391.260917) (xy 306.538372 -391.312252) (xy 306.522311 -391.361682)
			(xy 306.498715 -391.407992) (xy 306.468165 -391.45004) (xy 306.431414 -391.486791) (xy 306.389366 -391.517341)
			(xy 306.343056 -391.540937) (xy 306.293626 -391.556998) (xy 306.242291 -391.565128) (xy 306.190317 -391.565128)
			(xy 306.138982 -391.556998) (xy 306.089552 -391.540937) (xy 306.043242 -391.517341) (xy 306.001194 -391.486791)
			(xy 305.964443 -391.45004) (xy 305.933893 -391.407992) (xy 305.910297 -391.361682) (xy 305.894236 -391.312252)
			(xy 305.886106 -391.260917) (xy 305.346606 -391.260917) (xy 305.338476 -391.312252) (xy 305.322415 -391.361682)
			(xy 305.298819 -391.407992) (xy 305.268269 -391.45004) (xy 305.231518 -391.486791) (xy 305.18947 -391.517341)
			(xy 305.14316 -391.540937) (xy 305.09373 -391.556998) (xy 305.042395 -391.565128) (xy 304.990421 -391.565128)
			(xy 304.939086 -391.556998) (xy 304.889656 -391.540937) (xy 304.843346 -391.517341) (xy 304.801298 -391.486791)
			(xy 304.764547 -391.45004) (xy 304.733997 -391.407992) (xy 304.710401 -391.361682) (xy 304.69434 -391.312252)
			(xy 304.68621 -391.260917) (xy 304.146456 -391.260917) (xy 304.138326 -391.312252) (xy 304.122265 -391.361682)
			(xy 304.098669 -391.407992) (xy 304.068119 -391.45004) (xy 304.031368 -391.486791) (xy 303.98932 -391.517341)
			(xy 303.94301 -391.540937) (xy 303.89358 -391.556998) (xy 303.842245 -391.565128) (xy 303.790271 -391.565128)
			(xy 303.738936 -391.556998) (xy 303.689506 -391.540937) (xy 303.643196 -391.517341) (xy 303.601148 -391.486791)
			(xy 303.564397 -391.45004) (xy 303.533847 -391.407992) (xy 303.510251 -391.361682) (xy 303.49419 -391.312252)
			(xy 303.48606 -391.260917) (xy 302.79798 -391.260917) (xy 302.798478 -391.264061) (xy 302.798988 -391.290048)
			(xy 302.798478 -391.316035) (xy 302.790348 -391.36737) (xy 302.774287 -391.4168) (xy 302.750691 -391.46311)
			(xy 302.720141 -391.505158) (xy 302.68339 -391.541909) (xy 302.641342 -391.572459) (xy 302.595032 -391.596055)
			(xy 302.545602 -391.612116) (xy 302.494267 -391.620246) (xy 302.442293 -391.620246) (xy 302.390958 -391.612116)
			(xy 302.341528 -391.596055) (xy 302.295218 -391.572459) (xy 302.25317 -391.541909) (xy 302.216419 -391.505158)
			(xy 302.185869 -391.46311) (xy 302.162273 -391.4168) (xy 302.146212 -391.36737) (xy 302.138082 -391.316035)
			(xy 300.975014 -391.316035) (xy 300.975014 -392.453622) (xy 300.975488 -392.46389) (xy 300.983544 -392.482782)
			(xy 300.998358 -392.497006) (xy 301.00778 -392.50112) (xy 301.111666 -392.540236) (xy 301.1424 -392.532616)
			(xy 301.152814 -392.520678) (xy 301.171835 -392.500019) (xy 301.215559 -392.464791) (xy 301.2646 -392.437444)
			(xy 301.317552 -392.418764) (xy 301.372897 -392.409286) (xy 301.400972 -392.408664) (xy 301.426965 -392.409145)
			(xy 301.478311 -392.417274) (xy 301.527754 -392.433335) (xy 301.574075 -392.456933) (xy 301.616134 -392.487487)
			(xy 301.652895 -392.524245) (xy 301.683452 -392.566301) (xy 301.707055 -392.61262) (xy 301.72312 -392.662062)
			(xy 301.731253 -392.713407) (xy 301.731253 -392.765393) (xy 301.72312 -392.816738) (xy 301.707055 -392.86618)
			(xy 301.683452 -392.912499) (xy 301.652895 -392.954555) (xy 301.616134 -392.991313) (xy 301.574075 -393.021867)
			(xy 301.566533 -393.025709) (xy 303.131984 -393.025709) (xy 303.131984 -392.973735) (xy 303.140114 -392.9224)
			(xy 303.156175 -392.87297) (xy 303.179771 -392.82666) (xy 303.210321 -392.784612) (xy 303.247072 -392.747861)
			(xy 303.28912 -392.717311) (xy 303.33543 -392.693715) (xy 303.38486 -392.677654) (xy 303.436195 -392.669524)
			(xy 303.488169 -392.669524) (xy 303.539504 -392.677654) (xy 303.588934 -392.693715) (xy 303.635244 -392.717311)
			(xy 303.677292 -392.747861) (xy 303.714043 -392.784612) (xy 303.744593 -392.82666) (xy 303.768189 -392.87297)
			(xy 303.78425 -392.9224) (xy 303.79238 -392.973735) (xy 303.79289 -392.999722) (xy 303.79238 -393.025709)
			(xy 304.33188 -393.025709) (xy 304.33188 -392.973735) (xy 304.34001 -392.9224) (xy 304.356071 -392.87297)
			(xy 304.379667 -392.82666) (xy 304.410217 -392.784612) (xy 304.446968 -392.747861) (xy 304.489016 -392.717311)
			(xy 304.535326 -392.693715) (xy 304.584756 -392.677654) (xy 304.636091 -392.669524) (xy 304.688065 -392.669524)
			(xy 304.7394 -392.677654) (xy 304.78883 -392.693715) (xy 304.83514 -392.717311) (xy 304.877188 -392.747861)
			(xy 304.913939 -392.784612) (xy 304.944489 -392.82666) (xy 304.968085 -392.87297) (xy 304.984146 -392.9224)
			(xy 304.992276 -392.973735) (xy 304.992786 -392.999722) (xy 304.992276 -393.025709) (xy 305.53203 -393.025709)
			(xy 305.53203 -392.973735) (xy 305.54016 -392.9224) (xy 305.556221 -392.87297) (xy 305.579817 -392.82666)
			(xy 305.610367 -392.784612) (xy 305.647118 -392.747861) (xy 305.689166 -392.717311) (xy 305.735476 -392.693715)
			(xy 305.784906 -392.677654) (xy 305.836241 -392.669524) (xy 305.888215 -392.669524) (xy 305.93955 -392.677654)
			(xy 305.98898 -392.693715) (xy 306.03529 -392.717311) (xy 306.077338 -392.747861) (xy 306.114089 -392.784612)
			(xy 306.144639 -392.82666) (xy 306.168235 -392.87297) (xy 306.184296 -392.9224) (xy 306.192426 -392.973735)
			(xy 306.192936 -392.999722) (xy 306.192426 -393.025709) (xy 306.731926 -393.025709) (xy 306.731926 -392.973735)
			(xy 306.740056 -392.9224) (xy 306.756117 -392.87297) (xy 306.779713 -392.82666) (xy 306.810263 -392.784612)
			(xy 306.847014 -392.747861) (xy 306.889062 -392.717311) (xy 306.935372 -392.693715) (xy 306.984802 -392.677654)
			(xy 307.036137 -392.669524) (xy 307.088111 -392.669524) (xy 307.139446 -392.677654) (xy 307.188876 -392.693715)
			(xy 307.235186 -392.717311) (xy 307.277234 -392.747861) (xy 307.313985 -392.784612) (xy 307.344535 -392.82666)
			(xy 307.368131 -392.87297) (xy 307.384192 -392.9224) (xy 307.392322 -392.973735) (xy 307.392832 -392.999722)
			(xy 307.392322 -393.025709) (xy 307.932076 -393.025709) (xy 307.932076 -392.973735) (xy 307.940206 -392.9224)
			(xy 307.956267 -392.87297) (xy 307.979863 -392.82666) (xy 308.010413 -392.784612) (xy 308.047164 -392.747861)
			(xy 308.089212 -392.717311) (xy 308.135522 -392.693715) (xy 308.184952 -392.677654) (xy 308.236287 -392.669524)
			(xy 308.288261 -392.669524) (xy 308.339596 -392.677654) (xy 308.389026 -392.693715) (xy 308.435336 -392.717311)
			(xy 308.477384 -392.747861) (xy 308.514135 -392.784612) (xy 308.544685 -392.82666) (xy 308.568281 -392.87297)
			(xy 308.584342 -392.9224) (xy 308.592472 -392.973735) (xy 308.592982 -392.999722) (xy 308.592472 -393.025709)
			(xy 309.131972 -393.025709) (xy 309.131972 -392.973735) (xy 309.140102 -392.9224) (xy 309.156163 -392.87297)
			(xy 309.179759 -392.82666) (xy 309.210309 -392.784612) (xy 309.24706 -392.747861) (xy 309.289108 -392.717311)
			(xy 309.335418 -392.693715) (xy 309.384848 -392.677654) (xy 309.436183 -392.669524) (xy 309.488157 -392.669524)
			(xy 309.539492 -392.677654) (xy 309.588922 -392.693715) (xy 309.635232 -392.717311) (xy 309.67728 -392.747861)
			(xy 309.714031 -392.784612) (xy 309.744581 -392.82666) (xy 309.768177 -392.87297) (xy 309.784238 -392.9224)
			(xy 309.792368 -392.973735) (xy 309.792878 -392.999722) (xy 309.792368 -393.025709) (xy 310.331868 -393.025709)
			(xy 310.331868 -392.973735) (xy 310.339998 -392.9224) (xy 310.356059 -392.87297) (xy 310.379655 -392.82666)
			(xy 310.410205 -392.784612) (xy 310.446956 -392.747861) (xy 310.489004 -392.717311) (xy 310.535314 -392.693715)
			(xy 310.584744 -392.677654) (xy 310.636079 -392.669524) (xy 310.688053 -392.669524) (xy 310.739388 -392.677654)
			(xy 310.788818 -392.693715) (xy 310.835128 -392.717311) (xy 310.877176 -392.747861) (xy 310.913927 -392.784612)
			(xy 310.944477 -392.82666) (xy 310.968073 -392.87297) (xy 310.984134 -392.9224) (xy 310.992264 -392.973735)
			(xy 310.992774 -392.999722) (xy 310.992264 -393.025709) (xy 311.532018 -393.025709) (xy 311.532018 -392.973735)
			(xy 311.540148 -392.9224) (xy 311.556209 -392.87297) (xy 311.579805 -392.82666) (xy 311.610355 -392.784612)
			(xy 311.647106 -392.747861) (xy 311.689154 -392.717311) (xy 311.735464 -392.693715) (xy 311.784894 -392.677654)
			(xy 311.836229 -392.669524) (xy 311.888203 -392.669524) (xy 311.939538 -392.677654) (xy 311.988968 -392.693715)
			(xy 312.035278 -392.717311) (xy 312.077326 -392.747861) (xy 312.114077 -392.784612) (xy 312.144627 -392.82666)
			(xy 312.168223 -392.87297) (xy 312.184284 -392.9224) (xy 312.192414 -392.973735) (xy 312.192924 -392.999722)
			(xy 312.192414 -393.025709) (xy 312.731914 -393.025709) (xy 312.731914 -392.973735) (xy 312.740044 -392.9224)
			(xy 312.756105 -392.87297) (xy 312.779701 -392.82666) (xy 312.810251 -392.784612) (xy 312.847002 -392.747861)
			(xy 312.88905 -392.717311) (xy 312.93536 -392.693715) (xy 312.98479 -392.677654) (xy 313.036125 -392.669524)
			(xy 313.088099 -392.669524) (xy 313.139434 -392.677654) (xy 313.188864 -392.693715) (xy 313.235174 -392.717311)
			(xy 313.277222 -392.747861) (xy 313.313973 -392.784612) (xy 313.344523 -392.82666) (xy 313.368119 -392.87297)
			(xy 313.38418 -392.9224) (xy 313.39231 -392.973735) (xy 313.39282 -392.999722) (xy 313.39231 -393.025709)
			(xy 313.932064 -393.025709) (xy 313.932064 -392.973735) (xy 313.940194 -392.9224) (xy 313.956255 -392.87297)
			(xy 313.979851 -392.82666) (xy 314.010401 -392.784612) (xy 314.047152 -392.747861) (xy 314.0892 -392.717311)
			(xy 314.13551 -392.693715) (xy 314.18494 -392.677654) (xy 314.236275 -392.669524) (xy 314.288249 -392.669524)
			(xy 314.339584 -392.677654) (xy 314.389014 -392.693715) (xy 314.435324 -392.717311) (xy 314.477372 -392.747861)
			(xy 314.514123 -392.784612) (xy 314.544673 -392.82666) (xy 314.568269 -392.87297) (xy 314.58433 -392.9224)
			(xy 314.59246 -392.973735) (xy 314.59297 -392.999722) (xy 314.59246 -393.025709) (xy 315.13196 -393.025709)
			(xy 315.13196 -392.973735) (xy 315.14009 -392.9224) (xy 315.156151 -392.87297) (xy 315.179747 -392.82666)
			(xy 315.210297 -392.784612) (xy 315.247048 -392.747861) (xy 315.289096 -392.717311) (xy 315.335406 -392.693715)
			(xy 315.384836 -392.677654) (xy 315.436171 -392.669524) (xy 315.488145 -392.669524) (xy 315.53948 -392.677654)
			(xy 315.58891 -392.693715) (xy 315.63522 -392.717311) (xy 315.677268 -392.747861) (xy 315.714019 -392.784612)
			(xy 315.744569 -392.82666) (xy 315.768165 -392.87297) (xy 315.784226 -392.9224) (xy 315.792356 -392.973735)
			(xy 315.792866 -392.999722) (xy 315.792356 -393.025709) (xy 316.331856 -393.025709) (xy 316.331856 -392.973735)
			(xy 316.339986 -392.9224) (xy 316.356047 -392.87297) (xy 316.379643 -392.82666) (xy 316.410193 -392.784612)
			(xy 316.446944 -392.747861) (xy 316.488992 -392.717311) (xy 316.535302 -392.693715) (xy 316.584732 -392.677654)
			(xy 316.636067 -392.669524) (xy 316.688041 -392.669524) (xy 316.739376 -392.677654) (xy 316.788806 -392.693715)
			(xy 316.835116 -392.717311) (xy 316.877164 -392.747861) (xy 316.913915 -392.784612) (xy 316.944465 -392.82666)
			(xy 316.968061 -392.87297) (xy 316.984122 -392.9224) (xy 316.992252 -392.973735) (xy 316.992762 -392.999722)
			(xy 316.992252 -393.025709) (xy 317.532006 -393.025709) (xy 317.532006 -392.973735) (xy 317.540136 -392.9224)
			(xy 317.556197 -392.87297) (xy 317.579793 -392.82666) (xy 317.610343 -392.784612) (xy 317.647094 -392.747861)
			(xy 317.689142 -392.717311) (xy 317.735452 -392.693715) (xy 317.784882 -392.677654) (xy 317.836217 -392.669524)
			(xy 317.888191 -392.669524) (xy 317.939526 -392.677654) (xy 317.988956 -392.693715) (xy 318.035266 -392.717311)
			(xy 318.077314 -392.747861) (xy 318.114065 -392.784612) (xy 318.144615 -392.82666) (xy 318.168211 -392.87297)
			(xy 318.184272 -392.9224) (xy 318.192402 -392.973735) (xy 318.192912 -392.999722) (xy 318.192402 -393.025709)
			(xy 318.731902 -393.025709) (xy 318.731902 -392.973735) (xy 318.740032 -392.9224) (xy 318.756093 -392.87297)
			(xy 318.779689 -392.82666) (xy 318.810239 -392.784612) (xy 318.84699 -392.747861) (xy 318.889038 -392.717311)
			(xy 318.935348 -392.693715) (xy 318.984778 -392.677654) (xy 319.036113 -392.669524) (xy 319.088087 -392.669524)
			(xy 319.139422 -392.677654) (xy 319.188852 -392.693715) (xy 319.235162 -392.717311) (xy 319.27721 -392.747861)
			(xy 319.313961 -392.784612) (xy 319.344511 -392.82666) (xy 319.368107 -392.87297) (xy 319.384168 -392.9224)
			(xy 319.392298 -392.973735) (xy 319.392808 -392.999722) (xy 319.392298 -393.025709) (xy 319.932052 -393.025709)
			(xy 319.932052 -392.973735) (xy 319.940182 -392.9224) (xy 319.956243 -392.87297) (xy 319.979839 -392.82666)
			(xy 320.010389 -392.784612) (xy 320.04714 -392.747861) (xy 320.089188 -392.717311) (xy 320.135498 -392.693715)
			(xy 320.184928 -392.677654) (xy 320.236263 -392.669524) (xy 320.288237 -392.669524) (xy 320.339572 -392.677654)
			(xy 320.389002 -392.693715) (xy 320.435312 -392.717311) (xy 320.47736 -392.747861) (xy 320.514111 -392.784612)
			(xy 320.544661 -392.82666) (xy 320.568257 -392.87297) (xy 320.584318 -392.9224) (xy 320.592448 -392.973735)
			(xy 320.592958 -392.999722) (xy 320.592448 -393.025709) (xy 321.131948 -393.025709) (xy 321.131948 -392.973735)
			(xy 321.140078 -392.9224) (xy 321.156139 -392.87297) (xy 321.179735 -392.82666) (xy 321.210285 -392.784612)
			(xy 321.247036 -392.747861) (xy 321.289084 -392.717311) (xy 321.335394 -392.693715) (xy 321.384824 -392.677654)
			(xy 321.436159 -392.669524) (xy 321.488133 -392.669524) (xy 321.539468 -392.677654) (xy 321.588898 -392.693715)
			(xy 321.635208 -392.717311) (xy 321.677256 -392.747861) (xy 321.714007 -392.784612) (xy 321.744557 -392.82666)
			(xy 321.768153 -392.87297) (xy 321.784214 -392.9224) (xy 321.792344 -392.973735) (xy 321.792854 -392.999722)
			(xy 321.792344 -393.025709) (xy 321.784214 -393.077044) (xy 321.768153 -393.126474) (xy 321.744557 -393.172784)
			(xy 321.714007 -393.214832) (xy 321.677256 -393.251583) (xy 321.635208 -393.282133) (xy 321.588898 -393.305729)
			(xy 321.539468 -393.32179) (xy 321.488133 -393.32992) (xy 321.436159 -393.32992) (xy 321.384824 -393.32179)
			(xy 321.335394 -393.305729) (xy 321.289084 -393.282133) (xy 321.247036 -393.251583) (xy 321.210285 -393.214832)
			(xy 321.179735 -393.172784) (xy 321.156139 -393.126474) (xy 321.140078 -393.077044) (xy 321.131948 -393.025709)
			(xy 320.592448 -393.025709) (xy 320.584318 -393.077044) (xy 320.568257 -393.126474) (xy 320.544661 -393.172784)
			(xy 320.514111 -393.214832) (xy 320.47736 -393.251583) (xy 320.435312 -393.282133) (xy 320.389002 -393.305729)
			(xy 320.339572 -393.32179) (xy 320.288237 -393.32992) (xy 320.236263 -393.32992) (xy 320.184928 -393.32179)
			(xy 320.135498 -393.305729) (xy 320.089188 -393.282133) (xy 320.04714 -393.251583) (xy 320.010389 -393.214832)
			(xy 319.979839 -393.172784) (xy 319.956243 -393.126474) (xy 319.940182 -393.077044) (xy 319.932052 -393.025709)
			(xy 319.392298 -393.025709) (xy 319.384168 -393.077044) (xy 319.368107 -393.126474) (xy 319.344511 -393.172784)
			(xy 319.313961 -393.214832) (xy 319.27721 -393.251583) (xy 319.235162 -393.282133) (xy 319.188852 -393.305729)
			(xy 319.139422 -393.32179) (xy 319.088087 -393.32992) (xy 319.036113 -393.32992) (xy 318.984778 -393.32179)
			(xy 318.935348 -393.305729) (xy 318.889038 -393.282133) (xy 318.84699 -393.251583) (xy 318.810239 -393.214832)
			(xy 318.779689 -393.172784) (xy 318.756093 -393.126474) (xy 318.740032 -393.077044) (xy 318.731902 -393.025709)
			(xy 318.192402 -393.025709) (xy 318.184272 -393.077044) (xy 318.168211 -393.126474) (xy 318.144615 -393.172784)
			(xy 318.114065 -393.214832) (xy 318.077314 -393.251583) (xy 318.035266 -393.282133) (xy 317.988956 -393.305729)
			(xy 317.939526 -393.32179) (xy 317.888191 -393.32992) (xy 317.836217 -393.32992) (xy 317.784882 -393.32179)
			(xy 317.735452 -393.305729) (xy 317.689142 -393.282133) (xy 317.647094 -393.251583) (xy 317.610343 -393.214832)
			(xy 317.579793 -393.172784) (xy 317.556197 -393.126474) (xy 317.540136 -393.077044) (xy 317.532006 -393.025709)
			(xy 316.992252 -393.025709) (xy 316.984122 -393.077044) (xy 316.968061 -393.126474) (xy 316.944465 -393.172784)
			(xy 316.913915 -393.214832) (xy 316.877164 -393.251583) (xy 316.835116 -393.282133) (xy 316.788806 -393.305729)
			(xy 316.739376 -393.32179) (xy 316.688041 -393.32992) (xy 316.636067 -393.32992) (xy 316.584732 -393.32179)
			(xy 316.535302 -393.305729) (xy 316.488992 -393.282133) (xy 316.446944 -393.251583) (xy 316.410193 -393.214832)
			(xy 316.379643 -393.172784) (xy 316.356047 -393.126474) (xy 316.339986 -393.077044) (xy 316.331856 -393.025709)
			(xy 315.792356 -393.025709) (xy 315.784226 -393.077044) (xy 315.768165 -393.126474) (xy 315.744569 -393.172784)
			(xy 315.714019 -393.214832) (xy 315.677268 -393.251583) (xy 315.63522 -393.282133) (xy 315.58891 -393.305729)
			(xy 315.53948 -393.32179) (xy 315.488145 -393.32992) (xy 315.436171 -393.32992) (xy 315.384836 -393.32179)
			(xy 315.335406 -393.305729) (xy 315.289096 -393.282133) (xy 315.247048 -393.251583) (xy 315.210297 -393.214832)
			(xy 315.179747 -393.172784) (xy 315.156151 -393.126474) (xy 315.14009 -393.077044) (xy 315.13196 -393.025709)
			(xy 314.59246 -393.025709) (xy 314.58433 -393.077044) (xy 314.568269 -393.126474) (xy 314.544673 -393.172784)
			(xy 314.514123 -393.214832) (xy 314.477372 -393.251583) (xy 314.435324 -393.282133) (xy 314.389014 -393.305729)
			(xy 314.339584 -393.32179) (xy 314.288249 -393.32992) (xy 314.236275 -393.32992) (xy 314.18494 -393.32179)
			(xy 314.13551 -393.305729) (xy 314.0892 -393.282133) (xy 314.047152 -393.251583) (xy 314.010401 -393.214832)
			(xy 313.979851 -393.172784) (xy 313.956255 -393.126474) (xy 313.940194 -393.077044) (xy 313.932064 -393.025709)
			(xy 313.39231 -393.025709) (xy 313.38418 -393.077044) (xy 313.368119 -393.126474) (xy 313.344523 -393.172784)
			(xy 313.313973 -393.214832) (xy 313.277222 -393.251583) (xy 313.235174 -393.282133) (xy 313.188864 -393.305729)
			(xy 313.139434 -393.32179) (xy 313.088099 -393.32992) (xy 313.036125 -393.32992) (xy 312.98479 -393.32179)
			(xy 312.93536 -393.305729) (xy 312.88905 -393.282133) (xy 312.847002 -393.251583) (xy 312.810251 -393.214832)
			(xy 312.779701 -393.172784) (xy 312.756105 -393.126474) (xy 312.740044 -393.077044) (xy 312.731914 -393.025709)
			(xy 312.192414 -393.025709) (xy 312.184284 -393.077044) (xy 312.168223 -393.126474) (xy 312.144627 -393.172784)
			(xy 312.114077 -393.214832) (xy 312.077326 -393.251583) (xy 312.035278 -393.282133) (xy 311.988968 -393.305729)
			(xy 311.939538 -393.32179) (xy 311.888203 -393.32992) (xy 311.836229 -393.32992) (xy 311.784894 -393.32179)
			(xy 311.735464 -393.305729) (xy 311.689154 -393.282133) (xy 311.647106 -393.251583) (xy 311.610355 -393.214832)
			(xy 311.579805 -393.172784) (xy 311.556209 -393.126474) (xy 311.540148 -393.077044) (xy 311.532018 -393.025709)
			(xy 310.992264 -393.025709) (xy 310.984134 -393.077044) (xy 310.968073 -393.126474) (xy 310.944477 -393.172784)
			(xy 310.913927 -393.214832) (xy 310.877176 -393.251583) (xy 310.835128 -393.282133) (xy 310.788818 -393.305729)
			(xy 310.739388 -393.32179) (xy 310.688053 -393.32992) (xy 310.636079 -393.32992) (xy 310.584744 -393.32179)
			(xy 310.535314 -393.305729) (xy 310.489004 -393.282133) (xy 310.446956 -393.251583) (xy 310.410205 -393.214832)
			(xy 310.379655 -393.172784) (xy 310.356059 -393.126474) (xy 310.339998 -393.077044) (xy 310.331868 -393.025709)
			(xy 309.792368 -393.025709) (xy 309.784238 -393.077044) (xy 309.768177 -393.126474) (xy 309.744581 -393.172784)
			(xy 309.714031 -393.214832) (xy 309.67728 -393.251583) (xy 309.635232 -393.282133) (xy 309.588922 -393.305729)
			(xy 309.539492 -393.32179) (xy 309.488157 -393.32992) (xy 309.436183 -393.32992) (xy 309.384848 -393.32179)
			(xy 309.335418 -393.305729) (xy 309.289108 -393.282133) (xy 309.24706 -393.251583) (xy 309.210309 -393.214832)
			(xy 309.179759 -393.172784) (xy 309.156163 -393.126474) (xy 309.140102 -393.077044) (xy 309.131972 -393.025709)
			(xy 308.592472 -393.025709) (xy 308.584342 -393.077044) (xy 308.568281 -393.126474) (xy 308.544685 -393.172784)
			(xy 308.514135 -393.214832) (xy 308.477384 -393.251583) (xy 308.435336 -393.282133) (xy 308.389026 -393.305729)
			(xy 308.339596 -393.32179) (xy 308.288261 -393.32992) (xy 308.236287 -393.32992) (xy 308.184952 -393.32179)
			(xy 308.135522 -393.305729) (xy 308.089212 -393.282133) (xy 308.047164 -393.251583) (xy 308.010413 -393.214832)
			(xy 307.979863 -393.172784) (xy 307.956267 -393.126474) (xy 307.940206 -393.077044) (xy 307.932076 -393.025709)
			(xy 307.392322 -393.025709) (xy 307.384192 -393.077044) (xy 307.368131 -393.126474) (xy 307.344535 -393.172784)
			(xy 307.313985 -393.214832) (xy 307.277234 -393.251583) (xy 307.235186 -393.282133) (xy 307.188876 -393.305729)
			(xy 307.139446 -393.32179) (xy 307.088111 -393.32992) (xy 307.036137 -393.32992) (xy 306.984802 -393.32179)
			(xy 306.935372 -393.305729) (xy 306.889062 -393.282133) (xy 306.847014 -393.251583) (xy 306.810263 -393.214832)
			(xy 306.779713 -393.172784) (xy 306.756117 -393.126474) (xy 306.740056 -393.077044) (xy 306.731926 -393.025709)
			(xy 306.192426 -393.025709) (xy 306.184296 -393.077044) (xy 306.168235 -393.126474) (xy 306.144639 -393.172784)
			(xy 306.114089 -393.214832) (xy 306.077338 -393.251583) (xy 306.03529 -393.282133) (xy 305.98898 -393.305729)
			(xy 305.93955 -393.32179) (xy 305.888215 -393.32992) (xy 305.836241 -393.32992) (xy 305.784906 -393.32179)
			(xy 305.735476 -393.305729) (xy 305.689166 -393.282133) (xy 305.647118 -393.251583) (xy 305.610367 -393.214832)
			(xy 305.579817 -393.172784) (xy 305.556221 -393.126474) (xy 305.54016 -393.077044) (xy 305.53203 -393.025709)
			(xy 304.992276 -393.025709) (xy 304.984146 -393.077044) (xy 304.968085 -393.126474) (xy 304.944489 -393.172784)
			(xy 304.913939 -393.214832) (xy 304.877188 -393.251583) (xy 304.83514 -393.282133) (xy 304.78883 -393.305729)
			(xy 304.7394 -393.32179) (xy 304.688065 -393.32992) (xy 304.636091 -393.32992) (xy 304.584756 -393.32179)
			(xy 304.535326 -393.305729) (xy 304.489016 -393.282133) (xy 304.446968 -393.251583) (xy 304.410217 -393.214832)
			(xy 304.379667 -393.172784) (xy 304.356071 -393.126474) (xy 304.34001 -393.077044) (xy 304.33188 -393.025709)
			(xy 303.79238 -393.025709) (xy 303.78425 -393.077044) (xy 303.768189 -393.126474) (xy 303.744593 -393.172784)
			(xy 303.714043 -393.214832) (xy 303.677292 -393.251583) (xy 303.635244 -393.282133) (xy 303.588934 -393.305729)
			(xy 303.539504 -393.32179) (xy 303.488169 -393.32992) (xy 303.436195 -393.32992) (xy 303.38486 -393.32179)
			(xy 303.33543 -393.305729) (xy 303.28912 -393.282133) (xy 303.247072 -393.251583) (xy 303.210321 -393.214832)
			(xy 303.179771 -393.172784) (xy 303.156175 -393.126474) (xy 303.140114 -393.077044) (xy 303.131984 -393.025709)
			(xy 301.566533 -393.025709) (xy 301.527754 -393.045465) (xy 301.478311 -393.061526) (xy 301.426965 -393.069655)
			(xy 301.400972 -393.07008) (xy 301.372893 -393.069493) (xy 301.317538 -393.060025) (xy 301.264576 -393.041348)
			(xy 301.215527 -393.013999) (xy 301.171798 -392.978762) (xy 301.152814 -392.958066) (xy 301.1424 -392.946128)
			(xy 301.111666 -392.938508) (xy 301.00778 -392.977624) (xy 300.998343 -392.98171) (xy 300.983531 -392.995946)
			(xy 300.975486 -393.01485) (xy 300.975014 -393.025122) (xy 300.975014 -393.60602) (xy 300.97535 -393.615262)
			(xy 300.981801 -393.632578) (xy 300.993997 -393.64646) (xy 301.010337 -393.655089) (xy 301.019464 -393.656566)
			(xy 301.019718 -393.656566) (xy 301.0447 -393.6601) (xy 301.093267 -393.673761) (xy 301.139195 -393.694644)
			(xy 301.181416 -393.722263) (xy 301.218951 -393.755976) (xy 301.250926 -393.795002) (xy 301.2766 -393.838433)
			(xy 301.295377 -393.885261) (xy 301.30682 -393.934398) (xy 301.310664 -393.984704) (xy 301.306819 -394.03501)
			(xy 301.295375 -394.084147) (xy 301.276597 -394.130974) (xy 301.250921 -394.174405) (xy 301.218945 -394.21343)
			(xy 301.18141 -394.247143) (xy 301.139188 -394.27476) (xy 301.09326 -394.295642) (xy 301.044692 -394.309302)
			(xy 301.019718 -394.312902) (xy 301.019464 -394.312902) (xy 301.010364 -394.314459) (xy 300.994069 -394.323109)
			(xy 300.981883 -394.33696) (xy 300.975379 -394.354224) (xy 300.975014 -394.363448) (xy 300.975014 -394.43914)
			(xy 300.975398 -394.449276) (xy 300.983115 -394.468016) (xy 300.99 -394.475462) (xy 301.048674 -394.533374)
			(xy 301.06747 -394.54074) (xy 301.08144 -394.54074) (xy 301.107426 -394.541226) (xy 301.158757 -394.549363)
			(xy 301.208183 -394.565429) (xy 301.254487 -394.58903) (xy 301.296529 -394.619583) (xy 301.333274 -394.656338)
			(xy 301.363816 -394.698388) (xy 301.387405 -394.744699) (xy 301.403458 -394.794129) (xy 301.411581 -394.845462)
			(xy 301.412148 -394.871448) (xy 301.411589 -394.898777) (xy 301.402609 -394.952693) (xy 301.384883 -395.004398)
			(xy 301.358895 -395.052483) (xy 301.342552 -395.074394) (xy 301.337326 -395.081668) (xy 301.331855 -395.098712)
			(xy 301.331884 -395.107668) (xy 301.334678 -395.173708) (xy 301.335451 -395.182538) (xy 301.342202 -395.198912)
			(xy 301.347886 -395.205712) (xy 301.36426 -395.224121) (xy 301.391932 -395.264883) (xy 301.413247 -395.3093)
			(xy 301.427733 -395.356389) (xy 301.435069 -395.405107) (xy 301.435516 -395.42974) (xy 301.435003 -395.455725)
			(xy 301.426868 -395.507055) (xy 301.410804 -395.556481) (xy 301.387206 -395.602786) (xy 301.356655 -395.644829)
			(xy 301.319905 -395.681576) (xy 301.277858 -395.712122) (xy 301.231552 -395.735716) (xy 301.182124 -395.751775)
			(xy 301.130793 -395.759906) (xy 301.104808 -395.760448) (xy 301.083472 -395.759686) (xy 301.082964 -395.759686)
			(xy 301.07255 -395.759178) (xy 301.053246 -395.766036) (xy 300.991016 -395.824202) (xy 300.983745 -395.8317)
			(xy 300.975471 -395.850852) (xy 300.975014 -395.861286) (xy 300.975014 -396.246604) (xy 300.975527 -396.257023)
			(xy 300.983801 -396.276151) (xy 300.991016 -396.283688) (xy 301.045372 -396.334488) (xy 301.053285 -396.341236)
			(xy 301.072819 -396.348318) (xy 301.083218 -396.348204) (xy 301.104808 -396.347442) (xy 301.130791 -396.347952)
			(xy 301.182116 -396.356083) (xy 301.231538 -396.372142) (xy 301.27784 -396.395735) (xy 301.31988 -396.42628)
			(xy 301.356625 -396.463026) (xy 301.387169 -396.505067) (xy 301.410761 -396.551369) (xy 301.426819 -396.600791)
			(xy 301.434948 -396.652117) (xy 301.434948 -396.704083) (xy 301.426819 -396.755409) (xy 301.410761 -396.804831)
			(xy 301.387169 -396.851133) (xy 301.356625 -396.893174) (xy 301.31988 -396.92992) (xy 301.27784 -396.960465)
			(xy 301.231538 -396.984058) (xy 301.182116 -397.000117) (xy 301.130791 -397.008248) (xy 301.104808 -397.008858)
			(xy 301.083472 -397.008096) (xy 301.082964 -397.008096) (xy 301.07255 -397.007588) (xy 301.053246 -397.014446)
			(xy 300.991016 -397.072612) (xy 300.983746 -397.08011) (xy 300.975476 -397.099263) (xy 300.975014 -397.109696)
			(xy 300.975014 -398.034764) (xy 300.975427 -398.044789) (xy 300.983091 -398.063316) (xy 300.997266 -398.077496)
			(xy 301.015789 -398.085168) (xy 301.025814 -398.085564) (xy 301.093124 -398.085564) (xy 301.119104 -398.086029)
			(xy 301.170536 -398.093427) (xy 301.220391 -398.108068) (xy 301.267655 -398.129656) (xy 301.311366 -398.157749)
			(xy 301.350634 -398.191777) (xy 301.384661 -398.231047) (xy 301.412752 -398.274759) (xy 301.434337 -398.322024)
			(xy 301.448977 -398.37188) (xy 301.456372 -398.423312) (xy 301.456852 -398.449292) (xy 301.456413 -398.474426)
			(xy 301.449457 -398.52421) (xy 301.435706 -398.57256) (xy 301.415421 -398.618553) (xy 301.388989 -398.661311)
			(xy 301.373286 -398.68094) (xy 301.367875 -398.68795) (xy 301.361881 -398.704602) (xy 301.361602 -398.713452)
			(xy 301.361602 -398.743932) (xy 301.361989 -398.752762) (xy 301.367977 -398.769376) (xy 301.373286 -398.776444)
			(xy 301.38898 -398.796077) (xy 301.415388 -398.838844) (xy 301.435661 -398.884838) (xy 301.449414 -398.933183)
			(xy 301.456385 -398.982961) (xy 301.456852 -399.008092) (xy 301.456305 -399.036669) (xy 301.447332 -399.093115)
			(xy 301.429638 -399.147461) (xy 301.403658 -399.198369) (xy 301.370032 -399.244585) (xy 301.350172 -399.26514)
			(xy 301.194978 -399.420334) (xy 301.188128 -399.427731) (xy 301.180394 -399.44633) (xy 301.179992 -399.456402)
			(xy 301.179992 -400.183937) (xy 302.164498 -400.183937) (xy 302.164498 -400.131963) (xy 302.172628 -400.080628)
			(xy 302.188689 -400.031198) (xy 302.212285 -399.984888) (xy 302.242835 -399.94284) (xy 302.279586 -399.906089)
			(xy 302.321634 -399.875539) (xy 302.367944 -399.851943) (xy 302.417374 -399.835882) (xy 302.468709 -399.827752)
			(xy 302.520683 -399.827752) (xy 302.572018 -399.835882) (xy 302.621448 -399.851943) (xy 302.667758 -399.875539)
			(xy 302.709806 -399.906089) (xy 302.746557 -399.94284) (xy 302.777107 -399.984888) (xy 302.800703 -400.031198)
			(xy 302.816764 -400.080628) (xy 302.824894 -400.131963) (xy 302.825404 -400.15795) (xy 302.824894 -400.183937)
			(xy 302.816764 -400.235272) (xy 302.800703 -400.284702) (xy 302.777107 -400.331012) (xy 302.746557 -400.37306)
			(xy 302.709806 -400.409811) (xy 302.667758 -400.440361) (xy 302.621448 -400.463957) (xy 302.572018 -400.480018)
			(xy 302.520683 -400.488148) (xy 302.468709 -400.488148) (xy 302.417374 -400.480018) (xy 302.367944 -400.463957)
			(xy 302.321634 -400.440361) (xy 302.279586 -400.409811) (xy 302.242835 -400.37306) (xy 302.212285 -400.331012)
			(xy 302.188689 -400.284702) (xy 302.172628 -400.235272) (xy 302.164498 -400.183937) (xy 301.179992 -400.183937)
			(xy 301.179992 -400.525996) (xy 301.180414 -400.536067) (xy 301.188126 -400.554673) (xy 301.194978 -400.562064)
			(xy 301.778416 -401.145502) (xy 301.785816 -401.152345) (xy 301.804413 -401.160074) (xy 301.814484 -401.160488)
		)
		(stroke
			(width 0)
			(type solid)
		)
		(fill yes)
		(layer "In4.Cu")
		(net "NCF_CPU0_P0_GND")
	)
	(gr_poly
		(pts
			(xy 250.740164 -319.727072) (xy 250.750228 -319.726637) (xy 250.768813 -319.718903) (xy 250.776232 -319.712086)
			(xy 253.340362 -317.147956) (xy 253.347205 -317.140557) (xy 253.35493 -317.121958) (xy 253.355348 -317.111888)
			(xy 253.355348 -267.39215) (xy 253.354914 -267.382085) (xy 253.347181 -267.363499) (xy 253.340362 -267.356082)
			(xy 251.928376 -265.944096) (xy 251.920976 -265.937254) (xy 251.902378 -265.929529) (xy 251.892308 -265.92911)
			(xy 251.878338 -265.92911) (xy 251.868273 -265.928676) (xy 251.849683 -265.920947) (xy 251.84227 -265.914124)
			(xy 246.010684 -260.082538) (xy 246.003286 -260.07569) (xy 245.984688 -260.067955) (xy 245.974616 -260.067552)
			(xy 223.692212 -260.067552) (xy 223.682142 -260.067974) (xy 223.663539 -260.075692) (xy 223.656144 -260.082538)
			(xy 218.767152 -264.97153) (xy 218.760305 -264.978928) (xy 218.752573 -264.997526) (xy 218.752166 -265.007598)
			(xy 218.752166 -269.770955) (xy 221.508737 -269.770955) (xy 221.508737 -269.716445) (xy 221.516495 -269.662489)
			(xy 221.531853 -269.610186) (xy 221.554499 -269.560602) (xy 221.583971 -269.514745) (xy 221.619669 -269.473549)
			(xy 221.660867 -269.437854) (xy 221.706726 -269.408385) (xy 221.756312 -269.385743) (xy 221.808616 -269.370389)
			(xy 221.862573 -269.362635) (xy 221.889828 -269.362174) (xy 221.918744 -269.362716) (xy 221.975916 -269.371436)
			(xy 222.031115 -269.388688) (xy 222.083078 -269.414075) (xy 222.130612 -269.447016) (xy 222.172628 -269.486755)
			(xy 222.190818 -269.50924) (xy 222.19837 -269.518012) (xy 222.219136 -269.528188) (xy 222.230696 -269.528798)
			(xy 222.31096 -269.528798) (xy 222.322525 -269.528205) (xy 222.343296 -269.518027) (xy 222.350838 -269.50924)
			(xy 222.367591 -269.488457) (xy 222.405945 -269.451327) (xy 222.449099 -269.419905) (xy 222.496213 -269.394806)
			(xy 222.546365 -269.37652) (xy 222.598576 -269.365403) (xy 222.651828 -269.361673) (xy 222.70508 -269.365403)
			(xy 222.757291 -269.37652) (xy 222.807443 -269.394806) (xy 222.854557 -269.419905) (xy 222.897711 -269.451327)
			(xy 222.936065 -269.488457) (xy 222.952818 -269.50924) (xy 222.96037 -269.518012) (xy 222.981136 -269.528188)
			(xy 222.992696 -269.528798) (xy 223.07296 -269.528798) (xy 223.084525 -269.528205) (xy 223.105296 -269.518027)
			(xy 223.112838 -269.50924) (xy 223.129591 -269.488457) (xy 223.167945 -269.451327) (xy 223.211099 -269.419905)
			(xy 223.258213 -269.394806) (xy 223.308365 -269.37652) (xy 223.360576 -269.365403) (xy 223.413828 -269.361673)
			(xy 223.46708 -269.365403) (xy 223.519291 -269.37652) (xy 223.569443 -269.394806) (xy 223.616557 -269.419905)
			(xy 223.659711 -269.451327) (xy 223.698065 -269.488457) (xy 223.714818 -269.50924) (xy 223.72237 -269.518012)
			(xy 223.743136 -269.528188) (xy 223.754696 -269.528798) (xy 223.83496 -269.528798) (xy 223.846525 -269.528205)
			(xy 223.867296 -269.518027) (xy 223.874838 -269.50924) (xy 223.893018 -269.486747) (xy 223.935039 -269.44701)
			(xy 223.982575 -269.414071) (xy 224.034539 -269.388684) (xy 224.089739 -269.371431) (xy 224.146911 -269.362706)
			(xy 224.175828 -269.362174) (xy 224.203077 -269.362698) (xy 224.257019 -269.370458) (xy 224.309308 -269.385814)
			(xy 224.358879 -269.408456) (xy 224.404724 -269.437922) (xy 224.445908 -269.473611) (xy 224.481595 -269.514799)
			(xy 224.511057 -269.560646) (xy 224.533695 -269.610219) (xy 224.549048 -269.662509) (xy 224.556804 -269.716451)
			(xy 224.556804 -269.770949) (xy 224.549048 -269.824891) (xy 224.533695 -269.877181) (xy 224.511057 -269.926754)
			(xy 224.481595 -269.972601) (xy 224.445908 -270.013789) (xy 224.404724 -270.049478) (xy 224.358879 -270.078944)
			(xy 224.309308 -270.101586) (xy 224.257019 -270.116942) (xy 224.203077 -270.124702) (xy 224.175828 -270.12519)
			(xy 224.146912 -270.124655) (xy 224.089741 -270.11593) (xy 224.034542 -270.098676) (xy 223.982581 -270.073287)
			(xy 223.935046 -270.040346) (xy 223.893029 -270.000608) (xy 223.874838 -269.978124) (xy 223.867268 -269.969371)
			(xy 223.846515 -269.959186) (xy 223.83496 -269.958566) (xy 223.754696 -269.958566) (xy 223.743124 -269.959111)
			(xy 223.722352 -269.969321) (xy 223.714818 -269.978124) (xy 223.698065 -269.998907) (xy 223.659711 -270.036037)
			(xy 223.616557 -270.067459) (xy 223.569443 -270.092558) (xy 223.519291 -270.110844) (xy 223.46708 -270.121961)
			(xy 223.413828 -270.125691) (xy 223.360576 -270.121961) (xy 223.308365 -270.110844) (xy 223.258213 -270.092558)
			(xy 223.211099 -270.067459) (xy 223.167945 -270.036037) (xy 223.129591 -269.998907) (xy 223.112838 -269.978124)
			(xy 223.105268 -269.969371) (xy 223.084515 -269.959186) (xy 223.07296 -269.958566) (xy 222.992696 -269.958566)
			(xy 222.981124 -269.959111) (xy 222.960352 -269.969321) (xy 222.952818 -269.978124) (xy 222.936065 -269.998907)
			(xy 222.897711 -270.036037) (xy 222.854557 -270.067459) (xy 222.807443 -270.092558) (xy 222.757291 -270.110844)
			(xy 222.70508 -270.121961) (xy 222.651828 -270.125691) (xy 222.598576 -270.121961) (xy 222.546365 -270.110844)
			(xy 222.496213 -270.092558) (xy 222.449099 -270.067459) (xy 222.405945 -270.036037) (xy 222.367591 -269.998907)
			(xy 222.350838 -269.978124) (xy 222.343268 -269.969371) (xy 222.322515 -269.959186) (xy 222.31096 -269.958566)
			(xy 222.230696 -269.958566) (xy 222.219124 -269.959111) (xy 222.198352 -269.969321) (xy 222.190818 -269.978124)
			(xy 222.172623 -270.000604) (xy 222.130603 -270.040338) (xy 222.083069 -270.073277) (xy 222.031109 -270.098666)
			(xy 221.975912 -270.115923) (xy 221.918744 -270.124654) (xy 221.889828 -270.12519) (xy 221.862573 -270.124765)
			(xy 221.808616 -270.117011) (xy 221.756312 -270.101657) (xy 221.706726 -270.079015) (xy 221.660867 -270.049546)
			(xy 221.619669 -270.013851) (xy 221.583971 -269.972655) (xy 221.554499 -269.926798) (xy 221.531853 -269.877214)
			(xy 221.516495 -269.824911) (xy 221.508737 -269.770955) (xy 218.752166 -269.770955) (xy 218.752166 -271.407389)
			(xy 221.507795 -271.407389) (xy 221.511527 -271.354135) (xy 221.522646 -271.301921) (xy 221.540936 -271.251767)
			(xy 221.566039 -271.204652) (xy 221.597465 -271.161497) (xy 221.6346 -271.123145) (xy 221.655386 -271.106392)
			(xy 221.664145 -271.098827) (xy 221.674331 -271.078071) (xy 221.674944 -271.066514) (xy 221.674944 -270.98625)
			(xy 221.674365 -270.974683) (xy 221.664178 -270.95391) (xy 221.655386 -270.946372) (xy 221.632886 -270.9282)
			(xy 221.593153 -270.886176) (xy 221.560216 -270.838637) (xy 221.534831 -270.786672) (xy 221.517578 -270.731471)
			(xy 221.508853 -270.674299) (xy 221.50832 -270.645382) (xy 221.508738 -270.618127) (xy 221.516498 -270.564173)
			(xy 221.531858 -270.511873) (xy 221.554505 -270.462291) (xy 221.583977 -270.416436) (xy 221.619676 -270.375243)
			(xy 221.660873 -270.33955) (xy 221.706731 -270.310083) (xy 221.756316 -270.287442) (xy 221.808618 -270.272089)
			(xy 221.862573 -270.264335) (xy 221.889828 -270.263874) (xy 221.918744 -270.264416) (xy 221.975916 -270.273136)
			(xy 222.031115 -270.290388) (xy 222.083078 -270.315775) (xy 222.130612 -270.348716) (xy 222.172628 -270.388455)
			(xy 222.190818 -270.41094) (xy 222.19837 -270.419712) (xy 222.219136 -270.429888) (xy 222.230696 -270.430498)
			(xy 222.31096 -270.430498) (xy 222.322525 -270.429905) (xy 222.343296 -270.419727) (xy 222.350838 -270.41094)
			(xy 222.369018 -270.388447) (xy 222.411039 -270.34871) (xy 222.458575 -270.315771) (xy 222.510539 -270.290384)
			(xy 222.565739 -270.273131) (xy 222.622911 -270.264406) (xy 222.651828 -270.263874) (xy 222.679079 -270.264352)
			(xy 222.733026 -270.272112) (xy 222.78532 -270.287469) (xy 222.834896 -270.310112) (xy 222.880746 -270.33958)
			(xy 222.921935 -270.375272) (xy 222.957626 -270.416463) (xy 222.987092 -270.462313) (xy 223.009734 -270.511889)
			(xy 223.025091 -270.564184) (xy 223.032849 -270.618131) (xy 223.033336 -270.645382) (xy 223.032829 -270.6743)
			(xy 223.024101 -270.731472) (xy 223.006843 -270.786673) (xy 222.981449 -270.838635) (xy 222.948502 -270.886168)
			(xy 222.908757 -270.928183) (xy 222.88627 -270.946372) (xy 222.87752 -270.953945) (xy 222.867331 -270.974696)
			(xy 222.866712 -270.98625) (xy 222.866712 -271.066514) (xy 222.86727 -271.078084) (xy 222.877473 -271.098855)
			(xy 222.88627 -271.106392) (xy 222.907034 -271.123167) (xy 222.944161 -271.161519) (xy 222.975581 -271.204672)
			(xy 223.000678 -271.251783) (xy 223.018964 -271.301932) (xy 223.03008 -271.354141) (xy 223.033811 -271.407389)
			(xy 223.030083 -271.460638) (xy 223.01897 -271.512847) (xy 223.000687 -271.562997) (xy 222.975592 -271.610109)
			(xy 222.944176 -271.653264) (xy 222.90705 -271.691618) (xy 222.88627 -271.708372) (xy 222.87752 -271.715945)
			(xy 222.867331 -271.736696) (xy 222.866712 -271.74825) (xy 222.866712 -271.828514) (xy 222.86727 -271.840084)
			(xy 222.877473 -271.860855) (xy 222.88627 -271.868392) (xy 222.908743 -271.886595) (xy 222.948481 -271.928611)
			(xy 222.981422 -271.976144) (xy 223.006812 -272.028103) (xy 223.02407 -272.083298) (xy 223.0328 -272.140467)
			(xy 223.033336 -272.169382) (xy 223.032805 -272.196631) (xy 223.025052 -272.250576) (xy 223.0097 -272.302868)
			(xy 222.987063 -272.352443) (xy 222.957602 -272.398293) (xy 222.921915 -272.439482) (xy 222.880729 -272.475174)
			(xy 222.84236 -272.499836) (xy 231.378258 -272.499836) (xy 231.382272 -272.294152) (xy 231.394308 -272.088782)
			(xy 231.414347 -271.884038) (xy 231.44236 -271.680231) (xy 231.478303 -271.477672) (xy 231.522122 -271.27667)
			(xy 231.573749 -271.077531) (xy 231.633107 -270.880558) (xy 231.700105 -270.68605) (xy 231.774641 -270.494305)
			(xy 231.856601 -270.305614) (xy 231.945861 -270.120264) (xy 232.042284 -269.938538) (xy 232.145725 -269.760712)
			(xy 232.256024 -269.587058) (xy 232.373015 -269.417839) (xy 232.496519 -269.253313) (xy 232.626348 -269.093732)
			(xy 232.762305 -268.939337) (xy 232.904182 -268.790365) (xy 233.051763 -268.647041) (xy 233.204824 -268.509585)
			(xy 233.363131 -268.378205) (xy 233.526444 -268.253102) (xy 233.694513 -268.134465) (xy 233.867083 -268.022477)
			(xy 234.043891 -267.917306) (xy 234.224668 -267.819115) (xy 234.409138 -267.728051) (xy 234.59702 -267.644254)
			(xy 234.78803 -267.567851) (xy 234.981874 -267.498958) (xy 235.178259 -267.437681) (xy 235.376885 -267.384113)
			(xy 235.57745 -267.338336) (xy 235.779648 -267.300418) (xy 235.983172 -267.270419) (xy 236.187711 -267.248382)
			(xy 236.392954 -267.234343) (xy 236.598589 -267.228323) (xy 236.804302 -267.23033) (xy 237.00978 -267.240362)
			(xy 237.21471 -267.258403) (xy 237.41878 -267.284426) (xy 237.62168 -267.318391) (xy 237.8231 -267.360246)
			(xy 238.022733 -267.409928) (xy 238.220276 -267.467362) (xy 238.415428 -267.532459) (xy 238.607892 -267.60512)
			(xy 238.797374 -267.685236) (xy 238.983585 -267.772683) (xy 239.166244 -267.867329) (xy 239.34507 -267.969029)
			(xy 239.519792 -268.077629) (xy 239.690145 -268.192964) (xy 239.855867 -268.314857) (xy 240.016708 -268.443123)
			(xy 240.172421 -268.577566) (xy 240.322771 -268.717983) (xy 240.467528 -268.864159) (xy 240.606471 -269.015871)
			(xy 240.739389 -269.172889) (xy 240.86608 -269.334974) (xy 240.98635 -269.501877) (xy 241.072241 -269.631446)
			(xy 249.332814 -269.631446) (xy 249.332814 -269.576954) (xy 249.340569 -269.523015) (xy 249.35592 -269.47073)
			(xy 249.378555 -269.421161) (xy 249.408014 -269.375317) (xy 249.443696 -269.334132) (xy 249.484877 -269.298444)
			(xy 249.530717 -269.268979) (xy 249.580283 -269.246337) (xy 249.632567 -269.230979) (xy 249.686504 -269.223218)
			(xy 249.71375 -269.222728) (xy 249.742666 -269.223272) (xy 249.799837 -269.231994) (xy 249.855035 -269.249246)
			(xy 249.906997 -269.274633) (xy 249.954532 -269.307573) (xy 249.99655 -269.34731) (xy 250.01474 -269.369794)
			(xy 250.02229 -269.378569) (xy 250.043058 -269.388745) (xy 250.054618 -269.389352) (xy 250.134882 -269.389352)
			(xy 250.146451 -269.388788) (xy 250.167223 -269.37859) (xy 250.17476 -269.369794) (xy 250.191513 -269.349011)
			(xy 250.229867 -269.311881) (xy 250.273021 -269.280459) (xy 250.320135 -269.25536) (xy 250.370287 -269.237074)
			(xy 250.422498 -269.225957) (xy 250.47575 -269.222227) (xy 250.529002 -269.225957) (xy 250.581213 -269.237074)
			(xy 250.631365 -269.25536) (xy 250.678479 -269.280459) (xy 250.721633 -269.311881) (xy 250.759987 -269.349011)
			(xy 250.77674 -269.369794) (xy 250.78429 -269.378569) (xy 250.805058 -269.388745) (xy 250.816618 -269.389352)
			(xy 250.896882 -269.389352) (xy 250.908451 -269.388788) (xy 250.929223 -269.37859) (xy 250.93676 -269.369794)
			(xy 250.953513 -269.349011) (xy 250.991867 -269.311881) (xy 251.035021 -269.280459) (xy 251.082135 -269.25536)
			(xy 251.132287 -269.237074) (xy 251.184498 -269.225957) (xy 251.23775 -269.222227) (xy 251.291002 -269.225957)
			(xy 251.343213 -269.237074) (xy 251.393365 -269.25536) (xy 251.440479 -269.280459) (xy 251.483633 -269.311881)
			(xy 251.521987 -269.349011) (xy 251.53874 -269.369794) (xy 251.54629 -269.378569) (xy 251.567058 -269.388745)
			(xy 251.578618 -269.389352) (xy 251.658882 -269.389352) (xy 251.670451 -269.388788) (xy 251.691223 -269.37859)
			(xy 251.69876 -269.369794) (xy 251.716972 -269.347328) (xy 251.758988 -269.307592) (xy 251.806518 -269.274651)
			(xy 251.858475 -269.24926) (xy 251.913669 -269.232) (xy 251.970835 -269.223266) (xy 251.99975 -269.222728)
			(xy 252.027008 -269.223116) (xy 252.080969 -269.230867) (xy 252.133278 -269.246221) (xy 252.182869 -269.268862)
			(xy 252.228733 -269.298332) (xy 252.269936 -269.334029) (xy 252.305638 -269.375227) (xy 252.335114 -269.421087)
			(xy 252.357762 -269.470675) (xy 252.373122 -269.522982) (xy 252.380881 -269.576942) (xy 252.380881 -269.631458)
			(xy 252.373122 -269.685418) (xy 252.357762 -269.737725) (xy 252.335114 -269.787313) (xy 252.305638 -269.833173)
			(xy 252.269936 -269.874371) (xy 252.228733 -269.910068) (xy 252.182869 -269.939538) (xy 252.133278 -269.962179)
			(xy 252.080969 -269.977533) (xy 252.027008 -269.985284) (xy 251.99975 -269.985744) (xy 251.970833 -269.985211)
			(xy 251.913662 -269.976488) (xy 251.858462 -269.959235) (xy 251.8065 -269.933846) (xy 251.758966 -269.900904)
			(xy 251.71695 -269.861163) (xy 251.69876 -269.838678) (xy 251.691215 -269.829899) (xy 251.670443 -269.819726)
			(xy 251.658882 -269.81912) (xy 251.578618 -269.81912) (xy 251.56705 -269.819694) (xy 251.546279 -269.829885)
			(xy 251.53874 -269.838678) (xy 251.521987 -269.859461) (xy 251.483633 -269.896591) (xy 251.440479 -269.928013)
			(xy 251.393365 -269.953112) (xy 251.343213 -269.971398) (xy 251.291002 -269.982515) (xy 251.23775 -269.986245)
			(xy 251.184498 -269.982515) (xy 251.132287 -269.971398) (xy 251.082135 -269.953112) (xy 251.035021 -269.928013)
			(xy 250.991867 -269.896591) (xy 250.953513 -269.859461) (xy 250.93676 -269.838678) (xy 250.929215 -269.829899)
			(xy 250.908443 -269.819726) (xy 250.896882 -269.81912) (xy 250.816618 -269.81912) (xy 250.80505 -269.819694)
			(xy 250.784279 -269.829885) (xy 250.77674 -269.838678) (xy 250.759987 -269.859461) (xy 250.721633 -269.896591)
			(xy 250.678479 -269.928013) (xy 250.631365 -269.953112) (xy 250.581213 -269.971398) (xy 250.529002 -269.982515)
			(xy 250.47575 -269.986245) (xy 250.422498 -269.982515) (xy 250.370287 -269.971398) (xy 250.320135 -269.953112)
			(xy 250.273021 -269.928013) (xy 250.229867 -269.896591) (xy 250.191513 -269.859461) (xy 250.17476 -269.838678)
			(xy 250.167215 -269.829899) (xy 250.146443 -269.819726) (xy 250.134882 -269.81912) (xy 250.054618 -269.81912)
			(xy 250.04305 -269.819694) (xy 250.022279 -269.829885) (xy 250.01474 -269.838678) (xy 249.996521 -269.861138)
			(xy 249.954508 -269.900875) (xy 249.906979 -269.933818) (xy 249.855023 -269.959211) (xy 249.79983 -269.976472)
			(xy 249.742664 -269.985206) (xy 249.71375 -269.985744) (xy 249.686504 -269.985182) (xy 249.632567 -269.977421)
			(xy 249.580283 -269.962063) (xy 249.530717 -269.939421) (xy 249.484877 -269.909956) (xy 249.443697 -269.874268)
			(xy 249.408014 -269.833083) (xy 249.378555 -269.787239) (xy 249.35592 -269.73767) (xy 249.340569 -269.685385)
			(xy 249.332814 -269.631446) (xy 241.072241 -269.631446) (xy 241.100017 -269.673347) (xy 241.206907 -269.84912)
			(xy 241.306858 -270.02893) (xy 241.399717 -270.212503) (xy 241.485344 -270.399559) (xy 241.563606 -270.589814)
			(xy 241.634387 -270.782977) (xy 241.697577 -270.978755) (xy 241.75308 -271.176849) (xy 241.774804 -271.267922)
			(xy 250.855751 -271.267922) (xy 250.859478 -271.214673) (xy 250.870593 -271.162463) (xy 250.888877 -271.112313)
			(xy 250.913975 -271.065201) (xy 250.945396 -271.022049) (xy 250.982526 -270.983698) (xy 251.003308 -270.966946)
			(xy 251.012046 -270.959361) (xy 251.022242 -270.93862) (xy 251.022866 -270.927068) (xy 251.022866 -270.846804)
			(xy 251.022305 -270.835235) (xy 251.012105 -270.814463) (xy 251.003308 -270.806926) (xy 250.980839 -270.788718)
			(xy 250.941102 -270.746702) (xy 250.908161 -270.699171) (xy 250.88277 -270.647213) (xy 250.865511 -270.592018)
			(xy 250.856779 -270.534851) (xy 250.856242 -270.505936) (xy 250.856689 -270.478682) (xy 250.864442 -270.424728)
			(xy 250.879796 -270.372426) (xy 250.902438 -270.322843) (xy 250.931907 -270.276987) (xy 250.967603 -270.235793)
			(xy 251.008799 -270.200099) (xy 251.054655 -270.170632) (xy 251.10424 -270.147991) (xy 251.156541 -270.132639)
			(xy 251.210496 -270.124888) (xy 251.23775 -270.124428) (xy 251.266666 -270.124972) (xy 251.323837 -270.133694)
			(xy 251.379035 -270.150946) (xy 251.430997 -270.176333) (xy 251.478532 -270.209273) (xy 251.52055 -270.24901)
			(xy 251.53874 -270.271494) (xy 251.54629 -270.280269) (xy 251.567058 -270.290445) (xy 251.578618 -270.291052)
			(xy 251.658882 -270.291052) (xy 251.670451 -270.290488) (xy 251.691223 -270.28029) (xy 251.69876 -270.271494)
			(xy 251.716972 -270.249028) (xy 251.758988 -270.209292) (xy 251.806518 -270.176351) (xy 251.858475 -270.15096)
			(xy 251.913669 -270.1337) (xy 251.970835 -270.124966) (xy 251.99975 -270.124428) (xy 252.027003 -270.124902)
			(xy 252.080956 -270.132653) (xy 252.133256 -270.148005) (xy 252.182838 -270.170644) (xy 252.228693 -270.20011)
			(xy 252.269887 -270.235803) (xy 252.305582 -270.276996) (xy 252.335049 -270.32285) (xy 252.357691 -270.372431)
			(xy 252.373044 -270.424731) (xy 252.380797 -270.478683) (xy 252.381258 -270.505936) (xy 252.38071 -270.534852)
			(xy 252.371989 -270.592023) (xy 252.354738 -270.647221) (xy 252.329352 -270.699184) (xy 252.296413 -270.746718)
			(xy 252.256676 -270.788736) (xy 252.234192 -270.806926) (xy 252.225422 -270.81448) (xy 252.215243 -270.835245)
			(xy 252.214634 -270.846804) (xy 252.214634 -270.927068) (xy 252.215211 -270.938635) (xy 252.2254 -270.959407)
			(xy 252.234192 -270.966946) (xy 252.255013 -270.983656) (xy 252.292148 -271.022012) (xy 252.323574 -271.065171)
			(xy 252.348675 -271.112289) (xy 252.366962 -271.162447) (xy 252.378078 -271.214665) (xy 252.381806 -271.267922)
			(xy 252.378072 -271.321179) (xy 252.36695 -271.373395) (xy 252.348657 -271.423551) (xy 252.32355 -271.470667)
			(xy 252.29212 -271.513822) (xy 252.25498 -271.552174) (xy 252.234192 -271.568926) (xy 252.225422 -271.57648)
			(xy 252.215243 -271.597245) (xy 252.214634 -271.608804) (xy 252.214634 -271.689068) (xy 252.215211 -271.700635)
			(xy 252.2254 -271.721407) (xy 252.234192 -271.728946) (xy 252.256648 -271.74717) (xy 252.296385 -271.789182)
			(xy 252.329328 -271.83671) (xy 252.354721 -271.888665) (xy 252.371983 -271.943857) (xy 252.380719 -272.001022)
			(xy 252.381258 -272.029936) (xy 252.380878 -272.057192) (xy 252.373115 -272.111149) (xy 252.357752 -272.163451)
			(xy 252.335102 -272.213035) (xy 252.305625 -272.25889) (xy 252.269923 -272.300084) (xy 252.228721 -272.335777)
			(xy 252.182859 -272.365243) (xy 252.13327 -272.387882) (xy 252.080964 -272.403234) (xy 252.027006 -272.410985)
			(xy 251.99975 -272.411444) (xy 251.970833 -272.410911) (xy 251.913662 -272.402188) (xy 251.858462 -272.384935)
			(xy 251.8065 -272.359546) (xy 251.758966 -272.326604) (xy 251.71695 -272.286863) (xy 251.69876 -272.264378)
			(xy 251.691215 -272.255599) (xy 251.670443 -272.245426) (xy 251.658882 -272.24482) (xy 251.578618 -272.24482)
			(xy 251.56705 -272.245394) (xy 251.546279 -272.255585) (xy 251.53874 -272.264378) (xy 251.520521 -272.286838)
			(xy 251.478508 -272.326575) (xy 251.430979 -272.359518) (xy 251.379023 -272.384911) (xy 251.32383 -272.402172)
			(xy 251.266664 -272.410906) (xy 251.23775 -272.411444) (xy 251.2105 -272.410898) (xy 251.156554 -272.403149)
			(xy 251.10426 -272.387801) (xy 251.054682 -272.365167) (xy 251.008831 -272.335708) (xy 250.967638 -272.300023)
			(xy 250.931944 -272.258838) (xy 250.902474 -272.212993) (xy 250.879829 -272.163421) (xy 250.864469 -272.11113)
			(xy 250.856708 -272.057186) (xy 250.856242 -272.029936) (xy 250.85677 -272.001019) (xy 250.865495 -271.943848)
			(xy 250.88275 -271.888648) (xy 250.90814 -271.836686) (xy 250.941082 -271.789152) (xy 250.980823 -271.747136)
			(xy 251.003308 -271.728946) (xy 251.012046 -271.721361) (xy 251.022242 -271.70062) (xy 251.022866 -271.689068)
			(xy 251.022866 -271.608804) (xy 251.022305 -271.597235) (xy 251.012105 -271.576463) (xy 251.003308 -271.568926)
			(xy 250.982558 -271.552131) (xy 250.945424 -271.513785) (xy 250.913999 -271.470636) (xy 250.888895 -271.423528)
			(xy 250.870605 -271.37338) (xy 250.859485 -271.321171) (xy 250.855751 -271.267922) (xy 241.774804 -271.267922)
			(xy 241.800812 -271.376958) (xy 241.840701 -271.578776) (xy 241.872685 -271.781998) (xy 241.896715 -271.986312)
			(xy 241.912756 -272.191408) (xy 241.920782 -272.396975) (xy 241.921284 -272.499836) (xy 241.920782 -272.602697)
			(xy 241.912756 -272.808264) (xy 241.900979 -272.958846) (xy 249.332814 -272.958846) (xy 249.332814 -272.904354)
			(xy 249.340569 -272.850415) (xy 249.35592 -272.79813) (xy 249.378555 -272.748561) (xy 249.408014 -272.702717)
			(xy 249.443696 -272.661532) (xy 249.484877 -272.625844) (xy 249.530717 -272.596379) (xy 249.580283 -272.573737)
			(xy 249.632567 -272.558379) (xy 249.686504 -272.550618) (xy 249.71375 -272.550128) (xy 249.742666 -272.550672)
			(xy 249.799837 -272.559394) (xy 249.855035 -272.576646) (xy 249.906997 -272.602033) (xy 249.954532 -272.634973)
			(xy 249.99655 -272.67471) (xy 250.01474 -272.697194) (xy 250.02229 -272.705969) (xy 250.043058 -272.716145)
			(xy 250.054618 -272.716752) (xy 250.134882 -272.716752) (xy 250.146451 -272.716188) (xy 250.167223 -272.70599)
			(xy 250.17476 -272.697194) (xy 250.191513 -272.676411) (xy 250.229867 -272.639281) (xy 250.273021 -272.607859)
			(xy 250.320135 -272.58276) (xy 250.370287 -272.564474) (xy 250.422498 -272.553357) (xy 250.47575 -272.549627)
			(xy 250.529002 -272.553357) (xy 250.581213 -272.564474) (xy 250.631365 -272.58276) (xy 250.678479 -272.607859)
			(xy 250.721633 -272.639281) (xy 250.759987 -272.676411) (xy 250.77674 -272.697194) (xy 250.78429 -272.705969)
			(xy 250.805058 -272.716145) (xy 250.816618 -272.716752) (xy 250.896882 -272.716752) (xy 250.908451 -272.716188)
			(xy 250.929223 -272.70599) (xy 250.93676 -272.697194) (xy 250.953513 -272.676411) (xy 250.991867 -272.639281)
			(xy 251.035021 -272.607859) (xy 251.082135 -272.58276) (xy 251.132287 -272.564474) (xy 251.184498 -272.553357)
			(xy 251.23775 -272.549627) (xy 251.291002 -272.553357) (xy 251.343213 -272.564474) (xy 251.393365 -272.58276)
			(xy 251.440479 -272.607859) (xy 251.483633 -272.639281) (xy 251.521987 -272.676411) (xy 251.53874 -272.697194)
			(xy 251.54629 -272.705969) (xy 251.567058 -272.716145) (xy 251.578618 -272.716752) (xy 251.658882 -272.716752)
			(xy 251.670451 -272.716188) (xy 251.691223 -272.70599) (xy 251.69876 -272.697194) (xy 251.716972 -272.674728)
			(xy 251.758988 -272.634992) (xy 251.806518 -272.602051) (xy 251.858475 -272.57666) (xy 251.913669 -272.5594)
			(xy 251.970835 -272.550666) (xy 251.99975 -272.550128) (xy 252.027008 -272.550516) (xy 252.080969 -272.558267)
			(xy 252.133278 -272.573621) (xy 252.182869 -272.596262) (xy 252.228733 -272.625732) (xy 252.269936 -272.661429)
			(xy 252.305638 -272.702627) (xy 252.335114 -272.748487) (xy 252.357762 -272.798075) (xy 252.373122 -272.850382)
			(xy 252.380881 -272.904342) (xy 252.380881 -272.958858) (xy 252.373122 -273.012818) (xy 252.357762 -273.065125)
			(xy 252.335114 -273.114713) (xy 252.305638 -273.160573) (xy 252.269936 -273.201771) (xy 252.228733 -273.237468)
			(xy 252.182869 -273.266938) (xy 252.133278 -273.289579) (xy 252.080969 -273.304933) (xy 252.027008 -273.312684)
			(xy 251.99975 -273.313144) (xy 251.970833 -273.312611) (xy 251.913662 -273.303888) (xy 251.858462 -273.286635)
			(xy 251.8065 -273.261246) (xy 251.758966 -273.228304) (xy 251.71695 -273.188563) (xy 251.69876 -273.166078)
			(xy 251.691215 -273.157299) (xy 251.670443 -273.147126) (xy 251.658882 -273.14652) (xy 251.578618 -273.14652)
			(xy 251.56705 -273.147094) (xy 251.546279 -273.157285) (xy 251.53874 -273.166078) (xy 251.521987 -273.186861)
			(xy 251.483633 -273.223991) (xy 251.440479 -273.255413) (xy 251.393365 -273.280512) (xy 251.343213 -273.298798)
			(xy 251.291002 -273.309915) (xy 251.23775 -273.313645) (xy 251.184498 -273.309915) (xy 251.132287 -273.298798)
			(xy 251.082135 -273.280512) (xy 251.035021 -273.255413) (xy 250.991867 -273.223991) (xy 250.953513 -273.186861)
			(xy 250.93676 -273.166078) (xy 250.929215 -273.157299) (xy 250.908443 -273.147126) (xy 250.896882 -273.14652)
			(xy 250.816618 -273.14652) (xy 250.80505 -273.147094) (xy 250.784279 -273.157285) (xy 250.77674 -273.166078)
			(xy 250.759987 -273.186861) (xy 250.721633 -273.223991) (xy 250.678479 -273.255413) (xy 250.631365 -273.280512)
			(xy 250.581213 -273.298798) (xy 250.529002 -273.309915) (xy 250.47575 -273.313645) (xy 250.422498 -273.309915)
			(xy 250.370287 -273.298798) (xy 250.320135 -273.280512) (xy 250.273021 -273.255413) (xy 250.229867 -273.223991)
			(xy 250.191513 -273.186861) (xy 250.17476 -273.166078) (xy 250.167215 -273.157299) (xy 250.146443 -273.147126)
			(xy 250.134882 -273.14652) (xy 250.054618 -273.14652) (xy 250.04305 -273.147094) (xy 250.022279 -273.157285)
			(xy 250.01474 -273.166078) (xy 249.996521 -273.188538) (xy 249.954508 -273.228275) (xy 249.906979 -273.261218)
			(xy 249.855023 -273.286611) (xy 249.79983 -273.303872) (xy 249.742664 -273.312606) (xy 249.71375 -273.313144)
			(xy 249.686504 -273.312582) (xy 249.632567 -273.304821) (xy 249.580283 -273.289463) (xy 249.530717 -273.266821)
			(xy 249.484877 -273.237356) (xy 249.443697 -273.201668) (xy 249.408014 -273.160483) (xy 249.378555 -273.114639)
			(xy 249.35592 -273.06507) (xy 249.340569 -273.012785) (xy 249.332814 -272.958846) (xy 241.900979 -272.958846)
			(xy 241.896715 -273.01336) (xy 241.872685 -273.217674) (xy 241.840701 -273.420896) (xy 241.800812 -273.622714)
			(xy 241.75308 -273.822823) (xy 241.697577 -274.020917) (xy 241.634387 -274.216695) (xy 241.563606 -274.409858)
			(xy 241.485344 -274.600113) (xy 241.399717 -274.787169) (xy 241.306858 -274.970742) (xy 241.206907 -275.150552)
			(xy 241.100017 -275.326325) (xy 240.98635 -275.497795) (xy 240.86608 -275.664698) (xy 240.739389 -275.826783)
			(xy 240.606471 -275.983801) (xy 240.467528 -276.135513) (xy 240.322771 -276.281689) (xy 240.172421 -276.422106)
			(xy 240.016708 -276.556549) (xy 239.855867 -276.684815) (xy 239.690145 -276.806708) (xy 239.519792 -276.922043)
			(xy 239.34507 -277.030643) (xy 239.166244 -277.132343) (xy 238.983585 -277.226989) (xy 238.797374 -277.314436)
			(xy 238.607892 -277.394552) (xy 238.415428 -277.467213) (xy 238.220276 -277.53231) (xy 238.022733 -277.589744)
			(xy 237.8231 -277.639426) (xy 237.62168 -277.681281) (xy 237.41878 -277.715246) (xy 237.21471 -277.741269)
			(xy 237.00978 -277.75931) (xy 236.804302 -277.769342) (xy 236.598589 -277.771349) (xy 236.392954 -277.765329)
			(xy 236.187711 -277.75129) (xy 235.983172 -277.729253) (xy 235.779648 -277.699254) (xy 235.57745 -277.661336)
			(xy 235.376885 -277.615559) (xy 235.178259 -277.561991) (xy 234.981874 -277.500714) (xy 234.78803 -277.431821)
			(xy 234.59702 -277.355418) (xy 234.409138 -277.271621) (xy 234.224668 -277.180557) (xy 234.043891 -277.082366)
			(xy 233.867083 -276.977195) (xy 233.694513 -276.865207) (xy 233.526444 -276.74657) (xy 233.363131 -276.621467)
			(xy 233.204824 -276.490087) (xy 233.051763 -276.352631) (xy 232.904182 -276.209307) (xy 232.762305 -276.060335)
			(xy 232.626348 -275.90594) (xy 232.496519 -275.746359) (xy 232.373015 -275.581833) (xy 232.256024 -275.412614)
			(xy 232.145725 -275.23896) (xy 232.042284 -275.061134) (xy 231.945861 -274.879408) (xy 231.856601 -274.694058)
			(xy 231.774641 -274.505367) (xy 231.700105 -274.313622) (xy 231.633107 -274.119114) (xy 231.573749 -273.922141)
			(xy 231.522122 -273.723002) (xy 231.478303 -273.522) (xy 231.44236 -273.319441) (xy 231.414347 -273.115634)
			(xy 231.394308 -272.91089) (xy 231.382272 -272.70552) (xy 231.378258 -272.499836) (xy 222.84236 -272.499836)
			(xy 222.834884 -272.504641) (xy 222.785311 -272.527284) (xy 222.733021 -272.542642) (xy 222.679077 -272.550402)
			(xy 222.651828 -272.55089) (xy 222.622912 -272.550355) (xy 222.565741 -272.54163) (xy 222.510542 -272.524376)
			(xy 222.458581 -272.498987) (xy 222.411046 -272.466046) (xy 222.369029 -272.426308) (xy 222.350838 -272.403824)
			(xy 222.343268 -272.395071) (xy 222.322515 -272.384886) (xy 222.31096 -272.384266) (xy 222.230696 -272.384266)
			(xy 222.219124 -272.384811) (xy 222.198352 -272.395021) (xy 222.190818 -272.403824) (xy 222.172623 -272.426304)
			(xy 222.130603 -272.466038) (xy 222.083069 -272.498977) (xy 222.031109 -272.524366) (xy 221.975912 -272.541623)
			(xy 221.918744 -272.550354) (xy 221.889828 -272.55089) (xy 221.862575 -272.550419) (xy 221.808623 -272.542665)
			(xy 221.756325 -272.527312) (xy 221.706743 -272.504671) (xy 221.660889 -272.475204) (xy 221.619696 -272.439511)
			(xy 221.584002 -272.398319) (xy 221.554534 -272.352465) (xy 221.531892 -272.302885) (xy 221.516537 -272.250586)
			(xy 221.508782 -272.196635) (xy 221.50832 -272.169382) (xy 221.508889 -272.140467) (xy 221.517607 -272.083298)
			(xy 221.534854 -272.0281) (xy 221.560236 -271.976137) (xy 221.593171 -271.928602) (xy 221.632904 -271.886583)
			(xy 221.655386 -271.868392) (xy 221.664145 -271.860827) (xy 221.674331 -271.840071) (xy 221.674944 -271.828514)
			(xy 221.674944 -271.74825) (xy 221.674365 -271.736683) (xy 221.664178 -271.71591) (xy 221.655386 -271.708372)
			(xy 221.634584 -271.691641) (xy 221.597451 -271.653286) (xy 221.566027 -271.610129) (xy 221.540927 -271.563013)
			(xy 221.52264 -271.512858) (xy 221.511524 -271.460643) (xy 221.507795 -271.407389) (xy 218.752166 -271.407389)
			(xy 218.752166 -273.098355) (xy 221.508737 -273.098355) (xy 221.508737 -273.043845) (xy 221.516495 -272.989889)
			(xy 221.531853 -272.937586) (xy 221.554499 -272.888002) (xy 221.583971 -272.842145) (xy 221.619669 -272.800949)
			(xy 221.660867 -272.765254) (xy 221.706726 -272.735785) (xy 221.756312 -272.713143) (xy 221.808616 -272.697789)
			(xy 221.862573 -272.690035) (xy 221.889828 -272.689574) (xy 221.918744 -272.690116) (xy 221.975916 -272.698836)
			(xy 222.031115 -272.716088) (xy 222.083078 -272.741475) (xy 222.130612 -272.774416) (xy 222.172628 -272.814155)
			(xy 222.190818 -272.83664) (xy 222.19837 -272.845412) (xy 222.219136 -272.855588) (xy 222.230696 -272.856198)
			(xy 222.31096 -272.856198) (xy 222.322525 -272.855605) (xy 222.343296 -272.845427) (xy 222.350838 -272.83664)
			(xy 222.367591 -272.815857) (xy 222.405945 -272.778727) (xy 222.449099 -272.747305) (xy 222.496213 -272.722206)
			(xy 222.546365 -272.70392) (xy 222.598576 -272.692803) (xy 222.651828 -272.689073) (xy 222.70508 -272.692803)
			(xy 222.757291 -272.70392) (xy 222.807443 -272.722206) (xy 222.854557 -272.747305) (xy 222.897711 -272.778727)
			(xy 222.936065 -272.815857) (xy 222.952818 -272.83664) (xy 222.96037 -272.845412) (xy 222.981136 -272.855588)
			(xy 222.992696 -272.856198) (xy 223.07296 -272.856198) (xy 223.084525 -272.855605) (xy 223.105296 -272.845427)
			(xy 223.112838 -272.83664) (xy 223.129591 -272.815857) (xy 223.167945 -272.778727) (xy 223.211099 -272.747305)
			(xy 223.258213 -272.722206) (xy 223.308365 -272.70392) (xy 223.360576 -272.692803) (xy 223.413828 -272.689073)
			(xy 223.46708 -272.692803) (xy 223.519291 -272.70392) (xy 223.569443 -272.722206) (xy 223.616557 -272.747305)
			(xy 223.659711 -272.778727) (xy 223.698065 -272.815857) (xy 223.714818 -272.83664) (xy 223.72237 -272.845412)
			(xy 223.743136 -272.855588) (xy 223.754696 -272.856198) (xy 223.83496 -272.856198) (xy 223.846525 -272.855605)
			(xy 223.867296 -272.845427) (xy 223.874838 -272.83664) (xy 223.893018 -272.814147) (xy 223.935039 -272.77441)
			(xy 223.982575 -272.741471) (xy 224.034539 -272.716084) (xy 224.089739 -272.698831) (xy 224.146911 -272.690106)
			(xy 224.175828 -272.689574) (xy 224.203077 -272.690098) (xy 224.257019 -272.697858) (xy 224.309308 -272.713214)
			(xy 224.358879 -272.735856) (xy 224.404724 -272.765322) (xy 224.445908 -272.801011) (xy 224.481595 -272.842199)
			(xy 224.511057 -272.888046) (xy 224.533695 -272.937619) (xy 224.549048 -272.989909) (xy 224.556804 -273.043851)
			(xy 224.556804 -273.098349) (xy 224.549048 -273.152291) (xy 224.533695 -273.204581) (xy 224.511057 -273.254154)
			(xy 224.481595 -273.300001) (xy 224.445908 -273.341189) (xy 224.404724 -273.376878) (xy 224.358879 -273.406344)
			(xy 224.309308 -273.428986) (xy 224.257019 -273.444342) (xy 224.203077 -273.452102) (xy 224.175828 -273.45259)
			(xy 224.146912 -273.452055) (xy 224.089741 -273.44333) (xy 224.034542 -273.426076) (xy 223.982581 -273.400687)
			(xy 223.935046 -273.367746) (xy 223.893029 -273.328008) (xy 223.874838 -273.305524) (xy 223.867268 -273.296771)
			(xy 223.846515 -273.286586) (xy 223.83496 -273.285966) (xy 223.754696 -273.285966) (xy 223.743124 -273.286511)
			(xy 223.722352 -273.296721) (xy 223.714818 -273.305524) (xy 223.698065 -273.326307) (xy 223.659711 -273.363437)
			(xy 223.616557 -273.394859) (xy 223.569443 -273.419958) (xy 223.519291 -273.438244) (xy 223.46708 -273.449361)
			(xy 223.413828 -273.453091) (xy 223.360576 -273.449361) (xy 223.308365 -273.438244) (xy 223.258213 -273.419958)
			(xy 223.211099 -273.394859) (xy 223.167945 -273.363437) (xy 223.129591 -273.326307) (xy 223.112838 -273.305524)
			(xy 223.105268 -273.296771) (xy 223.084515 -273.286586) (xy 223.07296 -273.285966) (xy 222.992696 -273.285966)
			(xy 222.981124 -273.286511) (xy 222.960352 -273.296721) (xy 222.952818 -273.305524) (xy 222.936065 -273.326307)
			(xy 222.897711 -273.363437) (xy 222.854557 -273.394859) (xy 222.807443 -273.419958) (xy 222.757291 -273.438244)
			(xy 222.70508 -273.449361) (xy 222.651828 -273.453091) (xy 222.598576 -273.449361) (xy 222.546365 -273.438244)
			(xy 222.496213 -273.419958) (xy 222.449099 -273.394859) (xy 222.405945 -273.363437) (xy 222.367591 -273.326307)
			(xy 222.350838 -273.305524) (xy 222.343268 -273.296771) (xy 222.322515 -273.286586) (xy 222.31096 -273.285966)
			(xy 222.230696 -273.285966) (xy 222.219124 -273.286511) (xy 222.198352 -273.296721) (xy 222.190818 -273.305524)
			(xy 222.172623 -273.328004) (xy 222.130603 -273.367738) (xy 222.083069 -273.400677) (xy 222.031109 -273.426066)
			(xy 221.975912 -273.443323) (xy 221.918744 -273.452054) (xy 221.889828 -273.45259) (xy 221.862573 -273.452165)
			(xy 221.808616 -273.444411) (xy 221.756312 -273.429057) (xy 221.706726 -273.406415) (xy 221.660867 -273.376946)
			(xy 221.619669 -273.341251) (xy 221.583971 -273.300055) (xy 221.554499 -273.254198) (xy 221.531853 -273.204614)
			(xy 221.516495 -273.152311) (xy 221.508737 -273.098355) (xy 218.752166 -273.098355) (xy 218.752166 -288.15538)
			(xy 225.493324 -288.15538) (xy 225.497395 -288.099758) (xy 225.509521 -288.045321) (xy 225.529444 -287.99323)
			(xy 225.55674 -287.944595) (xy 225.590826 -287.900452) (xy 225.630975 -287.861743) (xy 225.676333 -287.829292)
			(xy 225.725933 -287.803791) (xy 225.778717 -287.785784) (xy 225.83356 -287.775654) (xy 225.889294 -287.773617)
			(xy 225.944731 -287.779717) (xy 225.998688 -287.793823) (xy 226.050017 -287.815635) (xy 226.097623 -287.844689)
			(xy 226.140491 -287.880364) (xy 226.177708 -287.921901) (xy 226.208481 -287.968414) (xy 226.232153 -288.018911)
			(xy 226.248221 -288.072318) (xy 226.255698 -288.123122) (xy 237.653574 -288.123122) (xy 237.657645 -288.0675)
			(xy 237.669771 -288.013063) (xy 237.689694 -287.960972) (xy 237.71699 -287.912337) (xy 237.751076 -287.868194)
			(xy 237.791225 -287.829485) (xy 237.836583 -287.797034) (xy 237.886183 -287.771533) (xy 237.938967 -287.753526)
			(xy 237.99381 -287.743396) (xy 238.049544 -287.741359) (xy 238.104981 -287.747459) (xy 238.158938 -287.761565)
			(xy 238.210267 -287.783377) (xy 238.257873 -287.812431) (xy 238.300741 -287.848106) (xy 238.337958 -287.889643)
			(xy 238.368731 -287.936156) (xy 238.392403 -287.986653) (xy 238.408471 -288.04006) (xy 238.416591 -288.095236)
			(xy 238.4171 -288.123122) (xy 238.416591 -288.151008) (xy 238.408471 -288.206184) (xy 238.392403 -288.259591)
			(xy 238.368731 -288.310088) (xy 238.337958 -288.356601) (xy 238.300741 -288.398138) (xy 238.257873 -288.433813)
			(xy 238.210267 -288.462867) (xy 238.158938 -288.484679) (xy 238.104981 -288.498785) (xy 238.049544 -288.504885)
			(xy 237.99381 -288.502848) (xy 237.938967 -288.492718) (xy 237.886183 -288.474711) (xy 237.836583 -288.44921)
			(xy 237.791225 -288.416759) (xy 237.751076 -288.37805) (xy 237.71699 -288.333907) (xy 237.689694 -288.285272)
			(xy 237.669771 -288.233181) (xy 237.657645 -288.178744) (xy 237.653574 -288.123122) (xy 226.255698 -288.123122)
			(xy 226.256341 -288.127494) (xy 226.25685 -288.15538) (xy 226.256341 -288.183266) (xy 226.248221 -288.238442)
			(xy 226.232153 -288.291849) (xy 226.208481 -288.342346) (xy 226.177708 -288.388859) (xy 226.140491 -288.430396)
			(xy 226.097623 -288.466071) (xy 226.050017 -288.495125) (xy 225.998688 -288.516937) (xy 225.944731 -288.531043)
			(xy 225.889294 -288.537143) (xy 225.83356 -288.535106) (xy 225.778717 -288.524976) (xy 225.725933 -288.506969)
			(xy 225.676333 -288.481468) (xy 225.630975 -288.449017) (xy 225.590826 -288.410308) (xy 225.55674 -288.366165)
			(xy 225.529444 -288.31753) (xy 225.509521 -288.265439) (xy 225.497395 -288.211002) (xy 225.493324 -288.15538)
			(xy 218.752166 -288.15538) (xy 218.752166 -288.939732) (xy 228.82352 -288.939732) (xy 228.824006 -288.912481)
			(xy 228.831762 -288.858533) (xy 228.847117 -288.806238) (xy 228.869759 -288.756661) (xy 228.899225 -288.710811)
			(xy 228.934916 -288.66962) (xy 228.976107 -288.633929) (xy 229.021957 -288.604463) (xy 229.071534 -288.581821)
			(xy 229.123829 -288.566466) (xy 229.177777 -288.55871) (xy 229.232279 -288.55871) (xy 229.286227 -288.566466)
			(xy 229.338522 -288.581821) (xy 229.388099 -288.604463) (xy 229.433949 -288.633929) (xy 229.47514 -288.66962)
			(xy 229.510831 -288.710811) (xy 229.540297 -288.756661) (xy 229.562939 -288.806238) (xy 229.578294 -288.858533)
			(xy 229.58605 -288.912481) (xy 229.586536 -288.939732) (xy 240.76787 -288.939732) (xy 240.768356 -288.912481)
			(xy 240.776112 -288.858533) (xy 240.791467 -288.806238) (xy 240.814109 -288.756661) (xy 240.843575 -288.710811)
			(xy 240.879266 -288.66962) (xy 240.920457 -288.633929) (xy 240.966307 -288.604463) (xy 241.015884 -288.581821)
			(xy 241.068179 -288.566466) (xy 241.122127 -288.55871) (xy 241.176629 -288.55871) (xy 241.230577 -288.566466)
			(xy 241.282872 -288.581821) (xy 241.332449 -288.604463) (xy 241.378299 -288.633929) (xy 241.41949 -288.66962)
			(xy 241.455181 -288.710811) (xy 241.484647 -288.756661) (xy 241.507289 -288.806238) (xy 241.522644 -288.858533)
			(xy 241.5304 -288.912481) (xy 241.530886 -288.939732) (xy 241.530366 -288.967593) (xy 241.522273 -289.022725)
			(xy 241.506249 -289.076094) (xy 241.482635 -289.126566) (xy 241.451932 -289.173067) (xy 241.414794 -289.214609)
			(xy 241.393726 -289.232848) (xy 241.393472 -289.232848) (xy 241.384934 -289.240783) (xy 241.375541 -289.262087)
			(xy 241.375438 -289.273742) (xy 241.377978 -289.353752) (xy 241.378916 -289.36527) (xy 241.389786 -289.385641)
			(xy 241.398806 -289.392868) (xy 241.39906 -289.393122) (xy 241.41961 -289.408545) (xy 241.456743 -289.444058)
			(xy 241.488774 -289.484233) (xy 241.515123 -289.528344) (xy 241.535312 -289.575593) (xy 241.548976 -289.625124)
			(xy 241.555869 -289.676041) (xy 241.556286 -289.701732) (xy 241.5558 -289.728983) (xy 241.548044 -289.782931)
			(xy 241.532689 -289.835226) (xy 241.510047 -289.884803) (xy 241.480581 -289.930653) (xy 241.44489 -289.971844)
			(xy 241.403699 -290.007535) (xy 241.357849 -290.037001) (xy 241.308272 -290.059643) (xy 241.255977 -290.074998)
			(xy 241.202029 -290.082754) (xy 241.147527 -290.082754) (xy 241.093579 -290.074998) (xy 241.041284 -290.059643)
			(xy 240.991707 -290.037001) (xy 240.945857 -290.007535) (xy 240.904666 -289.971844) (xy 240.868975 -289.930653)
			(xy 240.839509 -289.884803) (xy 240.816867 -289.835226) (xy 240.801512 -289.782931) (xy 240.793756 -289.728983)
			(xy 240.79327 -289.701732) (xy 240.793781 -289.67387) (xy 240.801878 -289.618739) (xy 240.817905 -289.565371)
			(xy 240.841521 -289.514899) (xy 240.872224 -289.468398) (xy 240.909363 -289.426856) (xy 240.93043 -289.408616)
			(xy 240.930684 -289.408616) (xy 240.939232 -289.40069) (xy 240.948622 -289.37938) (xy 240.948718 -289.367722)
			(xy 240.946178 -289.287712) (xy 240.945184 -289.276204) (xy 240.934353 -289.255831) (xy 240.92535 -289.248596)
			(xy 240.925096 -289.248342) (xy 240.904589 -289.232864) (xy 240.867451 -289.197363) (xy 240.835415 -289.157198)
			(xy 240.809061 -289.113096) (xy 240.788864 -289.065855) (xy 240.775192 -289.016331) (xy 240.768292 -288.96542)
			(xy 240.76787 -288.939732) (xy 229.586536 -288.939732) (xy 229.585998 -288.967593) (xy 229.577906 -289.022723)
			(xy 229.561885 -289.076091) (xy 229.538274 -289.126562) (xy 229.507575 -289.173063) (xy 229.470441 -289.214608)
			(xy 229.449376 -289.232848) (xy 229.449122 -289.232848) (xy 229.440592 -289.24079) (xy 229.431192 -289.262088)
			(xy 229.431088 -289.273742) (xy 229.433628 -289.353752) (xy 229.434585 -289.365267) (xy 229.445443 -289.385637)
			(xy 229.454456 -289.392868) (xy 229.45471 -289.393122) (xy 229.475249 -289.408559) (xy 229.512385 -289.444068)
			(xy 229.544418 -289.48424) (xy 229.570769 -289.528349) (xy 229.59096 -289.575596) (xy 229.604625 -289.625126)
			(xy 229.611519 -289.676042) (xy 229.611936 -289.701732) (xy 229.61145 -289.728983) (xy 229.603694 -289.782931)
			(xy 229.588339 -289.835226) (xy 229.565697 -289.884803) (xy 229.536231 -289.930653) (xy 229.50054 -289.971844)
			(xy 229.459349 -290.007535) (xy 229.413499 -290.037001) (xy 229.363922 -290.059643) (xy 229.311627 -290.074998)
			(xy 229.257679 -290.082754) (xy 229.203177 -290.082754) (xy 229.149229 -290.074998) (xy 229.096934 -290.059643)
			(xy 229.047357 -290.037001) (xy 229.001507 -290.007535) (xy 228.960316 -289.971844) (xy 228.924625 -289.930653)
			(xy 228.895159 -289.884803) (xy 228.872517 -289.835226) (xy 228.857162 -289.782931) (xy 228.849406 -289.728983)
			(xy 228.84892 -289.701732) (xy 228.849448 -289.673871) (xy 228.857544 -289.618741) (xy 228.873569 -289.565374)
			(xy 228.897182 -289.514903) (xy 228.927881 -289.468402) (xy 228.965015 -289.426857) (xy 228.98608 -289.408616)
			(xy 228.986334 -289.408616) (xy 228.99489 -289.400698) (xy 229.004273 -289.379381) (xy 229.004368 -289.367722)
			(xy 229.001828 -289.287712) (xy 229.000852 -289.2762) (xy 228.99001 -289.255827) (xy 228.981 -289.248596)
			(xy 228.980746 -289.248342) (xy 228.960228 -289.232879) (xy 228.923093 -289.197373) (xy 228.891059 -289.157205)
			(xy 228.864707 -289.1131) (xy 228.844512 -289.065858) (xy 228.830842 -289.016333) (xy 228.823942 -288.965421)
			(xy 228.82352 -288.939732) (xy 218.752166 -288.939732) (xy 218.752166 -290.844732) (xy 236.659418 -290.844732)
			(xy 236.663489 -290.78911) (xy 236.675615 -290.734673) (xy 236.695538 -290.682582) (xy 236.722834 -290.633947)
			(xy 236.75692 -290.589804) (xy 236.797069 -290.551095) (xy 236.842427 -290.518644) (xy 236.892027 -290.493143)
			(xy 236.944811 -290.475136) (xy 236.999654 -290.465006) (xy 237.055388 -290.462969) (xy 237.110825 -290.469069)
			(xy 237.164782 -290.483175) (xy 237.216111 -290.504987) (xy 237.263717 -290.534041) (xy 237.306585 -290.569716)
			(xy 237.343802 -290.611253) (xy 237.374575 -290.657766) (xy 237.398247 -290.708263) (xy 237.414315 -290.76167)
			(xy 237.422435 -290.816846) (xy 237.422944 -290.844732) (xy 237.422435 -290.872618) (xy 237.414315 -290.927794)
			(xy 237.398247 -290.981201) (xy 237.374575 -291.031698) (xy 237.343802 -291.078211) (xy 237.306585 -291.119748)
			(xy 237.263717 -291.155423) (xy 237.216111 -291.184477) (xy 237.164782 -291.206289) (xy 237.110825 -291.220395)
			(xy 237.055388 -291.226495) (xy 236.999654 -291.224458) (xy 236.944811 -291.214328) (xy 236.892027 -291.196321)
			(xy 236.842427 -291.17082) (xy 236.797069 -291.138369) (xy 236.75692 -291.09966) (xy 236.722834 -291.055517)
			(xy 236.695538 -291.006882) (xy 236.675615 -290.954791) (xy 236.663489 -290.900354) (xy 236.659418 -290.844732)
			(xy 218.752166 -290.844732) (xy 218.752166 -291.614098) (xy 237.461804 -291.614098) (xy 237.465875 -291.558476)
			(xy 237.478001 -291.504039) (xy 237.497924 -291.451948) (xy 237.52522 -291.403313) (xy 237.559306 -291.35917)
			(xy 237.599455 -291.320461) (xy 237.644813 -291.28801) (xy 237.694413 -291.262509) (xy 237.747197 -291.244502)
			(xy 237.80204 -291.234372) (xy 237.857774 -291.232335) (xy 237.913211 -291.238435) (xy 237.967168 -291.252541)
			(xy 238.018497 -291.274353) (xy 238.066103 -291.303407) (xy 238.108971 -291.339082) (xy 238.146188 -291.380619)
			(xy 238.176961 -291.427132) (xy 238.200633 -291.477629) (xy 238.216701 -291.531036) (xy 238.224821 -291.586212)
			(xy 238.22533 -291.614098) (xy 238.224821 -291.641984) (xy 238.216701 -291.69716) (xy 238.200633 -291.750567)
			(xy 238.176961 -291.801064) (xy 238.146188 -291.847577) (xy 238.108971 -291.889114) (xy 238.066103 -291.924789)
			(xy 238.018497 -291.953843) (xy 237.967168 -291.975655) (xy 237.913211 -291.989761) (xy 237.857774 -291.995861)
			(xy 237.80204 -291.993824) (xy 237.747197 -291.983694) (xy 237.694413 -291.965687) (xy 237.644813 -291.940186)
			(xy 237.599455 -291.907735) (xy 237.559306 -291.869026) (xy 237.52522 -291.824883) (xy 237.497924 -291.776248)
			(xy 237.478001 -291.724157) (xy 237.465875 -291.66972) (xy 237.461804 -291.614098) (xy 218.752166 -291.614098)
			(xy 218.752166 -292.025578) (xy 226.184966 -292.025578) (xy 226.189037 -291.969956) (xy 226.201163 -291.915519)
			(xy 226.221086 -291.863428) (xy 226.248382 -291.814793) (xy 226.282468 -291.77065) (xy 226.322617 -291.731941)
			(xy 226.367975 -291.69949) (xy 226.417575 -291.673989) (xy 226.470359 -291.655982) (xy 226.525202 -291.645852)
			(xy 226.580936 -291.643815) (xy 226.636373 -291.649915) (xy 226.69033 -291.664021) (xy 226.741659 -291.685833)
			(xy 226.789265 -291.714887) (xy 226.832133 -291.750562) (xy 226.86935 -291.792099) (xy 226.900123 -291.838612)
			(xy 226.923795 -291.889109) (xy 226.939863 -291.942516) (xy 226.947983 -291.997692) (xy 226.948492 -292.025578)
			(xy 226.947983 -292.053464) (xy 226.939863 -292.10864) (xy 226.923795 -292.162047) (xy 226.900123 -292.212544)
			(xy 226.86935 -292.259057) (xy 226.836853 -292.295326) (xy 228.289102 -292.295326) (xy 228.293173 -292.239704)
			(xy 228.305299 -292.185267) (xy 228.325222 -292.133176) (xy 228.352518 -292.084541) (xy 228.386604 -292.040398)
			(xy 228.426753 -292.001689) (xy 228.472111 -291.969238) (xy 228.521711 -291.943737) (xy 228.574495 -291.92573)
			(xy 228.629338 -291.9156) (xy 228.685072 -291.913563) (xy 228.740509 -291.919663) (xy 228.794466 -291.933769)
			(xy 228.845795 -291.955581) (xy 228.893401 -291.984635) (xy 228.936269 -292.02031) (xy 228.973486 -292.061847)
			(xy 229.004259 -292.10836) (xy 229.027931 -292.158857) (xy 229.043999 -292.212264) (xy 229.052119 -292.26744)
			(xy 229.052628 -292.295326) (xy 240.233452 -292.295326) (xy 240.237523 -292.239704) (xy 240.249649 -292.185267)
			(xy 240.269572 -292.133176) (xy 240.296868 -292.084541) (xy 240.330954 -292.040398) (xy 240.371103 -292.001689)
			(xy 240.416461 -291.969238) (xy 240.466061 -291.943737) (xy 240.518845 -291.92573) (xy 240.573688 -291.9156)
			(xy 240.629422 -291.913563) (xy 240.684859 -291.919663) (xy 240.738816 -291.933769) (xy 240.790145 -291.955581)
			(xy 240.837751 -291.984635) (xy 240.880619 -292.02031) (xy 240.917836 -292.061847) (xy 240.948609 -292.10836)
			(xy 240.972281 -292.158857) (xy 240.988349 -292.212264) (xy 240.996469 -292.26744) (xy 240.996978 -292.295326)
			(xy 240.996469 -292.323212) (xy 240.988349 -292.378388) (xy 240.972281 -292.431795) (xy 240.948609 -292.482292)
			(xy 240.917836 -292.528805) (xy 240.880619 -292.570342) (xy 240.837751 -292.606017) (xy 240.790145 -292.635071)
			(xy 240.738816 -292.656883) (xy 240.684859 -292.670989) (xy 240.629422 -292.677089) (xy 240.573688 -292.675052)
			(xy 240.518845 -292.664922) (xy 240.466061 -292.646915) (xy 240.416461 -292.621414) (xy 240.371103 -292.588963)
			(xy 240.330954 -292.550254) (xy 240.296868 -292.506111) (xy 240.269572 -292.457476) (xy 240.249649 -292.405385)
			(xy 240.237523 -292.350948) (xy 240.233452 -292.295326) (xy 229.052628 -292.295326) (xy 229.052119 -292.323212)
			(xy 229.043999 -292.378388) (xy 229.027931 -292.431795) (xy 229.004259 -292.482292) (xy 228.973486 -292.528805)
			(xy 228.936269 -292.570342) (xy 228.893401 -292.606017) (xy 228.845795 -292.635071) (xy 228.794466 -292.656883)
			(xy 228.740509 -292.670989) (xy 228.685072 -292.677089) (xy 228.629338 -292.675052) (xy 228.574495 -292.664922)
			(xy 228.521711 -292.646915) (xy 228.472111 -292.621414) (xy 228.426753 -292.588963) (xy 228.386604 -292.550254)
			(xy 228.352518 -292.506111) (xy 228.325222 -292.457476) (xy 228.305299 -292.405385) (xy 228.293173 -292.350948)
			(xy 228.289102 -292.295326) (xy 226.836853 -292.295326) (xy 226.832133 -292.300594) (xy 226.789265 -292.336269)
			(xy 226.741659 -292.365323) (xy 226.69033 -292.387135) (xy 226.636373 -292.401241) (xy 226.580936 -292.407341)
			(xy 226.525202 -292.405304) (xy 226.470359 -292.395174) (xy 226.417575 -292.377167) (xy 226.367975 -292.351666)
			(xy 226.322617 -292.319215) (xy 226.282468 -292.280506) (xy 226.248382 -292.236363) (xy 226.221086 -292.187728)
			(xy 226.201163 -292.135637) (xy 226.189037 -292.0812) (xy 226.184966 -292.025578) (xy 218.752166 -292.025578)
			(xy 218.752166 -293.537132) (xy 233.241848 -293.537132) (xy 233.245919 -293.48151) (xy 233.258045 -293.427073)
			(xy 233.277968 -293.374982) (xy 233.305264 -293.326347) (xy 233.33935 -293.282204) (xy 233.379499 -293.243495)
			(xy 233.424857 -293.211044) (xy 233.474457 -293.185543) (xy 233.527241 -293.167536) (xy 233.582084 -293.157406)
			(xy 233.637818 -293.155369) (xy 233.693255 -293.161469) (xy 233.747212 -293.175575) (xy 233.798541 -293.197387)
			(xy 233.846147 -293.226441) (xy 233.889015 -293.262116) (xy 233.926232 -293.303653) (xy 233.957005 -293.350166)
			(xy 233.980677 -293.400663) (xy 233.996745 -293.45407) (xy 234.004865 -293.509246) (xy 234.005374 -293.537132)
			(xy 245.186198 -293.537132) (xy 245.190269 -293.48151) (xy 245.202395 -293.427073) (xy 245.222318 -293.374982)
			(xy 245.249614 -293.326347) (xy 245.2837 -293.282204) (xy 245.323849 -293.243495) (xy 245.369207 -293.211044)
			(xy 245.418807 -293.185543) (xy 245.471591 -293.167536) (xy 245.526434 -293.157406) (xy 245.582168 -293.155369)
			(xy 245.637605 -293.161469) (xy 245.691562 -293.175575) (xy 245.742891 -293.197387) (xy 245.790497 -293.226441)
			(xy 245.833365 -293.262116) (xy 245.870582 -293.303653) (xy 245.901355 -293.350166) (xy 245.925027 -293.400663)
			(xy 245.941095 -293.45407) (xy 245.949215 -293.509246) (xy 245.949724 -293.537132) (xy 245.949215 -293.565018)
			(xy 245.941095 -293.620194) (xy 245.925027 -293.673601) (xy 245.901355 -293.724098) (xy 245.870582 -293.770611)
			(xy 245.833365 -293.812148) (xy 245.790497 -293.847823) (xy 245.742891 -293.876877) (xy 245.691562 -293.898689)
			(xy 245.637605 -293.912795) (xy 245.582168 -293.918895) (xy 245.526434 -293.916858) (xy 245.471591 -293.906728)
			(xy 245.418807 -293.888721) (xy 245.369207 -293.86322) (xy 245.323849 -293.830769) (xy 245.2837 -293.79206)
			(xy 245.249614 -293.747917) (xy 245.222318 -293.699282) (xy 245.202395 -293.647191) (xy 245.190269 -293.592754)
			(xy 245.186198 -293.537132) (xy 234.005374 -293.537132) (xy 234.004865 -293.565018) (xy 233.996745 -293.620194)
			(xy 233.980677 -293.673601) (xy 233.957005 -293.724098) (xy 233.926232 -293.770611) (xy 233.889015 -293.812148)
			(xy 233.846147 -293.847823) (xy 233.798541 -293.876877) (xy 233.747212 -293.898689) (xy 233.693255 -293.912795)
			(xy 233.637818 -293.918895) (xy 233.582084 -293.916858) (xy 233.527241 -293.906728) (xy 233.474457 -293.888721)
			(xy 233.424857 -293.86322) (xy 233.379499 -293.830769) (xy 233.33935 -293.79206) (xy 233.305264 -293.747917)
			(xy 233.277968 -293.699282) (xy 233.258045 -293.647191) (xy 233.245919 -293.592754) (xy 233.241848 -293.537132)
			(xy 218.752166 -293.537132) (xy 218.752166 -310.520088) (xy 225.232699 -310.520088) (xy 225.236431 -310.466833)
			(xy 225.247551 -310.414618) (xy 225.265842 -310.364464) (xy 225.290946 -310.317349) (xy 225.322373 -310.274194)
			(xy 225.35951 -310.235842) (xy 225.380296 -310.21909) (xy 225.389057 -310.211527) (xy 225.399241 -310.190769)
			(xy 225.399854 -310.179212) (xy 225.399854 -310.098948) (xy 225.399272 -310.087381) (xy 225.389087 -310.066609)
			(xy 225.380296 -310.05907) (xy 225.357797 -310.040897) (xy 225.318063 -309.998873) (xy 225.285126 -309.951335)
			(xy 225.25974 -309.89937) (xy 225.242488 -309.844169) (xy 225.233763 -309.786997) (xy 225.23323 -309.75808)
			(xy 225.233636 -309.730825) (xy 225.241397 -309.67687) (xy 225.256758 -309.624569) (xy 225.279405 -309.574986)
			(xy 225.308879 -309.529131) (xy 225.344579 -309.487937) (xy 225.385777 -309.452244) (xy 225.431637 -309.422777)
			(xy 225.481223 -309.400137) (xy 225.533527 -309.384785) (xy 225.587483 -309.377032) (xy 225.614738 -309.376572)
			(xy 225.643655 -309.377108) (xy 225.700826 -309.385829) (xy 225.756026 -309.403082) (xy 225.807988 -309.42847)
			(xy 225.855522 -309.461412) (xy 225.897538 -309.501153) (xy 225.915728 -309.523638) (xy 225.923276 -309.532414)
			(xy 225.944045 -309.542588) (xy 225.955606 -309.543196) (xy 226.03587 -309.543196) (xy 226.047436 -309.54261)
			(xy 226.068207 -309.532426) (xy 226.075748 -309.523638) (xy 226.093978 -309.501187) (xy 226.135988 -309.461448)
			(xy 226.183515 -309.428504) (xy 226.235469 -309.40311) (xy 226.29066 -309.385847) (xy 226.347824 -309.377111)
			(xy 226.376738 -309.376572) (xy 226.403989 -309.377042) (xy 226.457937 -309.384804) (xy 226.51023 -309.400163)
			(xy 226.559806 -309.422807) (xy 226.605656 -309.452275) (xy 226.646845 -309.487968) (xy 226.682536 -309.529159)
			(xy 226.712002 -309.575009) (xy 226.734644 -309.624587) (xy 226.75 -309.676881) (xy 226.757759 -309.730829)
			(xy 226.758246 -309.75808) (xy 226.757734 -309.786997) (xy 226.749006 -309.84417) (xy 226.731749 -309.89937)
			(xy 226.706356 -309.951332) (xy 226.67341 -309.998865) (xy 226.633667 -310.040881) (xy 226.61118 -310.05907)
			(xy 226.602433 -310.066646) (xy 226.592242 -310.087394) (xy 226.591622 -310.098948) (xy 226.591622 -310.179212)
			(xy 226.592178 -310.190782) (xy 226.602382 -310.211553) (xy 226.61118 -310.21909) (xy 226.631941 -310.235868)
			(xy 226.669068 -310.27422) (xy 226.700486 -310.317372) (xy 226.725583 -310.364483) (xy 226.743868 -310.414632)
			(xy 226.754985 -310.46684) (xy 226.758716 -310.520088) (xy 231.279453 -310.520088) (xy 231.283184 -310.466835)
			(xy 231.294301 -310.414623) (xy 231.312588 -310.36447) (xy 231.337687 -310.317356) (xy 231.369108 -310.2742)
			(xy 231.406237 -310.235845) (xy 231.42702 -310.21909) (xy 231.435785 -310.211532) (xy 231.445966 -310.19077)
			(xy 231.446578 -310.179212) (xy 231.446578 -310.098948) (xy 231.445988 -310.087383) (xy 231.435808 -310.066611)
			(xy 231.42702 -310.05907) (xy 231.404526 -310.040891) (xy 231.364791 -309.998869) (xy 231.331852 -309.951332)
			(xy 231.306466 -309.899368) (xy 231.289212 -309.844168) (xy 231.280487 -309.786997) (xy 231.279954 -309.75808)
			(xy 231.280459 -309.73083) (xy 231.288217 -309.676885) (xy 231.303573 -309.624593) (xy 231.326214 -309.575018)
			(xy 231.355679 -309.52917) (xy 231.391368 -309.487981) (xy 231.432555 -309.452289) (xy 231.478402 -309.422822)
			(xy 231.527976 -309.400179) (xy 231.580267 -309.384821) (xy 231.634212 -309.37706) (xy 231.661462 -309.376572)
			(xy 231.690379 -309.37709) (xy 231.747552 -309.385815) (xy 231.802752 -309.403071) (xy 231.854714 -309.428463)
			(xy 231.902248 -309.461408) (xy 231.944263 -309.501151) (xy 231.962452 -309.523638) (xy 231.970033 -309.53238)
			(xy 231.990777 -309.542573) (xy 232.00233 -309.543196) (xy 232.082594 -309.543196) (xy 232.094162 -309.542624)
			(xy 232.114933 -309.532431) (xy 232.122472 -309.523638) (xy 232.140688 -309.501176) (xy 232.182702 -309.461438)
			(xy 232.230231 -309.428495) (xy 232.282188 -309.403103) (xy 232.337381 -309.385842) (xy 232.394547 -309.377109)
			(xy 232.423462 -309.376572) (xy 232.450713 -309.377091) (xy 232.504661 -309.384842) (xy 232.556957 -309.400192)
			(xy 232.606535 -309.422829) (xy 232.652388 -309.452291) (xy 232.69358 -309.487979) (xy 232.729274 -309.529166)
			(xy 232.758743 -309.575014) (xy 232.781388 -309.624589) (xy 232.796746 -309.676882) (xy 232.804505 -309.730829)
			(xy 232.80497 -309.75808) (xy 232.804449 -309.786997) (xy 232.795722 -309.844169) (xy 232.778465 -309.899368)
			(xy 232.753074 -309.95133) (xy 232.720131 -309.998864) (xy 232.68039 -310.04088) (xy 232.657904 -310.05907)
			(xy 232.649161 -310.06665) (xy 232.638967 -310.087395) (xy 232.638346 -310.098948) (xy 232.638346 -310.179212)
			(xy 232.638894 -310.190783) (xy 232.649103 -310.211555) (xy 232.657904 -310.21909) (xy 232.678669 -310.235866)
			(xy 232.715802 -310.274215) (xy 232.747227 -310.317366) (xy 232.772329 -310.364477) (xy 232.790618 -310.414627)
			(xy 232.801737 -310.466837) (xy 232.805469 -310.520088) (xy 239.165648 -310.520088) (xy 239.169379 -310.466836)
			(xy 239.180496 -310.414624) (xy 239.198782 -310.364471) (xy 239.223881 -310.317356) (xy 239.255301 -310.2742)
			(xy 239.29243 -310.235845) (xy 239.313212 -310.21909) (xy 239.321976 -310.21153) (xy 239.332158 -310.19077)
			(xy 239.33277 -310.179212) (xy 239.33277 -310.098948) (xy 239.332182 -310.087382) (xy 239.322001 -310.06661)
			(xy 239.313212 -310.05907) (xy 239.290717 -310.040893) (xy 239.250982 -309.998871) (xy 239.218044 -309.951333)
			(xy 239.192657 -309.899369) (xy 239.175404 -309.844169) (xy 239.166679 -309.786997) (xy 239.166146 -309.75808)
			(xy 239.166659 -309.73083) (xy 239.174417 -309.676886) (xy 239.189772 -309.624595) (xy 239.212413 -309.57502)
			(xy 239.241877 -309.529172) (xy 239.277565 -309.487983) (xy 239.318751 -309.452292) (xy 239.364597 -309.422825)
			(xy 239.41417 -309.400182) (xy 239.466461 -309.384823) (xy 239.520404 -309.377061) (xy 239.547654 -309.376572)
			(xy 239.576571 -309.377096) (xy 239.633743 -309.38582) (xy 239.688943 -309.403075) (xy 239.740905 -309.428466)
			(xy 239.788439 -309.46141) (xy 239.830455 -309.501152) (xy 239.848644 -309.523638) (xy 239.856185 -309.532422)
			(xy 239.87696 -309.542592) (xy 239.888522 -309.543196) (xy 239.968786 -309.543196) (xy 239.980353 -309.542619)
			(xy 240.001124 -309.532429) (xy 240.008664 -309.523638) (xy 240.026885 -309.50118) (xy 240.068897 -309.461441)
			(xy 240.116426 -309.428498) (xy 240.168381 -309.403105) (xy 240.223574 -309.385844) (xy 240.28074 -309.37711)
			(xy 240.309654 -309.376572) (xy 240.336905 -309.377098) (xy 240.390852 -309.384848) (xy 240.443148 -309.400197)
			(xy 240.492727 -309.422833) (xy 240.538579 -309.452294) (xy 240.579772 -309.487982) (xy 240.615466 -309.529168)
			(xy 240.644935 -309.575015) (xy 240.667579 -309.62459) (xy 240.682938 -309.676883) (xy 240.690697 -309.730829)
			(xy 240.691162 -309.75808) (xy 240.690644 -309.786997) (xy 240.681917 -309.844169) (xy 240.66466 -309.899368)
			(xy 240.639268 -309.95133) (xy 240.606324 -309.998864) (xy 240.566582 -310.04088) (xy 240.544096 -310.05907)
			(xy 240.535351 -310.066649) (xy 240.525159 -310.087395) (xy 240.524538 -310.098948) (xy 240.524538 -310.179212)
			(xy 240.525089 -310.190783) (xy 240.535296 -310.211554) (xy 240.544096 -310.21909) (xy 240.564861 -310.235866)
			(xy 240.601995 -310.274214) (xy 240.63342 -310.317366) (xy 240.658523 -310.364476) (xy 240.676813 -310.414627)
			(xy 240.687932 -310.466837) (xy 240.691664 -310.520088) (xy 245.212363 -310.520088) (xy 245.216094 -310.466835)
			(xy 245.227212 -310.414622) (xy 245.245499 -310.364469) (xy 245.270599 -310.317354) (xy 245.302022 -310.274199)
			(xy 245.339153 -310.235844) (xy 245.359936 -310.21909) (xy 245.368704 -310.211534) (xy 245.378883 -310.190771)
			(xy 245.379494 -310.179212) (xy 245.379494 -310.098948) (xy 245.378898 -310.087383) (xy 245.368722 -310.066612)
			(xy 245.359936 -310.05907) (xy 245.337446 -310.040887) (xy 245.297709 -309.998867) (xy 245.26477 -309.95133)
			(xy 245.239382 -309.899367) (xy 245.222128 -309.844168) (xy 245.213403 -309.786997) (xy 245.21287 -309.75808)
			(xy 245.213359 -309.730829) (xy 245.221118 -309.676883) (xy 245.236474 -309.624589) (xy 245.259116 -309.575014)
			(xy 245.288583 -309.529164) (xy 245.324274 -309.487975) (xy 245.365463 -309.452284) (xy 245.411312 -309.422817)
			(xy 245.460888 -309.400175) (xy 245.513181 -309.384818) (xy 245.567127 -309.377059) (xy 245.594378 -309.376572)
			(xy 245.623296 -309.377079) (xy 245.680469 -309.385806) (xy 245.735669 -309.403065) (xy 245.787631 -309.428458)
			(xy 245.835165 -309.461405) (xy 245.877179 -309.50115) (xy 245.895368 -309.523638) (xy 245.902942 -309.532387)
			(xy 245.923692 -309.542576) (xy 245.935246 -309.543196) (xy 246.01551 -309.543196) (xy 246.027079 -309.542633)
			(xy 246.04785 -309.532433) (xy 246.055388 -309.523638) (xy 246.073595 -309.501168) (xy 246.115611 -309.46143)
			(xy 246.163142 -309.428489) (xy 246.2151 -309.403098) (xy 246.270295 -309.385839) (xy 246.327463 -309.377108)
			(xy 246.356378 -309.376572) (xy 246.383629 -309.377076) (xy 246.437578 -309.384829) (xy 246.489874 -309.400181)
			(xy 246.539452 -309.42282) (xy 246.585305 -309.452284) (xy 246.626497 -309.487973) (xy 246.662191 -309.529162)
			(xy 246.69166 -309.575011) (xy 246.714304 -309.624587) (xy 246.729662 -309.676881) (xy 246.737421 -309.730829)
			(xy 246.737886 -309.75808) (xy 246.737359 -309.786997) (xy 246.728632 -309.844168) (xy 246.711376 -309.899366)
			(xy 246.685986 -309.951328) (xy 246.653044 -309.998862) (xy 246.613305 -310.04088) (xy 246.59082 -310.05907)
			(xy 246.582063 -310.066636) (xy 246.57188 -310.087392) (xy 246.571262 -310.098948) (xy 246.571262 -310.179212)
			(xy 246.571804 -310.190784) (xy 246.582017 -310.211556) (xy 246.59082 -310.21909) (xy 246.611584 -310.235867)
			(xy 246.648716 -310.274216) (xy 246.680139 -310.317368) (xy 246.70524 -310.364478) (xy 246.723528 -310.414628)
			(xy 246.734647 -310.466838) (xy 246.738378 -310.520088) (xy 246.73465 -310.573338) (xy 246.723535 -310.625548)
			(xy 246.70525 -310.675699) (xy 246.680152 -310.722812) (xy 246.648732 -310.765965) (xy 246.611602 -310.804317)
			(xy 246.59082 -310.82107) (xy 246.582063 -310.828636) (xy 246.57188 -310.849392) (xy 246.571262 -310.860948)
			(xy 246.571262 -310.941212) (xy 246.571804 -310.952784) (xy 246.582017 -310.973556) (xy 246.59082 -310.98109)
			(xy 246.613303 -310.999282) (xy 246.653037 -311.041302) (xy 246.685976 -311.088837) (xy 246.711364 -311.140798)
			(xy 246.728621 -311.195995) (xy 246.73735 -311.253164) (xy 246.737886 -311.28208) (xy 246.737426 -311.309333)
			(xy 246.729671 -311.363286) (xy 246.714317 -311.415585) (xy 246.691675 -311.465166) (xy 246.662207 -311.511021)
			(xy 246.626513 -311.552214) (xy 246.585319 -311.587908) (xy 246.539465 -311.617376) (xy 246.489883 -311.640017)
			(xy 246.437584 -311.655372) (xy 246.383631 -311.663126) (xy 246.356378 -311.663588) (xy 246.327463 -311.663018)
			(xy 246.270294 -311.654301) (xy 246.215096 -311.637053) (xy 246.163134 -311.611671) (xy 246.115599 -311.578737)
			(xy 246.07358 -311.539004) (xy 246.055388 -311.516522) (xy 246.04784 -311.507746) (xy 246.02707 -311.497574)
			(xy 246.01551 -311.496964) (xy 245.935246 -311.496964) (xy 245.923678 -311.497538) (xy 245.902905 -311.507728)
			(xy 245.895368 -311.516522) (xy 245.877201 -311.539025) (xy 245.835175 -311.578758) (xy 245.787635 -311.611694)
			(xy 245.735669 -311.637079) (xy 245.680468 -311.654331) (xy 245.623295 -311.663056) (xy 245.594378 -311.663588)
			(xy 245.567125 -311.663143) (xy 245.513175 -311.655383) (xy 245.460878 -311.640024) (xy 245.4113 -311.617378)
			(xy 245.365448 -311.587908) (xy 245.324258 -311.552212) (xy 245.288567 -311.511018) (xy 245.259101 -311.465163)
			(xy 245.236462 -311.415582) (xy 245.221108 -311.363284) (xy 245.213354 -311.309333) (xy 245.21287 -311.28208)
			(xy 245.213419 -311.253164) (xy 245.222138 -311.195993) (xy 245.239388 -311.140794) (xy 245.264774 -311.088831)
			(xy 245.297714 -311.041297) (xy 245.337452 -310.99928) (xy 245.359936 -310.98109) (xy 245.368704 -310.973534)
			(xy 245.378883 -310.952771) (xy 245.379494 -310.941212) (xy 245.379494 -310.860948) (xy 245.378898 -310.849383)
			(xy 245.368722 -310.828612) (xy 245.359936 -310.82107) (xy 245.339134 -310.80434) (xy 245.302006 -310.765983)
			(xy 245.270586 -310.722825) (xy 245.245489 -310.675709) (xy 245.227205 -310.625554) (xy 245.216091 -310.573341)
			(xy 245.212363 -310.520088) (xy 240.691664 -310.520088) (xy 240.687935 -310.573339) (xy 240.676819 -310.62555)
			(xy 240.658533 -310.675701) (xy 240.633434 -310.722814) (xy 240.602011 -310.765967) (xy 240.564879 -310.804318)
			(xy 240.544096 -310.82107) (xy 240.535351 -310.828649) (xy 240.525159 -310.849395) (xy 240.524538 -310.860948)
			(xy 240.524538 -310.941212) (xy 240.525089 -310.952783) (xy 240.535296 -310.973554) (xy 240.544096 -310.98109)
			(xy 240.566574 -310.999288) (xy 240.60631 -311.041306) (xy 240.639249 -311.088839) (xy 240.664639 -311.140799)
			(xy 240.681896 -311.195996) (xy 240.690626 -311.253164) (xy 240.691162 -311.28208) (xy 240.690726 -311.309334)
			(xy 240.68297 -311.363289) (xy 240.667615 -311.41559) (xy 240.644971 -311.465173) (xy 240.615501 -311.511028)
			(xy 240.579804 -311.552223) (xy 240.538608 -311.587917) (xy 240.49275 -311.617384) (xy 240.443166 -311.640024)
			(xy 240.390863 -311.655376) (xy 240.336908 -311.663128) (xy 240.309654 -311.663588) (xy 240.280738 -311.663035)
			(xy 240.223568 -311.654314) (xy 240.16837 -311.637063) (xy 240.116408 -311.611678) (xy 240.068873 -311.57874)
			(xy 240.026855 -311.539005) (xy 240.008664 -311.516522) (xy 240.001127 -311.507735) (xy 239.980349 -311.497569)
			(xy 239.968786 -311.496964) (xy 239.888522 -311.496964) (xy 239.876952 -311.497525) (xy 239.85618 -311.507724)
			(xy 239.848644 -311.516522) (xy 239.830434 -311.538989) (xy 239.788417 -311.578724) (xy 239.740886 -311.611665)
			(xy 239.688929 -311.637055) (xy 239.633735 -311.654316) (xy 239.576569 -311.66305) (xy 239.547654 -311.663588)
			(xy 239.520401 -311.663165) (xy 239.46645 -311.655402) (xy 239.414153 -311.64004) (xy 239.364574 -311.617392)
			(xy 239.318723 -311.587919) (xy 239.277532 -311.552221) (xy 239.241842 -311.511024) (xy 239.212377 -311.465168)
			(xy 239.189737 -311.415586) (xy 239.174384 -311.363286) (xy 239.16663 -311.309333) (xy 239.166146 -311.28208)
			(xy 239.166705 -311.253164) (xy 239.175423 -311.195994) (xy 239.192672 -311.140796) (xy 239.218056 -311.088833)
			(xy 239.250993 -311.041299) (xy 239.290729 -310.999281) (xy 239.313212 -310.98109) (xy 239.321976 -310.97353)
			(xy 239.332158 -310.95277) (xy 239.33277 -310.941212) (xy 239.33277 -310.860948) (xy 239.332182 -310.849382)
			(xy 239.322001 -310.82861) (xy 239.313212 -310.82107) (xy 239.292411 -310.804339) (xy 239.255285 -310.765981)
			(xy 239.223868 -310.722823) (xy 239.198772 -310.675707) (xy 239.180489 -310.625553) (xy 239.169376 -310.57334)
			(xy 239.165648 -310.520088) (xy 232.805469 -310.520088) (xy 232.80174 -310.573338) (xy 232.790625 -310.625549)
			(xy 232.772339 -310.675701) (xy 232.74724 -310.722813) (xy 232.715818 -310.765966) (xy 232.678687 -310.804317)
			(xy 232.657904 -310.82107) (xy 232.649161 -310.82865) (xy 232.638967 -310.849395) (xy 232.638346 -310.860948)
			(xy 232.638346 -310.941212) (xy 232.638894 -310.952783) (xy 232.649103 -310.973555) (xy 232.657904 -310.98109)
			(xy 232.680384 -310.999286) (xy 232.720119 -311.041305) (xy 232.753058 -311.088839) (xy 232.778447 -311.140799)
			(xy 232.795704 -311.195996) (xy 232.804434 -311.253164) (xy 232.80497 -311.28208) (xy 232.804526 -311.309334)
			(xy 232.796771 -311.363288) (xy 232.781415 -311.415588) (xy 232.758772 -311.465171) (xy 232.729303 -311.511026)
			(xy 232.693607 -311.55222) (xy 232.652411 -311.587914) (xy 232.606555 -311.617381) (xy 232.556971 -311.640022)
			(xy 232.50467 -311.655375) (xy 232.450716 -311.663127) (xy 232.423462 -311.663588) (xy 232.394547 -311.66303)
			(xy 232.337377 -311.65431) (xy 232.282179 -311.63706) (xy 232.230217 -311.611676) (xy 232.182682 -311.578739)
			(xy 232.140663 -311.539005) (xy 232.122472 -311.516522) (xy 232.114931 -311.507739) (xy 232.094156 -311.49757)
			(xy 232.082594 -311.496964) (xy 232.00233 -311.496964) (xy 231.990761 -311.497529) (xy 231.969988 -311.507725)
			(xy 231.962452 -311.516522) (xy 231.944237 -311.538985) (xy 231.902222 -311.578721) (xy 231.854692 -311.611661)
			(xy 231.802735 -311.637053) (xy 231.747542 -311.654314) (xy 231.690376 -311.663049) (xy 231.661462 -311.663588)
			(xy 231.634209 -311.663157) (xy 231.580258 -311.655395) (xy 231.527961 -311.640034) (xy 231.478382 -311.617387)
			(xy 231.432531 -311.587915) (xy 231.391341 -311.552218) (xy 231.35565 -311.511022) (xy 231.326185 -311.465167)
			(xy 231.303545 -311.415584) (xy 231.288192 -311.363285) (xy 231.280438 -311.309333) (xy 231.279954 -311.28208)
			(xy 231.280509 -311.253164) (xy 231.289228 -311.195994) (xy 231.306477 -311.140795) (xy 231.331862 -311.088833)
			(xy 231.3648 -311.041298) (xy 231.404537 -310.999281) (xy 231.42702 -310.98109) (xy 231.435785 -310.973532)
			(xy 231.445966 -310.95277) (xy 231.446578 -310.941212) (xy 231.446578 -310.860948) (xy 231.445988 -310.849383)
			(xy 231.435808 -310.828611) (xy 231.42702 -310.82107) (xy 231.406219 -310.804339) (xy 231.369092 -310.765981)
			(xy 231.337674 -310.722823) (xy 231.312578 -310.675707) (xy 231.294295 -310.625553) (xy 231.283181 -310.57334)
			(xy 231.279453 -310.520088) (xy 226.758716 -310.520088) (xy 226.754988 -310.573336) (xy 226.743875 -310.625544)
			(xy 226.725593 -310.675694) (xy 226.700499 -310.722807) (xy 226.669084 -310.765961) (xy 226.63196 -310.804316)
			(xy 226.61118 -310.82107) (xy 226.602433 -310.828646) (xy 226.592242 -310.849394) (xy 226.591622 -310.860948)
			(xy 226.591622 -310.941212) (xy 226.592178 -310.952782) (xy 226.602382 -310.973553) (xy 226.61118 -310.98109)
			(xy 226.633655 -310.999292) (xy 226.673391 -311.041309) (xy 226.706332 -311.088841) (xy 226.731722 -311.1408)
			(xy 226.74898 -311.195996) (xy 226.75771 -311.253165) (xy 226.758246 -311.28208) (xy 226.757703 -311.309329)
			(xy 226.74995 -311.363273) (xy 226.7346 -311.415564) (xy 226.711964 -311.465139) (xy 226.682503 -311.510987)
			(xy 226.646818 -311.552177) (xy 226.605634 -311.587868) (xy 226.559789 -311.617336) (xy 226.510218 -311.63998)
			(xy 226.457929 -311.655338) (xy 226.403987 -311.663099) (xy 226.376738 -311.663588) (xy 226.347822 -311.663047)
			(xy 226.290652 -311.654323) (xy 226.235453 -311.63707) (xy 226.183491 -311.611683) (xy 226.135957 -311.578743)
			(xy 226.093939 -311.539006) (xy 226.075748 -311.516522) (xy 226.068174 -311.507773) (xy 226.047424 -311.497586)
			(xy 226.03587 -311.496964) (xy 225.955606 -311.496964) (xy 225.944035 -311.497516) (xy 225.923263 -311.507721)
			(xy 225.915728 -311.516522) (xy 225.897527 -311.538997) (xy 225.855508 -311.578731) (xy 225.807975 -311.611671)
			(xy 225.756016 -311.63706) (xy 225.700821 -311.654319) (xy 225.643653 -311.663051) (xy 225.614738 -311.663588)
			(xy 225.587485 -311.663109) (xy 225.533534 -311.655357) (xy 225.481235 -311.640005) (xy 225.431654 -311.617365)
			(xy 225.385799 -311.587899) (xy 225.344606 -311.552207) (xy 225.308911 -311.511015) (xy 225.279443 -311.465162)
			(xy 225.256802 -311.415582) (xy 225.241447 -311.363284) (xy 225.233692 -311.309333) (xy 225.23323 -311.28208)
			(xy 225.233795 -311.253165) (xy 225.242513 -311.195995) (xy 225.259761 -311.140797) (xy 225.285143 -311.088835)
			(xy 225.31808 -311.0413) (xy 225.357814 -310.999281) (xy 225.380296 -310.98109) (xy 225.389057 -310.973527)
			(xy 225.399241 -310.952769) (xy 225.399854 -310.941212) (xy 225.399854 -310.860948) (xy 225.399272 -310.849381)
			(xy 225.389087 -310.828609) (xy 225.380296 -310.82107) (xy 225.359492 -310.804341) (xy 225.322357 -310.765987)
			(xy 225.290933 -310.72283) (xy 225.265832 -310.675714) (xy 225.247545 -310.625558) (xy 225.236428 -310.573343)
			(xy 225.232699 -310.520088) (xy 218.752166 -310.520088) (xy 218.752166 -313.076827) (xy 222.352414 -313.076827)
			(xy 222.356139 -313.023581) (xy 222.36725 -312.971374) (xy 222.38553 -312.921226) (xy 222.410622 -312.874115)
			(xy 222.442035 -312.830962) (xy 222.479157 -312.792608) (xy 222.499936 -312.775854) (xy 222.50872 -312.768314)
			(xy 222.51889 -312.747538) (xy 222.519494 -312.735976) (xy 222.519494 -312.655712) (xy 222.518919 -312.644145)
			(xy 222.508728 -312.623374) (xy 222.499936 -312.615834) (xy 222.477476 -312.597615) (xy 222.437738 -312.555602)
			(xy 222.404795 -312.508073) (xy 222.379402 -312.456117) (xy 222.362141 -312.400924) (xy 222.353407 -312.343759)
			(xy 222.35287 -312.314844) (xy 222.353356 -312.287593) (xy 222.361112 -312.233645) (xy 222.376467 -312.18135)
			(xy 222.399109 -312.131773) (xy 222.428575 -312.085923) (xy 222.464266 -312.044732) (xy 222.505457 -312.009041)
			(xy 222.551307 -311.979575) (xy 222.600884 -311.956933) (xy 222.653179 -311.941578) (xy 222.707127 -311.933822)
			(xy 222.761629 -311.933822) (xy 222.815577 -311.941578) (xy 222.867872 -311.956933) (xy 222.917449 -311.979575)
			(xy 222.963299 -312.009041) (xy 223.00449 -312.044732) (xy 223.040181 -312.085923) (xy 223.069647 -312.131773)
			(xy 223.092289 -312.18135) (xy 223.107644 -312.233645) (xy 223.1154 -312.287593) (xy 223.115886 -312.314844)
			(xy 223.115333 -312.34376) (xy 223.106612 -312.40093) (xy 223.089361 -312.456128) (xy 223.063976 -312.50809)
			(xy 223.031038 -312.555625) (xy 222.991303 -312.597643) (xy 222.96882 -312.615834) (xy 222.960034 -312.623372)
			(xy 222.949867 -312.644149) (xy 222.949262 -312.655712) (xy 222.949262 -312.735976) (xy 222.949825 -312.747545)
			(xy 222.960023 -312.768318) (xy 222.96882 -312.775854) (xy 222.989647 -312.792555) (xy 223.02678 -312.830913)
			(xy 223.058203 -312.874074) (xy 223.083303 -312.921193) (xy 223.101588 -312.971352) (xy 223.112703 -313.02357)
			(xy 223.116429 -313.076827) (xy 223.113276 -313.121801) (xy 223.568279 -313.121801) (xy 223.572008 -313.068551)
			(xy 223.583124 -313.01634) (xy 223.601408 -312.966188) (xy 223.626505 -312.919075) (xy 223.657924 -312.87592)
			(xy 223.695052 -312.837566) (xy 223.715834 -312.820812) (xy 223.724592 -312.813246) (xy 223.734776 -312.79249)
			(xy 223.735392 -312.780934) (xy 223.735392 -312.70067) (xy 223.734784 -312.689107) (xy 223.724616 -312.668335)
			(xy 223.715834 -312.660792) (xy 223.693354 -312.642597) (xy 223.653617 -312.600579) (xy 223.620676 -312.553045)
			(xy 223.595287 -312.501085) (xy 223.578031 -312.445887) (xy 223.569302 -312.388718) (xy 223.568768 -312.359802)
			(xy 223.569254 -312.332551) (xy 223.57701 -312.278603) (xy 223.592365 -312.226308) (xy 223.615007 -312.176731)
			(xy 223.644473 -312.130881) (xy 223.680164 -312.08969) (xy 223.721355 -312.053999) (xy 223.767205 -312.024533)
			(xy 223.816782 -312.001891) (xy 223.869077 -311.986536) (xy 223.923025 -311.97878) (xy 223.977527 -311.97878)
			(xy 224.031475 -311.986536) (xy 224.08377 -312.001891) (xy 224.133347 -312.024533) (xy 224.179197 -312.053999)
			(xy 224.220388 -312.08969) (xy 224.256079 -312.130881) (xy 224.285545 -312.176731) (xy 224.308187 -312.226308)
			(xy 224.323542 -312.278603) (xy 224.331298 -312.332551) (xy 224.331784 -312.359802) (xy 224.331273 -312.388719)
			(xy 224.322543 -312.445891) (xy 224.305284 -312.50109) (xy 224.279891 -312.553052) (xy 224.246946 -312.600586)
			(xy 224.207204 -312.642602) (xy 224.184718 -312.660792) (xy 224.17595 -312.668347) (xy 224.165773 -312.689112)
			(xy 224.16516 -312.70067) (xy 224.16516 -312.780934) (xy 224.165747 -312.7925) (xy 224.175928 -312.813273)
			(xy 224.184718 -312.820812) (xy 224.205504 -312.837562) (xy 224.242637 -312.875915) (xy 224.27406 -312.919069)
			(xy 224.29916 -312.966183) (xy 224.317448 -313.016336) (xy 224.328565 -313.068549) (xy 224.332295 -313.121801)
			(xy 224.329501 -313.161688) (xy 224.841563 -313.161688) (xy 224.845294 -313.108435) (xy 224.856412 -313.056222)
			(xy 224.874699 -313.006069) (xy 224.899799 -312.958954) (xy 224.931222 -312.915799) (xy 224.968353 -312.877444)
			(xy 224.989136 -312.86069) (xy 224.997904 -312.853134) (xy 225.008083 -312.832371) (xy 225.008694 -312.820812)
			(xy 225.008694 -312.740548) (xy 225.008098 -312.728983) (xy 224.997922 -312.708212) (xy 224.989136 -312.70067)
			(xy 224.966646 -312.682487) (xy 224.926909 -312.640467) (xy 224.89397 -312.59293) (xy 224.868582 -312.540967)
			(xy 224.851328 -312.485768) (xy 224.842603 -312.428597) (xy 224.84207 -312.39968) (xy 224.842556 -312.372429)
			(xy 224.850312 -312.318481) (xy 224.865667 -312.266186) (xy 224.888309 -312.216609) (xy 224.917775 -312.170759)
			(xy 224.953466 -312.129568) (xy 224.994657 -312.093877) (xy 225.040507 -312.064411) (xy 225.090084 -312.041769)
			(xy 225.142379 -312.026414) (xy 225.196327 -312.018658) (xy 225.250829 -312.018658) (xy 225.304777 -312.026414)
			(xy 225.357072 -312.041769) (xy 225.406649 -312.064411) (xy 225.452499 -312.093877) (xy 225.49369 -312.129568)
			(xy 225.529381 -312.170759) (xy 225.558847 -312.216609) (xy 225.581489 -312.266186) (xy 225.596844 -312.318481)
			(xy 225.6046 -312.372429) (xy 225.605086 -312.39968) (xy 225.604559 -312.428597) (xy 225.595832 -312.485768)
			(xy 225.578576 -312.540966) (xy 225.553186 -312.592928) (xy 225.520244 -312.640462) (xy 225.480505 -312.68248)
			(xy 225.45802 -312.70067) (xy 225.449263 -312.708236) (xy 225.43908 -312.728992) (xy 225.438462 -312.740548)
			(xy 225.438462 -312.820812) (xy 225.439004 -312.832384) (xy 225.449217 -312.853156) (xy 225.45802 -312.86069)
			(xy 225.478784 -312.877467) (xy 225.515916 -312.915816) (xy 225.547339 -312.958968) (xy 225.57244 -313.006078)
			(xy 225.590728 -313.056228) (xy 225.601847 -313.108438) (xy 225.605578 -313.161688) (xy 225.60185 -313.214938)
			(xy 225.590735 -313.267148) (xy 225.57245 -313.317299) (xy 225.547352 -313.364412) (xy 225.515932 -313.407565)
			(xy 225.478802 -313.445917) (xy 225.45802 -313.46267) (xy 225.449263 -313.470236) (xy 225.43908 -313.490992)
			(xy 225.438462 -313.502548) (xy 225.438462 -313.582812) (xy 225.439004 -313.594384) (xy 225.449217 -313.615156)
			(xy 225.45802 -313.62269) (xy 225.480503 -313.640882) (xy 225.520237 -313.682902) (xy 225.553176 -313.730437)
			(xy 225.578564 -313.782398) (xy 225.595821 -313.837595) (xy 225.60455 -313.894764) (xy 225.605086 -313.92368)
			(xy 225.6046 -313.950931) (xy 225.596844 -314.004879) (xy 225.581489 -314.057174) (xy 225.558847 -314.106751)
			(xy 225.529381 -314.152601) (xy 225.49369 -314.193792) (xy 225.452499 -314.229483) (xy 225.406649 -314.258949)
			(xy 225.357072 -314.281591) (xy 225.304777 -314.296946) (xy 225.250829 -314.304702) (xy 225.196327 -314.304702)
			(xy 225.142379 -314.296946) (xy 225.090084 -314.281591) (xy 225.040507 -314.258949) (xy 224.994657 -314.229483)
			(xy 224.953466 -314.193792) (xy 224.917775 -314.152601) (xy 224.888309 -314.106751) (xy 224.865667 -314.057174)
			(xy 224.850312 -314.004879) (xy 224.842556 -313.950931) (xy 224.84207 -313.92368) (xy 224.842619 -313.894764)
			(xy 224.851338 -313.837593) (xy 224.868588 -313.782394) (xy 224.893974 -313.730431) (xy 224.926914 -313.682897)
			(xy 224.966652 -313.64088) (xy 224.989136 -313.62269) (xy 224.997904 -313.615134) (xy 225.008083 -313.594371)
			(xy 225.008694 -313.582812) (xy 225.008694 -313.502548) (xy 225.008098 -313.490983) (xy 224.997922 -313.470212)
			(xy 224.989136 -313.46267) (xy 224.968334 -313.44594) (xy 224.931206 -313.407583) (xy 224.899786 -313.364425)
			(xy 224.874689 -313.317309) (xy 224.856405 -313.267154) (xy 224.845291 -313.214941) (xy 224.841563 -313.161688)
			(xy 224.329501 -313.161688) (xy 224.328565 -313.175054) (xy 224.317447 -313.227266) (xy 224.299159 -313.277419)
			(xy 224.274059 -313.324533) (xy 224.242635 -313.367687) (xy 224.205502 -313.406039) (xy 224.184718 -313.422792)
			(xy 224.17595 -313.430347) (xy 224.165773 -313.451112) (xy 224.16516 -313.46267) (xy 224.16516 -313.542934)
			(xy 224.165747 -313.5545) (xy 224.175928 -313.575273) (xy 224.184718 -313.582812) (xy 224.207211 -313.600992)
			(xy 224.246945 -313.643014) (xy 224.279882 -313.690552) (xy 224.305269 -313.742515) (xy 224.322523 -313.797714)
			(xy 224.33125 -313.854885) (xy 224.331784 -313.883802) (xy 224.331355 -313.909545) (xy 224.324435 -313.960563)
			(xy 224.310722 -314.010189) (xy 224.290463 -314.057521) (xy 224.264028 -314.101701) (xy 224.231894 -314.141928)
			(xy 224.194646 -314.177471) (xy 224.17405 -314.19292) (xy 224.163636 -314.200286) (xy 224.15246 -314.222892)
			(xy 224.156524 -314.332874) (xy 224.169224 -314.354718) (xy 224.180146 -314.361576) (xy 224.203415 -314.376576)
			(xy 224.245749 -314.41225) (xy 224.282478 -314.453672) (xy 224.312831 -314.49997) (xy 224.336169 -314.550171)
			(xy 224.352002 -314.603219) (xy 224.359997 -314.658) (xy 224.360486 -314.68568) (xy 224.359959 -314.714597)
			(xy 224.351232 -314.771768) (xy 224.333976 -314.826966) (xy 224.308586 -314.878928) (xy 224.275644 -314.926462)
			(xy 224.235905 -314.96848) (xy 224.21342 -314.98667) (xy 224.204663 -314.994236) (xy 224.19448 -315.014992)
			(xy 224.193862 -315.026548) (xy 224.193862 -315.106812) (xy 224.194404 -315.118384) (xy 224.204617 -315.139156)
			(xy 224.21342 -315.14669) (xy 224.235903 -315.164882) (xy 224.275637 -315.206902) (xy 224.308576 -315.254437)
			(xy 224.333964 -315.306398) (xy 224.351221 -315.361595) (xy 224.35995 -315.418764) (xy 224.360486 -315.44768)
			(xy 227.43287 -315.44768) (xy 227.433419 -315.418764) (xy 227.442138 -315.361593) (xy 227.459388 -315.306394)
			(xy 227.484774 -315.254431) (xy 227.517714 -315.206897) (xy 227.557452 -315.16488) (xy 227.579936 -315.14669)
			(xy 227.588704 -315.139134) (xy 227.598883 -315.118371) (xy 227.599494 -315.106812) (xy 227.599494 -315.026548)
			(xy 227.598898 -315.014983) (xy 227.588722 -314.994212) (xy 227.579936 -314.98667) (xy 227.557446 -314.968487)
			(xy 227.517709 -314.926467) (xy 227.48477 -314.87893) (xy 227.459382 -314.826967) (xy 227.442128 -314.771768)
			(xy 227.433403 -314.714597) (xy 227.43287 -314.68568) (xy 227.433289 -314.659704) (xy 227.440335 -314.608231)
			(xy 227.454307 -314.558193) (xy 227.474946 -314.510516) (xy 227.501871 -314.466085) (xy 227.53458 -314.425723)
			(xy 227.572469 -314.390177) (xy 227.593398 -314.374784) (xy 227.603304 -314.367672) (xy 227.61448 -314.346336)
			(xy 227.616766 -314.240926) (xy 227.606606 -314.219082) (xy 227.596954 -314.211716) (xy 227.576197 -314.194932)
			(xy 227.539067 -314.156582) (xy 227.507646 -314.113431) (xy 227.482547 -314.066321) (xy 227.46426 -314.016173)
			(xy 227.453142 -313.963964) (xy 227.44941 -313.910716) (xy 227.453137 -313.857467) (xy 227.464251 -313.805258)
			(xy 227.482534 -313.755108) (xy 227.507629 -313.707996) (xy 227.539047 -313.664842) (xy 227.576173 -313.626489)
			(xy 227.596954 -313.609736) (xy 227.605704 -313.602164) (xy 227.615892 -313.581412) (xy 227.616512 -313.569858)
			(xy 227.616512 -313.489594) (xy 227.615941 -313.478026) (xy 227.605746 -313.457256) (xy 227.596954 -313.449716)
			(xy 227.576197 -313.432932) (xy 227.539067 -313.394582) (xy 227.507646 -313.351431) (xy 227.482547 -313.304321)
			(xy 227.46426 -313.254173) (xy 227.453142 -313.201964) (xy 227.44941 -313.148716) (xy 227.453137 -313.095467)
			(xy 227.464251 -313.043258) (xy 227.482534 -312.993108) (xy 227.507629 -312.945996) (xy 227.539047 -312.902842)
			(xy 227.576173 -312.864489) (xy 227.596954 -312.847736) (xy 227.605704 -312.840164) (xy 227.615892 -312.819412)
			(xy 227.616512 -312.807858) (xy 227.616512 -312.727594) (xy 227.615941 -312.716026) (xy 227.605746 -312.695256)
			(xy 227.596954 -312.687716) (xy 227.574469 -312.669528) (xy 227.534736 -312.627506) (xy 227.501798 -312.57997)
			(xy 227.476411 -312.528008) (xy 227.459154 -312.472811) (xy 227.450424 -312.415642) (xy 227.449888 -312.386726)
			(xy 227.450374 -312.359475) (xy 227.45813 -312.305527) (xy 227.473485 -312.253232) (xy 227.496127 -312.203655)
			(xy 227.525593 -312.157805) (xy 227.561284 -312.116614) (xy 227.602475 -312.080923) (xy 227.648325 -312.051457)
			(xy 227.697902 -312.028815) (xy 227.750197 -312.01346) (xy 227.804145 -312.005704) (xy 227.858647 -312.005704)
			(xy 227.912595 -312.01346) (xy 227.96489 -312.028815) (xy 228.014467 -312.051457) (xy 228.060317 -312.080923)
			(xy 228.101508 -312.116614) (xy 228.137199 -312.157805) (xy 228.166665 -312.203655) (xy 228.189307 -312.253232)
			(xy 228.204662 -312.305527) (xy 228.212418 -312.359475) (xy 228.212904 -312.386726) (xy 228.212369 -312.415643)
			(xy 228.203648 -312.472815) (xy 228.186396 -312.528015) (xy 228.161008 -312.579977) (xy 228.128065 -312.627511)
			(xy 228.088324 -312.669527) (xy 228.065838 -312.687716) (xy 228.057063 -312.695265) (xy 228.046889 -312.716034)
			(xy 228.04628 -312.727594) (xy 228.04628 -312.807858) (xy 228.046882 -312.819422) (xy 228.057055 -312.840192)
			(xy 228.065838 -312.847736) (xy 228.086647 -312.864459) (xy 228.123778 -312.902815) (xy 228.155199 -312.945974)
			(xy 228.180298 -312.993091) (xy 228.198583 -313.043246) (xy 228.209698 -313.095461) (xy 228.213426 -313.148716)
			(xy 228.21216 -313.166775) (xy 229.48998 -313.166775) (xy 229.493714 -313.113519) (xy 229.504836 -313.061303)
			(xy 229.523128 -313.011147) (xy 229.548235 -312.964031) (xy 229.579664 -312.920875) (xy 229.616803 -312.882522)
			(xy 229.63759 -312.86577) (xy 229.646359 -312.858215) (xy 229.656539 -312.837451) (xy 229.657148 -312.825892)
			(xy 229.657148 -312.745628) (xy 229.656579 -312.734059) (xy 229.646385 -312.713287) (xy 229.63759 -312.70575)
			(xy 229.615128 -312.687533) (xy 229.575392 -312.645519) (xy 229.542451 -312.597989) (xy 229.517059 -312.546033)
			(xy 229.499798 -312.49084) (xy 229.491063 -312.433674) (xy 229.490524 -312.40476) (xy 229.49101 -312.377509)
			(xy 229.498766 -312.323561) (xy 229.514121 -312.271266) (xy 229.536763 -312.221689) (xy 229.566229 -312.175839)
			(xy 229.60192 -312.134648) (xy 229.643111 -312.098957) (xy 229.688961 -312.069491) (xy 229.738538 -312.046849)
			(xy 229.790833 -312.031494) (xy 229.844781 -312.023738) (xy 229.899283 -312.023738) (xy 229.953231 -312.031494)
			(xy 230.005526 -312.046849) (xy 230.055103 -312.069491) (xy 230.100953 -312.098957) (xy 230.142144 -312.134648)
			(xy 230.177835 -312.175839) (xy 230.207301 -312.221689) (xy 230.229943 -312.271266) (xy 230.245298 -312.323561)
			(xy 230.253054 -312.377509) (xy 230.25354 -312.40476) (xy 230.253016 -312.433677) (xy 230.244291 -312.490849)
			(xy 230.227036 -312.546049) (xy 230.201646 -312.598011) (xy 230.168702 -312.645545) (xy 230.12896 -312.687561)
			(xy 230.106474 -312.70575) (xy 230.097735 -312.713333) (xy 230.08754 -312.734076) (xy 230.086916 -312.745628)
			(xy 230.086916 -312.825892) (xy 230.087486 -312.83746) (xy 230.09768 -312.858231) (xy 230.106474 -312.86577)
			(xy 230.127216 -312.882571) (xy 230.164343 -312.92092) (xy 230.195762 -312.96407) (xy 230.220859 -313.011178)
			(xy 230.239146 -313.061324) (xy 230.250264 -313.11353) (xy 230.253639 -313.161688) (xy 230.937563 -313.161688)
			(xy 230.941294 -313.108435) (xy 230.952412 -313.056222) (xy 230.970699 -313.006069) (xy 230.995799 -312.958954)
			(xy 231.027222 -312.915799) (xy 231.064353 -312.877444) (xy 231.085136 -312.86069) (xy 231.093904 -312.853134)
			(xy 231.104083 -312.832371) (xy 231.104694 -312.820812) (xy 231.104694 -312.740548) (xy 231.104098 -312.728983)
			(xy 231.093922 -312.708212) (xy 231.085136 -312.70067) (xy 231.062646 -312.682487) (xy 231.022909 -312.640467)
			(xy 230.98997 -312.59293) (xy 230.964582 -312.540967) (xy 230.947328 -312.485768) (xy 230.938603 -312.428597)
			(xy 230.93807 -312.39968) (xy 230.938556 -312.372429) (xy 230.946312 -312.318481) (xy 230.961667 -312.266186)
			(xy 230.984309 -312.216609) (xy 231.013775 -312.170759) (xy 231.049466 -312.129568) (xy 231.090657 -312.093877)
			(xy 231.136507 -312.064411) (xy 231.186084 -312.041769) (xy 231.238379 -312.026414) (xy 231.292327 -312.018658)
			(xy 231.346829 -312.018658) (xy 231.400777 -312.026414) (xy 231.453072 -312.041769) (xy 231.502649 -312.064411)
			(xy 231.548499 -312.093877) (xy 231.58969 -312.129568) (xy 231.625381 -312.170759) (xy 231.654847 -312.216609)
			(xy 231.677489 -312.266186) (xy 231.692844 -312.318481) (xy 231.7006 -312.372429) (xy 231.701086 -312.39968)
			(xy 231.700559 -312.428597) (xy 231.691832 -312.485768) (xy 231.674576 -312.540966) (xy 231.649186 -312.592928)
			(xy 231.616244 -312.640462) (xy 231.576505 -312.68248) (xy 231.55402 -312.70067) (xy 231.545263 -312.708236)
			(xy 231.53508 -312.728992) (xy 231.534462 -312.740548) (xy 231.534462 -312.820812) (xy 231.535004 -312.832384)
			(xy 231.545217 -312.853156) (xy 231.55402 -312.86069) (xy 231.574784 -312.877467) (xy 231.611916 -312.915816)
			(xy 231.643339 -312.958968) (xy 231.66844 -313.006078) (xy 231.686728 -313.056228) (xy 231.697847 -313.108438)
			(xy 231.701578 -313.161688) (xy 231.69785 -313.214938) (xy 231.686735 -313.267148) (xy 231.66845 -313.317299)
			(xy 231.643352 -313.364412) (xy 231.611932 -313.407565) (xy 231.574802 -313.445917) (xy 231.55402 -313.46267)
			(xy 231.545263 -313.470236) (xy 231.53508 -313.490992) (xy 231.534462 -313.502548) (xy 231.534462 -313.582812)
			(xy 231.535004 -313.594384) (xy 231.545217 -313.615156) (xy 231.55402 -313.62269) (xy 231.576503 -313.640882)
			(xy 231.616237 -313.682902) (xy 231.649176 -313.730437) (xy 231.674564 -313.782398) (xy 231.691821 -313.837595)
			(xy 231.70055 -313.894764) (xy 231.701086 -313.92368) (xy 231.7006 -313.950931) (xy 231.692844 -314.004879)
			(xy 231.677489 -314.057174) (xy 231.654847 -314.106751) (xy 231.625381 -314.152601) (xy 231.58969 -314.193792)
			(xy 231.548499 -314.229483) (xy 231.502649 -314.258949) (xy 231.453072 -314.281591) (xy 231.400777 -314.296946)
			(xy 231.346829 -314.304702) (xy 231.292327 -314.304702) (xy 231.238379 -314.296946) (xy 231.186084 -314.281591)
			(xy 231.136507 -314.258949) (xy 231.090657 -314.229483) (xy 231.049466 -314.193792) (xy 231.013775 -314.152601)
			(xy 230.984309 -314.106751) (xy 230.961667 -314.057174) (xy 230.946312 -314.004879) (xy 230.938556 -313.950931)
			(xy 230.93807 -313.92368) (xy 230.938619 -313.894764) (xy 230.947338 -313.837593) (xy 230.964588 -313.782394)
			(xy 230.989974 -313.730431) (xy 231.022914 -313.682897) (xy 231.062652 -313.64088) (xy 231.085136 -313.62269)
			(xy 231.093904 -313.615134) (xy 231.104083 -313.594371) (xy 231.104694 -313.582812) (xy 231.104694 -313.502548)
			(xy 231.104098 -313.490983) (xy 231.093922 -313.470212) (xy 231.085136 -313.46267) (xy 231.064334 -313.44594)
			(xy 231.027206 -313.407583) (xy 230.995786 -313.364425) (xy 230.970689 -313.317309) (xy 230.952405 -313.267154)
			(xy 230.941291 -313.214941) (xy 230.937563 -313.161688) (xy 230.253639 -313.161688) (xy 230.253996 -313.166775)
			(xy 230.250271 -313.220022) (xy 230.239159 -313.272229) (xy 230.220879 -313.322377) (xy 230.195788 -313.369488)
			(xy 230.164375 -313.412642) (xy 230.127253 -313.450996) (xy 230.106474 -313.46775) (xy 230.097735 -313.475333)
			(xy 230.08754 -313.496076) (xy 230.086916 -313.507628) (xy 230.086916 -313.587892) (xy 230.087486 -313.59946)
			(xy 230.09768 -313.620231) (xy 230.106474 -313.62777) (xy 230.128938 -313.645985) (xy 230.168675 -313.687999)
			(xy 230.201617 -313.735528) (xy 230.227009 -313.787485) (xy 230.24427 -313.842679) (xy 230.253003 -313.899845)
			(xy 230.25354 -313.92876) (xy 230.253041 -313.957405) (xy 230.244467 -314.014049) (xy 230.227521 -314.068776)
			(xy 230.202583 -314.120353) (xy 230.170215 -314.167623) (xy 230.131143 -314.209522) (xy 230.109014 -314.227718)
			(xy 230.09987 -314.235084) (xy 230.08971 -314.255658) (xy 230.08971 -314.359036) (xy 230.099616 -314.37961)
			(xy 230.109014 -314.386976) (xy 230.131125 -314.405145) (xy 230.170123 -314.44703) (xy 230.202428 -314.494269)
			(xy 230.227313 -314.545805) (xy 230.244221 -314.600479) (xy 230.252773 -314.657065) (xy 230.253286 -314.68568)
			(xy 230.253286 -314.685688) (xy 233.325163 -314.685688) (xy 233.328894 -314.632435) (xy 233.340012 -314.580222)
			(xy 233.358299 -314.530069) (xy 233.383399 -314.482954) (xy 233.414822 -314.439799) (xy 233.451953 -314.401444)
			(xy 233.472736 -314.38469) (xy 233.481504 -314.377134) (xy 233.491683 -314.356371) (xy 233.492294 -314.344812)
			(xy 233.492294 -314.264548) (xy 233.491698 -314.252983) (xy 233.481522 -314.232212) (xy 233.472736 -314.22467)
			(xy 233.451934 -314.20794) (xy 233.414806 -314.169583) (xy 233.383386 -314.126425) (xy 233.358289 -314.079309)
			(xy 233.340005 -314.029154) (xy 233.328891 -313.976941) (xy 233.325163 -313.923688) (xy 233.328894 -313.870435)
			(xy 233.340012 -313.818222) (xy 233.358299 -313.768069) (xy 233.383399 -313.720954) (xy 233.414822 -313.677799)
			(xy 233.451953 -313.639444) (xy 233.472736 -313.62269) (xy 233.481504 -313.615134) (xy 233.491683 -313.594371)
			(xy 233.492294 -313.582812) (xy 233.492294 -313.502548) (xy 233.491698 -313.490983) (xy 233.481522 -313.470212)
			(xy 233.472736 -313.46267) (xy 233.451934 -313.44594) (xy 233.414806 -313.407583) (xy 233.383386 -313.364425)
			(xy 233.358289 -313.317309) (xy 233.340005 -313.267154) (xy 233.328891 -313.214941) (xy 233.325163 -313.161688)
			(xy 233.328894 -313.108435) (xy 233.340012 -313.056222) (xy 233.358299 -313.006069) (xy 233.383399 -312.958954)
			(xy 233.414822 -312.915799) (xy 233.451953 -312.877444) (xy 233.472736 -312.86069) (xy 233.481504 -312.853134)
			(xy 233.491683 -312.832371) (xy 233.492294 -312.820812) (xy 233.492294 -312.740548) (xy 233.491698 -312.728983)
			(xy 233.481522 -312.708212) (xy 233.472736 -312.70067) (xy 233.450246 -312.682487) (xy 233.410509 -312.640467)
			(xy 233.37757 -312.59293) (xy 233.352182 -312.540967) (xy 233.334928 -312.485768) (xy 233.326203 -312.428597)
			(xy 233.32567 -312.39968) (xy 233.326156 -312.372429) (xy 233.333912 -312.318481) (xy 233.349267 -312.266186)
			(xy 233.371909 -312.216609) (xy 233.401375 -312.170759) (xy 233.437066 -312.129568) (xy 233.478257 -312.093877)
			(xy 233.524107 -312.064411) (xy 233.573684 -312.041769) (xy 233.625979 -312.026414) (xy 233.679927 -312.018658)
			(xy 233.734429 -312.018658) (xy 233.788377 -312.026414) (xy 233.840672 -312.041769) (xy 233.890249 -312.064411)
			(xy 233.936099 -312.093877) (xy 233.97729 -312.129568) (xy 234.012981 -312.170759) (xy 234.042447 -312.216609)
			(xy 234.065089 -312.266186) (xy 234.080444 -312.318481) (xy 234.0882 -312.372429) (xy 234.088686 -312.39968)
			(xy 234.088159 -312.428597) (xy 234.079432 -312.485768) (xy 234.062176 -312.540966) (xy 234.036786 -312.592928)
			(xy 234.003844 -312.640462) (xy 233.964105 -312.68248) (xy 233.94162 -312.70067) (xy 233.932863 -312.708236)
			(xy 233.92268 -312.728992) (xy 233.922062 -312.740548) (xy 233.922062 -312.820812) (xy 233.922604 -312.832384)
			(xy 233.932817 -312.853156) (xy 233.94162 -312.86069) (xy 233.962384 -312.877467) (xy 233.999516 -312.915816)
			(xy 234.030939 -312.958968) (xy 234.05604 -313.006078) (xy 234.074328 -313.056228) (xy 234.078715 -313.076827)
			(xy 237.334336 -313.076827) (xy 237.338061 -313.02358) (xy 237.349174 -312.971372) (xy 237.367456 -312.921223)
			(xy 237.39255 -312.874112) (xy 237.423966 -312.830959) (xy 237.461092 -312.792607) (xy 237.481872 -312.775854)
			(xy 237.490662 -312.76832) (xy 237.500827 -312.74754) (xy 237.50143 -312.735976) (xy 237.50143 -312.655712)
			(xy 237.500877 -312.644141) (xy 237.490672 -312.623369) (xy 237.481872 -312.615834) (xy 237.459399 -312.597631)
			(xy 237.419664 -312.555613) (xy 237.386725 -312.50808) (xy 237.361335 -312.456121) (xy 237.344076 -312.400926)
			(xy 237.335343 -312.343759) (xy 237.334806 -312.314844) (xy 237.335292 -312.287593) (xy 237.343048 -312.233645)
			(xy 237.358403 -312.18135) (xy 237.381045 -312.131773) (xy 237.410511 -312.085923) (xy 237.446202 -312.044732)
			(xy 237.487393 -312.009041) (xy 237.533243 -311.979575) (xy 237.58282 -311.956933) (xy 237.635115 -311.941578)
			(xy 237.689063 -311.933822) (xy 237.743565 -311.933822) (xy 237.797513 -311.941578) (xy 237.849808 -311.956933)
			(xy 237.899385 -311.979575) (xy 237.945235 -312.009041) (xy 237.986426 -312.044732) (xy 238.022117 -312.085923)
			(xy 238.051583 -312.131773) (xy 238.074225 -312.18135) (xy 238.08958 -312.233645) (xy 238.097336 -312.287593)
			(xy 238.097822 -312.314844) (xy 238.097293 -312.343761) (xy 238.08857 -312.400933) (xy 238.071316 -312.456133)
			(xy 238.045927 -312.508095) (xy 238.012984 -312.555629) (xy 237.973242 -312.597645) (xy 237.950756 -312.615834)
			(xy 237.941976 -312.623378) (xy 237.931804 -312.644151) (xy 237.931198 -312.655712) (xy 237.931198 -312.735976)
			(xy 237.931783 -312.747542) (xy 237.941967 -312.768313) (xy 237.950756 -312.775854) (xy 237.971582 -312.792556)
			(xy 238.008711 -312.830916) (xy 238.040131 -312.874077) (xy 238.065228 -312.921196) (xy 238.083512 -312.971354)
			(xy 238.094625 -313.023571) (xy 238.098351 -313.076827) (xy 238.095199 -313.121801) (xy 238.550201 -313.121801)
			(xy 238.553931 -313.06855) (xy 238.565047 -313.016338) (xy 238.583334 -312.966186) (xy 238.608433 -312.919072)
			(xy 238.639855 -312.875918) (xy 238.676987 -312.837565) (xy 238.69777 -312.820812) (xy 238.706534 -312.813253)
			(xy 238.716713 -312.792491) (xy 238.717328 -312.780934) (xy 238.717328 -312.70067) (xy 238.716743 -312.689103)
			(xy 238.706561 -312.66833) (xy 238.69777 -312.660792) (xy 238.675276 -312.642613) (xy 238.635543 -312.60059)
			(xy 238.602606 -312.553052) (xy 238.57722 -312.501089) (xy 238.559966 -312.445889) (xy 238.551238 -312.388719)
			(xy 238.550704 -312.359802) (xy 238.55119 -312.332551) (xy 238.558946 -312.278603) (xy 238.574301 -312.226308)
			(xy 238.596943 -312.176731) (xy 238.626409 -312.130881) (xy 238.6621 -312.08969) (xy 238.703291 -312.053999)
			(xy 238.749141 -312.024533) (xy 238.798718 -312.001891) (xy 238.851013 -311.986536) (xy 238.904961 -311.97878)
			(xy 238.959463 -311.97878) (xy 239.013411 -311.986536) (xy 239.065706 -312.001891) (xy 239.115283 -312.024533)
			(xy 239.161133 -312.053999) (xy 239.202324 -312.08969) (xy 239.238015 -312.130881) (xy 239.267481 -312.176731)
			(xy 239.290123 -312.226308) (xy 239.305478 -312.278603) (xy 239.313234 -312.332551) (xy 239.31372 -312.359802)
			(xy 239.313233 -312.38872) (xy 239.304502 -312.445895) (xy 239.28724 -312.501095) (xy 239.261842 -312.553058)
			(xy 239.228892 -312.60059) (xy 239.189143 -312.642604) (xy 239.166654 -312.660792) (xy 239.157893 -312.668354)
			(xy 239.147711 -312.689113) (xy 239.147096 -312.70067) (xy 239.147096 -312.780934) (xy 239.147706 -312.792497)
			(xy 239.157873 -312.813268) (xy 239.166654 -312.820812) (xy 239.187438 -312.837563) (xy 239.224568 -312.875917)
			(xy 239.255988 -312.919073) (xy 239.281086 -312.966186) (xy 239.299372 -313.016338) (xy 239.310488 -313.06855)
			(xy 239.314217 -313.121801) (xy 239.311423 -313.161688) (xy 239.823485 -313.161688) (xy 239.827216 -313.108434)
			(xy 239.838336 -313.05622) (xy 239.856625 -313.006066) (xy 239.881727 -312.958951) (xy 239.913153 -312.915796)
			(xy 239.950287 -312.877443) (xy 239.971072 -312.86069) (xy 239.979846 -312.85314) (xy 239.99002 -312.832372)
			(xy 239.99063 -312.820812) (xy 239.99063 -312.740548) (xy 239.990056 -312.72898) (xy 239.979866 -312.708207)
			(xy 239.971072 -312.70067) (xy 239.948568 -312.682503) (xy 239.908836 -312.640477) (xy 239.8759 -312.592937)
			(xy 239.850515 -312.540971) (xy 239.833263 -312.48577) (xy 239.824539 -312.428597) (xy 239.824006 -312.39968)
			(xy 239.824492 -312.372429) (xy 239.832248 -312.318481) (xy 239.847603 -312.266186) (xy 239.870245 -312.216609)
			(xy 239.899711 -312.170759) (xy 239.935402 -312.129568) (xy 239.976593 -312.093877) (xy 240.022443 -312.064411)
			(xy 240.07202 -312.041769) (xy 240.124315 -312.026414) (xy 240.178263 -312.018658) (xy 240.232765 -312.018658)
			(xy 240.286713 -312.026414) (xy 240.339008 -312.041769) (xy 240.388585 -312.064411) (xy 240.434435 -312.093877)
			(xy 240.475626 -312.129568) (xy 240.511317 -312.170759) (xy 240.540783 -312.216609) (xy 240.563425 -312.266186)
			(xy 240.57878 -312.318481) (xy 240.586536 -312.372429) (xy 240.587022 -312.39968) (xy 240.586519 -312.428598)
			(xy 240.577791 -312.485771) (xy 240.560532 -312.540972) (xy 240.535138 -312.592934) (xy 240.50219 -312.640467)
			(xy 240.462444 -312.682482) (xy 240.439956 -312.70067) (xy 240.431205 -312.708242) (xy 240.421017 -312.728993)
			(xy 240.420398 -312.740548) (xy 240.420398 -312.820812) (xy 240.420962 -312.832381) (xy 240.431161 -312.853151)
			(xy 240.439956 -312.86069) (xy 240.460719 -312.877467) (xy 240.497847 -312.915818) (xy 240.529268 -312.95897)
			(xy 240.554366 -313.006081) (xy 240.572652 -313.05623) (xy 240.58377 -313.108439) (xy 240.587501 -313.161688)
			(xy 240.583773 -313.214937) (xy 240.572659 -313.267146) (xy 240.554376 -313.317296) (xy 240.529281 -313.364409)
			(xy 240.497863 -313.407563) (xy 240.460737 -313.445916) (xy 240.439956 -313.46267) (xy 240.431205 -313.470242)
			(xy 240.421017 -313.490993) (xy 240.420398 -313.502548) (xy 240.420398 -313.582812) (xy 240.420962 -313.594381)
			(xy 240.431161 -313.615151) (xy 240.439956 -313.62269) (xy 240.462426 -313.640898) (xy 240.502164 -313.682913)
			(xy 240.535106 -313.730444) (xy 240.560497 -313.782402) (xy 240.577755 -313.837597) (xy 240.586486 -313.894765)
			(xy 240.587022 -313.92368) (xy 240.586536 -313.950931) (xy 240.57878 -314.004879) (xy 240.563425 -314.057174)
			(xy 240.540783 -314.106751) (xy 240.511317 -314.152601) (xy 240.475626 -314.193792) (xy 240.434435 -314.229483)
			(xy 240.388585 -314.258949) (xy 240.339008 -314.281591) (xy 240.286713 -314.296946) (xy 240.232765 -314.304702)
			(xy 240.178263 -314.304702) (xy 240.124315 -314.296946) (xy 240.07202 -314.281591) (xy 240.022443 -314.258949)
			(xy 239.976593 -314.229483) (xy 239.935402 -314.193792) (xy 239.899711 -314.152601) (xy 239.870245 -314.106751)
			(xy 239.847603 -314.057174) (xy 239.832248 -314.004879) (xy 239.824492 -313.950931) (xy 239.824006 -313.92368)
			(xy 239.824579 -313.894765) (xy 239.833297 -313.837596) (xy 239.850543 -313.782398) (xy 239.875925 -313.730436)
			(xy 239.908859 -313.682901) (xy 239.948591 -313.640882) (xy 239.971072 -313.62269) (xy 239.979846 -313.61514)
			(xy 239.99002 -313.594372) (xy 239.99063 -313.582812) (xy 239.99063 -313.502548) (xy 239.990056 -313.49098)
			(xy 239.979866 -313.470207) (xy 239.971072 -313.46267) (xy 239.950269 -313.445941) (xy 239.913137 -313.407585)
			(xy 239.881714 -313.364428) (xy 239.856615 -313.317312) (xy 239.838329 -313.267157) (xy 239.827213 -313.214942)
			(xy 239.823485 -313.161688) (xy 239.311423 -313.161688) (xy 239.310487 -313.175052) (xy 239.299371 -313.227264)
			(xy 239.281085 -313.277416) (xy 239.255987 -313.32453) (xy 239.224566 -313.367685) (xy 239.187437 -313.406038)
			(xy 239.166654 -313.422792) (xy 239.157893 -313.430354) (xy 239.147711 -313.451113) (xy 239.147096 -313.46267)
			(xy 239.147096 -313.542934) (xy 239.147706 -313.554497) (xy 239.157873 -313.575268) (xy 239.166654 -313.582812)
			(xy 239.189154 -313.600983) (xy 239.228886 -313.643008) (xy 239.261822 -313.690548) (xy 239.287207 -313.742513)
			(xy 239.30446 -313.797713) (xy 239.313186 -313.854885) (xy 239.31372 -313.883802) (xy 239.313317 -313.909546)
			(xy 239.306396 -313.960566) (xy 239.29268 -314.010194) (xy 239.272418 -314.057527) (xy 239.245978 -314.101707)
			(xy 239.213839 -314.141933) (xy 239.176585 -314.177473) (xy 239.155986 -314.19292) (xy 239.145572 -314.200286)
			(xy 239.134396 -314.222892) (xy 239.13846 -314.332874) (xy 239.15116 -314.354718) (xy 239.162082 -314.361576)
			(xy 239.185359 -314.376563) (xy 239.227691 -314.412241) (xy 239.264419 -314.453666) (xy 239.29477 -314.499966)
			(xy 239.318107 -314.550168) (xy 239.333939 -314.603218) (xy 239.341933 -314.657999) (xy 239.342422 -314.68568)
			(xy 239.341919 -314.714598) (xy 239.333191 -314.771771) (xy 239.315932 -314.826972) (xy 239.290538 -314.878934)
			(xy 239.25759 -314.926467) (xy 239.217844 -314.968482) (xy 239.195356 -314.98667) (xy 239.186605 -314.994242)
			(xy 239.176417 -315.014993) (xy 239.175798 -315.026548) (xy 239.175798 -315.106812) (xy 239.176362 -315.118381)
			(xy 239.186561 -315.139151) (xy 239.195356 -315.14669) (xy 239.217826 -315.164898) (xy 239.257564 -315.206913)
			(xy 239.290506 -315.254444) (xy 239.315897 -315.306402) (xy 239.333155 -315.361597) (xy 239.341886 -315.418765)
			(xy 239.342422 -315.44768) (xy 242.414806 -315.44768) (xy 242.415379 -315.418765) (xy 242.424097 -315.361596)
			(xy 242.441343 -315.306398) (xy 242.466725 -315.254436) (xy 242.499659 -315.206901) (xy 242.539391 -315.164882)
			(xy 242.561872 -315.14669) (xy 242.570646 -315.13914) (xy 242.58082 -315.118372) (xy 242.58143 -315.106812)
			(xy 242.58143 -315.026548) (xy 242.580856 -315.01498) (xy 242.570666 -314.994207) (xy 242.561872 -314.98667)
			(xy 242.539368 -314.968503) (xy 242.499636 -314.926477) (xy 242.4667 -314.878937) (xy 242.441315 -314.826971)
			(xy 242.424063 -314.77177) (xy 242.415339 -314.714597) (xy 242.414806 -314.68568) (xy 242.415252 -314.659705)
			(xy 242.422296 -314.608235) (xy 242.436266 -314.558198) (xy 242.456902 -314.510523) (xy 242.483821 -314.466091)
			(xy 242.516525 -314.425727) (xy 242.554408 -314.390179) (xy 242.575334 -314.374784) (xy 242.58524 -314.367672)
			(xy 242.596416 -314.346336) (xy 242.598702 -314.240926) (xy 242.588542 -314.219082) (xy 242.57889 -314.211716)
			(xy 242.558131 -314.194933) (xy 242.520999 -314.156584) (xy 242.489575 -314.113434) (xy 242.464473 -314.066324)
			(xy 242.446184 -314.016175) (xy 242.435065 -313.963965) (xy 242.431332 -313.910716) (xy 242.43506 -313.857466)
			(xy 242.446175 -313.805256) (xy 242.46446 -313.755105) (xy 242.489558 -313.707993) (xy 242.520978 -313.66484)
			(xy 242.558108 -313.626489) (xy 242.57889 -313.609736) (xy 242.58763 -313.602152) (xy 242.597826 -313.58141)
			(xy 242.598448 -313.569858) (xy 242.598448 -313.489594) (xy 242.597899 -313.478023) (xy 242.587691 -313.457251)
			(xy 242.57889 -313.449716) (xy 242.558131 -313.432933) (xy 242.520999 -313.394584) (xy 242.489575 -313.351434)
			(xy 242.464473 -313.304324) (xy 242.446184 -313.254175) (xy 242.435065 -313.201965) (xy 242.431332 -313.148716)
			(xy 242.43506 -313.095466) (xy 242.446175 -313.043256) (xy 242.46446 -312.993105) (xy 242.489558 -312.945993)
			(xy 242.520978 -312.90284) (xy 242.558108 -312.864489) (xy 242.57889 -312.847736) (xy 242.58763 -312.840152)
			(xy 242.597826 -312.81941) (xy 242.598448 -312.807858) (xy 242.598448 -312.727594) (xy 242.597899 -312.716023)
			(xy 242.587691 -312.695251) (xy 242.57889 -312.687716) (xy 242.556412 -312.669518) (xy 242.516677 -312.6275)
			(xy 242.483738 -312.579966) (xy 242.458348 -312.528006) (xy 242.441091 -312.47281) (xy 242.43236 -312.415642)
			(xy 242.431824 -312.386726) (xy 242.43231 -312.359475) (xy 242.440066 -312.305527) (xy 242.455421 -312.253232)
			(xy 242.478063 -312.203655) (xy 242.507529 -312.157805) (xy 242.54322 -312.116614) (xy 242.584411 -312.080923)
			(xy 242.630261 -312.051457) (xy 242.679838 -312.028815) (xy 242.732133 -312.01346) (xy 242.786081 -312.005704)
			(xy 242.840583 -312.005704) (xy 242.894531 -312.01346) (xy 242.946826 -312.028815) (xy 242.996403 -312.051457)
			(xy 243.042253 -312.080923) (xy 243.083444 -312.116614) (xy 243.119135 -312.157805) (xy 243.148601 -312.203655)
			(xy 243.171243 -312.253232) (xy 243.186598 -312.305527) (xy 243.194354 -312.359475) (xy 243.19484 -312.386726)
			(xy 243.194291 -312.415642) (xy 243.185572 -312.472813) (xy 243.168321 -312.528012) (xy 243.142935 -312.579974)
			(xy 243.109996 -312.627509) (xy 243.070258 -312.669526) (xy 243.047774 -312.687716) (xy 243.039005 -312.695271)
			(xy 243.028826 -312.716035) (xy 243.028216 -312.727594) (xy 243.028216 -312.807858) (xy 243.028805 -312.819424)
			(xy 243.038986 -312.840195) (xy 243.047774 -312.847736) (xy 243.070026 -312.865711) (xy 243.109402 -312.9072)
			(xy 243.142143 -312.954104) (xy 243.167513 -313.005371) (xy 243.184944 -313.05985) (xy 243.194046 -313.116322)
			(xy 243.19484 -313.144916) (xy 243.19484 -313.155076) (xy 243.202714 -313.17311) (xy 243.260626 -313.230768)
			(xy 243.268051 -313.237429) (xy 243.286477 -313.245015) (xy 243.29644 -313.2455) (xy 244.371368 -313.2455)
			(xy 244.381092 -313.245011) (xy 244.399119 -313.237714) (xy 244.40642 -313.231276) (xy 244.464332 -313.176158)
			(xy 244.47246 -313.158632) (xy 244.472968 -313.148726) (xy 244.474747 -313.12137) (xy 244.48511 -313.067541)
			(xy 244.503082 -313.015753) (xy 244.528289 -312.967076) (xy 244.560212 -312.922512) (xy 244.598192 -312.882984)
			(xy 244.619526 -312.86577) (xy 244.628301 -312.858221) (xy 244.638476 -312.837452) (xy 244.639084 -312.825892)
			(xy 244.639084 -312.745628) (xy 244.638503 -312.734061) (xy 244.628317 -312.71329) (xy 244.619526 -312.70575)
			(xy 244.597072 -312.687524) (xy 244.557334 -312.645512) (xy 244.52439 -312.597985) (xy 244.498997 -312.54603)
			(xy 244.481734 -312.490839) (xy 244.472999 -312.433674) (xy 244.47246 -312.40476) (xy 244.472946 -312.377509)
			(xy 244.480702 -312.323561) (xy 244.496057 -312.271266) (xy 244.518699 -312.221689) (xy 244.548165 -312.175839)
			(xy 244.583856 -312.134648) (xy 244.625047 -312.098957) (xy 244.670897 -312.069491) (xy 244.720474 -312.046849)
			(xy 244.772769 -312.031494) (xy 244.826717 -312.023738) (xy 244.881219 -312.023738) (xy 244.935167 -312.031494)
			(xy 244.987462 -312.046849) (xy 245.037039 -312.069491) (xy 245.082889 -312.098957) (xy 245.12408 -312.134648)
			(xy 245.159771 -312.175839) (xy 245.189237 -312.221689) (xy 245.211879 -312.271266) (xy 245.227234 -312.323561)
			(xy 245.23499 -312.377509) (xy 245.235476 -312.40476) (xy 245.234938 -312.433676) (xy 245.226214 -312.490847)
			(xy 245.208961 -312.546046) (xy 245.183573 -312.598008) (xy 245.150633 -312.645542) (xy 245.110894 -312.68756)
			(xy 245.08841 -312.70575) (xy 245.079677 -312.71334) (xy 245.069477 -312.734077) (xy 245.068852 -312.745628)
			(xy 245.068852 -312.825892) (xy 245.069409 -312.837462) (xy 245.079611 -312.858234) (xy 245.08841 -312.86577)
			(xy 245.109155 -312.88257) (xy 245.146287 -312.920916) (xy 245.177711 -312.964065) (xy 245.202814 -313.011173)
			(xy 245.221103 -313.06132) (xy 245.232223 -313.113528) (xy 245.235599 -313.161688) (xy 245.919485 -313.161688)
			(xy 245.923216 -313.108434) (xy 245.934336 -313.05622) (xy 245.952625 -313.006066) (xy 245.977727 -312.958951)
			(xy 246.009153 -312.915796) (xy 246.046287 -312.877443) (xy 246.067072 -312.86069) (xy 246.075846 -312.85314)
			(xy 246.08602 -312.832372) (xy 246.08663 -312.820812) (xy 246.08663 -312.740548) (xy 246.086056 -312.72898)
			(xy 246.075866 -312.708207) (xy 246.067072 -312.70067) (xy 246.044568 -312.682503) (xy 246.004836 -312.640477)
			(xy 245.9719 -312.592937) (xy 245.946515 -312.540971) (xy 245.929263 -312.48577) (xy 245.920539 -312.428597)
			(xy 245.920006 -312.39968) (xy 245.920492 -312.372429) (xy 245.928248 -312.318481) (xy 245.943603 -312.266186)
			(xy 245.966245 -312.216609) (xy 245.995711 -312.170759) (xy 246.031402 -312.129568) (xy 246.072593 -312.093877)
			(xy 246.118443 -312.064411) (xy 246.16802 -312.041769) (xy 246.220315 -312.026414) (xy 246.274263 -312.018658)
			(xy 246.328765 -312.018658) (xy 246.382713 -312.026414) (xy 246.435008 -312.041769) (xy 246.484585 -312.064411)
			(xy 246.530435 -312.093877) (xy 246.571626 -312.129568) (xy 246.607317 -312.170759) (xy 246.636783 -312.216609)
			(xy 246.659425 -312.266186) (xy 246.67478 -312.318481) (xy 246.682536 -312.372429) (xy 246.683022 -312.39968)
			(xy 246.682519 -312.428598) (xy 246.673791 -312.485771) (xy 246.656532 -312.540972) (xy 246.631138 -312.592934)
			(xy 246.59819 -312.640467) (xy 246.558444 -312.682482) (xy 246.535956 -312.70067) (xy 246.527205 -312.708242)
			(xy 246.517017 -312.728993) (xy 246.516398 -312.740548) (xy 246.516398 -312.820812) (xy 246.516962 -312.832381)
			(xy 246.527161 -312.853151) (xy 246.535956 -312.86069) (xy 246.556719 -312.877467) (xy 246.593847 -312.915818)
			(xy 246.625268 -312.95897) (xy 246.650366 -313.006081) (xy 246.668652 -313.05623) (xy 246.67977 -313.108439)
			(xy 246.683501 -313.161688) (xy 246.679773 -313.214937) (xy 246.668659 -313.267146) (xy 246.650376 -313.317296)
			(xy 246.625281 -313.364409) (xy 246.593863 -313.407563) (xy 246.556737 -313.445916) (xy 246.535956 -313.46267)
			(xy 246.527205 -313.470242) (xy 246.517017 -313.490993) (xy 246.516398 -313.502548) (xy 246.516398 -313.582812)
			(xy 246.516962 -313.594381) (xy 246.527161 -313.615151) (xy 246.535956 -313.62269) (xy 246.558426 -313.640898)
			(xy 246.598164 -313.682913) (xy 246.631106 -313.730444) (xy 246.656497 -313.782402) (xy 246.673755 -313.837597)
			(xy 246.682486 -313.894765) (xy 246.683022 -313.92368) (xy 246.682536 -313.950931) (xy 246.67478 -314.004879)
			(xy 246.659425 -314.057174) (xy 246.636783 -314.106751) (xy 246.607317 -314.152601) (xy 246.571626 -314.193792)
			(xy 246.530435 -314.229483) (xy 246.484585 -314.258949) (xy 246.435008 -314.281591) (xy 246.382713 -314.296946)
			(xy 246.328765 -314.304702) (xy 246.274263 -314.304702) (xy 246.220315 -314.296946) (xy 246.16802 -314.281591)
			(xy 246.118443 -314.258949) (xy 246.072593 -314.229483) (xy 246.031402 -314.193792) (xy 245.995711 -314.152601)
			(xy 245.966245 -314.106751) (xy 245.943603 -314.057174) (xy 245.928248 -314.004879) (xy 245.920492 -313.950931)
			(xy 245.920006 -313.92368) (xy 245.920579 -313.894765) (xy 245.929297 -313.837596) (xy 245.946543 -313.782398)
			(xy 245.971925 -313.730436) (xy 246.004859 -313.682901) (xy 246.044591 -313.640882) (xy 246.067072 -313.62269)
			(xy 246.075846 -313.61514) (xy 246.08602 -313.594372) (xy 246.08663 -313.582812) (xy 246.08663 -313.502548)
			(xy 246.086056 -313.49098) (xy 246.075866 -313.470207) (xy 246.067072 -313.46267) (xy 246.046269 -313.445941)
			(xy 246.009137 -313.407585) (xy 245.977714 -313.364428) (xy 245.952615 -313.317312) (xy 245.934329 -313.267157)
			(xy 245.923213 -313.214942) (xy 245.919485 -313.161688) (xy 245.235599 -313.161688) (xy 245.235956 -313.166775)
			(xy 245.23223 -313.220024) (xy 245.221117 -313.272233) (xy 245.202834 -313.322382) (xy 245.177738 -313.369494)
			(xy 245.146319 -313.412646) (xy 245.109191 -313.450997) (xy 245.08841 -313.46775) (xy 245.079677 -313.47534)
			(xy 245.069477 -313.496077) (xy 245.068852 -313.507628) (xy 245.068852 -313.587892) (xy 245.069409 -313.599462)
			(xy 245.079611 -313.620234) (xy 245.08841 -313.62777) (xy 245.110881 -313.645975) (xy 245.150617 -313.687992)
			(xy 245.183557 -313.735524) (xy 245.208947 -313.787483) (xy 245.226206 -313.842678) (xy 245.234939 -313.899845)
			(xy 245.235476 -313.92876) (xy 245.234963 -313.957404) (xy 245.22639 -314.014048) (xy 245.209446 -314.068773)
			(xy 245.184511 -314.12035) (xy 245.152146 -314.16762) (xy 245.113077 -314.209521) (xy 245.09095 -314.227718)
			(xy 245.081806 -314.235084) (xy 245.071646 -314.255658) (xy 245.071646 -314.359036) (xy 245.081552 -314.37961)
			(xy 245.09095 -314.386976) (xy 245.113047 -314.405162) (xy 245.152049 -314.447041) (xy 245.184357 -314.494276)
			(xy 245.209245 -314.545809) (xy 245.226156 -314.600481) (xy 245.234708 -314.657066) (xy 245.235222 -314.68568)
			(xy 245.235222 -314.685688) (xy 248.307085 -314.685688) (xy 248.310816 -314.632434) (xy 248.321936 -314.58022)
			(xy 248.340225 -314.530066) (xy 248.365327 -314.482951) (xy 248.396753 -314.439796) (xy 248.433887 -314.401443)
			(xy 248.454672 -314.38469) (xy 248.463446 -314.37714) (xy 248.47362 -314.356372) (xy 248.47423 -314.344812)
			(xy 248.47423 -314.264548) (xy 248.473656 -314.25298) (xy 248.463466 -314.232207) (xy 248.454672 -314.22467)
			(xy 248.433869 -314.207941) (xy 248.396737 -314.169585) (xy 248.365314 -314.126428) (xy 248.340215 -314.079312)
			(xy 248.321929 -314.029157) (xy 248.310813 -313.976942) (xy 248.307085 -313.923688) (xy 248.310816 -313.870434)
			(xy 248.321936 -313.81822) (xy 248.340225 -313.768066) (xy 248.365327 -313.720951) (xy 248.396753 -313.677796)
			(xy 248.433887 -313.639443) (xy 248.454672 -313.62269) (xy 248.463446 -313.61514) (xy 248.47362 -313.594372)
			(xy 248.47423 -313.582812) (xy 248.47423 -313.502548) (xy 248.473656 -313.49098) (xy 248.463466 -313.470207)
			(xy 248.454672 -313.46267) (xy 248.433869 -313.445941) (xy 248.396737 -313.407585) (xy 248.365314 -313.364428)
			(xy 248.340215 -313.317312) (xy 248.321929 -313.267157) (xy 248.310813 -313.214942) (xy 248.307085 -313.161688)
			(xy 248.310816 -313.108434) (xy 248.321936 -313.05622) (xy 248.340225 -313.006066) (xy 248.365327 -312.958951)
			(xy 248.396753 -312.915796) (xy 248.433887 -312.877443) (xy 248.454672 -312.86069) (xy 248.463446 -312.85314)
			(xy 248.47362 -312.832372) (xy 248.47423 -312.820812) (xy 248.47423 -312.740548) (xy 248.473656 -312.72898)
			(xy 248.463466 -312.708207) (xy 248.454672 -312.70067) (xy 248.432168 -312.682503) (xy 248.392436 -312.640477)
			(xy 248.3595 -312.592937) (xy 248.334115 -312.540971) (xy 248.316863 -312.48577) (xy 248.308139 -312.428597)
			(xy 248.307606 -312.39968) (xy 248.308092 -312.372429) (xy 248.315848 -312.318481) (xy 248.331203 -312.266186)
			(xy 248.353845 -312.216609) (xy 248.383311 -312.170759) (xy 248.419002 -312.129568) (xy 248.460193 -312.093877)
			(xy 248.506043 -312.064411) (xy 248.55562 -312.041769) (xy 248.607915 -312.026414) (xy 248.661863 -312.018658)
			(xy 248.716365 -312.018658) (xy 248.770313 -312.026414) (xy 248.822608 -312.041769) (xy 248.872185 -312.064411)
			(xy 248.918035 -312.093877) (xy 248.959226 -312.129568) (xy 248.994917 -312.170759) (xy 249.024383 -312.216609)
			(xy 249.047025 -312.266186) (xy 249.06238 -312.318481) (xy 249.070136 -312.372429) (xy 249.070622 -312.39968)
			(xy 249.070119 -312.428598) (xy 249.061391 -312.485771) (xy 249.044132 -312.540972) (xy 249.018738 -312.592934)
			(xy 248.98579 -312.640467) (xy 248.946044 -312.682482) (xy 248.923556 -312.70067) (xy 248.914805 -312.708242)
			(xy 248.904617 -312.728993) (xy 248.903998 -312.740548) (xy 248.903998 -312.820812) (xy 248.904562 -312.832381)
			(xy 248.914761 -312.853151) (xy 248.923556 -312.86069) (xy 248.944319 -312.877467) (xy 248.981447 -312.915818)
			(xy 249.012868 -312.95897) (xy 249.037966 -313.006081) (xy 249.056252 -313.05623) (xy 249.06737 -313.108439)
			(xy 249.071101 -313.161688) (xy 249.067373 -313.214937) (xy 249.056259 -313.267146) (xy 249.037976 -313.317296)
			(xy 249.012881 -313.364409) (xy 248.981463 -313.407563) (xy 248.944337 -313.445916) (xy 248.923556 -313.46267)
			(xy 248.914805 -313.470242) (xy 248.904617 -313.490993) (xy 248.903998 -313.502548) (xy 248.903998 -313.582812)
			(xy 248.904562 -313.594381) (xy 248.914761 -313.615151) (xy 248.923556 -313.62269) (xy 248.944319 -313.639467)
			(xy 248.981447 -313.677818) (xy 249.012868 -313.72097) (xy 249.037966 -313.768081) (xy 249.056252 -313.81823)
			(xy 249.06737 -313.870439) (xy 249.071101 -313.923688) (xy 249.067373 -313.976937) (xy 249.056259 -314.029146)
			(xy 249.037976 -314.079296) (xy 249.012881 -314.126409) (xy 248.981463 -314.169563) (xy 248.944337 -314.207916)
			(xy 248.923556 -314.22467) (xy 248.914805 -314.232242) (xy 248.904617 -314.252993) (xy 248.903998 -314.264548)
			(xy 248.903998 -314.344812) (xy 248.904562 -314.356381) (xy 248.914761 -314.377151) (xy 248.923556 -314.38469)
			(xy 248.944319 -314.401467) (xy 248.981447 -314.439818) (xy 249.012868 -314.48297) (xy 249.037966 -314.530081)
			(xy 249.056252 -314.58023) (xy 249.06737 -314.632439) (xy 249.071101 -314.685688) (xy 249.067373 -314.738937)
			(xy 249.056259 -314.791146) (xy 249.037976 -314.841296) (xy 249.012881 -314.888409) (xy 248.981463 -314.931563)
			(xy 248.944337 -314.969916) (xy 248.923556 -314.98667) (xy 248.914805 -314.994242) (xy 248.904617 -315.014993)
			(xy 248.903998 -315.026548) (xy 248.903998 -315.106812) (xy 248.904562 -315.118381) (xy 248.914761 -315.139151)
			(xy 248.923556 -315.14669) (xy 248.946026 -315.164898) (xy 248.985764 -315.206913) (xy 249.018706 -315.254444)
			(xy 249.044097 -315.306402) (xy 249.061355 -315.361597) (xy 249.070086 -315.418765) (xy 249.070622 -315.44768)
			(xy 249.070136 -315.474931) (xy 249.06238 -315.528879) (xy 249.047025 -315.581174) (xy 249.024383 -315.630751)
			(xy 248.994917 -315.676601) (xy 248.959226 -315.717792) (xy 248.918035 -315.753483) (xy 248.872185 -315.782949)
			(xy 248.822608 -315.805591) (xy 248.770313 -315.820946) (xy 248.716365 -315.828702) (xy 248.661863 -315.828702)
			(xy 248.607915 -315.820946) (xy 248.55562 -315.805591) (xy 248.506043 -315.782949) (xy 248.460193 -315.753483)
			(xy 248.419002 -315.717792) (xy 248.383311 -315.676601) (xy 248.353845 -315.630751) (xy 248.331203 -315.581174)
			(xy 248.315848 -315.528879) (xy 248.308092 -315.474931) (xy 248.307606 -315.44768) (xy 248.308179 -315.418765)
			(xy 248.316897 -315.361596) (xy 248.334143 -315.306398) (xy 248.359525 -315.254436) (xy 248.392459 -315.206901)
			(xy 248.432191 -315.164882) (xy 248.454672 -315.14669) (xy 248.463446 -315.13914) (xy 248.47362 -315.118372)
			(xy 248.47423 -315.106812) (xy 248.47423 -315.026548) (xy 248.473656 -315.01498) (xy 248.463466 -314.994207)
			(xy 248.454672 -314.98667) (xy 248.433869 -314.969941) (xy 248.396737 -314.931585) (xy 248.365314 -314.888428)
			(xy 248.340215 -314.841312) (xy 248.321929 -314.791157) (xy 248.310813 -314.738942) (xy 248.307085 -314.685688)
			(xy 245.235222 -314.685688) (xy 245.234719 -314.714598) (xy 245.225991 -314.771771) (xy 245.208732 -314.826972)
			(xy 245.183338 -314.878934) (xy 245.15039 -314.926467) (xy 245.110644 -314.968482) (xy 245.088156 -314.98667)
			(xy 245.079405 -314.994242) (xy 245.069217 -315.014993) (xy 245.068598 -315.026548) (xy 245.068598 -315.106812)
			(xy 245.069162 -315.118381) (xy 245.079361 -315.139151) (xy 245.088156 -315.14669) (xy 245.110626 -315.164898)
			(xy 245.150364 -315.206913) (xy 245.183306 -315.254444) (xy 245.208697 -315.306402) (xy 245.225955 -315.361597)
			(xy 245.234686 -315.418765) (xy 245.235222 -315.44768) (xy 245.234736 -315.474931) (xy 245.22698 -315.528879)
			(xy 245.211625 -315.581174) (xy 245.188983 -315.630751) (xy 245.159517 -315.676601) (xy 245.123826 -315.717792)
			(xy 245.082635 -315.753483) (xy 245.036785 -315.782949) (xy 244.987208 -315.805591) (xy 244.934913 -315.820946)
			(xy 244.880965 -315.828702) (xy 244.826463 -315.828702) (xy 244.772515 -315.820946) (xy 244.72022 -315.805591)
			(xy 244.670643 -315.782949) (xy 244.624793 -315.753483) (xy 244.583602 -315.717792) (xy 244.547911 -315.676601)
			(xy 244.518445 -315.630751) (xy 244.495803 -315.581174) (xy 244.480448 -315.528879) (xy 244.472692 -315.474931)
			(xy 244.472206 -315.44768) (xy 244.472779 -315.418765) (xy 244.481497 -315.361596) (xy 244.498743 -315.306398)
			(xy 244.524125 -315.254436) (xy 244.557059 -315.206901) (xy 244.596791 -315.164882) (xy 244.619272 -315.14669)
			(xy 244.628046 -315.13914) (xy 244.63822 -315.118372) (xy 244.63883 -315.106812) (xy 244.63883 -315.026548)
			(xy 244.638256 -315.01498) (xy 244.628066 -314.994207) (xy 244.619272 -314.98667) (xy 244.596768 -314.968503)
			(xy 244.557036 -314.926477) (xy 244.5241 -314.878937) (xy 244.498715 -314.826971) (xy 244.481463 -314.77177)
			(xy 244.472739 -314.714597) (xy 244.472206 -314.68568) (xy 244.472754 -314.657037) (xy 244.48132 -314.600396)
			(xy 244.498258 -314.545671) (xy 244.523187 -314.494094) (xy 244.555546 -314.446823) (xy 244.594608 -314.40492)
			(xy 244.616732 -314.386722) (xy 244.625876 -314.379356) (xy 244.636036 -314.358782) (xy 244.636036 -314.255404)
			(xy 244.62613 -314.23483) (xy 244.616732 -314.227464) (xy 244.597039 -314.211295) (xy 244.561703 -314.174586)
			(xy 244.531556 -314.133509) (xy 244.507132 -314.08879) (xy 244.497606 -314.065158) (xy 244.492018 -314.050426)
			(xy 244.46611 -314.032392) (xy 243.194332 -314.032392) (xy 243.169186 -314.049156) (xy 243.16309 -314.063126)
			(xy 243.152375 -314.086658) (xy 243.125485 -314.130823) (xy 243.092875 -314.17095) (xy 243.055144 -314.206304)
			(xy 243.034312 -314.221622) (xy 243.024406 -314.228734) (xy 243.01323 -314.25007) (xy 243.010944 -314.35548)
			(xy 243.021104 -314.377324) (xy 243.030756 -314.38469) (xy 243.051519 -314.401467) (xy 243.088647 -314.439818)
			(xy 243.120068 -314.48297) (xy 243.145166 -314.530081) (xy 243.163452 -314.58023) (xy 243.17457 -314.632439)
			(xy 243.178301 -314.685688) (xy 243.174573 -314.738937) (xy 243.163459 -314.791146) (xy 243.145176 -314.841296)
			(xy 243.120081 -314.888409) (xy 243.088663 -314.931563) (xy 243.051537 -314.969916) (xy 243.030756 -314.98667)
			(xy 243.022005 -314.994242) (xy 243.011817 -315.014993) (xy 243.011198 -315.026548) (xy 243.011198 -315.106812)
			(xy 243.011762 -315.118381) (xy 243.021961 -315.139151) (xy 243.030756 -315.14669) (xy 243.053226 -315.164898)
			(xy 243.092964 -315.206913) (xy 243.125906 -315.254444) (xy 243.151297 -315.306402) (xy 243.168555 -315.361597)
			(xy 243.177286 -315.418765) (xy 243.177822 -315.44768) (xy 243.177336 -315.474931) (xy 243.16958 -315.528879)
			(xy 243.154225 -315.581174) (xy 243.131583 -315.630751) (xy 243.102117 -315.676601) (xy 243.066426 -315.717792)
			(xy 243.025235 -315.753483) (xy 242.979385 -315.782949) (xy 242.929808 -315.805591) (xy 242.877513 -315.820946)
			(xy 242.823565 -315.828702) (xy 242.769063 -315.828702) (xy 242.715115 -315.820946) (xy 242.66282 -315.805591)
			(xy 242.613243 -315.782949) (xy 242.567393 -315.753483) (xy 242.526202 -315.717792) (xy 242.490511 -315.676601)
			(xy 242.461045 -315.630751) (xy 242.438403 -315.581174) (xy 242.423048 -315.528879) (xy 242.415292 -315.474931)
			(xy 242.414806 -315.44768) (xy 239.342422 -315.44768) (xy 239.341936 -315.474931) (xy 239.33418 -315.528879)
			(xy 239.318825 -315.581174) (xy 239.296183 -315.630751) (xy 239.266717 -315.676601) (xy 239.231026 -315.717792)
			(xy 239.189835 -315.753483) (xy 239.143985 -315.782949) (xy 239.094408 -315.805591) (xy 239.042113 -315.820946)
			(xy 238.988165 -315.828702) (xy 238.933663 -315.828702) (xy 238.879715 -315.820946) (xy 238.82742 -315.805591)
			(xy 238.777843 -315.782949) (xy 238.731993 -315.753483) (xy 238.690802 -315.717792) (xy 238.655111 -315.676601)
			(xy 238.625645 -315.630751) (xy 238.603003 -315.581174) (xy 238.587648 -315.528879) (xy 238.579892 -315.474931)
			(xy 238.579406 -315.44768) (xy 238.579979 -315.418765) (xy 238.588697 -315.361596) (xy 238.605943 -315.306398)
			(xy 238.631325 -315.254436) (xy 238.664259 -315.206901) (xy 238.703991 -315.164882) (xy 238.726472 -315.14669)
			(xy 238.735246 -315.13914) (xy 238.74542 -315.118372) (xy 238.74603 -315.106812) (xy 238.74603 -315.026548)
			(xy 238.745456 -315.01498) (xy 238.735266 -314.994207) (xy 238.726472 -314.98667) (xy 238.703968 -314.968503)
			(xy 238.664236 -314.926477) (xy 238.6313 -314.878937) (xy 238.605915 -314.826971) (xy 238.588663 -314.77177)
			(xy 238.579939 -314.714597) (xy 238.579406 -314.68568) (xy 238.579826 -314.659937) (xy 238.586748 -314.608918)
			(xy 238.600463 -314.559293) (xy 238.620723 -314.511961) (xy 238.64716 -314.467781) (xy 238.679295 -314.427554)
			(xy 238.716544 -314.392011) (xy 238.73714 -314.376562) (xy 238.747554 -314.369196) (xy 238.75873 -314.34659)
			(xy 238.754666 -314.236608) (xy 238.741966 -314.214764) (xy 238.731044 -314.207906) (xy 238.707765 -314.192922)
			(xy 238.665432 -314.157244) (xy 238.628703 -314.11582) (xy 238.598351 -314.069519) (xy 238.575015 -314.019316)
			(xy 238.559184 -313.966265) (xy 238.551192 -313.911483) (xy 238.550704 -313.883802) (xy 238.551222 -313.854885)
			(xy 238.559951 -313.797714) (xy 238.577209 -313.742515) (xy 238.602601 -313.690553) (xy 238.635544 -313.643019)
			(xy 238.675285 -313.601002) (xy 238.69777 -313.582812) (xy 238.706534 -313.575253) (xy 238.716713 -313.554491)
			(xy 238.717328 -313.542934) (xy 238.717328 -313.46267) (xy 238.716743 -313.451103) (xy 238.706561 -313.43033)
			(xy 238.69777 -313.422792) (xy 238.676988 -313.406037) (xy 238.639857 -313.367684) (xy 238.608435 -313.32453)
			(xy 238.583335 -313.277417) (xy 238.565048 -313.227265) (xy 238.553931 -313.175053) (xy 238.550201 -313.121801)
			(xy 238.095199 -313.121801) (xy 238.094618 -313.130083) (xy 238.083497 -313.182298) (xy 238.065206 -313.232453)
			(xy 238.040103 -313.279569) (xy 238.008676 -313.322725) (xy 237.971541 -313.36108) (xy 237.950756 -313.377834)
			(xy 237.941976 -313.385378) (xy 237.931804 -313.406151) (xy 237.931198 -313.417712) (xy 237.931198 -313.497976)
			(xy 237.931783 -313.509542) (xy 237.941967 -313.530313) (xy 237.950756 -313.537854) (xy 237.973208 -313.556082)
			(xy 238.012947 -313.598093) (xy 238.045891 -313.64562) (xy 238.071286 -313.697574) (xy 238.088548 -313.752765)
			(xy 238.097284 -313.80993) (xy 238.097822 -313.838844) (xy 238.097336 -313.866095) (xy 238.08958 -313.920043)
			(xy 238.074225 -313.972338) (xy 238.051583 -314.021915) (xy 238.022117 -314.067765) (xy 237.986426 -314.108956)
			(xy 237.945235 -314.144647) (xy 237.899385 -314.174113) (xy 237.849808 -314.196755) (xy 237.797513 -314.21211)
			(xy 237.743565 -314.219866) (xy 237.689063 -314.219866) (xy 237.635115 -314.21211) (xy 237.58282 -314.196755)
			(xy 237.533243 -314.174113) (xy 237.487393 -314.144647) (xy 237.446202 -314.108956) (xy 237.410511 -314.067765)
			(xy 237.381045 -314.021915) (xy 237.358403 -313.972338) (xy 237.343048 -313.920043) (xy 237.335292 -313.866095)
			(xy 237.334806 -313.838844) (xy 237.335354 -313.809928) (xy 237.344076 -313.752758) (xy 237.361328 -313.69756)
			(xy 237.386714 -313.645598) (xy 237.419653 -313.598063) (xy 237.459389 -313.556045) (xy 237.481872 -313.537854)
			(xy 237.490662 -313.53032) (xy 237.500827 -313.50954) (xy 237.50143 -313.497976) (xy 237.50143 -313.417712)
			(xy 237.500877 -313.406141) (xy 237.490672 -313.385369) (xy 237.481872 -313.377834) (xy 237.461132 -313.361029)
			(xy 237.424001 -313.322682) (xy 237.392578 -313.279534) (xy 237.367478 -313.232427) (xy 237.349189 -313.18228)
			(xy 237.338069 -313.130074) (xy 237.334336 -313.076827) (xy 234.078715 -313.076827) (xy 234.085447 -313.108438)
			(xy 234.089178 -313.161688) (xy 234.08545 -313.214938) (xy 234.074335 -313.267148) (xy 234.05605 -313.317299)
			(xy 234.030952 -313.364412) (xy 233.999532 -313.407565) (xy 233.962402 -313.445917) (xy 233.94162 -313.46267)
			(xy 233.932863 -313.470236) (xy 233.92268 -313.490992) (xy 233.922062 -313.502548) (xy 233.922062 -313.582812)
			(xy 233.922604 -313.594384) (xy 233.932817 -313.615156) (xy 233.94162 -313.62269) (xy 233.962384 -313.639467)
			(xy 233.999516 -313.677816) (xy 234.030939 -313.720968) (xy 234.05604 -313.768078) (xy 234.074328 -313.818228)
			(xy 234.085447 -313.870438) (xy 234.089178 -313.923688) (xy 234.08545 -313.976938) (xy 234.074335 -314.029148)
			(xy 234.05605 -314.079299) (xy 234.030952 -314.126412) (xy 233.999532 -314.169565) (xy 233.962402 -314.207917)
			(xy 233.94162 -314.22467) (xy 233.932863 -314.232236) (xy 233.92268 -314.252992) (xy 233.922062 -314.264548)
			(xy 233.922062 -314.344812) (xy 233.922604 -314.356384) (xy 233.932817 -314.377156) (xy 233.94162 -314.38469)
			(xy 233.962384 -314.401467) (xy 233.999516 -314.439816) (xy 234.030939 -314.482968) (xy 234.05604 -314.530078)
			(xy 234.074328 -314.580228) (xy 234.085447 -314.632438) (xy 234.089178 -314.685688) (xy 234.08545 -314.738938)
			(xy 234.074335 -314.791148) (xy 234.057224 -314.83808) (xy 237.33836 -314.83808) (xy 237.342431 -314.782458)
			(xy 237.354557 -314.728021) (xy 237.37448 -314.67593) (xy 237.401776 -314.627295) (xy 237.435862 -314.583152)
			(xy 237.476011 -314.544443) (xy 237.521369 -314.511992) (xy 237.570969 -314.486491) (xy 237.623753 -314.468484)
			(xy 237.678596 -314.458354) (xy 237.73433 -314.456317) (xy 237.789767 -314.462417) (xy 237.843724 -314.476523)
			(xy 237.895053 -314.498335) (xy 237.942659 -314.527389) (xy 237.985527 -314.563064) (xy 238.022744 -314.604601)
			(xy 238.053517 -314.651114) (xy 238.077189 -314.701611) (xy 238.093257 -314.755018) (xy 238.101377 -314.810194)
			(xy 238.101886 -314.83808) (xy 238.101377 -314.865966) (xy 238.093257 -314.921142) (xy 238.077189 -314.974549)
			(xy 238.053517 -315.025046) (xy 238.022744 -315.071559) (xy 237.985527 -315.113096) (xy 237.942659 -315.148771)
			(xy 237.895053 -315.177825) (xy 237.843724 -315.199637) (xy 237.789767 -315.213743) (xy 237.73433 -315.219843)
			(xy 237.678596 -315.217806) (xy 237.623753 -315.207676) (xy 237.570969 -315.189669) (xy 237.521369 -315.164168)
			(xy 237.476011 -315.131717) (xy 237.435862 -315.093008) (xy 237.401776 -315.048865) (xy 237.37448 -315.00023)
			(xy 237.354557 -314.948139) (xy 237.342431 -314.893702) (xy 237.33836 -314.83808) (xy 234.057224 -314.83808)
			(xy 234.05605 -314.841299) (xy 234.030952 -314.888412) (xy 233.999532 -314.931565) (xy 233.962402 -314.969917)
			(xy 233.94162 -314.98667) (xy 233.932863 -314.994236) (xy 233.92268 -315.014992) (xy 233.922062 -315.026548)
			(xy 233.922062 -315.106812) (xy 233.922604 -315.118384) (xy 233.932817 -315.139156) (xy 233.94162 -315.14669)
			(xy 233.964103 -315.164882) (xy 234.003837 -315.206902) (xy 234.036776 -315.254437) (xy 234.062164 -315.306398)
			(xy 234.079421 -315.361595) (xy 234.08815 -315.418764) (xy 234.088686 -315.44768) (xy 234.0882 -315.474931)
			(xy 234.080444 -315.528879) (xy 234.065089 -315.581174) (xy 234.042447 -315.630751) (xy 234.012981 -315.676601)
			(xy 233.97729 -315.717792) (xy 233.936099 -315.753483) (xy 233.890249 -315.782949) (xy 233.840672 -315.805591)
			(xy 233.788377 -315.820946) (xy 233.734429 -315.828702) (xy 233.679927 -315.828702) (xy 233.625979 -315.820946)
			(xy 233.573684 -315.805591) (xy 233.524107 -315.782949) (xy 233.478257 -315.753483) (xy 233.437066 -315.717792)
			(xy 233.401375 -315.676601) (xy 233.371909 -315.630751) (xy 233.349267 -315.581174) (xy 233.333912 -315.528879)
			(xy 233.326156 -315.474931) (xy 233.32567 -315.44768) (xy 233.326219 -315.418764) (xy 233.334938 -315.361593)
			(xy 233.352188 -315.306394) (xy 233.377574 -315.254431) (xy 233.410514 -315.206897) (xy 233.450252 -315.16488)
			(xy 233.472736 -315.14669) (xy 233.481504 -315.139134) (xy 233.491683 -315.118371) (xy 233.492294 -315.106812)
			(xy 233.492294 -315.026548) (xy 233.491698 -315.014983) (xy 233.481522 -314.994212) (xy 233.472736 -314.98667)
			(xy 233.451934 -314.96994) (xy 233.414806 -314.931583) (xy 233.383386 -314.888425) (xy 233.358289 -314.841309)
			(xy 233.340005 -314.791154) (xy 233.328891 -314.738941) (xy 233.325163 -314.685688) (xy 230.253286 -314.685688)
			(xy 230.252759 -314.714597) (xy 230.244032 -314.771768) (xy 230.226776 -314.826966) (xy 230.201386 -314.878928)
			(xy 230.168444 -314.926462) (xy 230.128705 -314.96848) (xy 230.10622 -314.98667) (xy 230.097463 -314.994236)
			(xy 230.08728 -315.014992) (xy 230.086662 -315.026548) (xy 230.086662 -315.106812) (xy 230.087204 -315.118384)
			(xy 230.097417 -315.139156) (xy 230.10622 -315.14669) (xy 230.128703 -315.164882) (xy 230.168437 -315.206902)
			(xy 230.201376 -315.254437) (xy 230.226764 -315.306398) (xy 230.244021 -315.361595) (xy 230.25275 -315.418764)
			(xy 230.253286 -315.44768) (xy 230.2528 -315.474931) (xy 230.245044 -315.528879) (xy 230.229689 -315.581174)
			(xy 230.207047 -315.630751) (xy 230.177581 -315.676601) (xy 230.14189 -315.717792) (xy 230.100699 -315.753483)
			(xy 230.054849 -315.782949) (xy 230.005272 -315.805591) (xy 229.952977 -315.820946) (xy 229.899029 -315.828702)
			(xy 229.844527 -315.828702) (xy 229.790579 -315.820946) (xy 229.738284 -315.805591) (xy 229.688707 -315.782949)
			(xy 229.642857 -315.753483) (xy 229.601666 -315.717792) (xy 229.565975 -315.676601) (xy 229.536509 -315.630751)
			(xy 229.513867 -315.581174) (xy 229.498512 -315.528879) (xy 229.490756 -315.474931) (xy 229.49027 -315.44768)
			(xy 229.490819 -315.418764) (xy 229.499538 -315.361593) (xy 229.516788 -315.306394) (xy 229.542174 -315.254431)
			(xy 229.575114 -315.206897) (xy 229.614852 -315.16488) (xy 229.637336 -315.14669) (xy 229.646104 -315.139134)
			(xy 229.656283 -315.118371) (xy 229.656894 -315.106812) (xy 229.656894 -315.026548) (xy 229.656298 -315.014983)
			(xy 229.646122 -314.994212) (xy 229.637336 -314.98667) (xy 229.614846 -314.968487) (xy 229.575109 -314.926467)
			(xy 229.54217 -314.87893) (xy 229.516782 -314.826967) (xy 229.499528 -314.771768) (xy 229.490803 -314.714597)
			(xy 229.49027 -314.68568) (xy 229.490794 -314.657036) (xy 229.499362 -314.600392) (xy 229.516303 -314.545666)
			(xy 229.541236 -314.494089) (xy 229.5736 -314.446818) (xy 229.612668 -314.404918) (xy 229.634796 -314.386722)
			(xy 229.64394 -314.379356) (xy 229.6541 -314.358782) (xy 229.6541 -314.255404) (xy 229.644194 -314.23483)
			(xy 229.634796 -314.227464) (xy 229.612706 -314.20927) (xy 229.573706 -314.167391) (xy 229.541399 -314.120157)
			(xy 229.51651 -314.068626) (xy 229.499597 -314.013956) (xy 229.49104 -313.957373) (xy 229.490524 -313.92876)
			(xy 229.491076 -313.899844) (xy 229.499797 -313.842674) (xy 229.517047 -313.787476) (xy 229.542433 -313.735514)
			(xy 229.575371 -313.687979) (xy 229.615107 -313.645961) (xy 229.63759 -313.62777) (xy 229.646359 -313.620215)
			(xy 229.656539 -313.599451) (xy 229.657148 -313.587892) (xy 229.657148 -313.507628) (xy 229.656579 -313.496059)
			(xy 229.646385 -313.475287) (xy 229.63759 -313.46775) (xy 229.616766 -313.451045) (xy 229.579632 -313.412687)
			(xy 229.548208 -313.369527) (xy 229.523108 -313.322408) (xy 229.504822 -313.27225) (xy 229.493707 -313.220033)
			(xy 229.48998 -313.166775) (xy 228.21216 -313.166775) (xy 228.209694 -313.20197) (xy 228.198574 -313.254184)
			(xy 228.180285 -313.304339) (xy 228.155182 -313.351454) (xy 228.123757 -313.394609) (xy 228.086623 -313.432963)
			(xy 228.065838 -313.449716) (xy 228.057063 -313.457265) (xy 228.046889 -313.478034) (xy 228.04628 -313.489594)
			(xy 228.04628 -313.569858) (xy 228.046882 -313.581422) (xy 228.057055 -313.602192) (xy 228.065838 -313.609736)
			(xy 228.088347 -313.627897) (xy 228.128079 -313.669924) (xy 228.161013 -313.717466) (xy 228.186397 -313.769433)
			(xy 228.203648 -313.824635) (xy 228.212372 -313.881808) (xy 228.212904 -313.910726) (xy 228.212459 -313.936701)
			(xy 228.205413 -313.988171) (xy 228.191444 -314.038207) (xy 228.170808 -314.085883) (xy 228.143888 -314.130314)
			(xy 228.111184 -314.170678) (xy 228.073301 -314.206227) (xy 228.052376 -314.221622) (xy 228.04247 -314.228734)
			(xy 228.031294 -314.25007) (xy 228.029008 -314.35548) (xy 228.039168 -314.377324) (xy 228.04882 -314.38469)
			(xy 228.069584 -314.401467) (xy 228.106716 -314.439816) (xy 228.138139 -314.482968) (xy 228.16324 -314.530078)
			(xy 228.181528 -314.580228) (xy 228.192647 -314.632438) (xy 228.196378 -314.685688) (xy 228.19265 -314.738938)
			(xy 228.181535 -314.791148) (xy 228.16325 -314.841299) (xy 228.138152 -314.888412) (xy 228.106732 -314.931565)
			(xy 228.069602 -314.969917) (xy 228.04882 -314.98667) (xy 228.040063 -314.994236) (xy 228.02988 -315.014992)
			(xy 228.029262 -315.026548) (xy 228.029262 -315.106812) (xy 228.029804 -315.118384) (xy 228.040017 -315.139156)
			(xy 228.04882 -315.14669) (xy 228.071303 -315.164882) (xy 228.111037 -315.206902) (xy 228.143976 -315.254437)
			(xy 228.169364 -315.306398) (xy 228.186621 -315.361595) (xy 228.19535 -315.418764) (xy 228.195886 -315.44768)
			(xy 228.1954 -315.474931) (xy 228.187644 -315.528879) (xy 228.172289 -315.581174) (xy 228.149647 -315.630751)
			(xy 228.120181 -315.676601) (xy 228.08449 -315.717792) (xy 228.043299 -315.753483) (xy 227.997449 -315.782949)
			(xy 227.947872 -315.805591) (xy 227.895577 -315.820946) (xy 227.841629 -315.828702) (xy 227.787127 -315.828702)
			(xy 227.733179 -315.820946) (xy 227.680884 -315.805591) (xy 227.631307 -315.782949) (xy 227.585457 -315.753483)
			(xy 227.544266 -315.717792) (xy 227.508575 -315.676601) (xy 227.479109 -315.630751) (xy 227.456467 -315.581174)
			(xy 227.441112 -315.528879) (xy 227.433356 -315.474931) (xy 227.43287 -315.44768) (xy 224.360486 -315.44768)
			(xy 224.36 -315.474931) (xy 224.352244 -315.528879) (xy 224.336889 -315.581174) (xy 224.314247 -315.630751)
			(xy 224.284781 -315.676601) (xy 224.24909 -315.717792) (xy 224.207899 -315.753483) (xy 224.162049 -315.782949)
			(xy 224.112472 -315.805591) (xy 224.060177 -315.820946) (xy 224.006229 -315.828702) (xy 223.951727 -315.828702)
			(xy 223.897779 -315.820946) (xy 223.845484 -315.805591) (xy 223.795907 -315.782949) (xy 223.750057 -315.753483)
			(xy 223.708866 -315.717792) (xy 223.673175 -315.676601) (xy 223.643709 -315.630751) (xy 223.621067 -315.581174)
			(xy 223.605712 -315.528879) (xy 223.597956 -315.474931) (xy 223.59747 -315.44768) (xy 223.598019 -315.418764)
			(xy 223.606738 -315.361593) (xy 223.623988 -315.306394) (xy 223.649374 -315.254431) (xy 223.682314 -315.206897)
			(xy 223.722052 -315.16488) (xy 223.744536 -315.14669) (xy 223.753304 -315.139134) (xy 223.763483 -315.118371)
			(xy 223.764094 -315.106812) (xy 223.764094 -315.026548) (xy 223.763498 -315.014983) (xy 223.753322 -314.994212)
			(xy 223.744536 -314.98667) (xy 223.722046 -314.968487) (xy 223.682309 -314.926467) (xy 223.64937 -314.87893)
			(xy 223.623982 -314.826967) (xy 223.606728 -314.771768) (xy 223.598003 -314.714597) (xy 223.59747 -314.68568)
			(xy 223.597864 -314.659936) (xy 223.604787 -314.608915) (xy 223.618505 -314.559288) (xy 223.638768 -314.511955)
			(xy 223.66521 -314.467775) (xy 223.69735 -314.427549) (xy 223.734605 -314.392009) (xy 223.755204 -314.376562)
			(xy 223.765618 -314.369196) (xy 223.776794 -314.34659) (xy 223.77273 -314.236608) (xy 223.76003 -314.214764)
			(xy 223.749108 -314.207906) (xy 223.725821 -314.192934) (xy 223.683489 -314.157253) (xy 223.646763 -314.115826)
			(xy 223.616413 -314.069523) (xy 223.593077 -314.019318) (xy 223.577247 -313.966267) (xy 223.569256 -313.911484)
			(xy 223.568768 -313.883802) (xy 223.569262 -313.854884) (xy 223.577992 -313.79771) (xy 223.595253 -313.74251)
			(xy 223.62065 -313.690548) (xy 223.653599 -313.643015) (xy 223.693346 -313.601) (xy 223.715834 -313.582812)
			(xy 223.724592 -313.575246) (xy 223.734776 -313.55449) (xy 223.735392 -313.542934) (xy 223.735392 -313.46267)
			(xy 223.734784 -313.451107) (xy 223.724616 -313.430335) (xy 223.715834 -313.422792) (xy 223.695054 -313.406036)
			(xy 223.657926 -313.367682) (xy 223.626507 -313.324527) (xy 223.601409 -313.277414) (xy 223.583124 -313.227262)
			(xy 223.572008 -313.175052) (xy 223.568279 -313.121801) (xy 223.113276 -313.121801) (xy 223.112695 -313.130084)
			(xy 223.101573 -313.1823) (xy 223.083281 -313.232456) (xy 223.058175 -313.279572) (xy 223.026745 -313.322728)
			(xy 222.989607 -313.361081) (xy 222.96882 -313.377834) (xy 222.960034 -313.385372) (xy 222.949867 -313.406149)
			(xy 222.949262 -313.417712) (xy 222.949262 -313.497976) (xy 222.949825 -313.509545) (xy 222.960023 -313.530318)
			(xy 222.96882 -313.537854) (xy 222.991286 -313.556066) (xy 223.031021 -313.598082) (xy 223.063962 -313.645613)
			(xy 223.089353 -313.69757) (xy 223.106613 -313.752763) (xy 223.115348 -313.809929) (xy 223.115886 -313.838844)
			(xy 223.1154 -313.866095) (xy 223.107644 -313.920043) (xy 223.092289 -313.972338) (xy 223.069647 -314.021915)
			(xy 223.040181 -314.067765) (xy 223.00449 -314.108956) (xy 222.963299 -314.144647) (xy 222.917449 -314.174113)
			(xy 222.867872 -314.196755) (xy 222.815577 -314.21211) (xy 222.761629 -314.219866) (xy 222.707127 -314.219866)
			(xy 222.653179 -314.21211) (xy 222.600884 -314.196755) (xy 222.551307 -314.174113) (xy 222.505457 -314.144647)
			(xy 222.464266 -314.108956) (xy 222.428575 -314.067765) (xy 222.399109 -314.021915) (xy 222.376467 -313.972338)
			(xy 222.361112 -313.920043) (xy 222.353356 -313.866095) (xy 222.35287 -313.838844) (xy 222.353393 -313.809927)
			(xy 222.362117 -313.752755) (xy 222.379373 -313.697555) (xy 222.404763 -313.645592) (xy 222.437707 -313.598059)
			(xy 222.47745 -313.556043) (xy 222.499936 -313.537854) (xy 222.50872 -313.530314) (xy 222.51889 -313.509538)
			(xy 222.519494 -313.497976) (xy 222.519494 -313.417712) (xy 222.518919 -313.406145) (xy 222.508728 -313.385374)
			(xy 222.499936 -313.377834) (xy 222.479198 -313.361028) (xy 222.44207 -313.32268) (xy 222.41065 -313.279531)
			(xy 222.385552 -313.232424) (xy 222.367265 -313.182278) (xy 222.356147 -313.130073) (xy 222.352414 -313.076827)
			(xy 218.752166 -313.076827) (xy 218.752166 -314.83808) (xy 222.356424 -314.83808) (xy 222.360495 -314.782458)
			(xy 222.372621 -314.728021) (xy 222.392544 -314.67593) (xy 222.41984 -314.627295) (xy 222.453926 -314.583152)
			(xy 222.494075 -314.544443) (xy 222.539433 -314.511992) (xy 222.589033 -314.486491) (xy 222.641817 -314.468484)
			(xy 222.69666 -314.458354) (xy 222.752394 -314.456317) (xy 222.807831 -314.462417) (xy 222.861788 -314.476523)
			(xy 222.913117 -314.498335) (xy 222.960723 -314.527389) (xy 223.003591 -314.563064) (xy 223.040808 -314.604601)
			(xy 223.071581 -314.651114) (xy 223.095253 -314.701611) (xy 223.111321 -314.755018) (xy 223.119441 -314.810194)
			(xy 223.11995 -314.83808) (xy 223.119441 -314.865966) (xy 223.111321 -314.921142) (xy 223.095253 -314.974549)
			(xy 223.071581 -315.025046) (xy 223.040808 -315.071559) (xy 223.003591 -315.113096) (xy 222.960723 -315.148771)
			(xy 222.913117 -315.177825) (xy 222.861788 -315.199637) (xy 222.807831 -315.213743) (xy 222.752394 -315.219843)
			(xy 222.69666 -315.217806) (xy 222.641817 -315.207676) (xy 222.589033 -315.189669) (xy 222.539433 -315.164168)
			(xy 222.494075 -315.131717) (xy 222.453926 -315.093008) (xy 222.41984 -315.048865) (xy 222.392544 -315.00023)
			(xy 222.372621 -314.948139) (xy 222.360495 -314.893702) (xy 222.356424 -314.83808) (xy 218.752166 -314.83808)
			(xy 218.752166 -314.949332) (xy 218.752597 -314.959398) (xy 218.760327 -314.977988) (xy 218.767152 -314.9854)
			(xy 223.493838 -319.712086) (xy 223.501238 -319.718928) (xy 223.519836 -319.726651) (xy 223.529906 -319.727072)
		)
		(stroke
			(width 0)
			(type solid)
		)
		(fill yes)
		(layer "In4.Cu")
		(net "GND")
	)
	(gr_poly
		(pts
			(xy 125.376432 -263.084564) (xy 125.382803 -263.084329) (xy 125.395136 -263.081111) (xy 125.400816 -263.078214)
			(xy 125.407326 -263.074324) (xy 125.417923 -263.063485) (xy 125.421644 -263.056878) (xy 125.46838 -262.965184)
			(xy 125.466094 -262.93699) (xy 125.457458 -262.925306) (xy 125.443819 -262.905642) (xy 125.422173 -262.862962)
			(xy 125.407441 -262.817432) (xy 125.399981 -262.770163) (xy 125.399546 -262.746236) (xy 125.400068 -262.720981)
			(xy 125.408381 -262.671159) (xy 125.424782 -262.623385) (xy 125.448823 -262.578962) (xy 125.479847 -262.539102)
			(xy 125.517009 -262.504892) (xy 125.559295 -262.477266) (xy 125.605551 -262.456976) (xy 125.654516 -262.444576)
			(xy 125.704854 -262.440405) (xy 125.755192 -262.444576) (xy 125.804157 -262.456976) (xy 125.850413 -262.477266)
			(xy 125.892699 -262.504892) (xy 125.929861 -262.539102) (xy 125.960885 -262.578962) (xy 125.984926 -262.623385)
			(xy 126.001327 -262.671159) (xy 126.00964 -262.720981) (xy 126.010162 -262.746236) (xy 126.009722 -262.770166)
			(xy 126.002298 -262.817444) (xy 125.987575 -262.862981) (xy 125.965915 -262.905657) (xy 125.95225 -262.925306)
			(xy 125.943614 -262.93699) (xy 125.941328 -262.965184) (xy 125.988064 -263.056878) (xy 125.991733 -263.063527)
			(xy 126.002327 -263.074399) (xy 126.008892 -263.078214) (xy 126.020322 -263.084564) (xy 127.256286 -263.084564)
			(xy 127.262659 -263.084335) (xy 127.274997 -263.081126) (xy 127.28067 -263.078214) (xy 127.287175 -263.07432)
			(xy 127.297762 -263.063476) (xy 127.301498 -263.056878) (xy 127.348234 -262.965184) (xy 127.345948 -262.93699)
			(xy 127.337312 -262.925306) (xy 127.323675 -262.905641) (xy 127.302033 -262.862961) (xy 127.287302 -262.817431)
			(xy 127.279843 -262.770163) (xy 127.2794 -262.746236) (xy 127.279922 -262.720981) (xy 127.288235 -262.671159)
			(xy 127.304636 -262.623385) (xy 127.328677 -262.578962) (xy 127.359701 -262.539102) (xy 127.396863 -262.504892)
			(xy 127.439149 -262.477266) (xy 127.485405 -262.456976) (xy 127.53437 -262.444576) (xy 127.584708 -262.440405)
			(xy 127.635046 -262.444576) (xy 127.684011 -262.456976) (xy 127.730267 -262.477266) (xy 127.772553 -262.504892)
			(xy 127.809715 -262.539102) (xy 127.840739 -262.578962) (xy 127.86478 -262.623385) (xy 127.881181 -262.671159)
			(xy 127.889494 -262.720981) (xy 127.890016 -262.746236) (xy 127.889576 -262.770165) (xy 127.882151 -262.817443)
			(xy 127.867426 -262.862979) (xy 127.845763 -262.905654) (xy 127.832104 -262.925306) (xy 127.823468 -262.93699)
			(xy 127.821182 -262.965184) (xy 127.867918 -263.056878) (xy 127.87159 -263.063524) (xy 127.882189 -263.074386)
			(xy 127.888746 -263.078214) (xy 127.900176 -263.084564) (xy 128.19634 -263.084564) (xy 128.203006 -263.084365)
			(xy 128.215876 -263.080885) (xy 128.22174 -263.077706) (xy 128.227931 -263.07383) (xy 128.238004 -263.063262)
			(xy 128.241552 -263.056878) (xy 128.282954 -262.975598) (xy 128.280668 -262.946642) (xy 128.271778 -262.934958)
			(xy 128.25703 -262.914388) (xy 128.233593 -262.869529) (xy 128.217624 -262.821503) (xy 128.209533 -262.771542)
			(xy 128.20904 -262.746236) (xy 128.209527 -262.721426) (xy 128.217289 -262.672418) (xy 128.232622 -262.625228)
			(xy 128.255149 -262.581017) (xy 128.284314 -262.540874) (xy 128.3194 -262.505788) (xy 128.359543 -262.476623)
			(xy 128.403754 -262.454096) (xy 128.450944 -262.438763) (xy 128.499952 -262.431001) (xy 128.549572 -262.431001)
			(xy 128.59858 -262.438763) (xy 128.64577 -262.454096) (xy 128.689981 -262.476623) (xy 128.730124 -262.505788)
			(xy 128.76521 -262.540874) (xy 128.794375 -262.581017) (xy 128.816902 -262.625228) (xy 128.832235 -262.672418)
			(xy 128.839997 -262.721426) (xy 128.840484 -262.746236) (xy 128.83996 -262.771539) (xy 128.831848 -262.821491)
			(xy 128.815887 -262.869514) (xy 128.792482 -262.914383) (xy 128.777746 -262.934958) (xy 128.768856 -262.946642)
			(xy 128.76657 -262.975598) (xy 128.807972 -263.056878) (xy 128.811507 -263.063273) (xy 128.821572 -263.073859)
			(xy 128.827784 -263.077706) (xy 128.839722 -263.084564) (xy 129.136394 -263.084564) (xy 129.143062 -263.084371)
			(xy 129.155938 -263.080901) (xy 129.161794 -263.077706) (xy 129.16798 -263.073825) (xy 129.178044 -263.063253)
			(xy 129.181606 -263.056878) (xy 129.223008 -262.975598) (xy 129.220722 -262.946642) (xy 129.211832 -262.934958)
			(xy 129.197122 -262.914374) (xy 129.173761 -262.869503) (xy 129.157861 -262.821478) (xy 129.149829 -262.771531)
			(xy 129.149348 -262.746236) (xy 129.149834 -262.721446) (xy 129.15759 -262.672478) (xy 129.172911 -262.625325)
			(xy 129.19542 -262.58115) (xy 129.224562 -262.541039) (xy 129.259619 -262.505982) (xy 129.29973 -262.47684)
			(xy 129.343905 -262.454331) (xy 129.391058 -262.43901) (xy 129.440026 -262.431254) (xy 129.489606 -262.431254)
			(xy 129.538574 -262.43901) (xy 129.585727 -262.454331) (xy 129.629902 -262.47684) (xy 129.670013 -262.505982)
			(xy 129.70507 -262.541039) (xy 129.734212 -262.58115) (xy 129.756721 -262.625325) (xy 129.772042 -262.672478)
			(xy 129.779798 -262.721446) (xy 129.780284 -262.746236) (xy 129.779804 -262.771531) (xy 129.771773 -262.821479)
			(xy 129.755874 -262.869505) (xy 129.732515 -262.914378) (xy 129.7178 -262.934958) (xy 129.70891 -262.946642)
			(xy 129.706624 -262.975598) (xy 129.748026 -263.056878) (xy 129.751564 -263.06327) (xy 129.761634 -263.073846)
			(xy 129.767838 -263.077706) (xy 129.779776 -263.084564) (xy 130.089402 -263.084564) (xy 130.100832 -263.078214)
			(xy 130.107341 -263.074323) (xy 130.117935 -263.063482) (xy 130.12166 -263.056878) (xy 130.168396 -262.965184)
			(xy 130.16611 -262.93699) (xy 130.157474 -262.925306) (xy 130.143838 -262.90564) (xy 130.122199 -262.86296)
			(xy 130.10747 -262.81743) (xy 130.100012 -262.770162) (xy 130.099562 -262.746236) (xy 130.100005 -262.72224)
			(xy 130.107508 -262.674839) (xy 130.122333 -262.629194) (xy 130.144115 -262.586431) (xy 130.17232 -262.547602)
			(xy 130.206251 -262.513663) (xy 130.245074 -262.48545) (xy 130.287833 -262.463658) (xy 130.333474 -262.448823)
			(xy 130.380874 -262.441311) (xy 130.40487 -262.440928) (xy 130.405886 -262.440928) (xy 130.415629 -262.441023)
			(xy 130.435075 -262.442295) (xy 130.444748 -262.443468) (xy 130.446272 -262.443722) (xy 130.449574 -262.443976)
			(xy 130.459585 -262.444132) (xy 130.478531 -262.437718) (xy 130.486404 -262.43153) (xy 130.542792 -262.382254)
			(xy 130.550584 -262.374716) (xy 130.559518 -262.354983) (xy 130.560064 -262.344154) (xy 130.560064 -261.528306)
			(xy 130.559576 -261.517462) (xy 130.550642 -261.497701) (xy 130.542792 -261.490206) (xy 130.486404 -261.44093)
			(xy 130.478586 -261.434649) (xy 130.4596 -261.428237) (xy 130.449574 -261.428484) (xy 130.446272 -261.428738)
			(xy 130.444494 -261.428992) (xy 130.434443 -261.430215) (xy 130.414233 -261.431484) (xy 130.404108 -261.431532)
			(xy 130.403346 -261.431532) (xy 130.379434 -261.430946) (xy 130.332228 -261.423248) (xy 130.2868 -261.408283)
			(xy 130.244261 -261.386419) (xy 130.205652 -261.358188) (xy 130.171916 -261.324283) (xy 130.14388 -261.285533)
			(xy 130.122228 -261.242885) (xy 130.107492 -261.197382) (xy 130.10003 -261.150139) (xy 130.099562 -261.126224)
			(xy 130.100018 -261.102396) (xy 130.107418 -261.055317) (xy 130.122043 -261.00996) (xy 130.143538 -260.967425)
			(xy 130.171379 -260.928747) (xy 130.204892 -260.894864) (xy 130.243262 -260.866599) (xy 130.285557 -260.844638)
			(xy 130.330751 -260.829515) (xy 130.377746 -260.821598) (xy 130.401568 -260.820916) (xy 130.40487 -260.820916)
			(xy 130.429706 -260.821409) (xy 130.478721 -260.829462) (xy 130.525785 -260.845343) (xy 130.569658 -260.868635)
			(xy 130.609181 -260.898722) (xy 130.626612 -260.91642) (xy 130.626866 -260.91642) (xy 130.634154 -260.923544)
			(xy 130.652762 -260.931813) (xy 130.662934 -260.932422) (xy 130.734054 -260.933184) (xy 130.744058 -260.932791)
			(xy 130.762615 -260.925331) (xy 130.770122 -260.918706) (xy 130.770376 -260.918452) (xy 131.281932 -260.406896)
			(xy 131.288644 -260.399657) (xy 131.296238 -260.381453) (xy 131.296664 -260.37159) (xy 131.296664 -257.010662)
			(xy 131.296664 -257.007614) (xy 131.295687 -256.998077) (xy 131.287587 -256.980718) (xy 131.280916 -256.973832)
			(xy 131.274058 -256.968498) (xy 131.195572 -256.915666) (xy 131.170426 -256.912872) (xy 131.158742 -256.917698)
			(xy 131.131366 -256.928008) (xy 131.073942 -256.939136) (xy 131.044696 -256.939796) (xy 131.020703 -256.939349)
			(xy 130.973309 -256.931842) (xy 130.927673 -256.917013) (xy 130.884918 -256.895227) (xy 130.846098 -256.867021)
			(xy 130.812168 -256.83309) (xy 130.783964 -256.794268) (xy 130.762181 -256.751512) (xy 130.747354 -256.705875)
			(xy 130.739849 -256.658481) (xy 130.739388 -256.634488) (xy 130.739898 -256.609037) (xy 130.748342 -256.558839)
			(xy 130.764994 -256.510737) (xy 130.789393 -256.466063) (xy 130.820863 -256.426054) (xy 130.858532 -256.391819)
			(xy 130.901358 -256.364304) (xy 130.924554 -256.353818) (xy 130.936238 -256.348738) (xy 130.951986 -256.32918)
			(xy 130.97002 -256.23647) (xy 130.971094 -256.229711) (xy 130.970054 -256.216071) (xy 130.967988 -256.209546)
			(xy 130.964178 -256.198878) (xy 130.84556 -256.08026) (xy 130.8387 -256.07401) (xy 130.821773 -256.066441)
			(xy 130.81254 -256.065528) (xy 130.79095 -256.064258) (xy 130.786442 -256.064129) (xy 130.777499 -256.06528)
			(xy 130.77317 -256.066544) (xy 130.752596 -256.072894) (xy 130.746246 -256.076958) (xy 130.727178 -256.089414)
			(xy 130.686129 -256.109141) (xy 130.642603 -256.122546) (xy 130.597568 -256.129331) (xy 130.574796 -256.12979)
			(xy 130.567938 -256.12979) (xy 130.544298 -256.128822) (xy 130.497725 -256.120488) (xy 130.452996 -256.105069)
			(xy 130.411181 -256.082934) (xy 130.373282 -256.054613) (xy 130.340206 -256.020783) (xy 130.312746 -255.982255)
			(xy 130.291559 -255.939952) (xy 130.277152 -255.894887) (xy 130.269871 -255.848138) (xy 130.269488 -255.824482)
			(xy 130.269616 -255.812942) (xy 130.271395 -255.78993) (xy 130.273044 -255.778508) (xy 130.273552 -255.774698)
			(xy 130.273552 -255.773682) (xy 130.278205 -255.749097) (xy 130.29445 -255.701776) (xy 130.318186 -255.657732)
			(xy 130.34878 -255.618144) (xy 130.385413 -255.584067) (xy 130.427108 -255.556413) (xy 130.472751 -255.535919)
			(xy 130.496818 -255.52908) (xy 130.513836 -255.524508) (xy 130.534664 -255.497584) (xy 130.534664 -255.259078)
			(xy 130.533648 -255.249172) (xy 130.5306 -255.23444) (xy 130.5306 -255.234186) (xy 130.524504 -255.2192)
			(xy 130.52425 -255.218692) (xy 130.523996 -255.218184) (xy 130.521322 -255.21229) (xy 130.51348 -255.201999)
			(xy 130.508502 -255.197864) (xy 130.508248 -255.19761) (xy 130.502795 -255.193576) (xy 130.490302 -255.188305)
			(xy 130.48361 -255.187196) (xy 130.397758 -255.175766) (xy 130.390895 -255.175103) (xy 130.37725 -255.177047)
			(xy 130.370834 -255.179576) (xy 130.364484 -255.182116) (xy 130.354324 -255.190498) (xy 130.350006 -255.196086)
			(xy 130.335502 -255.214915) (xy 130.301646 -255.248269) (xy 130.263033 -255.275978) (xy 130.220594 -255.297373)
			(xy 130.175355 -255.311937) (xy 130.128405 -255.319319) (xy 130.104642 -255.319784) (xy 130.079384 -255.319295)
			(xy 130.029556 -255.310986) (xy 129.981775 -255.294589) (xy 129.937346 -255.27055) (xy 129.897479 -255.239526)
			(xy 129.863263 -255.202362) (xy 129.835632 -255.160074) (xy 129.815338 -255.113813) (xy 129.802936 -255.064843)
			(xy 129.798764 -255.0145) (xy 129.802936 -254.964157) (xy 129.815338 -254.915187) (xy 129.835632 -254.868926)
			(xy 129.863263 -254.826638) (xy 129.897479 -254.789474) (xy 129.937346 -254.75845) (xy 129.981775 -254.734411)
			(xy 130.029556 -254.718014) (xy 130.079384 -254.709705) (xy 130.104642 -254.709168) (xy 130.128408 -254.709617)
			(xy 130.175367 -254.716979) (xy 130.220617 -254.731533) (xy 130.263062 -254.752928) (xy 130.301676 -254.780646)
			(xy 130.335525 -254.814016) (xy 130.350006 -254.832866) (xy 130.354324 -254.838454) (xy 130.364484 -254.846836)
			(xy 130.370834 -254.849376) (xy 130.377243 -254.851924) (xy 130.390893 -254.853848) (xy 130.397758 -254.853186)
			(xy 130.497326 -254.839978) (xy 130.51917 -254.82296) (xy 130.52425 -254.810006) (xy 130.538017 -254.776567)
			(xy 130.572952 -254.71325) (xy 130.615766 -254.65497) (xy 130.665742 -254.602702) (xy 130.722046 -254.557321)
			(xy 130.752596 -254.537972) (xy 130.75285 -254.537718) (xy 130.758438 -254.534162) (xy 130.762756 -254.529844)
			(xy 130.770122 -254.519938) (xy 130.781806 -254.499872) (xy 130.784948 -254.493994) (xy 130.788421 -254.481132)
			(xy 130.788664 -254.474472) (xy 130.788664 -254.065278) (xy 130.788584 -254.060601) (xy 130.786929 -254.051397)
			(xy 130.785362 -254.04699) (xy 130.775964 -254.02286) (xy 130.770122 -254.016002) (xy 130.770122 -254.015748)
			(xy 130.753385 -253.995989) (xy 130.723238 -253.953884) (xy 130.709924 -253.931674) (xy 130.613658 -253.765558)
			(xy 130.608832 -253.760732) (xy 130.460496 -253.612396) (xy 130.453384 -253.605284) (xy 130.434842 -253.59741)
			(xy 130.344672 -253.597156) (xy 130.326384 -253.604522) (xy 130.319018 -253.611888) (xy 130.301768 -253.628257)
			(xy 130.263136 -253.655984) (xy 130.22067 -253.677382) (xy 130.175399 -253.691934) (xy 130.128418 -253.699286)
			(xy 130.104642 -253.699772) (xy 130.079385 -253.699283) (xy 130.029559 -253.690975) (xy 129.98178 -253.674578)
			(xy 129.937352 -253.65054) (xy 129.897487 -253.619517) (xy 129.863273 -253.582355) (xy 129.835642 -253.540068)
			(xy 129.815349 -253.493809) (xy 129.802948 -253.444841) (xy 129.798776 -253.3945) (xy 129.802948 -253.344159)
			(xy 129.815349 -253.295191) (xy 129.835642 -253.248932) (xy 129.863273 -253.206645) (xy 129.897487 -253.169483)
			(xy 129.937352 -253.13846) (xy 129.98178 -253.114422) (xy 130.029559 -253.098025) (xy 130.079385 -253.089717)
			(xy 130.104642 -253.089156) (xy 130.127656 -253.089596) (xy 130.173159 -253.096535) (xy 130.21711 -253.110206)
			(xy 130.237992 -253.11989) (xy 130.24379 -253.122525) (xy 130.256262 -253.125088) (xy 130.26263 -253.12497)
			(xy 130.276092 -253.124208) (xy 130.358388 -253.072646) (xy 130.369056 -253.063756) (xy 130.375144 -253.05653)
			(xy 130.381929 -253.038909) (xy 130.382264 -253.029466) (xy 130.382264 -252.854968) (xy 130.382173 -252.849807)
			(xy 130.380128 -252.83969) (xy 130.3782 -252.834902) (xy 130.36677 -252.807978) (xy 130.359658 -252.80112)
			(xy 130.342879 -252.783815) (xy 130.314441 -252.744897) (xy 130.292473 -252.701994) (xy 130.277518 -252.656173)
			(xy 130.269949 -252.608571) (xy 130.269953 -252.56037) (xy 130.277532 -252.51277) (xy 130.292495 -252.466951)
			(xy 130.314473 -252.424053) (xy 130.342917 -252.385141) (xy 130.359658 -252.367796) (xy 130.36677 -252.360938)
			(xy 130.3782 -252.334014) (xy 130.38009 -252.329214) (xy 130.382139 -252.319105) (xy 130.382264 -252.313948)
			(xy 130.382264 -251.234956) (xy 130.382171 -251.229795) (xy 130.380125 -251.219679) (xy 130.3782 -251.21489)
			(xy 130.366516 -251.187712) (xy 130.358896 -251.180346) (xy 130.341247 -251.162005) (xy 130.311695 -251.120567)
			(xy 130.289427 -251.074801) (xy 130.275062 -251.025974) (xy 130.27152 -251.000768) (xy 130.27152 -251.00026)
			(xy 130.270199 -250.991911) (xy 130.26281 -250.976719) (xy 130.257042 -250.970542) (xy 129.93624 -250.64974)
			(xy 129.929128 -250.642374) (xy 129.910332 -250.634754) (xy 129.872232 -250.634754) (xy 129.862217 -250.635236)
			(xy 129.843706 -250.642888) (xy 129.829532 -250.657041) (xy 129.821851 -250.675539) (xy 129.821432 -250.685554)
			(xy 129.821432 -250.69673) (xy 129.83083 -250.716796) (xy 129.839466 -250.724162) (xy 129.859908 -250.742315)
			(xy 129.894816 -250.784383) (xy 129.921949 -250.831839) (xy 129.940493 -250.883262) (xy 129.949893 -250.937113)
			(xy 129.950464 -250.964446) (xy 129.949977 -250.989256) (xy 129.942215 -251.038264) (xy 129.926882 -251.085454)
			(xy 129.904355 -251.129665) (xy 129.87519 -251.169808) (xy 129.840104 -251.204894) (xy 129.799961 -251.234059)
			(xy 129.75575 -251.256586) (xy 129.70856 -251.271919) (xy 129.659552 -251.279681) (xy 129.609932 -251.279681)
			(xy 129.560924 -251.271919) (xy 129.513734 -251.256586) (xy 129.469523 -251.234059) (xy 129.42938 -251.204894)
			(xy 129.394294 -251.169808) (xy 129.365129 -251.129665) (xy 129.342602 -251.085454) (xy 129.327269 -251.038264)
			(xy 129.319507 -250.989256) (xy 129.31902 -250.964446) (xy 129.319488 -250.940122) (xy 129.326985 -250.892055)
			(xy 129.341763 -250.845705) (xy 129.363473 -250.802169) (xy 129.377186 -250.782074) (xy 129.385314 -250.77039)
			(xy 129.387346 -250.741942) (xy 129.345182 -250.661932) (xy 129.340533 -250.65395) (xy 129.326711 -250.641718)
			(xy 129.309453 -250.635173) (xy 129.300224 -250.634754) (xy 129.029206 -250.634754) (xy 129.019975 -250.635153)
			(xy 129.002713 -250.641701) (xy 128.988897 -250.653947) (xy 128.984248 -250.661932) (xy 128.943608 -250.739402)
			(xy 128.940581 -250.745562) (xy 128.937612 -250.758957) (xy 128.937766 -250.765818) (xy 128.938528 -250.780042)
			(xy 128.946656 -250.79198) (xy 128.959253 -250.811131) (xy 128.979183 -250.852411) (xy 128.992725 -250.896203)
			(xy 128.999577 -250.941527) (xy 128.999996 -250.964446) (xy 128.999996 -250.966478) (xy 128.999996 -250.971304)
			(xy 128.998945 -250.996188) (xy 128.989763 -251.045137) (xy 128.972759 -251.091947) (xy 128.948385 -251.135378)
			(xy 128.917288 -251.174278) (xy 128.88029 -251.207617) (xy 128.838373 -251.23451) (xy 128.792647 -251.254246)
			(xy 128.744325 -251.266301) (xy 128.694688 -251.270355) (xy 128.645051 -251.266301) (xy 128.596729 -251.254246)
			(xy 128.551003 -251.23451) (xy 128.509086 -251.207617) (xy 128.472088 -251.174278) (xy 128.440991 -251.135378)
			(xy 128.416617 -251.091947) (xy 128.399613 -251.045137) (xy 128.390431 -250.996188) (xy 128.38938 -250.971304)
			(xy 128.38938 -250.966478) (xy 128.38938 -250.964446) (xy 128.389787 -250.941525) (xy 128.396631 -250.896198)
			(xy 128.410173 -250.852402) (xy 128.430107 -250.811122) (xy 128.44272 -250.79198) (xy 128.446784 -250.786138)
			(xy 128.451102 -250.773184) (xy 128.45161 -250.765818) (xy 128.451731 -250.758959) (xy 128.448778 -250.745566)
			(xy 128.445768 -250.739402) (xy 128.405128 -250.661932) (xy 128.400481 -250.653945) (xy 128.386661 -250.6417)
			(xy 128.369402 -250.63514) (xy 128.36017 -250.634754) (xy 128.089152 -250.634754) (xy 128.079916 -250.635145)
			(xy 128.062642 -250.641683) (xy 128.048813 -250.653926) (xy 128.044194 -250.661932) (xy 128.00203 -250.741942)
			(xy 128.004062 -250.77039) (xy 128.01219 -250.782074) (xy 128.02589 -250.802177) (xy 128.0476 -250.845709)
			(xy 128.062373 -250.892057) (xy 128.06986 -250.940123) (xy 128.070356 -250.964446) (xy 128.069869 -250.989256)
			(xy 128.062107 -251.038264) (xy 128.046774 -251.085454) (xy 128.024247 -251.129665) (xy 127.995082 -251.169808)
			(xy 127.959996 -251.204894) (xy 127.919853 -251.234059) (xy 127.875642 -251.256586) (xy 127.828452 -251.271919)
			(xy 127.779444 -251.279681) (xy 127.729824 -251.279681) (xy 127.680816 -251.271919) (xy 127.633626 -251.256586)
			(xy 127.589415 -251.234059) (xy 127.549272 -251.204894) (xy 127.514186 -251.169808) (xy 127.485021 -251.129665)
			(xy 127.462494 -251.085454) (xy 127.447161 -251.038264) (xy 127.439399 -250.989256) (xy 127.438912 -250.964446)
			(xy 127.43938 -250.940122) (xy 127.446877 -250.892054) (xy 127.461655 -250.845705) (xy 127.483364 -250.802168)
			(xy 127.497078 -250.782074) (xy 127.505206 -250.77039) (xy 127.507238 -250.741942) (xy 127.465074 -250.661932)
			(xy 127.460425 -250.653951) (xy 127.446602 -250.641721) (xy 127.429344 -250.635179) (xy 127.420116 -250.634754)
			(xy 127.149352 -250.634754) (xy 127.140116 -250.635145) (xy 127.122842 -250.641683) (xy 127.109013 -250.653926)
			(xy 127.104394 -250.661932) (xy 127.063754 -250.739402) (xy 127.06073 -250.745563) (xy 127.057764 -250.758957)
			(xy 127.057912 -250.765818) (xy 127.058674 -250.780042) (xy 127.066802 -250.79198) (xy 127.079397 -250.811132)
			(xy 127.099324 -250.852412) (xy 127.112864 -250.896204) (xy 127.119715 -250.941527) (xy 127.120142 -250.964446)
			(xy 127.120142 -250.966478) (xy 127.120142 -250.971304) (xy 127.119091 -250.996188) (xy 127.109909 -251.045137)
			(xy 127.092905 -251.091947) (xy 127.068531 -251.135378) (xy 127.037434 -251.174278) (xy 127.000436 -251.207617)
			(xy 126.958519 -251.23451) (xy 126.912793 -251.254246) (xy 126.864471 -251.266301) (xy 126.814834 -251.270355)
			(xy 126.765197 -251.266301) (xy 126.716875 -251.254246) (xy 126.671149 -251.23451) (xy 126.629232 -251.207617)
			(xy 126.592234 -251.174278) (xy 126.561137 -251.135378) (xy 126.536763 -251.091947) (xy 126.519759 -251.045137)
			(xy 126.510577 -250.996188) (xy 126.509526 -250.971304) (xy 126.509526 -250.966478) (xy 126.509526 -250.964446)
			(xy 126.509933 -250.941525) (xy 126.516776 -250.896197) (xy 126.530315 -250.8524) (xy 126.550247 -250.811119)
			(xy 126.562866 -250.79198) (xy 126.56693 -250.786138) (xy 126.571248 -250.773184) (xy 126.571756 -250.765818)
			(xy 126.571876 -250.758959) (xy 126.568921 -250.745568) (xy 126.565914 -250.739402) (xy 126.525274 -250.661932)
			(xy 126.520625 -250.653951) (xy 126.506802 -250.641721) (xy 126.489544 -250.635179) (xy 126.480316 -250.634754)
			(xy 126.474474 -250.634754) (xy 126.4539 -250.61418) (xy 126.446788 -250.606814) (xy 126.427992 -250.599194)
			(xy 125.287278 -250.599194) (xy 125.277437 -250.599721) (xy 125.259263 -250.607295) (xy 125.251972 -250.613926)
			(xy 125.169168 -250.69673) (xy 125.16274 -250.703732) (xy 125.155132 -250.721137) (xy 125.154353 -250.740116)
			(xy 125.16051 -250.758085) (xy 125.166374 -250.765564) (xy 125.166628 -250.765818) (xy 125.183782 -250.786741)
			(xy 125.211183 -250.83339) (xy 125.229931 -250.884138) (xy 125.239442 -250.937395) (xy 125.240034 -250.964446)
			(xy 125.23956 -250.988436) (xy 125.232048 -251.035823) (xy 125.217217 -251.081453) (xy 125.195432 -251.124201)
			(xy 125.167228 -251.163015) (xy 125.1333 -251.196941) (xy 125.094484 -251.225142) (xy 125.051734 -251.246925)
			(xy 125.006104 -251.261753) (xy 124.958716 -251.269262) (xy 124.934726 -251.269754) (xy 124.909845 -251.269268)
			(xy 124.86074 -251.261211) (xy 124.813589 -251.245306) (xy 124.769636 -251.221974) (xy 124.74956 -251.20727)
			(xy 124.742448 -251.201682) (xy 124.725684 -251.196602) (xy 124.686822 -251.198126) (xy 124.67717 -251.198634)
			(xy 124.659898 -251.206) (xy 124.540772 -251.325126) (xy 124.538486 -251.327666) (xy 124.538232 -251.327666)
			(xy 124.530893 -251.33698) (xy 124.524931 -251.359899) (xy 124.526802 -251.371608) (xy 124.546614 -251.465588)
			(xy 124.563124 -251.484892) (xy 124.575316 -251.489718) (xy 124.599542 -251.49972) (xy 124.644431 -251.526769)
			(xy 124.684051 -251.561075) (xy 124.717241 -251.601634) (xy 124.743031 -251.647258) (xy 124.760664 -251.696611)
			(xy 124.769624 -251.748248) (xy 124.770134 -251.774452) (xy 126.038876 -251.774452) (xy 126.042836 -251.725398)
			(xy 126.054613 -251.677614) (xy 126.073904 -251.632338) (xy 126.100207 -251.590742) (xy 126.132842 -251.553905)
			(xy 126.170963 -251.52278) (xy 126.213584 -251.498173) (xy 126.2596 -251.480721) (xy 126.307819 -251.470877)
			(xy 126.356994 -251.468896) (xy 126.405849 -251.474828) (xy 126.45312 -251.48852) (xy 126.497582 -251.509618)
			(xy 126.538085 -251.537574) (xy 126.573578 -251.571666) (xy 126.603143 -251.61101) (xy 126.626014 -251.654587)
			(xy 126.641598 -251.701268) (xy 126.649493 -251.749845) (xy 126.649988 -251.774452) (xy 127.908553 -251.774452)
			(xy 127.912648 -251.723724) (xy 127.924827 -251.67431) (xy 127.944775 -251.62749) (xy 127.971976 -251.584476)
			(xy 128.005724 -251.546382) (xy 128.045146 -251.514195) (xy 128.08922 -251.488749) (xy 128.136806 -251.470702)
			(xy 128.18667 -251.460522) (xy 128.237522 -251.458473) (xy 128.288043 -251.464607) (xy 128.336927 -251.478767)
			(xy 128.382906 -251.500584) (xy 128.42479 -251.529494) (xy 128.461494 -251.564749) (xy 128.492067 -251.605435)
			(xy 128.515718 -251.650498) (xy 128.531834 -251.698772) (xy 128.539998 -251.749006) (xy 128.54051 -251.774452)
			(xy 128.859038 -251.774452) (xy 128.862998 -251.725398) (xy 128.874775 -251.677614) (xy 128.894066 -251.632338)
			(xy 128.920369 -251.590742) (xy 128.953004 -251.553905) (xy 128.991125 -251.52278) (xy 129.033746 -251.498173)
			(xy 129.079762 -251.480721) (xy 129.127981 -251.470877) (xy 129.177156 -251.468896) (xy 129.226011 -251.474828)
			(xy 129.273282 -251.48852) (xy 129.317744 -251.509618) (xy 129.358247 -251.537574) (xy 129.39374 -251.571666)
			(xy 129.423305 -251.61101) (xy 129.446176 -251.654587) (xy 129.46176 -251.701268) (xy 129.469655 -251.749845)
			(xy 129.47015 -251.774452) (xy 129.469655 -251.799059) (xy 129.46176 -251.847636) (xy 129.446176 -251.894317)
			(xy 129.423305 -251.937894) (xy 129.39374 -251.977238) (xy 129.358247 -252.01133) (xy 129.317744 -252.039286)
			(xy 129.273282 -252.060384) (xy 129.226011 -252.074076) (xy 129.177156 -252.080008) (xy 129.127981 -252.078027)
			(xy 129.079762 -252.068183) (xy 129.033746 -252.050731) (xy 128.991125 -252.026124) (xy 128.953004 -251.994999)
			(xy 128.920369 -251.958162) (xy 128.894066 -251.916566) (xy 128.874775 -251.87129) (xy 128.862998 -251.823506)
			(xy 128.859038 -251.774452) (xy 128.54051 -251.774452) (xy 128.539998 -251.799898) (xy 128.531834 -251.850132)
			(xy 128.515718 -251.898406) (xy 128.492067 -251.943469) (xy 128.461494 -251.984155) (xy 128.42479 -252.01941)
			(xy 128.382906 -252.04832) (xy 128.336927 -252.070137) (xy 128.288043 -252.084297) (xy 128.237522 -252.090431)
			(xy 128.18667 -252.088382) (xy 128.136806 -252.078202) (xy 128.08922 -252.060155) (xy 128.045146 -252.034709)
			(xy 128.005724 -252.002522) (xy 127.971976 -251.964428) (xy 127.944775 -251.921414) (xy 127.924827 -251.874594)
			(xy 127.912648 -251.82518) (xy 127.908553 -251.774452) (xy 126.649988 -251.774452) (xy 126.649493 -251.799059)
			(xy 126.641598 -251.847636) (xy 126.626014 -251.894317) (xy 126.603143 -251.937894) (xy 126.573578 -251.977238)
			(xy 126.538085 -252.01133) (xy 126.497582 -252.039286) (xy 126.45312 -252.060384) (xy 126.405849 -252.074076)
			(xy 126.356994 -252.080008) (xy 126.307819 -252.078027) (xy 126.2596 -252.068183) (xy 126.213584 -252.050731)
			(xy 126.170963 -252.026124) (xy 126.132842 -251.994999) (xy 126.100207 -251.958162) (xy 126.073904 -251.916566)
			(xy 126.054613 -251.87129) (xy 126.042836 -251.823506) (xy 126.038876 -251.774452) (xy 124.770134 -251.774452)
			(xy 124.769612 -251.799707) (xy 124.761299 -251.849529) (xy 124.744898 -251.897303) (xy 124.720857 -251.941726)
			(xy 124.689833 -251.981586) (xy 124.652671 -252.015796) (xy 124.610385 -252.043422) (xy 124.564129 -252.063712)
			(xy 124.515164 -252.076112) (xy 124.464826 -252.080283) (xy 124.414488 -252.076112) (xy 124.365523 -252.063712)
			(xy 124.319267 -252.043422) (xy 124.276981 -252.015796) (xy 124.239819 -251.981586) (xy 124.208795 -251.941726)
			(xy 124.184754 -251.897303) (xy 124.168353 -251.849529) (xy 124.16004 -251.799707) (xy 124.159518 -251.774452)
			(xy 124.160166 -251.745752) (xy 124.170901 -251.689365) (xy 124.180854 -251.662438) (xy 124.18314 -251.656596)
			(xy 124.184664 -251.644404) (xy 124.184156 -251.638054) (xy 124.183226 -251.631946) (xy 124.178857 -251.620394)
			(xy 124.17552 -251.615194) (xy 124.129546 -251.547376) (xy 124.122017 -251.537358) (xy 124.099899 -251.525643)
			(xy 124.087382 -251.525024) (xy 123.393708 -251.525024) (xy 123.383872 -251.524485) (xy 123.365714 -251.516895)
			(xy 123.358402 -251.510292) (xy 123.122182 -251.274072) (xy 123.100592 -251.266452) (xy 123.088908 -251.267722)
			(xy 123.054618 -251.269754) (xy 123.030625 -251.269285) (xy 122.983228 -251.261781) (xy 122.937589 -251.246956)
			(xy 122.89483 -251.225174) (xy 122.856005 -251.196972) (xy 122.82207 -251.163044) (xy 122.793859 -251.124225)
			(xy 122.772069 -251.081471) (xy 122.757234 -251.035834) (xy 122.74972 -250.988439) (xy 122.74931 -250.964446)
			(xy 122.751342 -250.930156) (xy 122.752612 -250.918472) (xy 122.744992 -250.896882) (xy 122.46229 -250.61418)
			(xy 122.455178 -250.606814) (xy 122.436382 -250.599194) (xy 121.520458 -250.599194) (xy 121.510618 -250.599725)
			(xy 121.492449 -250.607304) (xy 121.485152 -250.613926) (xy 121.420382 -250.678696) (xy 121.413843 -250.685762)
			(xy 121.406129 -250.703387) (xy 121.405396 -250.712986) (xy 121.40438 -250.743212) (xy 121.40446 -250.752121)
			(xy 121.410067 -250.769021) (xy 121.415302 -250.776232) (xy 121.430515 -250.796527) (xy 121.454703 -250.841105)
			(xy 121.471204 -250.889063) (xy 121.479565 -250.939087) (xy 121.480072 -250.964446) (xy 121.479598 -250.988434)
			(xy 121.472086 -251.035818) (xy 121.457254 -251.081443) (xy 121.435467 -251.124187) (xy 121.407263 -251.162996)
			(xy 121.373334 -251.196916) (xy 121.334517 -251.22511) (xy 121.291768 -251.246885) (xy 121.246138 -251.261705)
			(xy 121.198752 -251.269204) (xy 121.174764 -251.269754) (xy 121.16316 -251.269638) (xy 121.140021 -251.267861)
			(xy 121.128536 -251.266198) (xy 121.124726 -251.26569) (xy 121.123964 -251.26569) (xy 121.099097 -251.260941)
			(xy 121.051263 -251.244377) (xy 121.006804 -251.220172) (xy 120.98655 -251.204984) (xy 120.979334 -251.199785)
			(xy 120.962423 -251.194315) (xy 120.95353 -251.194316) (xy 120.923304 -251.195078) (xy 120.913708 -251.195828)
			(xy 120.896084 -251.203532) (xy 120.889014 -251.210064) (xy 120.775476 -251.323602) (xy 120.771264 -251.32807)
			(xy 120.764957 -251.338601) (xy 120.76303 -251.34443) (xy 120.761256 -251.350754) (xy 120.760618 -251.363869)
			(xy 120.76176 -251.370338) (xy 120.782334 -251.464318) (xy 120.799352 -251.483876) (xy 120.811544 -251.488448)
			(xy 120.836146 -251.498244) (xy 120.881806 -251.525053) (xy 120.922158 -251.559336) (xy 120.955992 -251.600065)
			(xy 120.982295 -251.646019) (xy 121.000277 -251.695821) (xy 121.0094 -251.747977) (xy 121.009918 -251.774452)
			(xy 122.278914 -251.774452) (xy 122.282874 -251.725398) (xy 122.294651 -251.677614) (xy 122.313942 -251.632338)
			(xy 122.340245 -251.590742) (xy 122.37288 -251.553905) (xy 122.411001 -251.52278) (xy 122.453622 -251.498173)
			(xy 122.499638 -251.480721) (xy 122.547857 -251.470877) (xy 122.597032 -251.468896) (xy 122.645887 -251.474828)
			(xy 122.693158 -251.48852) (xy 122.73762 -251.509618) (xy 122.778123 -251.537574) (xy 122.813616 -251.571666)
			(xy 122.843181 -251.61101) (xy 122.866052 -251.654587) (xy 122.881636 -251.701268) (xy 122.889531 -251.749845)
			(xy 122.890026 -251.774452) (xy 122.889531 -251.799059) (xy 122.881636 -251.847636) (xy 122.866052 -251.894317)
			(xy 122.843181 -251.937894) (xy 122.813616 -251.977238) (xy 122.778123 -252.01133) (xy 122.73762 -252.039286)
			(xy 122.693158 -252.060384) (xy 122.645887 -252.074076) (xy 122.597032 -252.080008) (xy 122.547857 -252.078027)
			(xy 122.499638 -252.068183) (xy 122.453622 -252.050731) (xy 122.411001 -252.026124) (xy 122.37288 -251.994999)
			(xy 122.340245 -251.958162) (xy 122.313942 -251.916566) (xy 122.294651 -251.87129) (xy 122.282874 -251.823506)
			(xy 122.278914 -251.774452) (xy 121.009918 -251.774452) (xy 121.009396 -251.799707) (xy 121.001083 -251.849529)
			(xy 120.984682 -251.897303) (xy 120.960641 -251.941726) (xy 120.929617 -251.981586) (xy 120.892455 -252.015796)
			(xy 120.850169 -252.043422) (xy 120.803913 -252.063712) (xy 120.754948 -252.076112) (xy 120.70461 -252.080283)
			(xy 120.654272 -252.076112) (xy 120.605307 -252.063712) (xy 120.559051 -252.043422) (xy 120.516765 -252.015796)
			(xy 120.479603 -251.981586) (xy 120.448579 -251.941726) (xy 120.424538 -251.897303) (xy 120.408137 -251.849529)
			(xy 120.399824 -251.799707) (xy 120.399302 -251.774452) (xy 120.39985 -251.748229) (xy 120.40882 -251.696556)
			(xy 120.426488 -251.647176) (xy 120.438926 -251.624084) (xy 120.442228 -251.618242) (xy 120.44553 -251.605796)
			(xy 120.44553 -251.598938) (xy 120.445359 -251.592207) (xy 120.441882 -251.579203) (xy 120.438672 -251.573284)
			(xy 120.395492 -251.49937) (xy 120.393206 -251.495814) (xy 120.386135 -251.486807) (xy 120.36622 -251.47557)
			(xy 120.354852 -251.474224) (xy 119.685308 -251.474224) (xy 119.675472 -251.473685) (xy 119.657314 -251.466095)
			(xy 119.650002 -251.459492) (xy 119.442738 -251.252228) (xy 119.414036 -251.245878) (xy 119.399812 -251.250958)
			(xy 119.374406 -251.259704) (xy 119.321519 -251.269162) (xy 119.294656 -251.269754) (xy 119.290592 -251.269754)
			(xy 119.267013 -251.268998) (xy 119.220503 -251.261117) (xy 119.175757 -251.246178) (xy 119.133841 -251.224536)
			(xy 119.095752 -251.196706) (xy 119.062395 -251.16335) (xy 119.034565 -251.12526) (xy 119.012922 -251.083344)
			(xy 118.997983 -251.038599) (xy 118.990102 -250.992089) (xy 118.989348 -250.96851) (xy 118.989348 -250.966478)
			(xy 118.989348 -250.964446) (xy 118.98993 -250.937582) (xy 118.999377 -250.88469) (xy 119.008144 -250.85929)
			(xy 119.013224 -250.845066) (xy 119.006874 -250.816364) (xy 118.80469 -250.61418) (xy 118.797578 -250.606814)
			(xy 118.778782 -250.599194) (xy 117.827298 -250.599194) (xy 117.817463 -250.599736) (xy 117.79931 -250.60733)
			(xy 117.791992 -250.613926) (xy 117.662198 -250.74372) (xy 117.658642 -250.779788) (xy 117.668802 -250.795028)
			(xy 117.680935 -250.813934) (xy 117.700117 -250.854554) (xy 117.713137 -250.897548) (xy 117.719715 -250.941985)
			(xy 117.72011 -250.964446) (xy 117.72011 -250.97105) (xy 117.719153 -250.99474) (xy 117.710821 -251.041412)
			(xy 117.695373 -251.086234) (xy 117.673182 -251.12813) (xy 117.644781 -251.166092) (xy 117.610853 -251.199206)
			(xy 117.572213 -251.226678) (xy 117.529791 -251.247845) (xy 117.484606 -251.2622) (xy 117.437746 -251.269398)
			(xy 117.41404 -251.269754) (xy 117.408198 -251.269754) (xy 117.386574 -251.268913) (xy 117.343876 -251.261876)
			(xy 117.302604 -251.248867) (xy 117.263588 -251.230148) (xy 117.245384 -251.218446) (xy 117.235298 -251.212427)
			(xy 117.212035 -251.209372) (xy 117.189813 -251.216898) (xy 117.181122 -251.224796) (xy 117.061742 -251.344176)
			(xy 117.053799 -251.353082) (xy 117.04638 -251.375731) (xy 117.047518 -251.38761) (xy 117.061488 -251.478796)
			(xy 117.075458 -251.498354) (xy 117.08638 -251.503942) (xy 117.107195 -251.515377) (xy 117.145324 -251.543687)
			(xy 117.178616 -251.577553) (xy 117.206271 -251.616161) (xy 117.227622 -251.658581) (xy 117.242155 -251.703792)
			(xy 117.249522 -251.750707) (xy 117.249956 -251.774452) (xy 118.518952 -251.774452) (xy 118.522912 -251.725398)
			(xy 118.534689 -251.677614) (xy 118.55398 -251.632338) (xy 118.580283 -251.590742) (xy 118.612918 -251.553905)
			(xy 118.651039 -251.52278) (xy 118.69366 -251.498173) (xy 118.739676 -251.480721) (xy 118.787895 -251.470877)
			(xy 118.83707 -251.468896) (xy 118.885925 -251.474828) (xy 118.933196 -251.48852) (xy 118.977658 -251.509618)
			(xy 119.018161 -251.537574) (xy 119.053654 -251.571666) (xy 119.083219 -251.61101) (xy 119.10609 -251.654587)
			(xy 119.121674 -251.701268) (xy 119.129569 -251.749845) (xy 119.130064 -251.774452) (xy 119.129569 -251.799059)
			(xy 119.121674 -251.847636) (xy 119.10609 -251.894317) (xy 119.083219 -251.937894) (xy 119.053654 -251.977238)
			(xy 119.018161 -252.01133) (xy 118.977658 -252.039286) (xy 118.933196 -252.060384) (xy 118.885925 -252.074076)
			(xy 118.83707 -252.080008) (xy 118.787895 -252.078027) (xy 118.739676 -252.068183) (xy 118.69366 -252.050731)
			(xy 118.651039 -252.026124) (xy 118.612918 -251.994999) (xy 118.580283 -251.958162) (xy 118.55398 -251.916566)
			(xy 118.534689 -251.87129) (xy 118.522912 -251.823506) (xy 118.518952 -251.774452) (xy 117.249956 -251.774452)
			(xy 117.249434 -251.799707) (xy 117.241121 -251.849529) (xy 117.22472 -251.897303) (xy 117.200679 -251.941726)
			(xy 117.169655 -251.981586) (xy 117.132493 -252.015796) (xy 117.090207 -252.043422) (xy 117.043951 -252.063712)
			(xy 116.994986 -252.076112) (xy 116.944648 -252.080283) (xy 116.89431 -252.076112) (xy 116.845345 -252.063712)
			(xy 116.799089 -252.043422) (xy 116.756803 -252.015796) (xy 116.719641 -251.981586) (xy 116.688617 -251.941726)
			(xy 116.664576 -251.897303) (xy 116.648175 -251.849529) (xy 116.639862 -251.799707) (xy 116.63934 -251.774452)
			(xy 116.639888 -251.748229) (xy 116.648859 -251.696557) (xy 116.666529 -251.647178) (xy 116.678964 -251.624084)
			(xy 116.682266 -251.618242) (xy 116.685568 -251.605796) (xy 116.685568 -251.598938) (xy 116.685398 -251.592206)
			(xy 116.681923 -251.579202) (xy 116.67871 -251.573284) (xy 116.63553 -251.49937) (xy 116.633244 -251.495814)
			(xy 116.626169 -251.486817) (xy 116.606252 -251.475604) (xy 116.59489 -251.474224) (xy 116.197888 -251.474224)
			(xy 116.188045 -251.473699) (xy 116.169867 -251.46613) (xy 116.162582 -251.459492) (xy 115.888008 -251.184918)
			(xy 115.885005 -251.182035) (xy 115.87824 -251.177185) (xy 115.874546 -251.175266) (xy 115.869279 -251.17283)
			(xy 115.857993 -251.170142) (xy 115.852194 -251.169932) (xy 115.782852 -251.169424) (xy 115.772996 -251.169825)
			(xy 115.754691 -251.177127) (xy 115.747292 -251.183648) (xy 115.747038 -251.183902) (xy 115.729846 -251.199913)
			(xy 115.691462 -251.226997) (xy 115.649385 -251.24789) (xy 115.604608 -251.262097) (xy 115.558183 -251.269285)
			(xy 115.534694 -251.269754) (xy 115.510702 -251.269283) (xy 115.463308 -251.261776) (xy 115.417672 -251.246949)
			(xy 115.374917 -251.225166) (xy 115.336095 -251.196963) (xy 115.302163 -251.163035) (xy 115.273955 -251.124217)
			(xy 115.252166 -251.081465) (xy 115.237333 -251.035831) (xy 115.22982 -250.988438) (xy 115.229386 -250.964446)
			(xy 115.229851 -250.939545) (xy 115.237883 -250.890395) (xy 115.25379 -250.843203) (xy 115.277151 -250.79922)
			(xy 115.307344 -250.759615) (xy 115.325144 -250.742196) (xy 115.332256 -250.735846) (xy 115.344194 -250.710954)
			(xy 115.346222 -250.706437) (xy 115.348657 -250.696842) (xy 115.34902 -250.691904) (xy 115.35029 -250.671584)
			(xy 115.350506 -250.660742) (xy 115.342881 -250.640464) (xy 115.335558 -250.632468) (xy 115.31727 -250.61418)
			(xy 115.310158 -250.606814) (xy 115.291362 -250.599194) (xy 113.961926 -250.599194) (xy 113.95221 -250.59962)
			(xy 113.93417 -250.606837) (xy 113.920107 -250.620245) (xy 113.915698 -250.628912) (xy 113.87201 -250.724416)
			(xy 113.876074 -250.753626) (xy 113.88598 -250.765056) (xy 113.903299 -250.786016) (xy 113.930983 -250.832804)
			(xy 113.949938 -250.883757) (xy 113.959564 -250.937263) (xy 113.960148 -250.964446) (xy 113.959626 -250.989701)
			(xy 113.951313 -251.039523) (xy 113.934912 -251.087297) (xy 113.910871 -251.13172) (xy 113.879847 -251.17158)
			(xy 113.842685 -251.20579) (xy 113.800399 -251.233416) (xy 113.754143 -251.253706) (xy 113.705178 -251.266106)
			(xy 113.65484 -251.270277) (xy 113.604502 -251.266106) (xy 113.555537 -251.253706) (xy 113.509281 -251.233416)
			(xy 113.466995 -251.20579) (xy 113.429833 -251.17158) (xy 113.398809 -251.13172) (xy 113.374768 -251.087297)
			(xy 113.358367 -251.039523) (xy 113.350054 -250.989701) (xy 113.349532 -250.964446) (xy 113.350131 -250.937266)
			(xy 113.359766 -250.883765) (xy 113.378722 -250.832817) (xy 113.406401 -250.78603) (xy 113.4237 -250.765056)
			(xy 113.433606 -250.753626) (xy 113.43767 -250.724416) (xy 113.393982 -250.628912) (xy 113.387632 -250.615196)
			(xy 113.362994 -250.599194) (xy 111.91875 -250.599194) (xy 111.910876 -250.601988) (xy 111.88404 -250.610439)
			(xy 111.828516 -250.619497) (xy 111.800386 -250.620022) (xy 111.772253 -250.619525) (xy 111.716725 -250.610466)
			(xy 111.689896 -250.601988) (xy 111.682022 -250.599194) (xy 109.438948 -250.599194) (xy 109.429109 -250.599727)
			(xy 109.410943 -250.607308) (xy 109.403642 -250.613926) (xy 109.233716 -250.783852) (xy 109.228382 -250.815856)
			(xy 109.235494 -250.830588) (xy 109.245262 -250.851536) (xy 109.259062 -250.895647) (xy 109.266039 -250.941336)
			(xy 109.266482 -250.964446) (xy 109.266008 -250.988434) (xy 109.258496 -251.035819) (xy 109.243664 -251.081445)
			(xy 109.221878 -251.124189) (xy 109.193673 -251.163) (xy 109.159745 -251.19692) (xy 109.120928 -251.225115)
			(xy 109.078178 -251.246892) (xy 109.032549 -251.261713) (xy 108.985162 -251.269214) (xy 108.961174 -251.269754)
			(xy 108.938066 -251.269308) (xy 108.892381 -251.26231) (xy 108.848268 -251.248522) (xy 108.827316 -251.238766)
			(xy 108.812584 -251.231654) (xy 108.78058 -251.236988) (xy 108.661708 -251.35586) (xy 108.654469 -251.362571)
			(xy 108.636264 -251.370165) (xy 108.626402 -251.370592) (xy 107.819698 -251.370592) (xy 107.809385 -251.371056)
			(xy 107.79042 -251.379161) (xy 107.776194 -251.394095) (xy 107.773479 -251.400564) (xy 111.932723 -251.400564)
			(xy 111.936753 -251.348066) (xy 111.94875 -251.296798) (xy 111.968433 -251.247963) (xy 111.995339 -251.202704)
			(xy 112.028839 -251.162083) (xy 112.068147 -251.127052) (xy 112.112342 -251.098432) (xy 112.160387 -251.076893)
			(xy 112.211158 -251.062941) (xy 112.263463 -251.056903) (xy 112.316077 -251.05892) (xy 112.367767 -251.068944)
			(xy 112.41732 -251.086742) (xy 112.463576 -251.111895) (xy 112.50545 -251.143814) (xy 112.541962 -251.181752)
			(xy 112.572254 -251.224818) (xy 112.595617 -251.272003) (xy 112.611503 -251.322202) (xy 112.61954 -251.374238)
			(xy 112.620044 -251.400564) (xy 112.61954 -251.42689) (xy 112.611503 -251.478926) (xy 112.595617 -251.529125)
			(xy 112.572254 -251.57631) (xy 112.541962 -251.619376) (xy 112.50545 -251.657314) (xy 112.463576 -251.689233)
			(xy 112.41732 -251.714386) (xy 112.367767 -251.732184) (xy 112.316077 -251.742208) (xy 112.263463 -251.744225)
			(xy 112.211158 -251.738187) (xy 112.160387 -251.724235) (xy 112.112342 -251.702696) (xy 112.068147 -251.674076)
			(xy 112.028839 -251.639045) (xy 111.995339 -251.598424) (xy 111.968433 -251.553165) (xy 111.94875 -251.50433)
			(xy 111.936753 -251.453062) (xy 111.932723 -251.400564) (xy 107.773479 -251.400564) (xy 107.7722 -251.403612)
			(xy 107.739688 -251.489972) (xy 107.736479 -251.499714) (xy 107.737277 -251.52019) (xy 107.74604 -251.538714)
			(xy 107.753404 -251.545852) (xy 107.7724 -251.563391) (xy 107.804783 -251.60369) (xy 107.82991 -251.648871)
			(xy 107.847063 -251.69764) (xy 107.855751 -251.748603) (xy 107.856274 -251.774452) (xy 109.12527 -251.774452)
			(xy 109.12923 -251.725398) (xy 109.141007 -251.677614) (xy 109.160298 -251.632338) (xy 109.186601 -251.590742)
			(xy 109.219236 -251.553905) (xy 109.257357 -251.52278) (xy 109.299978 -251.498173) (xy 109.345994 -251.480721)
			(xy 109.394213 -251.470877) (xy 109.443388 -251.468896) (xy 109.492243 -251.474828) (xy 109.539514 -251.48852)
			(xy 109.583976 -251.509618) (xy 109.624479 -251.537574) (xy 109.659972 -251.571666) (xy 109.689537 -251.61101)
			(xy 109.712408 -251.654587) (xy 109.727992 -251.701268) (xy 109.735887 -251.749845) (xy 109.736382 -251.774452)
			(xy 112.878882 -251.774452) (xy 112.882842 -251.725398) (xy 112.894619 -251.677614) (xy 112.91391 -251.632338)
			(xy 112.940213 -251.590742) (xy 112.972848 -251.553905) (xy 113.010969 -251.52278) (xy 113.05359 -251.498173)
			(xy 113.099606 -251.480721) (xy 113.147825 -251.470877) (xy 113.197 -251.468896) (xy 113.245855 -251.474828)
			(xy 113.293126 -251.48852) (xy 113.337588 -251.509618) (xy 113.378091 -251.537574) (xy 113.413584 -251.571666)
			(xy 113.443149 -251.61101) (xy 113.46602 -251.654587) (xy 113.481604 -251.701268) (xy 113.489499 -251.749845)
			(xy 113.489994 -251.774452) (xy 114.75899 -251.774452) (xy 114.76295 -251.725398) (xy 114.774727 -251.677614)
			(xy 114.794018 -251.632338) (xy 114.820321 -251.590742) (xy 114.852956 -251.553905) (xy 114.891077 -251.52278)
			(xy 114.933698 -251.498173) (xy 114.979714 -251.480721) (xy 115.027933 -251.470877) (xy 115.077108 -251.468896)
			(xy 115.125963 -251.474828) (xy 115.173234 -251.48852) (xy 115.217696 -251.509618) (xy 115.258199 -251.537574)
			(xy 115.293692 -251.571666) (xy 115.323257 -251.61101) (xy 115.346128 -251.654587) (xy 115.361712 -251.701268)
			(xy 115.369607 -251.749845) (xy 115.370102 -251.774452) (xy 115.369607 -251.799059) (xy 115.361712 -251.847636)
			(xy 115.346128 -251.894317) (xy 115.323257 -251.937894) (xy 115.293692 -251.977238) (xy 115.258199 -252.01133)
			(xy 115.217696 -252.039286) (xy 115.173234 -252.060384) (xy 115.125963 -252.074076) (xy 115.077108 -252.080008)
			(xy 115.027933 -252.078027) (xy 114.979714 -252.068183) (xy 114.933698 -252.050731) (xy 114.891077 -252.026124)
			(xy 114.852956 -251.994999) (xy 114.820321 -251.958162) (xy 114.794018 -251.916566) (xy 114.774727 -251.87129)
			(xy 114.76295 -251.823506) (xy 114.75899 -251.774452) (xy 113.489994 -251.774452) (xy 113.489499 -251.799059)
			(xy 113.481604 -251.847636) (xy 113.46602 -251.894317) (xy 113.443149 -251.937894) (xy 113.413584 -251.977238)
			(xy 113.378091 -252.01133) (xy 113.337588 -252.039286) (xy 113.293126 -252.060384) (xy 113.245855 -252.074076)
			(xy 113.197 -252.080008) (xy 113.147825 -252.078027) (xy 113.099606 -252.068183) (xy 113.05359 -252.050731)
			(xy 113.010969 -252.026124) (xy 112.972848 -251.994999) (xy 112.940213 -251.958162) (xy 112.91391 -251.916566)
			(xy 112.894619 -251.87129) (xy 112.882842 -251.823506) (xy 112.878882 -251.774452) (xy 109.736382 -251.774452)
			(xy 109.735887 -251.799059) (xy 109.727992 -251.847636) (xy 109.712408 -251.894317) (xy 109.689537 -251.937894)
			(xy 109.659972 -251.977238) (xy 109.624479 -252.01133) (xy 109.583976 -252.039286) (xy 109.539514 -252.060384)
			(xy 109.492243 -252.074076) (xy 109.443388 -252.080008) (xy 109.394213 -252.078027) (xy 109.345994 -252.068183)
			(xy 109.299978 -252.050731) (xy 109.257357 -252.026124) (xy 109.219236 -251.994999) (xy 109.186601 -251.958162)
			(xy 109.160298 -251.916566) (xy 109.141007 -251.87129) (xy 109.12923 -251.823506) (xy 109.12527 -251.774452)
			(xy 107.856274 -251.774452) (xy 107.855752 -251.799707) (xy 107.847439 -251.849529) (xy 107.831038 -251.897303)
			(xy 107.806997 -251.941726) (xy 107.775973 -251.981586) (xy 107.738811 -252.015796) (xy 107.696525 -252.043422)
			(xy 107.650269 -252.063712) (xy 107.601304 -252.076112) (xy 107.550966 -252.080283) (xy 107.500628 -252.076112)
			(xy 107.451663 -252.063712) (xy 107.405407 -252.043422) (xy 107.363121 -252.015796) (xy 107.325959 -251.981586)
			(xy 107.294935 -251.941726) (xy 107.270894 -251.897303) (xy 107.254493 -251.849529) (xy 107.24618 -251.799707)
			(xy 107.245658 -251.774452) (xy 107.245797 -251.761689) (xy 107.24796 -251.736255) (xy 107.249976 -251.723652)
			(xy 107.249722 -251.723652) (xy 107.254596 -251.698171) (xy 107.271773 -251.649223) (xy 107.296968 -251.603879)
			(xy 107.329457 -251.563439) (xy 107.348528 -251.545852) (xy 107.355853 -251.538687) (xy 107.364591 -251.520171)
			(xy 107.36542 -251.499714) (xy 107.362244 -251.489972) (xy 107.329732 -251.403612) (xy 107.325675 -251.394128)
			(xy 107.311461 -251.379206) (xy 107.292536 -251.371045) (xy 107.282234 -251.370592) (xy 105.939844 -251.370592)
			(xy 105.929537 -251.371066) (xy 105.91059 -251.379182) (xy 105.896381 -251.394116) (xy 105.892346 -251.403612)
			(xy 105.859834 -251.489972) (xy 105.856623 -251.499713) (xy 105.857421 -251.520189) (xy 105.866191 -251.538708)
			(xy 105.87355 -251.545852) (xy 105.892543 -251.563393) (xy 105.924921 -251.603693) (xy 105.950045 -251.648874)
			(xy 105.967195 -251.697643) (xy 105.975882 -251.748604) (xy 105.97642 -251.774452) (xy 105.975898 -251.799707)
			(xy 105.967585 -251.849529) (xy 105.951184 -251.897303) (xy 105.927143 -251.941726) (xy 105.896119 -251.981586)
			(xy 105.858957 -252.015796) (xy 105.816671 -252.043422) (xy 105.770415 -252.063712) (xy 105.72145 -252.076112)
			(xy 105.671112 -252.080283) (xy 105.620774 -252.076112) (xy 105.571809 -252.063712) (xy 105.525553 -252.043422)
			(xy 105.483267 -252.015796) (xy 105.446105 -251.981586) (xy 105.415081 -251.941726) (xy 105.39104 -251.897303)
			(xy 105.374639 -251.849529) (xy 105.366326 -251.799707) (xy 105.365804 -251.774452) (xy 105.365943 -251.761689)
			(xy 105.368106 -251.736255) (xy 105.370122 -251.723652) (xy 105.369868 -251.723652) (xy 105.374742 -251.698172)
			(xy 105.391921 -251.649226) (xy 105.417119 -251.603884) (xy 105.449611 -251.563448) (xy 105.468674 -251.545852)
			(xy 105.475994 -251.538684) (xy 105.484723 -251.52017) (xy 105.485552 -251.499717) (xy 105.48239 -251.489972)
			(xy 105.449878 -251.403612) (xy 105.445818 -251.394134) (xy 105.431601 -251.379227) (xy 105.412678 -251.371085)
			(xy 105.40238 -251.370592) (xy 104.059736 -251.370592) (xy 104.04943 -251.371068) (xy 104.030485 -251.379186)
			(xy 104.016279 -251.394119) (xy 104.012238 -251.403612) (xy 103.979726 -251.489972) (xy 103.976516 -251.499713)
			(xy 103.977313 -251.520189) (xy 103.986082 -251.538709) (xy 103.993442 -251.545852) (xy 104.012436 -251.563393)
			(xy 104.044815 -251.603693) (xy 104.069939 -251.648874) (xy 104.08709 -251.697642) (xy 104.095776 -251.748604)
			(xy 104.096312 -251.774452) (xy 104.09579 -251.799707) (xy 104.087477 -251.849529) (xy 104.071076 -251.897303)
			(xy 104.047035 -251.941726) (xy 104.016011 -251.981586) (xy 103.978849 -252.015796) (xy 103.936563 -252.043422)
			(xy 103.890307 -252.063712) (xy 103.841342 -252.076112) (xy 103.791004 -252.080283) (xy 103.740666 -252.076112)
			(xy 103.691701 -252.063712) (xy 103.645445 -252.043422) (xy 103.603159 -252.015796) (xy 103.565997 -251.981586)
			(xy 103.534973 -251.941726) (xy 103.510932 -251.897303) (xy 103.494531 -251.849529) (xy 103.486218 -251.799707)
			(xy 103.485696 -251.774452) (xy 103.485835 -251.761689) (xy 103.487998 -251.736255) (xy 103.490014 -251.723652)
			(xy 103.48976 -251.723652) (xy 103.494634 -251.698172) (xy 103.511813 -251.649225) (xy 103.53701 -251.603883)
			(xy 103.569502 -251.563447) (xy 103.588566 -251.545852) (xy 103.595887 -251.538685) (xy 103.604618 -251.52017)
			(xy 103.605446 -251.499717) (xy 103.602282 -251.489972) (xy 103.56977 -251.403612) (xy 103.56571 -251.394135)
			(xy 103.551492 -251.37923) (xy 103.53257 -251.371092) (xy 103.522272 -251.370592) (xy 102.179628 -251.370592)
			(xy 102.169791 -251.371128) (xy 102.151629 -251.378714) (xy 102.144322 -251.385324) (xy 102.119938 -251.409708)
			(xy 102.118922 -251.410724) (xy 102.112439 -251.418208) (xy 102.105258 -251.43664) (xy 102.104952 -251.446538)
			(xy 102.106222 -251.527818) (xy 102.11435 -251.54636) (xy 102.121716 -251.553472) (xy 102.140757 -251.572392)
			(xy 102.172548 -251.615638) (xy 102.196296 -251.663772) (xy 102.211269 -251.715315) (xy 102.21468 -251.74194)
			(xy 102.215696 -251.75083) (xy 102.223062 -251.766324) (xy 102.352602 -251.895864) (xy 102.353364 -251.896626)
			(xy 102.355396 -251.898404) (xy 102.35565 -251.898658) (xy 102.357428 -251.900436) (xy 102.494334 -252.037342)
			(xy 102.495604 -252.038612) (xy 102.496112 -252.03912) (xy 102.497128 -252.04039) (xy 102.531926 -252.077474)
			(xy 102.533196 -252.076204) (xy 102.873556 -252.416564) (xy 111.913673 -252.416564) (xy 111.917703 -252.364066)
			(xy 111.9297 -252.312798) (xy 111.949383 -252.263963) (xy 111.976289 -252.218704) (xy 112.009789 -252.178083)
			(xy 112.049097 -252.143052) (xy 112.093292 -252.114432) (xy 112.141337 -252.092893) (xy 112.192108 -252.078941)
			(xy 112.244413 -252.072903) (xy 112.297027 -252.07492) (xy 112.348717 -252.084944) (xy 112.39827 -252.102742)
			(xy 112.444526 -252.127895) (xy 112.4864 -252.159814) (xy 112.522912 -252.197752) (xy 112.553204 -252.240818)
			(xy 112.576567 -252.288003) (xy 112.592453 -252.338202) (xy 112.60049 -252.390238) (xy 112.600994 -252.416564)
			(xy 112.60049 -252.44289) (xy 112.592453 -252.494926) (xy 112.576567 -252.545125) (xy 112.557092 -252.584458)
			(xy 120.86896 -252.584458) (xy 120.87292 -252.535404) (xy 120.884697 -252.48762) (xy 120.903988 -252.442344)
			(xy 120.930291 -252.400748) (xy 120.962926 -252.363911) (xy 121.001047 -252.332786) (xy 121.043668 -252.308179)
			(xy 121.089684 -252.290727) (xy 121.137903 -252.280883) (xy 121.187078 -252.278902) (xy 121.235933 -252.284834)
			(xy 121.283204 -252.298526) (xy 121.327666 -252.319624) (xy 121.368169 -252.34758) (xy 121.403662 -252.381672)
			(xy 121.433227 -252.421016) (xy 121.456098 -252.464593) (xy 121.471682 -252.511274) (xy 121.479577 -252.559851)
			(xy 121.480072 -252.584458) (xy 122.748814 -252.584458) (xy 122.752774 -252.535404) (xy 122.764551 -252.48762)
			(xy 122.783842 -252.442344) (xy 122.810145 -252.400748) (xy 122.84278 -252.363911) (xy 122.880901 -252.332786)
			(xy 122.923522 -252.308179) (xy 122.969538 -252.290727) (xy 123.017757 -252.280883) (xy 123.066932 -252.278902)
			(xy 123.115787 -252.284834) (xy 123.163058 -252.298526) (xy 123.20752 -252.319624) (xy 123.248023 -252.34758)
			(xy 123.283516 -252.381672) (xy 123.313081 -252.421016) (xy 123.335952 -252.464593) (xy 123.351536 -252.511274)
			(xy 123.359431 -252.559851) (xy 123.359926 -252.584458) (xy 124.628922 -252.584458) (xy 124.632882 -252.535404)
			(xy 124.644659 -252.48762) (xy 124.66395 -252.442344) (xy 124.690253 -252.400748) (xy 124.722888 -252.363911)
			(xy 124.761009 -252.332786) (xy 124.80363 -252.308179) (xy 124.849646 -252.290727) (xy 124.897865 -252.280883)
			(xy 124.94704 -252.278902) (xy 124.995895 -252.284834) (xy 125.043166 -252.298526) (xy 125.087628 -252.319624)
			(xy 125.128131 -252.34758) (xy 125.163624 -252.381672) (xy 125.193189 -252.421016) (xy 125.21606 -252.464593)
			(xy 125.231644 -252.511274) (xy 125.239539 -252.559851) (xy 125.240034 -252.584458) (xy 126.50903 -252.584458)
			(xy 126.51299 -252.535404) (xy 126.524767 -252.48762) (xy 126.544058 -252.442344) (xy 126.570361 -252.400748)
			(xy 126.602996 -252.363911) (xy 126.641117 -252.332786) (xy 126.683738 -252.308179) (xy 126.729754 -252.290727)
			(xy 126.777973 -252.280883) (xy 126.827148 -252.278902) (xy 126.876003 -252.284834) (xy 126.923274 -252.298526)
			(xy 126.967736 -252.319624) (xy 127.008239 -252.34758) (xy 127.043732 -252.381672) (xy 127.073297 -252.421016)
			(xy 127.096168 -252.464593) (xy 127.111752 -252.511274) (xy 127.119647 -252.559851) (xy 127.120142 -252.584458)
			(xy 127.44883 -252.584458) (xy 127.45279 -252.535404) (xy 127.464567 -252.48762) (xy 127.483858 -252.442344)
			(xy 127.510161 -252.400748) (xy 127.542796 -252.363911) (xy 127.580917 -252.332786) (xy 127.623538 -252.308179)
			(xy 127.669554 -252.290727) (xy 127.717773 -252.280883) (xy 127.766948 -252.278902) (xy 127.815803 -252.284834)
			(xy 127.863074 -252.298526) (xy 127.907536 -252.319624) (xy 127.948039 -252.34758) (xy 127.983532 -252.381672)
			(xy 128.013097 -252.421016) (xy 128.035968 -252.464593) (xy 128.051552 -252.511274) (xy 128.059447 -252.559851)
			(xy 128.059942 -252.584458) (xy 128.388884 -252.584458) (xy 128.392844 -252.535404) (xy 128.404621 -252.48762)
			(xy 128.423912 -252.442344) (xy 128.450215 -252.400748) (xy 128.48285 -252.363911) (xy 128.520971 -252.332786)
			(xy 128.563592 -252.308179) (xy 128.609608 -252.290727) (xy 128.657827 -252.280883) (xy 128.707002 -252.278902)
			(xy 128.755857 -252.284834) (xy 128.803128 -252.298526) (xy 128.84759 -252.319624) (xy 128.888093 -252.34758)
			(xy 128.923586 -252.381672) (xy 128.953151 -252.421016) (xy 128.976022 -252.464593) (xy 128.991606 -252.511274)
			(xy 128.999501 -252.559851) (xy 128.999996 -252.584458) (xy 129.318507 -252.584458) (xy 129.322602 -252.53373)
			(xy 129.334781 -252.484316) (xy 129.354729 -252.437496) (xy 129.38193 -252.394482) (xy 129.415678 -252.356388)
			(xy 129.4551 -252.324201) (xy 129.499174 -252.298755) (xy 129.54676 -252.280708) (xy 129.596624 -252.270528)
			(xy 129.647476 -252.268479) (xy 129.697997 -252.274613) (xy 129.746881 -252.288773) (xy 129.79286 -252.31059)
			(xy 129.834744 -252.3395) (xy 129.871448 -252.374755) (xy 129.902021 -252.415441) (xy 129.925672 -252.460504)
			(xy 129.941788 -252.508778) (xy 129.949952 -252.559012) (xy 129.950464 -252.584458) (xy 129.949952 -252.609904)
			(xy 129.941788 -252.660138) (xy 129.925672 -252.708412) (xy 129.902021 -252.753475) (xy 129.871448 -252.794161)
			(xy 129.834744 -252.829416) (xy 129.79286 -252.858326) (xy 129.746881 -252.880143) (xy 129.697997 -252.894303)
			(xy 129.647476 -252.900437) (xy 129.596624 -252.898388) (xy 129.54676 -252.888208) (xy 129.499174 -252.870161)
			(xy 129.4551 -252.844715) (xy 129.415678 -252.812528) (xy 129.38193 -252.774434) (xy 129.354729 -252.73142)
			(xy 129.334781 -252.6846) (xy 129.322602 -252.635186) (xy 129.318507 -252.584458) (xy 128.999996 -252.584458)
			(xy 128.999501 -252.609065) (xy 128.991606 -252.657642) (xy 128.976022 -252.704323) (xy 128.953151 -252.7479)
			(xy 128.923586 -252.787244) (xy 128.888093 -252.821336) (xy 128.84759 -252.849292) (xy 128.803128 -252.87039)
			(xy 128.755857 -252.884082) (xy 128.707002 -252.890014) (xy 128.657827 -252.888033) (xy 128.609608 -252.878189)
			(xy 128.563592 -252.860737) (xy 128.520971 -252.83613) (xy 128.48285 -252.805005) (xy 128.450215 -252.768168)
			(xy 128.423912 -252.726572) (xy 128.404621 -252.681296) (xy 128.392844 -252.633512) (xy 128.388884 -252.584458)
			(xy 128.059942 -252.584458) (xy 128.059447 -252.609065) (xy 128.051552 -252.657642) (xy 128.035968 -252.704323)
			(xy 128.013097 -252.7479) (xy 127.983532 -252.787244) (xy 127.948039 -252.821336) (xy 127.907536 -252.849292)
			(xy 127.863074 -252.87039) (xy 127.815803 -252.884082) (xy 127.766948 -252.890014) (xy 127.717773 -252.888033)
			(xy 127.669554 -252.878189) (xy 127.623538 -252.860737) (xy 127.580917 -252.83613) (xy 127.542796 -252.805005)
			(xy 127.510161 -252.768168) (xy 127.483858 -252.726572) (xy 127.464567 -252.681296) (xy 127.45279 -252.633512)
			(xy 127.44883 -252.584458) (xy 127.120142 -252.584458) (xy 127.119647 -252.609065) (xy 127.111752 -252.657642)
			(xy 127.096168 -252.704323) (xy 127.073297 -252.7479) (xy 127.043732 -252.787244) (xy 127.008239 -252.821336)
			(xy 126.967736 -252.849292) (xy 126.923274 -252.87039) (xy 126.876003 -252.884082) (xy 126.827148 -252.890014)
			(xy 126.777973 -252.888033) (xy 126.729754 -252.878189) (xy 126.683738 -252.860737) (xy 126.641117 -252.83613)
			(xy 126.602996 -252.805005) (xy 126.570361 -252.768168) (xy 126.544058 -252.726572) (xy 126.524767 -252.681296)
			(xy 126.51299 -252.633512) (xy 126.50903 -252.584458) (xy 125.240034 -252.584458) (xy 125.239539 -252.609065)
			(xy 125.231644 -252.657642) (xy 125.21606 -252.704323) (xy 125.193189 -252.7479) (xy 125.163624 -252.787244)
			(xy 125.128131 -252.821336) (xy 125.087628 -252.849292) (xy 125.043166 -252.87039) (xy 124.995895 -252.884082)
			(xy 124.94704 -252.890014) (xy 124.897865 -252.888033) (xy 124.849646 -252.878189) (xy 124.80363 -252.860737)
			(xy 124.761009 -252.83613) (xy 124.722888 -252.805005) (xy 124.690253 -252.768168) (xy 124.66395 -252.726572)
			(xy 124.644659 -252.681296) (xy 124.632882 -252.633512) (xy 124.628922 -252.584458) (xy 123.359926 -252.584458)
			(xy 123.359431 -252.609065) (xy 123.351536 -252.657642) (xy 123.335952 -252.704323) (xy 123.313081 -252.7479)
			(xy 123.283516 -252.787244) (xy 123.248023 -252.821336) (xy 123.20752 -252.849292) (xy 123.163058 -252.87039)
			(xy 123.115787 -252.884082) (xy 123.066932 -252.890014) (xy 123.017757 -252.888033) (xy 122.969538 -252.878189)
			(xy 122.923522 -252.860737) (xy 122.880901 -252.83613) (xy 122.84278 -252.805005) (xy 122.810145 -252.768168)
			(xy 122.783842 -252.726572) (xy 122.764551 -252.681296) (xy 122.752774 -252.633512) (xy 122.748814 -252.584458)
			(xy 121.480072 -252.584458) (xy 121.479577 -252.609065) (xy 121.471682 -252.657642) (xy 121.456098 -252.704323)
			(xy 121.433227 -252.7479) (xy 121.403662 -252.787244) (xy 121.368169 -252.821336) (xy 121.327666 -252.849292)
			(xy 121.283204 -252.87039) (xy 121.235933 -252.884082) (xy 121.187078 -252.890014) (xy 121.137903 -252.888033)
			(xy 121.089684 -252.878189) (xy 121.043668 -252.860737) (xy 121.001047 -252.83613) (xy 120.962926 -252.805005)
			(xy 120.930291 -252.768168) (xy 120.903988 -252.726572) (xy 120.884697 -252.681296) (xy 120.87292 -252.633512)
			(xy 120.86896 -252.584458) (xy 112.557092 -252.584458) (xy 112.553204 -252.59231) (xy 112.522912 -252.635376)
			(xy 112.4864 -252.673314) (xy 112.444526 -252.705233) (xy 112.39827 -252.730386) (xy 112.348717 -252.748184)
			(xy 112.297027 -252.758208) (xy 112.244413 -252.760225) (xy 112.192108 -252.754187) (xy 112.141337 -252.740235)
			(xy 112.093292 -252.718696) (xy 112.049097 -252.690076) (xy 112.009789 -252.655045) (xy 111.976289 -252.614424)
			(xy 111.949383 -252.569165) (xy 111.9297 -252.52033) (xy 111.917703 -252.469062) (xy 111.913673 -252.416564)
			(xy 102.873556 -252.416564) (xy 103.588058 -253.131066) (xy 103.621586 -253.135638) (xy 103.636826 -253.127002)
			(xy 103.659983 -253.114484) (xy 103.709528 -253.096709) (xy 103.761384 -253.087672) (xy 103.787702 -253.087124)
			(xy 103.787956 -253.087124) (xy 103.81195 -253.087567) (xy 103.859349 -253.095068) (xy 103.904991 -253.109893)
			(xy 103.947751 -253.131677) (xy 103.986576 -253.159882) (xy 104.02051 -253.193815) (xy 104.048717 -253.232639)
			(xy 104.070502 -253.275398) (xy 104.085329 -253.321039) (xy 104.092832 -253.368438) (xy 104.093264 -253.392432)
			(xy 105.362006 -253.392432) (xy 105.365966 -253.343378) (xy 105.377743 -253.295594) (xy 105.397034 -253.250318)
			(xy 105.423337 -253.208722) (xy 105.455972 -253.171885) (xy 105.494093 -253.14076) (xy 105.536714 -253.116153)
			(xy 105.58273 -253.098701) (xy 105.630949 -253.088857) (xy 105.680124 -253.086876) (xy 105.728979 -253.092808)
			(xy 105.77625 -253.1065) (xy 105.820712 -253.127598) (xy 105.861215 -253.155554) (xy 105.896708 -253.189646)
			(xy 105.926273 -253.22899) (xy 105.949144 -253.272567) (xy 105.964728 -253.319248) (xy 105.972623 -253.367825)
			(xy 105.973118 -253.392432) (xy 107.242114 -253.392432) (xy 107.246074 -253.343378) (xy 107.257851 -253.295594)
			(xy 107.277142 -253.250318) (xy 107.303445 -253.208722) (xy 107.33608 -253.171885) (xy 107.374201 -253.14076)
			(xy 107.416822 -253.116153) (xy 107.462838 -253.098701) (xy 107.511057 -253.088857) (xy 107.560232 -253.086876)
			(xy 107.609087 -253.092808) (xy 107.656358 -253.1065) (xy 107.70082 -253.127598) (xy 107.741323 -253.155554)
			(xy 107.776816 -253.189646) (xy 107.806381 -253.22899) (xy 107.829252 -253.272567) (xy 107.844836 -253.319248)
			(xy 107.852731 -253.367825) (xy 107.853226 -253.392432) (xy 109.122222 -253.392432) (xy 109.126182 -253.343378)
			(xy 109.137959 -253.295594) (xy 109.15725 -253.250318) (xy 109.183553 -253.208722) (xy 109.216188 -253.171885)
			(xy 109.254309 -253.14076) (xy 109.29693 -253.116153) (xy 109.342946 -253.098701) (xy 109.391165 -253.088857)
			(xy 109.44034 -253.086876) (xy 109.489195 -253.092808) (xy 109.536466 -253.1065) (xy 109.580928 -253.127598)
			(xy 109.621431 -253.155554) (xy 109.656924 -253.189646) (xy 109.686489 -253.22899) (xy 109.70936 -253.272567)
			(xy 109.724944 -253.319248) (xy 109.732839 -253.367825) (xy 109.733334 -253.392432) (xy 109.732839 -253.417039)
			(xy 109.730316 -253.432564) (xy 111.913673 -253.432564) (xy 111.917703 -253.380066) (xy 111.9297 -253.328798)
			(xy 111.949383 -253.279963) (xy 111.976289 -253.234704) (xy 112.009789 -253.194083) (xy 112.049097 -253.159052)
			(xy 112.093292 -253.130432) (xy 112.141337 -253.108893) (xy 112.192108 -253.094941) (xy 112.244413 -253.088903)
			(xy 112.297027 -253.09092) (xy 112.348717 -253.100944) (xy 112.39827 -253.118742) (xy 112.444526 -253.143895)
			(xy 112.4864 -253.175814) (xy 112.522912 -253.213752) (xy 112.553204 -253.256818) (xy 112.576567 -253.304003)
			(xy 112.592453 -253.354202) (xy 112.598358 -253.392432) (xy 112.882184 -253.392432) (xy 112.886144 -253.343378)
			(xy 112.897921 -253.295594) (xy 112.917212 -253.250318) (xy 112.943515 -253.208722) (xy 112.97615 -253.171885)
			(xy 113.014271 -253.14076) (xy 113.056892 -253.116153) (xy 113.102908 -253.098701) (xy 113.151127 -253.088857)
			(xy 113.200302 -253.086876) (xy 113.249157 -253.092808) (xy 113.296428 -253.1065) (xy 113.34089 -253.127598)
			(xy 113.381393 -253.155554) (xy 113.416886 -253.189646) (xy 113.446451 -253.22899) (xy 113.469322 -253.272567)
			(xy 113.484906 -253.319248) (xy 113.492801 -253.367825) (xy 113.493296 -253.392432) (xy 114.762038 -253.392432)
			(xy 114.765998 -253.343378) (xy 114.777775 -253.295594) (xy 114.797066 -253.250318) (xy 114.823369 -253.208722)
			(xy 114.856004 -253.171885) (xy 114.894125 -253.14076) (xy 114.936746 -253.116153) (xy 114.982762 -253.098701)
			(xy 115.030981 -253.088857) (xy 115.080156 -253.086876) (xy 115.129011 -253.092808) (xy 115.176282 -253.1065)
			(xy 115.220744 -253.127598) (xy 115.261247 -253.155554) (xy 115.29674 -253.189646) (xy 115.326305 -253.22899)
			(xy 115.349176 -253.272567) (xy 115.36476 -253.319248) (xy 115.372655 -253.367825) (xy 115.37315 -253.392432)
			(xy 116.642146 -253.392432) (xy 116.646106 -253.343378) (xy 116.657883 -253.295594) (xy 116.677174 -253.250318)
			(xy 116.703477 -253.208722) (xy 116.736112 -253.171885) (xy 116.774233 -253.14076) (xy 116.816854 -253.116153)
			(xy 116.86287 -253.098701) (xy 116.911089 -253.088857) (xy 116.960264 -253.086876) (xy 117.009119 -253.092808)
			(xy 117.05639 -253.1065) (xy 117.100852 -253.127598) (xy 117.141355 -253.155554) (xy 117.176848 -253.189646)
			(xy 117.206413 -253.22899) (xy 117.229284 -253.272567) (xy 117.244868 -253.319248) (xy 117.252763 -253.367825)
			(xy 117.253258 -253.392432) (xy 118.522 -253.392432) (xy 118.52596 -253.343378) (xy 118.537737 -253.295594)
			(xy 118.557028 -253.250318) (xy 118.583331 -253.208722) (xy 118.615966 -253.171885) (xy 118.654087 -253.14076)
			(xy 118.696708 -253.116153) (xy 118.742724 -253.098701) (xy 118.790943 -253.088857) (xy 118.840118 -253.086876)
			(xy 118.888973 -253.092808) (xy 118.936244 -253.1065) (xy 118.980706 -253.127598) (xy 119.021209 -253.155554)
			(xy 119.056702 -253.189646) (xy 119.086267 -253.22899) (xy 119.109138 -253.272567) (xy 119.124722 -253.319248)
			(xy 119.132617 -253.367825) (xy 119.133112 -253.392432) (xy 119.133071 -253.394464) (xy 122.278914 -253.394464)
			(xy 122.282874 -253.34541) (xy 122.294651 -253.297626) (xy 122.313942 -253.25235) (xy 122.340245 -253.210754)
			(xy 122.37288 -253.173917) (xy 122.411001 -253.142792) (xy 122.453622 -253.118185) (xy 122.499638 -253.100733)
			(xy 122.547857 -253.090889) (xy 122.597032 -253.088908) (xy 122.645887 -253.09484) (xy 122.693158 -253.108532)
			(xy 122.73762 -253.12963) (xy 122.778123 -253.157586) (xy 122.813616 -253.191678) (xy 122.843181 -253.231022)
			(xy 122.866052 -253.274599) (xy 122.881636 -253.32128) (xy 122.889531 -253.369857) (xy 122.890026 -253.394464)
			(xy 124.159022 -253.394464) (xy 124.162982 -253.34541) (xy 124.174759 -253.297626) (xy 124.19405 -253.25235)
			(xy 124.220353 -253.210754) (xy 124.252988 -253.173917) (xy 124.291109 -253.142792) (xy 124.33373 -253.118185)
			(xy 124.379746 -253.100733) (xy 124.427965 -253.090889) (xy 124.47714 -253.088908) (xy 124.525995 -253.09484)
			(xy 124.573266 -253.108532) (xy 124.617728 -253.12963) (xy 124.658231 -253.157586) (xy 124.693724 -253.191678)
			(xy 124.723289 -253.231022) (xy 124.74616 -253.274599) (xy 124.761744 -253.32128) (xy 124.769639 -253.369857)
			(xy 124.770134 -253.394464) (xy 126.038876 -253.394464) (xy 126.042836 -253.34541) (xy 126.054613 -253.297626)
			(xy 126.073904 -253.25235) (xy 126.100207 -253.210754) (xy 126.132842 -253.173917) (xy 126.170963 -253.142792)
			(xy 126.213584 -253.118185) (xy 126.2596 -253.100733) (xy 126.307819 -253.090889) (xy 126.356994 -253.088908)
			(xy 126.405849 -253.09484) (xy 126.45312 -253.108532) (xy 126.497582 -253.12963) (xy 126.538085 -253.157586)
			(xy 126.573578 -253.191678) (xy 126.603143 -253.231022) (xy 126.626014 -253.274599) (xy 126.641598 -253.32128)
			(xy 126.649493 -253.369857) (xy 126.649988 -253.394464) (xy 127.908553 -253.394464) (xy 127.912648 -253.343736)
			(xy 127.924827 -253.294322) (xy 127.944775 -253.247502) (xy 127.971976 -253.204488) (xy 128.005724 -253.166394)
			(xy 128.045146 -253.134207) (xy 128.08922 -253.108761) (xy 128.136806 -253.090714) (xy 128.18667 -253.080534)
			(xy 128.237522 -253.078485) (xy 128.288043 -253.084619) (xy 128.336927 -253.098779) (xy 128.382906 -253.120596)
			(xy 128.42479 -253.149506) (xy 128.461494 -253.184761) (xy 128.492067 -253.225447) (xy 128.515718 -253.27051)
			(xy 128.531834 -253.318784) (xy 128.539998 -253.369018) (xy 128.54051 -253.394464) (xy 128.848607 -253.394464)
			(xy 128.852702 -253.343736) (xy 128.864881 -253.294322) (xy 128.884829 -253.247502) (xy 128.91203 -253.204488)
			(xy 128.945778 -253.166394) (xy 128.9852 -253.134207) (xy 129.029274 -253.108761) (xy 129.07686 -253.090714)
			(xy 129.126724 -253.080534) (xy 129.177576 -253.078485) (xy 129.228097 -253.084619) (xy 129.276981 -253.098779)
			(xy 129.32296 -253.120596) (xy 129.364844 -253.149506) (xy 129.401548 -253.184761) (xy 129.432121 -253.225447)
			(xy 129.455772 -253.27051) (xy 129.471888 -253.318784) (xy 129.480052 -253.369018) (xy 129.480564 -253.394464)
			(xy 129.480052 -253.41991) (xy 129.471888 -253.470144) (xy 129.455772 -253.518418) (xy 129.432121 -253.563481)
			(xy 129.401548 -253.604167) (xy 129.364844 -253.639422) (xy 129.32296 -253.668332) (xy 129.276981 -253.690149)
			(xy 129.228097 -253.704309) (xy 129.177576 -253.710443) (xy 129.126724 -253.708394) (xy 129.07686 -253.698214)
			(xy 129.029274 -253.680167) (xy 128.9852 -253.654721) (xy 128.945778 -253.622534) (xy 128.91203 -253.58444)
			(xy 128.884829 -253.541426) (xy 128.864881 -253.494606) (xy 128.852702 -253.445192) (xy 128.848607 -253.394464)
			(xy 128.54051 -253.394464) (xy 128.539998 -253.41991) (xy 128.531834 -253.470144) (xy 128.515718 -253.518418)
			(xy 128.492067 -253.563481) (xy 128.461494 -253.604167) (xy 128.42479 -253.639422) (xy 128.382906 -253.668332)
			(xy 128.336927 -253.690149) (xy 128.288043 -253.704309) (xy 128.237522 -253.710443) (xy 128.18667 -253.708394)
			(xy 128.136806 -253.698214) (xy 128.08922 -253.680167) (xy 128.045146 -253.654721) (xy 128.005724 -253.622534)
			(xy 127.971976 -253.58444) (xy 127.944775 -253.541426) (xy 127.924827 -253.494606) (xy 127.912648 -253.445192)
			(xy 127.908553 -253.394464) (xy 126.649988 -253.394464) (xy 126.649493 -253.419071) (xy 126.641598 -253.467648)
			(xy 126.626014 -253.514329) (xy 126.603143 -253.557906) (xy 126.573578 -253.59725) (xy 126.538085 -253.631342)
			(xy 126.497582 -253.659298) (xy 126.45312 -253.680396) (xy 126.405849 -253.694088) (xy 126.356994 -253.70002)
			(xy 126.307819 -253.698039) (xy 126.2596 -253.688195) (xy 126.213584 -253.670743) (xy 126.170963 -253.646136)
			(xy 126.132842 -253.615011) (xy 126.100207 -253.578174) (xy 126.073904 -253.536578) (xy 126.054613 -253.491302)
			(xy 126.042836 -253.443518) (xy 126.038876 -253.394464) (xy 124.770134 -253.394464) (xy 124.769639 -253.419071)
			(xy 124.761744 -253.467648) (xy 124.74616 -253.514329) (xy 124.723289 -253.557906) (xy 124.693724 -253.59725)
			(xy 124.658231 -253.631342) (xy 124.617728 -253.659298) (xy 124.573266 -253.680396) (xy 124.525995 -253.694088)
			(xy 124.47714 -253.70002) (xy 124.427965 -253.698039) (xy 124.379746 -253.688195) (xy 124.33373 -253.670743)
			(xy 124.291109 -253.646136) (xy 124.252988 -253.615011) (xy 124.220353 -253.578174) (xy 124.19405 -253.536578)
			(xy 124.174759 -253.491302) (xy 124.162982 -253.443518) (xy 124.159022 -253.394464) (xy 122.890026 -253.394464)
			(xy 122.889531 -253.419071) (xy 122.881636 -253.467648) (xy 122.866052 -253.514329) (xy 122.843181 -253.557906)
			(xy 122.813616 -253.59725) (xy 122.778123 -253.631342) (xy 122.73762 -253.659298) (xy 122.693158 -253.680396)
			(xy 122.645887 -253.694088) (xy 122.597032 -253.70002) (xy 122.547857 -253.698039) (xy 122.499638 -253.688195)
			(xy 122.453622 -253.670743) (xy 122.411001 -253.646136) (xy 122.37288 -253.615011) (xy 122.340245 -253.578174)
			(xy 122.313942 -253.536578) (xy 122.294651 -253.491302) (xy 122.282874 -253.443518) (xy 122.278914 -253.394464)
			(xy 119.133071 -253.394464) (xy 119.132617 -253.417039) (xy 119.124722 -253.465616) (xy 119.109138 -253.512297)
			(xy 119.086267 -253.555874) (xy 119.056702 -253.595218) (xy 119.021209 -253.62931) (xy 118.980706 -253.657266)
			(xy 118.936244 -253.678364) (xy 118.888973 -253.692056) (xy 118.840118 -253.697988) (xy 118.790943 -253.696007)
			(xy 118.742724 -253.686163) (xy 118.696708 -253.668711) (xy 118.654087 -253.644104) (xy 118.615966 -253.612979)
			(xy 118.583331 -253.576142) (xy 118.557028 -253.534546) (xy 118.537737 -253.48927) (xy 118.52596 -253.441486)
			(xy 118.522 -253.392432) (xy 117.253258 -253.392432) (xy 117.252763 -253.417039) (xy 117.244868 -253.465616)
			(xy 117.229284 -253.512297) (xy 117.206413 -253.555874) (xy 117.176848 -253.595218) (xy 117.141355 -253.62931)
			(xy 117.100852 -253.657266) (xy 117.05639 -253.678364) (xy 117.009119 -253.692056) (xy 116.960264 -253.697988)
			(xy 116.911089 -253.696007) (xy 116.86287 -253.686163) (xy 116.816854 -253.668711) (xy 116.774233 -253.644104)
			(xy 116.736112 -253.612979) (xy 116.703477 -253.576142) (xy 116.677174 -253.534546) (xy 116.657883 -253.48927)
			(xy 116.646106 -253.441486) (xy 116.642146 -253.392432) (xy 115.37315 -253.392432) (xy 115.372655 -253.417039)
			(xy 115.36476 -253.465616) (xy 115.349176 -253.512297) (xy 115.326305 -253.555874) (xy 115.29674 -253.595218)
			(xy 115.261247 -253.62931) (xy 115.220744 -253.657266) (xy 115.176282 -253.678364) (xy 115.129011 -253.692056)
			(xy 115.080156 -253.697988) (xy 115.030981 -253.696007) (xy 114.982762 -253.686163) (xy 114.936746 -253.668711)
			(xy 114.894125 -253.644104) (xy 114.856004 -253.612979) (xy 114.823369 -253.576142) (xy 114.797066 -253.534546)
			(xy 114.777775 -253.48927) (xy 114.765998 -253.441486) (xy 114.762038 -253.392432) (xy 113.493296 -253.392432)
			(xy 113.492801 -253.417039) (xy 113.484906 -253.465616) (xy 113.469322 -253.512297) (xy 113.446451 -253.555874)
			(xy 113.416886 -253.595218) (xy 113.381393 -253.62931) (xy 113.34089 -253.657266) (xy 113.296428 -253.678364)
			(xy 113.249157 -253.692056) (xy 113.200302 -253.697988) (xy 113.151127 -253.696007) (xy 113.102908 -253.686163)
			(xy 113.056892 -253.668711) (xy 113.014271 -253.644104) (xy 112.97615 -253.612979) (xy 112.943515 -253.576142)
			(xy 112.917212 -253.534546) (xy 112.897921 -253.48927) (xy 112.886144 -253.441486) (xy 112.882184 -253.392432)
			(xy 112.598358 -253.392432) (xy 112.60049 -253.406238) (xy 112.600994 -253.432564) (xy 112.60049 -253.45889)
			(xy 112.592453 -253.510926) (xy 112.576567 -253.561125) (xy 112.553204 -253.60831) (xy 112.522912 -253.651376)
			(xy 112.4864 -253.689314) (xy 112.444526 -253.721233) (xy 112.39827 -253.746386) (xy 112.348717 -253.764184)
			(xy 112.297027 -253.774208) (xy 112.244413 -253.776225) (xy 112.192108 -253.770187) (xy 112.141337 -253.756235)
			(xy 112.093292 -253.734696) (xy 112.049097 -253.706076) (xy 112.009789 -253.671045) (xy 111.976289 -253.630424)
			(xy 111.949383 -253.585165) (xy 111.9297 -253.53633) (xy 111.917703 -253.485062) (xy 111.913673 -253.432564)
			(xy 109.730316 -253.432564) (xy 109.724944 -253.465616) (xy 109.70936 -253.512297) (xy 109.686489 -253.555874)
			(xy 109.656924 -253.595218) (xy 109.621431 -253.62931) (xy 109.580928 -253.657266) (xy 109.536466 -253.678364)
			(xy 109.489195 -253.692056) (xy 109.44034 -253.697988) (xy 109.391165 -253.696007) (xy 109.342946 -253.686163)
			(xy 109.29693 -253.668711) (xy 109.254309 -253.644104) (xy 109.216188 -253.612979) (xy 109.183553 -253.576142)
			(xy 109.15725 -253.534546) (xy 109.137959 -253.48927) (xy 109.126182 -253.441486) (xy 109.122222 -253.392432)
			(xy 107.853226 -253.392432) (xy 107.852731 -253.417039) (xy 107.844836 -253.465616) (xy 107.829252 -253.512297)
			(xy 107.806381 -253.555874) (xy 107.776816 -253.595218) (xy 107.741323 -253.62931) (xy 107.70082 -253.657266)
			(xy 107.656358 -253.678364) (xy 107.609087 -253.692056) (xy 107.560232 -253.697988) (xy 107.511057 -253.696007)
			(xy 107.462838 -253.686163) (xy 107.416822 -253.668711) (xy 107.374201 -253.644104) (xy 107.33608 -253.612979)
			(xy 107.303445 -253.576142) (xy 107.277142 -253.534546) (xy 107.257851 -253.48927) (xy 107.246074 -253.441486)
			(xy 107.242114 -253.392432) (xy 105.973118 -253.392432) (xy 105.972623 -253.417039) (xy 105.964728 -253.465616)
			(xy 105.949144 -253.512297) (xy 105.926273 -253.555874) (xy 105.896708 -253.595218) (xy 105.861215 -253.62931)
			(xy 105.820712 -253.657266) (xy 105.77625 -253.678364) (xy 105.728979 -253.692056) (xy 105.680124 -253.697988)
			(xy 105.630949 -253.696007) (xy 105.58273 -253.686163) (xy 105.536714 -253.668711) (xy 105.494093 -253.644104)
			(xy 105.455972 -253.612979) (xy 105.423337 -253.576142) (xy 105.397034 -253.534546) (xy 105.377743 -253.48927)
			(xy 105.365966 -253.441486) (xy 105.362006 -253.392432) (xy 104.093264 -253.392432) (xy 104.093264 -253.392686)
			(xy 104.092713 -253.419004) (xy 104.083687 -253.470862) (xy 104.065901 -253.520402) (xy 104.053386 -253.543562)
			(xy 104.04475 -253.558802) (xy 104.049322 -253.59233) (xy 104.905556 -254.448564) (xy 111.913673 -254.448564)
			(xy 111.917703 -254.396066) (xy 111.9297 -254.344798) (xy 111.949383 -254.295963) (xy 111.976289 -254.250704)
			(xy 112.009789 -254.210083) (xy 112.049097 -254.175052) (xy 112.093292 -254.146432) (xy 112.141337 -254.124893)
			(xy 112.192108 -254.110941) (xy 112.244413 -254.104903) (xy 112.297027 -254.10692) (xy 112.348717 -254.116944)
			(xy 112.39827 -254.134742) (xy 112.444526 -254.159895) (xy 112.4864 -254.191814) (xy 112.49858 -254.20447)
			(xy 120.86896 -254.20447) (xy 120.87292 -254.155416) (xy 120.884697 -254.107632) (xy 120.903988 -254.062356)
			(xy 120.930291 -254.02076) (xy 120.962926 -253.983923) (xy 121.001047 -253.952798) (xy 121.043668 -253.928191)
			(xy 121.089684 -253.910739) (xy 121.137903 -253.900895) (xy 121.187078 -253.898914) (xy 121.235933 -253.904846)
			(xy 121.283204 -253.918538) (xy 121.327666 -253.939636) (xy 121.368169 -253.967592) (xy 121.403662 -254.001684)
			(xy 121.433227 -254.041028) (xy 121.456098 -254.084605) (xy 121.471682 -254.131286) (xy 121.479577 -254.179863)
			(xy 121.480072 -254.20447) (xy 122.748814 -254.20447) (xy 122.752774 -254.155416) (xy 122.764551 -254.107632)
			(xy 122.783842 -254.062356) (xy 122.810145 -254.02076) (xy 122.84278 -253.983923) (xy 122.880901 -253.952798)
			(xy 122.923522 -253.928191) (xy 122.969538 -253.910739) (xy 123.017757 -253.900895) (xy 123.066932 -253.898914)
			(xy 123.115787 -253.904846) (xy 123.163058 -253.918538) (xy 123.20752 -253.939636) (xy 123.248023 -253.967592)
			(xy 123.283516 -254.001684) (xy 123.313081 -254.041028) (xy 123.335952 -254.084605) (xy 123.351536 -254.131286)
			(xy 123.359431 -254.179863) (xy 123.359926 -254.20447) (xy 124.628922 -254.20447) (xy 124.632882 -254.155416)
			(xy 124.644659 -254.107632) (xy 124.66395 -254.062356) (xy 124.690253 -254.02076) (xy 124.722888 -253.983923)
			(xy 124.761009 -253.952798) (xy 124.80363 -253.928191) (xy 124.849646 -253.910739) (xy 124.897865 -253.900895)
			(xy 124.94704 -253.898914) (xy 124.995895 -253.904846) (xy 125.043166 -253.918538) (xy 125.087628 -253.939636)
			(xy 125.128131 -253.967592) (xy 125.163624 -254.001684) (xy 125.193189 -254.041028) (xy 125.21606 -254.084605)
			(xy 125.231644 -254.131286) (xy 125.239539 -254.179863) (xy 125.240034 -254.20447) (xy 126.50903 -254.20447)
			(xy 126.51299 -254.155416) (xy 126.524767 -254.107632) (xy 126.544058 -254.062356) (xy 126.570361 -254.02076)
			(xy 126.602996 -253.983923) (xy 126.641117 -253.952798) (xy 126.683738 -253.928191) (xy 126.729754 -253.910739)
			(xy 126.777973 -253.900895) (xy 126.827148 -253.898914) (xy 126.876003 -253.904846) (xy 126.923274 -253.918538)
			(xy 126.967736 -253.939636) (xy 127.008239 -253.967592) (xy 127.043732 -254.001684) (xy 127.073297 -254.041028)
			(xy 127.096168 -254.084605) (xy 127.111752 -254.131286) (xy 127.119647 -254.179863) (xy 127.120142 -254.20447)
			(xy 127.438399 -254.20447) (xy 127.442494 -254.153742) (xy 127.454673 -254.104328) (xy 127.474621 -254.057508)
			(xy 127.501822 -254.014494) (xy 127.53557 -253.9764) (xy 127.574992 -253.944213) (xy 127.619066 -253.918767)
			(xy 127.666652 -253.90072) (xy 127.716516 -253.89054) (xy 127.767368 -253.888491) (xy 127.817889 -253.894625)
			(xy 127.866773 -253.908785) (xy 127.912752 -253.930602) (xy 127.954636 -253.959512) (xy 127.99134 -253.994767)
			(xy 128.021913 -254.035453) (xy 128.045564 -254.080516) (xy 128.06168 -254.12879) (xy 128.069844 -254.179024)
			(xy 128.070356 -254.20447) (xy 128.388884 -254.20447) (xy 128.392844 -254.155416) (xy 128.404621 -254.107632)
			(xy 128.423912 -254.062356) (xy 128.450215 -254.02076) (xy 128.48285 -253.983923) (xy 128.520971 -253.952798)
			(xy 128.563592 -253.928191) (xy 128.609608 -253.910739) (xy 128.657827 -253.900895) (xy 128.707002 -253.898914)
			(xy 128.755857 -253.904846) (xy 128.803128 -253.918538) (xy 128.84759 -253.939636) (xy 128.888093 -253.967592)
			(xy 128.923586 -254.001684) (xy 128.953151 -254.041028) (xy 128.976022 -254.084605) (xy 128.991606 -254.131286)
			(xy 128.999501 -254.179863) (xy 128.999996 -254.20447) (xy 129.318507 -254.20447) (xy 129.322602 -254.153742)
			(xy 129.334781 -254.104328) (xy 129.354729 -254.057508) (xy 129.38193 -254.014494) (xy 129.415678 -253.9764)
			(xy 129.4551 -253.944213) (xy 129.499174 -253.918767) (xy 129.54676 -253.90072) (xy 129.596624 -253.89054)
			(xy 129.647476 -253.888491) (xy 129.697997 -253.894625) (xy 129.746881 -253.908785) (xy 129.79286 -253.930602)
			(xy 129.834744 -253.959512) (xy 129.871448 -253.994767) (xy 129.902021 -254.035453) (xy 129.925672 -254.080516)
			(xy 129.941788 -254.12879) (xy 129.949952 -254.179024) (xy 129.950464 -254.20447) (xy 129.949952 -254.229916)
			(xy 129.941788 -254.28015) (xy 129.925672 -254.328424) (xy 129.902021 -254.373487) (xy 129.871448 -254.414173)
			(xy 129.834744 -254.449428) (xy 129.79286 -254.478338) (xy 129.746881 -254.500155) (xy 129.697997 -254.514315)
			(xy 129.647476 -254.520449) (xy 129.596624 -254.5184) (xy 129.54676 -254.50822) (xy 129.499174 -254.490173)
			(xy 129.4551 -254.464727) (xy 129.415678 -254.43254) (xy 129.38193 -254.394446) (xy 129.354729 -254.351432)
			(xy 129.334781 -254.304612) (xy 129.322602 -254.255198) (xy 129.318507 -254.20447) (xy 128.999996 -254.20447)
			(xy 128.999501 -254.229077) (xy 128.991606 -254.277654) (xy 128.976022 -254.324335) (xy 128.953151 -254.367912)
			(xy 128.923586 -254.407256) (xy 128.888093 -254.441348) (xy 128.84759 -254.469304) (xy 128.803128 -254.490402)
			(xy 128.755857 -254.504094) (xy 128.707002 -254.510026) (xy 128.657827 -254.508045) (xy 128.609608 -254.498201)
			(xy 128.563592 -254.480749) (xy 128.520971 -254.456142) (xy 128.48285 -254.425017) (xy 128.450215 -254.38818)
			(xy 128.423912 -254.346584) (xy 128.404621 -254.301308) (xy 128.392844 -254.253524) (xy 128.388884 -254.20447)
			(xy 128.070356 -254.20447) (xy 128.069844 -254.229916) (xy 128.06168 -254.28015) (xy 128.045564 -254.328424)
			(xy 128.021913 -254.373487) (xy 127.99134 -254.414173) (xy 127.954636 -254.449428) (xy 127.912752 -254.478338)
			(xy 127.866773 -254.500155) (xy 127.817889 -254.514315) (xy 127.767368 -254.520449) (xy 127.716516 -254.5184)
			(xy 127.666652 -254.50822) (xy 127.619066 -254.490173) (xy 127.574992 -254.464727) (xy 127.53557 -254.43254)
			(xy 127.501822 -254.394446) (xy 127.474621 -254.351432) (xy 127.454673 -254.304612) (xy 127.442494 -254.255198)
			(xy 127.438399 -254.20447) (xy 127.120142 -254.20447) (xy 127.119647 -254.229077) (xy 127.111752 -254.277654)
			(xy 127.096168 -254.324335) (xy 127.073297 -254.367912) (xy 127.043732 -254.407256) (xy 127.008239 -254.441348)
			(xy 126.967736 -254.469304) (xy 126.923274 -254.490402) (xy 126.876003 -254.504094) (xy 126.827148 -254.510026)
			(xy 126.777973 -254.508045) (xy 126.729754 -254.498201) (xy 126.683738 -254.480749) (xy 126.641117 -254.456142)
			(xy 126.602996 -254.425017) (xy 126.570361 -254.38818) (xy 126.544058 -254.346584) (xy 126.524767 -254.301308)
			(xy 126.51299 -254.253524) (xy 126.50903 -254.20447) (xy 125.240034 -254.20447) (xy 125.239539 -254.229077)
			(xy 125.231644 -254.277654) (xy 125.21606 -254.324335) (xy 125.193189 -254.367912) (xy 125.163624 -254.407256)
			(xy 125.128131 -254.441348) (xy 125.087628 -254.469304) (xy 125.043166 -254.490402) (xy 124.995895 -254.504094)
			(xy 124.94704 -254.510026) (xy 124.897865 -254.508045) (xy 124.849646 -254.498201) (xy 124.80363 -254.480749)
			(xy 124.761009 -254.456142) (xy 124.722888 -254.425017) (xy 124.690253 -254.38818) (xy 124.66395 -254.346584)
			(xy 124.644659 -254.301308) (xy 124.632882 -254.253524) (xy 124.628922 -254.20447) (xy 123.359926 -254.20447)
			(xy 123.359431 -254.229077) (xy 123.351536 -254.277654) (xy 123.335952 -254.324335) (xy 123.313081 -254.367912)
			(xy 123.283516 -254.407256) (xy 123.248023 -254.441348) (xy 123.20752 -254.469304) (xy 123.163058 -254.490402)
			(xy 123.115787 -254.504094) (xy 123.066932 -254.510026) (xy 123.017757 -254.508045) (xy 122.969538 -254.498201)
			(xy 122.923522 -254.480749) (xy 122.880901 -254.456142) (xy 122.84278 -254.425017) (xy 122.810145 -254.38818)
			(xy 122.783842 -254.346584) (xy 122.764551 -254.301308) (xy 122.752774 -254.253524) (xy 122.748814 -254.20447)
			(xy 121.480072 -254.20447) (xy 121.479577 -254.229077) (xy 121.471682 -254.277654) (xy 121.456098 -254.324335)
			(xy 121.433227 -254.367912) (xy 121.403662 -254.407256) (xy 121.368169 -254.441348) (xy 121.327666 -254.469304)
			(xy 121.283204 -254.490402) (xy 121.235933 -254.504094) (xy 121.187078 -254.510026) (xy 121.137903 -254.508045)
			(xy 121.089684 -254.498201) (xy 121.043668 -254.480749) (xy 121.001047 -254.456142) (xy 120.962926 -254.425017)
			(xy 120.930291 -254.38818) (xy 120.903988 -254.346584) (xy 120.884697 -254.301308) (xy 120.87292 -254.253524)
			(xy 120.86896 -254.20447) (xy 112.49858 -254.20447) (xy 112.522912 -254.229752) (xy 112.553204 -254.272818)
			(xy 112.576567 -254.320003) (xy 112.592453 -254.370202) (xy 112.60049 -254.422238) (xy 112.600994 -254.448564)
			(xy 112.60049 -254.47489) (xy 112.592453 -254.526926) (xy 112.576567 -254.577125) (xy 112.553204 -254.62431)
			(xy 112.522912 -254.667376) (xy 112.4864 -254.705314) (xy 112.444526 -254.737233) (xy 112.39827 -254.762386)
			(xy 112.348717 -254.780184) (xy 112.297027 -254.790208) (xy 112.244413 -254.792225) (xy 112.192108 -254.786187)
			(xy 112.141337 -254.772235) (xy 112.093292 -254.750696) (xy 112.049097 -254.722076) (xy 112.009789 -254.687045)
			(xy 111.976289 -254.646424) (xy 111.949383 -254.601165) (xy 111.9297 -254.55233) (xy 111.917703 -254.501062)
			(xy 111.913673 -254.448564) (xy 104.905556 -254.448564) (xy 105.471468 -255.014476) (xy 122.278914 -255.014476)
			(xy 122.282874 -254.965422) (xy 122.294651 -254.917638) (xy 122.313942 -254.872362) (xy 122.340245 -254.830766)
			(xy 122.37288 -254.793929) (xy 122.411001 -254.762804) (xy 122.453622 -254.738197) (xy 122.499638 -254.720745)
			(xy 122.547857 -254.710901) (xy 122.597032 -254.70892) (xy 122.645887 -254.714852) (xy 122.693158 -254.728544)
			(xy 122.73762 -254.749642) (xy 122.778123 -254.777598) (xy 122.813616 -254.81169) (xy 122.843181 -254.851034)
			(xy 122.866052 -254.894611) (xy 122.881636 -254.941292) (xy 122.889531 -254.989869) (xy 122.890026 -255.014476)
			(xy 124.159022 -255.014476) (xy 124.162982 -254.965422) (xy 124.174759 -254.917638) (xy 124.19405 -254.872362)
			(xy 124.220353 -254.830766) (xy 124.252988 -254.793929) (xy 124.291109 -254.762804) (xy 124.33373 -254.738197)
			(xy 124.379746 -254.720745) (xy 124.427965 -254.710901) (xy 124.47714 -254.70892) (xy 124.525995 -254.714852)
			(xy 124.573266 -254.728544) (xy 124.617728 -254.749642) (xy 124.658231 -254.777598) (xy 124.693724 -254.81169)
			(xy 124.723289 -254.851034) (xy 124.74616 -254.894611) (xy 124.761744 -254.941292) (xy 124.769639 -254.989869)
			(xy 124.770134 -255.014476) (xy 126.038876 -255.014476) (xy 126.042836 -254.965422) (xy 126.054613 -254.917638)
			(xy 126.073904 -254.872362) (xy 126.100207 -254.830766) (xy 126.132842 -254.793929) (xy 126.170963 -254.762804)
			(xy 126.213584 -254.738197) (xy 126.2596 -254.720745) (xy 126.307819 -254.710901) (xy 126.356994 -254.70892)
			(xy 126.405849 -254.714852) (xy 126.45312 -254.728544) (xy 126.497582 -254.749642) (xy 126.538085 -254.777598)
			(xy 126.573578 -254.81169) (xy 126.603143 -254.851034) (xy 126.626014 -254.894611) (xy 126.641598 -254.941292)
			(xy 126.649493 -254.989869) (xy 126.649988 -255.014476) (xy 127.908553 -255.014476) (xy 127.912648 -254.963748)
			(xy 127.924827 -254.914334) (xy 127.944775 -254.867514) (xy 127.971976 -254.8245) (xy 128.005724 -254.786406)
			(xy 128.045146 -254.754219) (xy 128.08922 -254.728773) (xy 128.136806 -254.710726) (xy 128.18667 -254.700546)
			(xy 128.237522 -254.698497) (xy 128.288043 -254.704631) (xy 128.336927 -254.718791) (xy 128.382906 -254.740608)
			(xy 128.42479 -254.769518) (xy 128.461494 -254.804773) (xy 128.492067 -254.845459) (xy 128.515718 -254.890522)
			(xy 128.531834 -254.938796) (xy 128.539998 -254.98903) (xy 128.54051 -255.014476) (xy 128.848607 -255.014476)
			(xy 128.852702 -254.963748) (xy 128.864881 -254.914334) (xy 128.884829 -254.867514) (xy 128.91203 -254.8245)
			(xy 128.945778 -254.786406) (xy 128.9852 -254.754219) (xy 129.029274 -254.728773) (xy 129.07686 -254.710726)
			(xy 129.126724 -254.700546) (xy 129.177576 -254.698497) (xy 129.228097 -254.704631) (xy 129.276981 -254.718791)
			(xy 129.32296 -254.740608) (xy 129.364844 -254.769518) (xy 129.401548 -254.804773) (xy 129.432121 -254.845459)
			(xy 129.455772 -254.890522) (xy 129.471888 -254.938796) (xy 129.480052 -254.98903) (xy 129.480564 -255.014476)
			(xy 129.480052 -255.039922) (xy 129.471888 -255.090156) (xy 129.455772 -255.13843) (xy 129.432121 -255.183493)
			(xy 129.401548 -255.224179) (xy 129.364844 -255.259434) (xy 129.32296 -255.288344) (xy 129.276981 -255.310161)
			(xy 129.228097 -255.324321) (xy 129.177576 -255.330455) (xy 129.126724 -255.328406) (xy 129.07686 -255.318226)
			(xy 129.029274 -255.300179) (xy 128.9852 -255.274733) (xy 128.945778 -255.242546) (xy 128.91203 -255.204452)
			(xy 128.884829 -255.161438) (xy 128.864881 -255.114618) (xy 128.852702 -255.065204) (xy 128.848607 -255.014476)
			(xy 128.54051 -255.014476) (xy 128.539998 -255.039922) (xy 128.531834 -255.090156) (xy 128.515718 -255.13843)
			(xy 128.492067 -255.183493) (xy 128.461494 -255.224179) (xy 128.42479 -255.259434) (xy 128.382906 -255.288344)
			(xy 128.336927 -255.310161) (xy 128.288043 -255.324321) (xy 128.237522 -255.330455) (xy 128.18667 -255.328406)
			(xy 128.136806 -255.318226) (xy 128.08922 -255.300179) (xy 128.045146 -255.274733) (xy 128.005724 -255.242546)
			(xy 127.971976 -255.204452) (xy 127.944775 -255.161438) (xy 127.924827 -255.114618) (xy 127.912648 -255.065204)
			(xy 127.908553 -255.014476) (xy 126.649988 -255.014476) (xy 126.649493 -255.039083) (xy 126.641598 -255.08766)
			(xy 126.626014 -255.134341) (xy 126.603143 -255.177918) (xy 126.573578 -255.217262) (xy 126.538085 -255.251354)
			(xy 126.497582 -255.27931) (xy 126.45312 -255.300408) (xy 126.405849 -255.3141) (xy 126.356994 -255.320032)
			(xy 126.307819 -255.318051) (xy 126.2596 -255.308207) (xy 126.213584 -255.290755) (xy 126.170963 -255.266148)
			(xy 126.132842 -255.235023) (xy 126.100207 -255.198186) (xy 126.073904 -255.15659) (xy 126.054613 -255.111314)
			(xy 126.042836 -255.06353) (xy 126.038876 -255.014476) (xy 124.770134 -255.014476) (xy 124.769639 -255.039083)
			(xy 124.761744 -255.08766) (xy 124.74616 -255.134341) (xy 124.723289 -255.177918) (xy 124.693724 -255.217262)
			(xy 124.658231 -255.251354) (xy 124.617728 -255.27931) (xy 124.573266 -255.300408) (xy 124.525995 -255.3141)
			(xy 124.47714 -255.320032) (xy 124.427965 -255.318051) (xy 124.379746 -255.308207) (xy 124.33373 -255.290755)
			(xy 124.291109 -255.266148) (xy 124.252988 -255.235023) (xy 124.220353 -255.198186) (xy 124.19405 -255.15659)
			(xy 124.174759 -255.111314) (xy 124.162982 -255.06353) (xy 124.159022 -255.014476) (xy 122.890026 -255.014476)
			(xy 122.889531 -255.039083) (xy 122.881636 -255.08766) (xy 122.866052 -255.134341) (xy 122.843181 -255.177918)
			(xy 122.813616 -255.217262) (xy 122.778123 -255.251354) (xy 122.73762 -255.27931) (xy 122.693158 -255.300408)
			(xy 122.645887 -255.3141) (xy 122.597032 -255.320032) (xy 122.547857 -255.318051) (xy 122.499638 -255.308207)
			(xy 122.453622 -255.290755) (xy 122.411001 -255.266148) (xy 122.37288 -255.235023) (xy 122.340245 -255.198186)
			(xy 122.313942 -255.15659) (xy 122.294651 -255.111314) (xy 122.282874 -255.06353) (xy 122.278914 -255.014476)
			(xy 105.471468 -255.014476) (xy 105.914444 -255.457452) (xy 105.919524 -255.46177) (xy 105.919524 -255.462024)
			(xy 105.928879 -255.468444) (xy 105.951034 -255.473199) (xy 105.962196 -255.471168) (xy 106.04373 -255.452118)
			(xy 106.049895 -255.450463) (xy 106.061208 -255.444556) (xy 106.066082 -255.440434) (xy 106.071162 -255.435862)
			(xy 106.078274 -255.425194) (xy 106.080306 -255.419098) (xy 106.089417 -255.394054) (xy 106.114267 -255.346914)
			(xy 106.1461 -255.304178) (xy 106.184152 -255.266872) (xy 106.22751 -255.235891) (xy 106.275133 -255.211979)
			(xy 106.325879 -255.19571) (xy 106.378527 -255.187475) (xy 106.405172 -255.186942) (xy 106.43087 -255.187397)
			(xy 106.481693 -255.195053) (xy 106.530807 -255.210199) (xy 106.577115 -255.232497) (xy 106.619583 -255.261447)
			(xy 106.65726 -255.296404) (xy 106.689307 -255.336586) (xy 106.715006 -255.381096) (xy 106.733785 -255.428939)
			(xy 106.745222 -255.479047) (xy 106.749063 -255.5303) (xy 106.749059 -255.53035) (xy 117.096797 -255.53035)
			(xy 117.100827 -255.477852) (xy 117.112824 -255.426584) (xy 117.132507 -255.377749) (xy 117.159413 -255.33249)
			(xy 117.192913 -255.291869) (xy 117.232221 -255.256838) (xy 117.276416 -255.228218) (xy 117.324461 -255.206679)
			(xy 117.375232 -255.192727) (xy 117.427537 -255.186689) (xy 117.480151 -255.188706) (xy 117.531841 -255.19873)
			(xy 117.581394 -255.216528) (xy 117.62765 -255.241681) (xy 117.669524 -255.2736) (xy 117.706036 -255.311538)
			(xy 117.736328 -255.354604) (xy 117.759691 -255.401789) (xy 117.775577 -255.451988) (xy 117.783614 -255.504024)
			(xy 117.784118 -255.53035) (xy 117.783614 -255.556676) (xy 117.775577 -255.608712) (xy 117.759691 -255.658911)
			(xy 117.736328 -255.706096) (xy 117.706036 -255.749162) (xy 117.669524 -255.7871) (xy 117.62765 -255.819019)
			(xy 117.617604 -255.824482) (xy 120.86896 -255.824482) (xy 120.87292 -255.775428) (xy 120.884697 -255.727644)
			(xy 120.903988 -255.682368) (xy 120.930291 -255.640772) (xy 120.962926 -255.603935) (xy 121.001047 -255.57281)
			(xy 121.043668 -255.548203) (xy 121.089684 -255.530751) (xy 121.137903 -255.520907) (xy 121.187078 -255.518926)
			(xy 121.235933 -255.524858) (xy 121.283204 -255.53855) (xy 121.327666 -255.559648) (xy 121.368169 -255.587604)
			(xy 121.403662 -255.621696) (xy 121.433227 -255.66104) (xy 121.456098 -255.704617) (xy 121.471682 -255.751298)
			(xy 121.479577 -255.799875) (xy 121.480072 -255.824482) (xy 122.748814 -255.824482) (xy 122.752774 -255.775428)
			(xy 122.764551 -255.727644) (xy 122.783842 -255.682368) (xy 122.810145 -255.640772) (xy 122.84278 -255.603935)
			(xy 122.880901 -255.57281) (xy 122.923522 -255.548203) (xy 122.969538 -255.530751) (xy 123.017757 -255.520907)
			(xy 123.066932 -255.518926) (xy 123.115787 -255.524858) (xy 123.163058 -255.53855) (xy 123.20752 -255.559648)
			(xy 123.248023 -255.587604) (xy 123.283516 -255.621696) (xy 123.313081 -255.66104) (xy 123.335952 -255.704617)
			(xy 123.351536 -255.751298) (xy 123.359431 -255.799875) (xy 123.359926 -255.824482) (xy 124.628922 -255.824482)
			(xy 124.632882 -255.775428) (xy 124.644659 -255.727644) (xy 124.66395 -255.682368) (xy 124.690253 -255.640772)
			(xy 124.722888 -255.603935) (xy 124.761009 -255.57281) (xy 124.80363 -255.548203) (xy 124.849646 -255.530751)
			(xy 124.897865 -255.520907) (xy 124.94704 -255.518926) (xy 124.995895 -255.524858) (xy 125.043166 -255.53855)
			(xy 125.087628 -255.559648) (xy 125.128131 -255.587604) (xy 125.163624 -255.621696) (xy 125.193189 -255.66104)
			(xy 125.21606 -255.704617) (xy 125.231644 -255.751298) (xy 125.239539 -255.799875) (xy 125.240034 -255.824482)
			(xy 126.50903 -255.824482) (xy 126.51299 -255.775428) (xy 126.524767 -255.727644) (xy 126.544058 -255.682368)
			(xy 126.570361 -255.640772) (xy 126.602996 -255.603935) (xy 126.641117 -255.57281) (xy 126.683738 -255.548203)
			(xy 126.729754 -255.530751) (xy 126.777973 -255.520907) (xy 126.827148 -255.518926) (xy 126.876003 -255.524858)
			(xy 126.923274 -255.53855) (xy 126.967736 -255.559648) (xy 127.008239 -255.587604) (xy 127.043732 -255.621696)
			(xy 127.073297 -255.66104) (xy 127.096168 -255.704617) (xy 127.111752 -255.751298) (xy 127.119647 -255.799875)
			(xy 127.120142 -255.824482) (xy 127.438399 -255.824482) (xy 127.442494 -255.773754) (xy 127.454673 -255.72434)
			(xy 127.474621 -255.67752) (xy 127.501822 -255.634506) (xy 127.53557 -255.596412) (xy 127.574992 -255.564225)
			(xy 127.619066 -255.538779) (xy 127.666652 -255.520732) (xy 127.716516 -255.510552) (xy 127.767368 -255.508503)
			(xy 127.817889 -255.514637) (xy 127.866773 -255.528797) (xy 127.912752 -255.550614) (xy 127.954636 -255.579524)
			(xy 127.99134 -255.614779) (xy 128.021913 -255.655465) (xy 128.045564 -255.700528) (xy 128.06168 -255.748802)
			(xy 128.069844 -255.799036) (xy 128.070356 -255.824482) (xy 128.388884 -255.824482) (xy 128.392844 -255.775428)
			(xy 128.404621 -255.727644) (xy 128.423912 -255.682368) (xy 128.450215 -255.640772) (xy 128.48285 -255.603935)
			(xy 128.520971 -255.57281) (xy 128.563592 -255.548203) (xy 128.609608 -255.530751) (xy 128.657827 -255.520907)
			(xy 128.707002 -255.518926) (xy 128.755857 -255.524858) (xy 128.803128 -255.53855) (xy 128.84759 -255.559648)
			(xy 128.888093 -255.587604) (xy 128.923586 -255.621696) (xy 128.953151 -255.66104) (xy 128.976022 -255.704617)
			(xy 128.991606 -255.751298) (xy 128.999501 -255.799875) (xy 128.999996 -255.824482) (xy 129.318507 -255.824482)
			(xy 129.322602 -255.773754) (xy 129.334781 -255.72434) (xy 129.354729 -255.67752) (xy 129.38193 -255.634506)
			(xy 129.415678 -255.596412) (xy 129.4551 -255.564225) (xy 129.499174 -255.538779) (xy 129.54676 -255.520732)
			(xy 129.596624 -255.510552) (xy 129.647476 -255.508503) (xy 129.697997 -255.514637) (xy 129.746881 -255.528797)
			(xy 129.79286 -255.550614) (xy 129.834744 -255.579524) (xy 129.871448 -255.614779) (xy 129.902021 -255.655465)
			(xy 129.925672 -255.700528) (xy 129.941788 -255.748802) (xy 129.949952 -255.799036) (xy 129.950464 -255.824482)
			(xy 129.949952 -255.849928) (xy 129.941788 -255.900162) (xy 129.925672 -255.948436) (xy 129.902021 -255.993499)
			(xy 129.871448 -256.034185) (xy 129.834744 -256.06944) (xy 129.79286 -256.09835) (xy 129.746881 -256.120167)
			(xy 129.697997 -256.134327) (xy 129.647476 -256.140461) (xy 129.596624 -256.138412) (xy 129.54676 -256.128232)
			(xy 129.499174 -256.110185) (xy 129.4551 -256.084739) (xy 129.415678 -256.052552) (xy 129.38193 -256.014458)
			(xy 129.354729 -255.971444) (xy 129.334781 -255.924624) (xy 129.322602 -255.87521) (xy 129.318507 -255.824482)
			(xy 128.999996 -255.824482) (xy 128.999501 -255.849089) (xy 128.991606 -255.897666) (xy 128.976022 -255.944347)
			(xy 128.953151 -255.987924) (xy 128.923586 -256.027268) (xy 128.888093 -256.06136) (xy 128.84759 -256.089316)
			(xy 128.803128 -256.110414) (xy 128.755857 -256.124106) (xy 128.707002 -256.130038) (xy 128.657827 -256.128057)
			(xy 128.609608 -256.118213) (xy 128.563592 -256.100761) (xy 128.520971 -256.076154) (xy 128.48285 -256.045029)
			(xy 128.450215 -256.008192) (xy 128.423912 -255.966596) (xy 128.404621 -255.92132) (xy 128.392844 -255.873536)
			(xy 128.388884 -255.824482) (xy 128.070356 -255.824482) (xy 128.069844 -255.849928) (xy 128.06168 -255.900162)
			(xy 128.045564 -255.948436) (xy 128.021913 -255.993499) (xy 127.99134 -256.034185) (xy 127.954636 -256.06944)
			(xy 127.912752 -256.09835) (xy 127.866773 -256.120167) (xy 127.817889 -256.134327) (xy 127.767368 -256.140461)
			(xy 127.716516 -256.138412) (xy 127.666652 -256.128232) (xy 127.619066 -256.110185) (xy 127.574992 -256.084739)
			(xy 127.53557 -256.052552) (xy 127.501822 -256.014458) (xy 127.474621 -255.971444) (xy 127.454673 -255.924624)
			(xy 127.442494 -255.87521) (xy 127.438399 -255.824482) (xy 127.120142 -255.824482) (xy 127.119647 -255.849089)
			(xy 127.111752 -255.897666) (xy 127.096168 -255.944347) (xy 127.073297 -255.987924) (xy 127.043732 -256.027268)
			(xy 127.008239 -256.06136) (xy 126.967736 -256.089316) (xy 126.923274 -256.110414) (xy 126.876003 -256.124106)
			(xy 126.827148 -256.130038) (xy 126.777973 -256.128057) (xy 126.729754 -256.118213) (xy 126.683738 -256.100761)
			(xy 126.641117 -256.076154) (xy 126.602996 -256.045029) (xy 126.570361 -256.008192) (xy 126.544058 -255.966596)
			(xy 126.524767 -255.92132) (xy 126.51299 -255.873536) (xy 126.50903 -255.824482) (xy 125.240034 -255.824482)
			(xy 125.239539 -255.849089) (xy 125.231644 -255.897666) (xy 125.21606 -255.944347) (xy 125.193189 -255.987924)
			(xy 125.163624 -256.027268) (xy 125.128131 -256.06136) (xy 125.087628 -256.089316) (xy 125.043166 -256.110414)
			(xy 124.995895 -256.124106) (xy 124.94704 -256.130038) (xy 124.897865 -256.128057) (xy 124.849646 -256.118213)
			(xy 124.80363 -256.100761) (xy 124.761009 -256.076154) (xy 124.722888 -256.045029) (xy 124.690253 -256.008192)
			(xy 124.66395 -255.966596) (xy 124.644659 -255.92132) (xy 124.632882 -255.873536) (xy 124.628922 -255.824482)
			(xy 123.359926 -255.824482) (xy 123.359431 -255.849089) (xy 123.351536 -255.897666) (xy 123.335952 -255.944347)
			(xy 123.313081 -255.987924) (xy 123.283516 -256.027268) (xy 123.248023 -256.06136) (xy 123.20752 -256.089316)
			(xy 123.163058 -256.110414) (xy 123.115787 -256.124106) (xy 123.066932 -256.130038) (xy 123.017757 -256.128057)
			(xy 122.969538 -256.118213) (xy 122.923522 -256.100761) (xy 122.880901 -256.076154) (xy 122.84278 -256.045029)
			(xy 122.810145 -256.008192) (xy 122.783842 -255.966596) (xy 122.764551 -255.92132) (xy 122.752774 -255.873536)
			(xy 122.748814 -255.824482) (xy 121.480072 -255.824482) (xy 121.479577 -255.849089) (xy 121.471682 -255.897666)
			(xy 121.456098 -255.944347) (xy 121.433227 -255.987924) (xy 121.403662 -256.027268) (xy 121.368169 -256.06136)
			(xy 121.327666 -256.089316) (xy 121.283204 -256.110414) (xy 121.235933 -256.124106) (xy 121.187078 -256.130038)
			(xy 121.137903 -256.128057) (xy 121.089684 -256.118213) (xy 121.043668 -256.100761) (xy 121.001047 -256.076154)
			(xy 120.962926 -256.045029) (xy 120.930291 -256.008192) (xy 120.903988 -255.966596) (xy 120.884697 -255.92132)
			(xy 120.87292 -255.873536) (xy 120.86896 -255.824482) (xy 117.617604 -255.824482) (xy 117.581394 -255.844172)
			(xy 117.531841 -255.86197) (xy 117.480151 -255.871994) (xy 117.427537 -255.874011) (xy 117.375232 -255.867973)
			(xy 117.324461 -255.854021) (xy 117.276416 -255.832482) (xy 117.232221 -255.803862) (xy 117.192913 -255.768831)
			(xy 117.159413 -255.72821) (xy 117.132507 -255.682951) (xy 117.112824 -255.634116) (xy 117.100827 -255.582848)
			(xy 117.096797 -255.53035) (xy 106.749059 -255.53035) (xy 106.745222 -255.581553) (xy 106.733785 -255.63166)
			(xy 106.715006 -255.679504) (xy 106.689307 -255.724014) (xy 106.65726 -255.764196) (xy 106.619583 -255.799153)
			(xy 106.577115 -255.828103) (xy 106.530807 -255.850401) (xy 106.481693 -255.865547) (xy 106.43087 -255.873203)
			(xy 106.405172 -255.873758) (xy 106.404918 -255.873758) (xy 106.382262 -255.873379) (xy 106.33735 -255.867378)
			(xy 106.293622 -255.855505) (xy 106.272584 -255.847088) (xy 106.27233 -255.847088) (xy 106.260466 -255.842841)
			(xy 106.23541 -255.845224) (xy 106.224578 -255.85166) (xy 106.155998 -255.897126) (xy 106.145934 -255.90464)
			(xy 106.134078 -255.926749) (xy 106.133392 -255.93929) (xy 106.133392 -256.07137) (xy 106.134027 -256.083931)
			(xy 106.145872 -256.10608) (xy 106.155998 -256.113534) (xy 106.224578 -256.159) (xy 106.235409 -256.165454)
			(xy 106.260474 -256.167861) (xy 106.27233 -256.163572) (xy 106.272584 -256.163572) (xy 106.293662 -256.155145)
			(xy 106.337479 -256.143276) (xy 106.382475 -256.137267) (xy 106.405172 -256.136902) (xy 106.409744 -256.136902)
			(xy 106.4361 -256.137739) (xy 106.488098 -256.1465) (xy 106.538146 -256.163105) (xy 106.585069 -256.187161)
			(xy 106.627764 -256.218106) (xy 106.66523 -256.255211) (xy 106.696586 -256.297606) (xy 106.721095 -256.344294)
			(xy 106.735928 -256.3876) (xy 107.304081 -256.3876) (xy 107.308111 -256.335102) (xy 107.320108 -256.283834)
			(xy 107.339791 -256.234999) (xy 107.366697 -256.18974) (xy 107.400197 -256.149119) (xy 107.439505 -256.114088)
			(xy 107.4837 -256.085468) (xy 107.531745 -256.063929) (xy 107.582516 -256.049977) (xy 107.634821 -256.043939)
			(xy 107.687435 -256.045956) (xy 107.739125 -256.05598) (xy 107.788678 -256.073778) (xy 107.834934 -256.098931)
			(xy 107.876808 -256.13085) (xy 107.91332 -256.168788) (xy 107.943612 -256.211854) (xy 107.966975 -256.259039)
			(xy 107.982861 -256.309238) (xy 107.990898 -256.361274) (xy 107.991402 -256.3876) (xy 108.254041 -256.3876)
			(xy 108.258071 -256.335102) (xy 108.270068 -256.283834) (xy 108.289751 -256.234999) (xy 108.316657 -256.18974)
			(xy 108.350157 -256.149119) (xy 108.389465 -256.114088) (xy 108.43366 -256.085468) (xy 108.481705 -256.063929)
			(xy 108.532476 -256.049977) (xy 108.584781 -256.043939) (xy 108.637395 -256.045956) (xy 108.689085 -256.05598)
			(xy 108.738638 -256.073778) (xy 108.784894 -256.098931) (xy 108.826768 -256.13085) (xy 108.86328 -256.168788)
			(xy 108.893572 -256.211854) (xy 108.916935 -256.259039) (xy 108.932821 -256.309238) (xy 108.940858 -256.361274)
			(xy 108.941362 -256.3876) (xy 109.204001 -256.3876) (xy 109.208031 -256.335102) (xy 109.220028 -256.283834)
			(xy 109.239711 -256.234999) (xy 109.266617 -256.18974) (xy 109.300117 -256.149119) (xy 109.339425 -256.114088)
			(xy 109.38362 -256.085468) (xy 109.431665 -256.063929) (xy 109.482436 -256.049977) (xy 109.534741 -256.043939)
			(xy 109.587355 -256.045956) (xy 109.639045 -256.05598) (xy 109.688598 -256.073778) (xy 109.734854 -256.098931)
			(xy 109.776728 -256.13085) (xy 109.81324 -256.168788) (xy 109.843532 -256.211854) (xy 109.866895 -256.259039)
			(xy 109.882781 -256.309238) (xy 109.890818 -256.361274) (xy 109.891322 -256.3876) (xy 110.153961 -256.3876)
			(xy 110.157991 -256.335102) (xy 110.169988 -256.283834) (xy 110.189671 -256.234999) (xy 110.216577 -256.18974)
			(xy 110.250077 -256.149119) (xy 110.289385 -256.114088) (xy 110.33358 -256.085468) (xy 110.381625 -256.063929)
			(xy 110.432396 -256.049977) (xy 110.484701 -256.043939) (xy 110.537315 -256.045956) (xy 110.589005 -256.05598)
			(xy 110.638558 -256.073778) (xy 110.684814 -256.098931) (xy 110.726688 -256.13085) (xy 110.7632 -256.168788)
			(xy 110.793492 -256.211854) (xy 110.816855 -256.259039) (xy 110.832741 -256.309238) (xy 110.840778 -256.361274)
			(xy 110.841282 -256.3876) (xy 111.103921 -256.3876) (xy 111.107951 -256.335102) (xy 111.119948 -256.283834)
			(xy 111.139631 -256.234999) (xy 111.166537 -256.18974) (xy 111.200037 -256.149119) (xy 111.239345 -256.114088)
			(xy 111.28354 -256.085468) (xy 111.331585 -256.063929) (xy 111.382356 -256.049977) (xy 111.434661 -256.043939)
			(xy 111.487275 -256.045956) (xy 111.538965 -256.05598) (xy 111.588518 -256.073778) (xy 111.634774 -256.098931)
			(xy 111.676648 -256.13085) (xy 111.71316 -256.168788) (xy 111.743452 -256.211854) (xy 111.766815 -256.259039)
			(xy 111.782701 -256.309238) (xy 111.790738 -256.361274) (xy 111.791242 -256.3876) (xy 112.053881 -256.3876)
			(xy 112.057911 -256.335102) (xy 112.069908 -256.283834) (xy 112.089591 -256.234999) (xy 112.116497 -256.18974)
			(xy 112.149997 -256.149119) (xy 112.189305 -256.114088) (xy 112.2335 -256.085468) (xy 112.281545 -256.063929)
			(xy 112.332316 -256.049977) (xy 112.384621 -256.043939) (xy 112.437235 -256.045956) (xy 112.488925 -256.05598)
			(xy 112.538478 -256.073778) (xy 112.584734 -256.098931) (xy 112.626608 -256.13085) (xy 112.66312 -256.168788)
			(xy 112.693412 -256.211854) (xy 112.716775 -256.259039) (xy 112.732661 -256.309238) (xy 112.740698 -256.361274)
			(xy 112.741202 -256.3876) (xy 113.004095 -256.3876) (xy 113.008125 -256.335102) (xy 113.020122 -256.283834)
			(xy 113.039805 -256.234999) (xy 113.066711 -256.18974) (xy 113.100211 -256.149119) (xy 113.139519 -256.114088)
			(xy 113.183714 -256.085468) (xy 113.231759 -256.063929) (xy 113.28253 -256.049977) (xy 113.334835 -256.043939)
			(xy 113.387449 -256.045956) (xy 113.439139 -256.05598) (xy 113.488692 -256.073778) (xy 113.534948 -256.098931)
			(xy 113.576822 -256.13085) (xy 113.613334 -256.168788) (xy 113.643626 -256.211854) (xy 113.666989 -256.259039)
			(xy 113.682875 -256.309238) (xy 113.690912 -256.361274) (xy 113.691416 -256.3876) (xy 113.954055 -256.3876)
			(xy 113.958085 -256.335102) (xy 113.970082 -256.283834) (xy 113.989765 -256.234999) (xy 114.016671 -256.18974)
			(xy 114.050171 -256.149119) (xy 114.089479 -256.114088) (xy 114.133674 -256.085468) (xy 114.181719 -256.063929)
			(xy 114.23249 -256.049977) (xy 114.284795 -256.043939) (xy 114.337409 -256.045956) (xy 114.389099 -256.05598)
			(xy 114.438652 -256.073778) (xy 114.484908 -256.098931) (xy 114.526782 -256.13085) (xy 114.563294 -256.168788)
			(xy 114.593586 -256.211854) (xy 114.616949 -256.259039) (xy 114.632835 -256.309238) (xy 114.640872 -256.361274)
			(xy 114.641376 -256.3876) (xy 114.904015 -256.3876) (xy 114.908045 -256.335102) (xy 114.920042 -256.283834)
			(xy 114.939725 -256.234999) (xy 114.966631 -256.18974) (xy 115.000131 -256.149119) (xy 115.039439 -256.114088)
			(xy 115.083634 -256.085468) (xy 115.131679 -256.063929) (xy 115.18245 -256.049977) (xy 115.234755 -256.043939)
			(xy 115.287369 -256.045956) (xy 115.339059 -256.05598) (xy 115.388612 -256.073778) (xy 115.434868 -256.098931)
			(xy 115.476742 -256.13085) (xy 115.513254 -256.168788) (xy 115.543546 -256.211854) (xy 115.566909 -256.259039)
			(xy 115.582795 -256.309238) (xy 115.590832 -256.361274) (xy 115.591336 -256.3876) (xy 115.853975 -256.3876)
			(xy 115.858005 -256.335102) (xy 115.870002 -256.283834) (xy 115.889685 -256.234999) (xy 115.916591 -256.18974)
			(xy 115.950091 -256.149119) (xy 115.989399 -256.114088) (xy 116.033594 -256.085468) (xy 116.081639 -256.063929)
			(xy 116.13241 -256.049977) (xy 116.184715 -256.043939) (xy 116.237329 -256.045956) (xy 116.289019 -256.05598)
			(xy 116.338572 -256.073778) (xy 116.384828 -256.098931) (xy 116.426702 -256.13085) (xy 116.463214 -256.168788)
			(xy 116.493506 -256.211854) (xy 116.516869 -256.259039) (xy 116.532755 -256.309238) (xy 116.540792 -256.361274)
			(xy 116.541296 -256.3876) (xy 116.540792 -256.413926) (xy 116.532755 -256.465962) (xy 116.528214 -256.48031)
			(xy 117.096797 -256.48031) (xy 117.100827 -256.427812) (xy 117.112824 -256.376544) (xy 117.132507 -256.327709)
			(xy 117.159413 -256.28245) (xy 117.192913 -256.241829) (xy 117.232221 -256.206798) (xy 117.276416 -256.178178)
			(xy 117.324461 -256.156639) (xy 117.375232 -256.142687) (xy 117.427537 -256.136649) (xy 117.480151 -256.138666)
			(xy 117.531841 -256.14869) (xy 117.581394 -256.166488) (xy 117.62765 -256.191641) (xy 117.669524 -256.22356)
			(xy 117.706036 -256.261498) (xy 117.736328 -256.304564) (xy 117.759691 -256.351749) (xy 117.775577 -256.401948)
			(xy 117.783614 -256.453984) (xy 117.784118 -256.48031) (xy 117.783614 -256.506636) (xy 117.775577 -256.558672)
			(xy 117.759691 -256.608871) (xy 117.747007 -256.634488) (xy 122.278914 -256.634488) (xy 122.282874 -256.585434)
			(xy 122.294651 -256.53765) (xy 122.313942 -256.492374) (xy 122.340245 -256.450778) (xy 122.37288 -256.413941)
			(xy 122.411001 -256.382816) (xy 122.453622 -256.358209) (xy 122.499638 -256.340757) (xy 122.547857 -256.330913)
			(xy 122.597032 -256.328932) (xy 122.645887 -256.334864) (xy 122.693158 -256.348556) (xy 122.73762 -256.369654)
			(xy 122.778123 -256.39761) (xy 122.813616 -256.431702) (xy 122.843181 -256.471046) (xy 122.866052 -256.514623)
			(xy 122.881636 -256.561304) (xy 122.889531 -256.609881) (xy 122.890026 -256.634488) (xy 124.159022 -256.634488)
			(xy 124.162982 -256.585434) (xy 124.174759 -256.53765) (xy 124.19405 -256.492374) (xy 124.220353 -256.450778)
			(xy 124.252988 -256.413941) (xy 124.291109 -256.382816) (xy 124.33373 -256.358209) (xy 124.379746 -256.340757)
			(xy 124.427965 -256.330913) (xy 124.47714 -256.328932) (xy 124.525995 -256.334864) (xy 124.573266 -256.348556)
			(xy 124.617728 -256.369654) (xy 124.658231 -256.39761) (xy 124.693724 -256.431702) (xy 124.723289 -256.471046)
			(xy 124.74616 -256.514623) (xy 124.761744 -256.561304) (xy 124.769639 -256.609881) (xy 124.770134 -256.634488)
			(xy 126.038876 -256.634488) (xy 126.042836 -256.585434) (xy 126.054613 -256.53765) (xy 126.073904 -256.492374)
			(xy 126.100207 -256.450778) (xy 126.132842 -256.413941) (xy 126.170963 -256.382816) (xy 126.213584 -256.358209)
			(xy 126.2596 -256.340757) (xy 126.307819 -256.330913) (xy 126.356994 -256.328932) (xy 126.405849 -256.334864)
			(xy 126.45312 -256.348556) (xy 126.497582 -256.369654) (xy 126.538085 -256.39761) (xy 126.573578 -256.431702)
			(xy 126.603143 -256.471046) (xy 126.626014 -256.514623) (xy 126.641598 -256.561304) (xy 126.649493 -256.609881)
			(xy 126.649988 -256.634488) (xy 127.918984 -256.634488) (xy 127.922944 -256.585434) (xy 127.934721 -256.53765)
			(xy 127.954012 -256.492374) (xy 127.980315 -256.450778) (xy 128.01295 -256.413941) (xy 128.051071 -256.382816)
			(xy 128.093692 -256.358209) (xy 128.139708 -256.340757) (xy 128.187927 -256.330913) (xy 128.237102 -256.328932)
			(xy 128.285957 -256.334864) (xy 128.333228 -256.348556) (xy 128.37769 -256.369654) (xy 128.418193 -256.39761)
			(xy 128.453686 -256.431702) (xy 128.483251 -256.471046) (xy 128.506122 -256.514623) (xy 128.521706 -256.561304)
			(xy 128.529601 -256.609881) (xy 128.530096 -256.634488) (xy 128.848607 -256.634488) (xy 128.852702 -256.58376)
			(xy 128.864881 -256.534346) (xy 128.884829 -256.487526) (xy 128.91203 -256.444512) (xy 128.945778 -256.406418)
			(xy 128.9852 -256.374231) (xy 129.029274 -256.348785) (xy 129.07686 -256.330738) (xy 129.126724 -256.320558)
			(xy 129.177576 -256.318509) (xy 129.228097 -256.324643) (xy 129.276981 -256.338803) (xy 129.32296 -256.36062)
			(xy 129.364844 -256.38953) (xy 129.401548 -256.424785) (xy 129.432121 -256.465471) (xy 129.455772 -256.510534)
			(xy 129.471888 -256.558808) (xy 129.480052 -256.609042) (xy 129.480564 -256.634488) (xy 129.480052 -256.659934)
			(xy 129.471888 -256.710168) (xy 129.455772 -256.758442) (xy 129.432121 -256.803505) (xy 129.401548 -256.844191)
			(xy 129.364844 -256.879446) (xy 129.32296 -256.908356) (xy 129.276981 -256.930173) (xy 129.228097 -256.944333)
			(xy 129.177576 -256.950467) (xy 129.126724 -256.948418) (xy 129.07686 -256.938238) (xy 129.029274 -256.920191)
			(xy 128.9852 -256.894745) (xy 128.945778 -256.862558) (xy 128.91203 -256.824464) (xy 128.884829 -256.78145)
			(xy 128.864881 -256.73463) (xy 128.852702 -256.685216) (xy 128.848607 -256.634488) (xy 128.530096 -256.634488)
			(xy 128.529601 -256.659095) (xy 128.521706 -256.707672) (xy 128.506122 -256.754353) (xy 128.483251 -256.79793)
			(xy 128.453686 -256.837274) (xy 128.418193 -256.871366) (xy 128.37769 -256.899322) (xy 128.333228 -256.92042)
			(xy 128.285957 -256.934112) (xy 128.237102 -256.940044) (xy 128.187927 -256.938063) (xy 128.139708 -256.928219)
			(xy 128.093692 -256.910767) (xy 128.051071 -256.88616) (xy 128.01295 -256.855035) (xy 127.980315 -256.818198)
			(xy 127.954012 -256.776602) (xy 127.934721 -256.731326) (xy 127.922944 -256.683542) (xy 127.918984 -256.634488)
			(xy 126.649988 -256.634488) (xy 126.649493 -256.659095) (xy 126.641598 -256.707672) (xy 126.626014 -256.754353)
			(xy 126.603143 -256.79793) (xy 126.573578 -256.837274) (xy 126.538085 -256.871366) (xy 126.497582 -256.899322)
			(xy 126.45312 -256.92042) (xy 126.405849 -256.934112) (xy 126.356994 -256.940044) (xy 126.307819 -256.938063)
			(xy 126.2596 -256.928219) (xy 126.213584 -256.910767) (xy 126.170963 -256.88616) (xy 126.132842 -256.855035)
			(xy 126.100207 -256.818198) (xy 126.073904 -256.776602) (xy 126.054613 -256.731326) (xy 126.042836 -256.683542)
			(xy 126.038876 -256.634488) (xy 124.770134 -256.634488) (xy 124.769639 -256.659095) (xy 124.761744 -256.707672)
			(xy 124.74616 -256.754353) (xy 124.723289 -256.79793) (xy 124.693724 -256.837274) (xy 124.658231 -256.871366)
			(xy 124.617728 -256.899322) (xy 124.573266 -256.92042) (xy 124.525995 -256.934112) (xy 124.47714 -256.940044)
			(xy 124.427965 -256.938063) (xy 124.379746 -256.928219) (xy 124.33373 -256.910767) (xy 124.291109 -256.88616)
			(xy 124.252988 -256.855035) (xy 124.220353 -256.818198) (xy 124.19405 -256.776602) (xy 124.174759 -256.731326)
			(xy 124.162982 -256.683542) (xy 124.159022 -256.634488) (xy 122.890026 -256.634488) (xy 122.889531 -256.659095)
			(xy 122.881636 -256.707672) (xy 122.866052 -256.754353) (xy 122.843181 -256.79793) (xy 122.813616 -256.837274)
			(xy 122.778123 -256.871366) (xy 122.73762 -256.899322) (xy 122.693158 -256.92042) (xy 122.645887 -256.934112)
			(xy 122.597032 -256.940044) (xy 122.547857 -256.938063) (xy 122.499638 -256.928219) (xy 122.453622 -256.910767)
			(xy 122.411001 -256.88616) (xy 122.37288 -256.855035) (xy 122.340245 -256.818198) (xy 122.313942 -256.776602)
			(xy 122.294651 -256.731326) (xy 122.282874 -256.683542) (xy 122.278914 -256.634488) (xy 117.747007 -256.634488)
			(xy 117.736328 -256.656056) (xy 117.706036 -256.699122) (xy 117.669524 -256.73706) (xy 117.62765 -256.768979)
			(xy 117.581394 -256.794132) (xy 117.531841 -256.81193) (xy 117.480151 -256.821954) (xy 117.427537 -256.823971)
			(xy 117.375232 -256.817933) (xy 117.324461 -256.803981) (xy 117.276416 -256.782442) (xy 117.232221 -256.753822)
			(xy 117.192913 -256.718791) (xy 117.159413 -256.67817) (xy 117.132507 -256.632911) (xy 117.112824 -256.584076)
			(xy 117.100827 -256.532808) (xy 117.096797 -256.48031) (xy 116.528214 -256.48031) (xy 116.516869 -256.516161)
			(xy 116.493506 -256.563346) (xy 116.463214 -256.606412) (xy 116.426702 -256.64435) (xy 116.384828 -256.676269)
			(xy 116.338572 -256.701422) (xy 116.289019 -256.71922) (xy 116.237329 -256.729244) (xy 116.184715 -256.731261)
			(xy 116.13241 -256.725223) (xy 116.081639 -256.711271) (xy 116.033594 -256.689732) (xy 115.989399 -256.661112)
			(xy 115.950091 -256.626081) (xy 115.916591 -256.58546) (xy 115.889685 -256.540201) (xy 115.870002 -256.491366)
			(xy 115.858005 -256.440098) (xy 115.853975 -256.3876) (xy 115.591336 -256.3876) (xy 115.590832 -256.413926)
			(xy 115.582795 -256.465962) (xy 115.566909 -256.516161) (xy 115.543546 -256.563346) (xy 115.513254 -256.606412)
			(xy 115.476742 -256.64435) (xy 115.434868 -256.676269) (xy 115.388612 -256.701422) (xy 115.339059 -256.71922)
			(xy 115.287369 -256.729244) (xy 115.234755 -256.731261) (xy 115.18245 -256.725223) (xy 115.131679 -256.711271)
			(xy 115.083634 -256.689732) (xy 115.039439 -256.661112) (xy 115.000131 -256.626081) (xy 114.966631 -256.58546)
			(xy 114.939725 -256.540201) (xy 114.920042 -256.491366) (xy 114.908045 -256.440098) (xy 114.904015 -256.3876)
			(xy 114.641376 -256.3876) (xy 114.640872 -256.413926) (xy 114.632835 -256.465962) (xy 114.616949 -256.516161)
			(xy 114.593586 -256.563346) (xy 114.563294 -256.606412) (xy 114.526782 -256.64435) (xy 114.484908 -256.676269)
			(xy 114.438652 -256.701422) (xy 114.389099 -256.71922) (xy 114.337409 -256.729244) (xy 114.284795 -256.731261)
			(xy 114.23249 -256.725223) (xy 114.181719 -256.711271) (xy 114.133674 -256.689732) (xy 114.089479 -256.661112)
			(xy 114.050171 -256.626081) (xy 114.016671 -256.58546) (xy 113.989765 -256.540201) (xy 113.970082 -256.491366)
			(xy 113.958085 -256.440098) (xy 113.954055 -256.3876) (xy 113.691416 -256.3876) (xy 113.690912 -256.413926)
			(xy 113.682875 -256.465962) (xy 113.666989 -256.516161) (xy 113.643626 -256.563346) (xy 113.613334 -256.606412)
			(xy 113.576822 -256.64435) (xy 113.534948 -256.676269) (xy 113.488692 -256.701422) (xy 113.439139 -256.71922)
			(xy 113.387449 -256.729244) (xy 113.334835 -256.731261) (xy 113.28253 -256.725223) (xy 113.231759 -256.711271)
			(xy 113.183714 -256.689732) (xy 113.139519 -256.661112) (xy 113.100211 -256.626081) (xy 113.066711 -256.58546)
			(xy 113.039805 -256.540201) (xy 113.020122 -256.491366) (xy 113.008125 -256.440098) (xy 113.004095 -256.3876)
			(xy 112.741202 -256.3876) (xy 112.740698 -256.413926) (xy 112.732661 -256.465962) (xy 112.716775 -256.516161)
			(xy 112.693412 -256.563346) (xy 112.66312 -256.606412) (xy 112.626608 -256.64435) (xy 112.584734 -256.676269)
			(xy 112.538478 -256.701422) (xy 112.488925 -256.71922) (xy 112.437235 -256.729244) (xy 112.384621 -256.731261)
			(xy 112.332316 -256.725223) (xy 112.281545 -256.711271) (xy 112.2335 -256.689732) (xy 112.189305 -256.661112)
			(xy 112.149997 -256.626081) (xy 112.116497 -256.58546) (xy 112.089591 -256.540201) (xy 112.069908 -256.491366)
			(xy 112.057911 -256.440098) (xy 112.053881 -256.3876) (xy 111.791242 -256.3876) (xy 111.790738 -256.413926)
			(xy 111.782701 -256.465962) (xy 111.766815 -256.516161) (xy 111.743452 -256.563346) (xy 111.71316 -256.606412)
			(xy 111.676648 -256.64435) (xy 111.634774 -256.676269) (xy 111.588518 -256.701422) (xy 111.538965 -256.71922)
			(xy 111.487275 -256.729244) (xy 111.434661 -256.731261) (xy 111.382356 -256.725223) (xy 111.331585 -256.711271)
			(xy 111.28354 -256.689732) (xy 111.239345 -256.661112) (xy 111.200037 -256.626081) (xy 111.166537 -256.58546)
			(xy 111.139631 -256.540201) (xy 111.119948 -256.491366) (xy 111.107951 -256.440098) (xy 111.103921 -256.3876)
			(xy 110.841282 -256.3876) (xy 110.840778 -256.413926) (xy 110.832741 -256.465962) (xy 110.816855 -256.516161)
			(xy 110.793492 -256.563346) (xy 110.7632 -256.606412) (xy 110.726688 -256.64435) (xy 110.684814 -256.676269)
			(xy 110.638558 -256.701422) (xy 110.589005 -256.71922) (xy 110.537315 -256.729244) (xy 110.484701 -256.731261)
			(xy 110.432396 -256.725223) (xy 110.381625 -256.711271) (xy 110.33358 -256.689732) (xy 110.289385 -256.661112)
			(xy 110.250077 -256.626081) (xy 110.216577 -256.58546) (xy 110.189671 -256.540201) (xy 110.169988 -256.491366)
			(xy 110.157991 -256.440098) (xy 110.153961 -256.3876) (xy 109.891322 -256.3876) (xy 109.890818 -256.413926)
			(xy 109.882781 -256.465962) (xy 109.866895 -256.516161) (xy 109.843532 -256.563346) (xy 109.81324 -256.606412)
			(xy 109.776728 -256.64435) (xy 109.734854 -256.676269) (xy 109.688598 -256.701422) (xy 109.639045 -256.71922)
			(xy 109.587355 -256.729244) (xy 109.534741 -256.731261) (xy 109.482436 -256.725223) (xy 109.431665 -256.711271)
			(xy 109.38362 -256.689732) (xy 109.339425 -256.661112) (xy 109.300117 -256.626081) (xy 109.266617 -256.58546)
			(xy 109.239711 -256.540201) (xy 109.220028 -256.491366) (xy 109.208031 -256.440098) (xy 109.204001 -256.3876)
			(xy 108.941362 -256.3876) (xy 108.940858 -256.413926) (xy 108.932821 -256.465962) (xy 108.916935 -256.516161)
			(xy 108.893572 -256.563346) (xy 108.86328 -256.606412) (xy 108.826768 -256.64435) (xy 108.784894 -256.676269)
			(xy 108.738638 -256.701422) (xy 108.689085 -256.71922) (xy 108.637395 -256.729244) (xy 108.584781 -256.731261)
			(xy 108.532476 -256.725223) (xy 108.481705 -256.711271) (xy 108.43366 -256.689732) (xy 108.389465 -256.661112)
			(xy 108.350157 -256.626081) (xy 108.316657 -256.58546) (xy 108.289751 -256.540201) (xy 108.270068 -256.491366)
			(xy 108.258071 -256.440098) (xy 108.254041 -256.3876) (xy 107.991402 -256.3876) (xy 107.990898 -256.413926)
			(xy 107.982861 -256.465962) (xy 107.966975 -256.516161) (xy 107.943612 -256.563346) (xy 107.91332 -256.606412)
			(xy 107.876808 -256.64435) (xy 107.834934 -256.676269) (xy 107.788678 -256.701422) (xy 107.739125 -256.71922)
			(xy 107.687435 -256.729244) (xy 107.634821 -256.731261) (xy 107.582516 -256.725223) (xy 107.531745 -256.711271)
			(xy 107.4837 -256.689732) (xy 107.439505 -256.661112) (xy 107.400197 -256.626081) (xy 107.366697 -256.58546)
			(xy 107.339791 -256.540201) (xy 107.320108 -256.491366) (xy 107.308111 -256.440098) (xy 107.304081 -256.3876)
			(xy 106.735928 -256.3876) (xy 106.738182 -256.39418) (xy 106.747445 -256.44609) (xy 106.74858 -256.472436)
			(xy 106.74858 -256.478278) (xy 106.74858 -256.48031) (xy 106.747974 -256.509723) (xy 106.737942 -256.567688)
			(xy 106.718173 -256.623093) (xy 106.689246 -256.674316) (xy 106.67111 -256.69748) (xy 106.67111 -256.697734)
			(xy 106.665328 -256.705392) (xy 106.659445 -256.72364) (xy 106.660709 -256.742772) (xy 106.664506 -256.751582)
			(xy 106.702606 -256.832354) (xy 106.707432 -256.840482) (xy 106.714508 -256.849315) (xy 106.73429 -256.86025)
			(xy 106.745532 -256.861564) (xy 107.233212 -256.861564) (xy 107.243055 -256.862089) (xy 107.261234 -256.869657)
			(xy 107.268518 -256.876296) (xy 107.3404 -256.948178) (xy 107.340908 -256.948686) (xy 107.348288 -256.955272)
			(xy 107.366587 -256.962733) (xy 107.376468 -256.963164) (xy 108.935012 -256.963164) (xy 108.944855 -256.963689)
			(xy 108.963034 -256.971257) (xy 108.970318 -256.977896) (xy 109.737652 -257.74523) (xy 110.988351 -257.74523)
			(xy 110.992381 -257.692732) (xy 111.004378 -257.641464) (xy 111.024061 -257.592629) (xy 111.050967 -257.54737)
			(xy 111.084467 -257.506749) (xy 111.123775 -257.471718) (xy 111.16797 -257.443098) (xy 111.216015 -257.421559)
			(xy 111.266786 -257.407607) (xy 111.319091 -257.401569) (xy 111.371705 -257.403586) (xy 111.423395 -257.41361)
			(xy 111.472948 -257.431408) (xy 111.519204 -257.456561) (xy 111.561078 -257.48848) (xy 111.59759 -257.526418)
			(xy 111.627882 -257.569484) (xy 111.651245 -257.616669) (xy 111.667131 -257.666868) (xy 111.675168 -257.718904)
			(xy 111.675672 -257.74523) (xy 113.238283 -257.74523) (xy 113.242313 -257.692732) (xy 113.25431 -257.641464)
			(xy 113.273993 -257.592629) (xy 113.300899 -257.54737) (xy 113.334399 -257.506749) (xy 113.373707 -257.471718)
			(xy 113.417902 -257.443098) (xy 113.465947 -257.421559) (xy 113.516718 -257.407607) (xy 113.569023 -257.401569)
			(xy 113.621637 -257.403586) (xy 113.673327 -257.41361) (xy 113.72288 -257.431408) (xy 113.769136 -257.456561)
			(xy 113.81101 -257.48848) (xy 113.847522 -257.526418) (xy 113.877814 -257.569484) (xy 113.901177 -257.616669)
			(xy 113.917063 -257.666868) (xy 113.9251 -257.718904) (xy 113.925604 -257.74523) (xy 115.838227 -257.74523)
			(xy 115.842257 -257.692732) (xy 115.854254 -257.641464) (xy 115.873937 -257.592629) (xy 115.900843 -257.54737)
			(xy 115.934343 -257.506749) (xy 115.973651 -257.471718) (xy 116.017846 -257.443098) (xy 116.065891 -257.421559)
			(xy 116.116662 -257.407607) (xy 116.168967 -257.401569) (xy 116.221581 -257.403586) (xy 116.273271 -257.41361)
			(xy 116.319656 -257.43027) (xy 117.096797 -257.43027) (xy 117.100827 -257.377772) (xy 117.112824 -257.326504)
			(xy 117.132507 -257.277669) (xy 117.159413 -257.23241) (xy 117.192913 -257.191789) (xy 117.232221 -257.156758)
			(xy 117.276416 -257.128138) (xy 117.324461 -257.106599) (xy 117.375232 -257.092647) (xy 117.427537 -257.086609)
			(xy 117.480151 -257.088626) (xy 117.531841 -257.09865) (xy 117.581394 -257.116448) (xy 117.62765 -257.141601)
			(xy 117.669524 -257.17352) (xy 117.706036 -257.211458) (xy 117.736328 -257.254524) (xy 117.759691 -257.301709)
			(xy 117.775577 -257.351908) (xy 117.783614 -257.403944) (xy 117.784118 -257.43027) (xy 117.783614 -257.456596)
			(xy 117.775577 -257.508632) (xy 117.759691 -257.558831) (xy 117.736328 -257.606016) (xy 117.706036 -257.649082)
			(xy 117.669524 -257.68702) (xy 117.62765 -257.718939) (xy 117.581394 -257.744092) (xy 117.531841 -257.76189)
			(xy 117.480151 -257.771914) (xy 117.427537 -257.773931) (xy 117.375232 -257.767893) (xy 117.324461 -257.753941)
			(xy 117.276416 -257.732402) (xy 117.232221 -257.703782) (xy 117.192913 -257.668751) (xy 117.159413 -257.62813)
			(xy 117.132507 -257.582871) (xy 117.112824 -257.534036) (xy 117.100827 -257.482768) (xy 117.096797 -257.43027)
			(xy 116.319656 -257.43027) (xy 116.322824 -257.431408) (xy 116.36908 -257.456561) (xy 116.410954 -257.48848)
			(xy 116.447466 -257.526418) (xy 116.477758 -257.569484) (xy 116.501121 -257.616669) (xy 116.517007 -257.666868)
			(xy 116.525044 -257.718904) (xy 116.525548 -257.74523) (xy 116.525044 -257.771556) (xy 116.517007 -257.823592)
			(xy 116.501121 -257.873791) (xy 116.477758 -257.920976) (xy 116.471132 -257.930396) (xy 120.865649 -257.930396)
			(xy 120.869679 -257.877898) (xy 120.881676 -257.82663) (xy 120.901359 -257.777795) (xy 120.928265 -257.732536)
			(xy 120.961765 -257.691915) (xy 121.001073 -257.656884) (xy 121.045268 -257.628264) (xy 121.093313 -257.606725)
			(xy 121.144084 -257.592773) (xy 121.196389 -257.586735) (xy 121.249003 -257.588752) (xy 121.300693 -257.598776)
			(xy 121.350246 -257.616574) (xy 121.396502 -257.641727) (xy 121.438376 -257.673646) (xy 121.474888 -257.711584)
			(xy 121.50518 -257.75465) (xy 121.528543 -257.801835) (xy 121.544429 -257.852034) (xy 121.552466 -257.90407)
			(xy 121.55297 -257.930396) (xy 122.791223 -257.930396) (xy 122.795253 -257.877898) (xy 122.80725 -257.82663)
			(xy 122.826933 -257.777795) (xy 122.853839 -257.732536) (xy 122.887339 -257.691915) (xy 122.926647 -257.656884)
			(xy 122.970842 -257.628264) (xy 123.018887 -257.606725) (xy 123.069658 -257.592773) (xy 123.121963 -257.586735)
			(xy 123.174577 -257.588752) (xy 123.226267 -257.598776) (xy 123.27582 -257.616574) (xy 123.322076 -257.641727)
			(xy 123.36395 -257.673646) (xy 123.400462 -257.711584) (xy 123.430754 -257.75465) (xy 123.454117 -257.801835)
			(xy 123.470003 -257.852034) (xy 123.47804 -257.90407) (xy 123.478544 -257.930396) (xy 124.696223 -257.930396)
			(xy 124.700253 -257.877898) (xy 124.71225 -257.82663) (xy 124.731933 -257.777795) (xy 124.758839 -257.732536)
			(xy 124.792339 -257.691915) (xy 124.831647 -257.656884) (xy 124.875842 -257.628264) (xy 124.923887 -257.606725)
			(xy 124.974658 -257.592773) (xy 125.026963 -257.586735) (xy 125.079577 -257.588752) (xy 125.131267 -257.598776)
			(xy 125.18082 -257.616574) (xy 125.227076 -257.641727) (xy 125.26895 -257.673646) (xy 125.305462 -257.711584)
			(xy 125.335754 -257.75465) (xy 125.359117 -257.801835) (xy 125.375003 -257.852034) (xy 125.38304 -257.90407)
			(xy 125.383544 -257.930396) (xy 125.38304 -257.956722) (xy 125.375003 -258.008758) (xy 125.359117 -258.058957)
			(xy 125.335754 -258.106142) (xy 125.305462 -258.149208) (xy 125.26895 -258.187146) (xy 125.227076 -258.219065)
			(xy 125.18082 -258.244218) (xy 125.131267 -258.262016) (xy 125.079577 -258.27204) (xy 125.026963 -258.274057)
			(xy 124.974658 -258.268019) (xy 124.923887 -258.254067) (xy 124.875842 -258.232528) (xy 124.831647 -258.203908)
			(xy 124.792339 -258.168877) (xy 124.758839 -258.128256) (xy 124.731933 -258.082997) (xy 124.71225 -258.034162)
			(xy 124.700253 -257.982894) (xy 124.696223 -257.930396) (xy 123.478544 -257.930396) (xy 123.47804 -257.956722)
			(xy 123.470003 -258.008758) (xy 123.454117 -258.058957) (xy 123.430754 -258.106142) (xy 123.400462 -258.149208)
			(xy 123.36395 -258.187146) (xy 123.322076 -258.219065) (xy 123.27582 -258.244218) (xy 123.226267 -258.262016)
			(xy 123.174577 -258.27204) (xy 123.121963 -258.274057) (xy 123.069658 -258.268019) (xy 123.018887 -258.254067)
			(xy 122.970842 -258.232528) (xy 122.926647 -258.203908) (xy 122.887339 -258.168877) (xy 122.853839 -258.128256)
			(xy 122.826933 -258.082997) (xy 122.80725 -258.034162) (xy 122.795253 -257.982894) (xy 122.791223 -257.930396)
			(xy 121.55297 -257.930396) (xy 121.552466 -257.956722) (xy 121.544429 -258.008758) (xy 121.528543 -258.058957)
			(xy 121.50518 -258.106142) (xy 121.474888 -258.149208) (xy 121.438376 -258.187146) (xy 121.396502 -258.219065)
			(xy 121.350246 -258.244218) (xy 121.300693 -258.262016) (xy 121.249003 -258.27204) (xy 121.196389 -258.274057)
			(xy 121.144084 -258.268019) (xy 121.093313 -258.254067) (xy 121.045268 -258.232528) (xy 121.001073 -258.203908)
			(xy 120.961765 -258.168877) (xy 120.928265 -258.128256) (xy 120.901359 -258.082997) (xy 120.881676 -258.034162)
			(xy 120.869679 -257.982894) (xy 120.865649 -257.930396) (xy 116.471132 -257.930396) (xy 116.447466 -257.964042)
			(xy 116.410954 -258.00198) (xy 116.36908 -258.033899) (xy 116.322824 -258.059052) (xy 116.273271 -258.07685)
			(xy 116.221581 -258.086874) (xy 116.168967 -258.088891) (xy 116.116662 -258.082853) (xy 116.065891 -258.068901)
			(xy 116.017846 -258.047362) (xy 115.973651 -258.018742) (xy 115.934343 -257.983711) (xy 115.900843 -257.94309)
			(xy 115.873937 -257.897831) (xy 115.854254 -257.848996) (xy 115.842257 -257.797728) (xy 115.838227 -257.74523)
			(xy 113.925604 -257.74523) (xy 113.9251 -257.771556) (xy 113.917063 -257.823592) (xy 113.901177 -257.873791)
			(xy 113.877814 -257.920976) (xy 113.847522 -257.964042) (xy 113.81101 -258.00198) (xy 113.769136 -258.033899)
			(xy 113.72288 -258.059052) (xy 113.673327 -258.07685) (xy 113.621637 -258.086874) (xy 113.569023 -258.088891)
			(xy 113.516718 -258.082853) (xy 113.465947 -258.068901) (xy 113.417902 -258.047362) (xy 113.373707 -258.018742)
			(xy 113.334399 -257.983711) (xy 113.300899 -257.94309) (xy 113.273993 -257.897831) (xy 113.25431 -257.848996)
			(xy 113.242313 -257.797728) (xy 113.238283 -257.74523) (xy 111.675672 -257.74523) (xy 111.675168 -257.771556)
			(xy 111.667131 -257.823592) (xy 111.651245 -257.873791) (xy 111.627882 -257.920976) (xy 111.59759 -257.964042)
			(xy 111.561078 -258.00198) (xy 111.519204 -258.033899) (xy 111.472948 -258.059052) (xy 111.423395 -258.07685)
			(xy 111.371705 -258.086874) (xy 111.319091 -258.088891) (xy 111.266786 -258.082853) (xy 111.216015 -258.068901)
			(xy 111.16797 -258.047362) (xy 111.123775 -258.018742) (xy 111.084467 -257.983711) (xy 111.050967 -257.94309)
			(xy 111.024061 -257.897831) (xy 111.004378 -257.848996) (xy 110.992381 -257.797728) (xy 110.988351 -257.74523)
			(xy 109.737652 -257.74523) (xy 110.236 -258.243578) (xy 110.236508 -258.244086) (xy 110.243888 -258.250672)
			(xy 110.262187 -258.258133) (xy 110.272068 -258.258564) (xy 111.475012 -258.258564) (xy 111.484855 -258.259089)
			(xy 111.503034 -258.266657) (xy 111.510318 -258.273296) (xy 111.617252 -258.38023) (xy 117.096797 -258.38023)
			(xy 117.100827 -258.327732) (xy 117.112824 -258.276464) (xy 117.132507 -258.227629) (xy 117.159413 -258.18237)
			(xy 117.192913 -258.141749) (xy 117.232221 -258.106718) (xy 117.276416 -258.078098) (xy 117.324461 -258.056559)
			(xy 117.375232 -258.042607) (xy 117.427537 -258.036569) (xy 117.480151 -258.038586) (xy 117.531841 -258.04861)
			(xy 117.581394 -258.066408) (xy 117.62765 -258.091561) (xy 117.669524 -258.12348) (xy 117.706036 -258.161418)
			(xy 117.736328 -258.204484) (xy 117.759691 -258.251669) (xy 117.775577 -258.301868) (xy 117.783614 -258.353904)
			(xy 117.784118 -258.38023) (xy 117.783614 -258.406556) (xy 117.775577 -258.458592) (xy 117.759691 -258.508791)
			(xy 117.736328 -258.555976) (xy 117.706036 -258.599042) (xy 117.669524 -258.63698) (xy 117.62765 -258.668899)
			(xy 117.581394 -258.694052) (xy 117.531841 -258.71185) (xy 117.480151 -258.721874) (xy 117.427537 -258.723891)
			(xy 117.375232 -258.717853) (xy 117.324461 -258.703901) (xy 117.276416 -258.682362) (xy 117.232221 -258.653742)
			(xy 117.192913 -258.618711) (xy 117.159413 -258.57809) (xy 117.132507 -258.532831) (xy 117.112824 -258.483996)
			(xy 117.100827 -258.432728) (xy 117.096797 -258.38023) (xy 111.617252 -258.38023) (xy 112.3696 -259.132578)
			(xy 112.370108 -259.133086) (xy 112.377488 -259.139672) (xy 112.395787 -259.147133) (xy 112.405668 -259.147564)
			(xy 113.21669 -259.147564) (xy 113.225889 -259.147164) (xy 113.243109 -259.140678) (xy 113.256958 -259.128564)
			(xy 113.261648 -259.12064) (xy 113.302542 -259.042916) (xy 113.306547 -259.034552) (xy 113.308862 -259.016169)
			(xy 113.304451 -258.998174) (xy 113.299494 -258.990338) (xy 113.285148 -258.968716) (xy 113.262443 -258.922059)
			(xy 113.24703 -258.872513) (xy 113.23926 -258.82121) (xy 113.238788 -258.795266) (xy 113.238788 -258.788154)
			(xy 113.239836 -258.761534) (xy 113.249142 -258.70908) (xy 113.266436 -258.658693) (xy 113.291305 -258.611581)
			(xy 113.323151 -258.568875) (xy 113.36121 -258.531599) (xy 113.404569 -258.500649) (xy 113.452188 -258.476765)
			(xy 113.502924 -258.460523) (xy 113.55556 -258.45231) (xy 113.582196 -258.451858) (xy 113.608838 -258.452367)
			(xy 113.66148 -258.460609) (xy 113.712219 -258.476879) (xy 113.759837 -258.500789) (xy 113.803193 -258.531763)
			(xy 113.841246 -258.56906) (xy 113.873085 -258.611786) (xy 113.897945 -258.658914) (xy 113.91523 -258.709316)
			(xy 113.924527 -258.761783) (xy 113.925604 -258.788408) (xy 113.925604 -258.79298) (xy 113.925604 -258.795266)
			(xy 113.925128 -258.821209) (xy 113.917328 -258.872504) (xy 113.901916 -258.922047) (xy 113.87924 -258.968715)
			(xy 113.864898 -258.990338) (xy 113.860007 -258.998202) (xy 113.855635 -259.016183) (xy 113.85788 -259.034551)
			(xy 113.86185 -259.042916) (xy 113.902744 -259.12064) (xy 113.907406 -259.128589) (xy 113.921242 -259.14074)
			(xy 113.938493 -259.14718) (xy 113.947702 -259.147564) (xy 115.816634 -259.147564) (xy 115.825829 -259.147157)
			(xy 115.843037 -259.140662) (xy 115.856874 -259.128544) (xy 115.861592 -259.12064) (xy 115.902486 -259.042916)
			(xy 115.906488 -259.034552) (xy 115.908802 -259.016169) (xy 115.904394 -258.998174) (xy 115.899438 -258.990338)
			(xy 115.88509 -258.968717) (xy 115.862383 -258.92206) (xy 115.846967 -258.872514) (xy 115.839196 -258.821211)
			(xy 115.838732 -258.795266) (xy 115.838732 -258.788154) (xy 115.839781 -258.761535) (xy 115.849086 -258.709084)
			(xy 115.866381 -258.6587) (xy 115.891251 -258.611591) (xy 115.923097 -258.568889) (xy 115.961157 -258.531617)
			(xy 116.004517 -258.500671) (xy 116.052135 -258.476794) (xy 116.102871 -258.460557) (xy 116.155505 -258.452351)
			(xy 116.18214 -258.451858) (xy 116.209124 -258.45239) (xy 116.262427 -258.460838) (xy 116.313753 -258.477519)
			(xy 116.361837 -258.502022) (xy 116.405498 -258.533745) (xy 116.443659 -258.571907) (xy 116.475381 -258.615568)
			(xy 116.499884 -258.663653) (xy 116.516564 -258.714979) (xy 116.52501 -258.768282) (xy 116.525548 -258.795266)
			(xy 116.524991 -258.82335) (xy 116.523842 -258.830318) (xy 120.865649 -258.830318) (xy 120.869679 -258.77782)
			(xy 120.881676 -258.726552) (xy 120.901359 -258.677717) (xy 120.928265 -258.632458) (xy 120.961765 -258.591837)
			(xy 121.001073 -258.556806) (xy 121.045268 -258.528186) (xy 121.093313 -258.506647) (xy 121.144084 -258.492695)
			(xy 121.196389 -258.486657) (xy 121.249003 -258.488674) (xy 121.300693 -258.498698) (xy 121.350246 -258.516496)
			(xy 121.396502 -258.541649) (xy 121.438376 -258.573568) (xy 121.474888 -258.611506) (xy 121.50518 -258.654572)
			(xy 121.528543 -258.701757) (xy 121.544429 -258.751956) (xy 121.552466 -258.803992) (xy 121.55297 -258.830318)
			(xy 122.791223 -258.830318) (xy 122.795253 -258.77782) (xy 122.80725 -258.726552) (xy 122.826933 -258.677717)
			(xy 122.853839 -258.632458) (xy 122.887339 -258.591837) (xy 122.926647 -258.556806) (xy 122.970842 -258.528186)
			(xy 123.018887 -258.506647) (xy 123.069658 -258.492695) (xy 123.121963 -258.486657) (xy 123.174577 -258.488674)
			(xy 123.226267 -258.498698) (xy 123.27582 -258.516496) (xy 123.322076 -258.541649) (xy 123.36395 -258.573568)
			(xy 123.400462 -258.611506) (xy 123.430754 -258.654572) (xy 123.454117 -258.701757) (xy 123.470003 -258.751956)
			(xy 123.47804 -258.803992) (xy 123.478544 -258.830318) (xy 124.696223 -258.830318) (xy 124.700253 -258.77782)
			(xy 124.71225 -258.726552) (xy 124.731933 -258.677717) (xy 124.758839 -258.632458) (xy 124.792339 -258.591837)
			(xy 124.831647 -258.556806) (xy 124.875842 -258.528186) (xy 124.923887 -258.506647) (xy 124.974658 -258.492695)
			(xy 125.026963 -258.486657) (xy 125.079577 -258.488674) (xy 125.131267 -258.498698) (xy 125.18082 -258.516496)
			(xy 125.227076 -258.541649) (xy 125.26895 -258.573568) (xy 125.305462 -258.611506) (xy 125.335754 -258.654572)
			(xy 125.359117 -258.701757) (xy 125.375003 -258.751956) (xy 125.38304 -258.803992) (xy 125.383544 -258.830318)
			(xy 125.38304 -258.856644) (xy 125.375003 -258.90868) (xy 125.359117 -258.958879) (xy 125.335754 -259.006064)
			(xy 125.305462 -259.04913) (xy 125.26895 -259.087068) (xy 125.227076 -259.118987) (xy 125.18082 -259.14414)
			(xy 125.131267 -259.161938) (xy 125.079577 -259.171962) (xy 125.026963 -259.173979) (xy 124.974658 -259.167941)
			(xy 124.923887 -259.153989) (xy 124.875842 -259.13245) (xy 124.831647 -259.10383) (xy 124.792339 -259.068799)
			(xy 124.758839 -259.028178) (xy 124.731933 -258.982919) (xy 124.71225 -258.934084) (xy 124.700253 -258.882816)
			(xy 124.696223 -258.830318) (xy 123.478544 -258.830318) (xy 123.47804 -258.856644) (xy 123.470003 -258.90868)
			(xy 123.454117 -258.958879) (xy 123.430754 -259.006064) (xy 123.400462 -259.04913) (xy 123.36395 -259.087068)
			(xy 123.322076 -259.118987) (xy 123.27582 -259.14414) (xy 123.226267 -259.161938) (xy 123.174577 -259.171962)
			(xy 123.121963 -259.173979) (xy 123.069658 -259.167941) (xy 123.018887 -259.153989) (xy 122.970842 -259.13245)
			(xy 122.926647 -259.10383) (xy 122.887339 -259.068799) (xy 122.853839 -259.028178) (xy 122.826933 -258.982919)
			(xy 122.80725 -258.934084) (xy 122.795253 -258.882816) (xy 122.791223 -258.830318) (xy 121.55297 -258.830318)
			(xy 121.552466 -258.856644) (xy 121.544429 -258.90868) (xy 121.528543 -258.958879) (xy 121.50518 -259.006064)
			(xy 121.474888 -259.04913) (xy 121.438376 -259.087068) (xy 121.396502 -259.118987) (xy 121.350246 -259.14414)
			(xy 121.300693 -259.161938) (xy 121.249003 -259.171962) (xy 121.196389 -259.173979) (xy 121.144084 -259.167941)
			(xy 121.093313 -259.153989) (xy 121.045268 -259.13245) (xy 121.001073 -259.10383) (xy 120.961765 -259.068799)
			(xy 120.928265 -259.028178) (xy 120.901359 -258.982919) (xy 120.881676 -258.934084) (xy 120.869679 -258.882816)
			(xy 120.865649 -258.830318) (xy 116.523842 -258.830318) (xy 116.515854 -258.878771) (xy 116.497818 -258.931965)
			(xy 116.471365 -258.981515) (xy 116.437199 -259.026098) (xy 116.41709 -259.04571) (xy 116.40947 -259.052822)
			(xy 116.401342 -259.07111) (xy 116.399818 -259.152898) (xy 116.399893 -259.159451) (xy 116.402985 -259.172181)
			(xy 116.405914 -259.178044) (xy 116.40947 -259.184648) (xy 116.555266 -259.330444) (xy 117.096797 -259.330444)
			(xy 117.100827 -259.277946) (xy 117.112824 -259.226678) (xy 117.132507 -259.177843) (xy 117.159413 -259.132584)
			(xy 117.192913 -259.091963) (xy 117.232221 -259.056932) (xy 117.276416 -259.028312) (xy 117.324461 -259.006773)
			(xy 117.375232 -258.992821) (xy 117.427537 -258.986783) (xy 117.480151 -258.9888) (xy 117.531841 -258.998824)
			(xy 117.581394 -259.016622) (xy 117.62765 -259.041775) (xy 117.669524 -259.073694) (xy 117.706036 -259.111632)
			(xy 117.736328 -259.154698) (xy 117.759691 -259.201883) (xy 117.775577 -259.252082) (xy 117.783614 -259.304118)
			(xy 117.784118 -259.330444) (xy 117.783614 -259.35677) (xy 117.775577 -259.408806) (xy 117.759691 -259.459005)
			(xy 117.736328 -259.50619) (xy 117.706036 -259.549256) (xy 117.669524 -259.587194) (xy 117.62765 -259.619113)
			(xy 117.581394 -259.644266) (xy 117.531841 -259.662064) (xy 117.480151 -259.672088) (xy 117.427537 -259.674105)
			(xy 117.375232 -259.668067) (xy 117.324461 -259.654115) (xy 117.276416 -259.632576) (xy 117.232221 -259.603956)
			(xy 117.192913 -259.568925) (xy 117.159413 -259.528304) (xy 117.132507 -259.483045) (xy 117.112824 -259.43421)
			(xy 117.100827 -259.382942) (xy 117.096797 -259.330444) (xy 116.555266 -259.330444) (xy 116.703602 -259.47878)
			(xy 116.710321 -259.486016) (xy 116.717928 -259.504221) (xy 116.718334 -259.514086) (xy 116.718334 -259.73024)
			(xy 120.865649 -259.73024) (xy 120.869679 -259.677742) (xy 120.881676 -259.626474) (xy 120.901359 -259.577639)
			(xy 120.928265 -259.53238) (xy 120.961765 -259.491759) (xy 121.001073 -259.456728) (xy 121.045268 -259.428108)
			(xy 121.093313 -259.406569) (xy 121.144084 -259.392617) (xy 121.196389 -259.386579) (xy 121.249003 -259.388596)
			(xy 121.300693 -259.39862) (xy 121.350246 -259.416418) (xy 121.396502 -259.441571) (xy 121.438376 -259.47349)
			(xy 121.474888 -259.511428) (xy 121.50518 -259.554494) (xy 121.528543 -259.601679) (xy 121.544429 -259.651878)
			(xy 121.552466 -259.703914) (xy 121.55297 -259.73024) (xy 122.791223 -259.73024) (xy 122.795253 -259.677742)
			(xy 122.80725 -259.626474) (xy 122.826933 -259.577639) (xy 122.853839 -259.53238) (xy 122.887339 -259.491759)
			(xy 122.926647 -259.456728) (xy 122.970842 -259.428108) (xy 123.018887 -259.406569) (xy 123.069658 -259.392617)
			(xy 123.121963 -259.386579) (xy 123.174577 -259.388596) (xy 123.226267 -259.39862) (xy 123.27582 -259.416418)
			(xy 123.322076 -259.441571) (xy 123.36395 -259.47349) (xy 123.400462 -259.511428) (xy 123.430754 -259.554494)
			(xy 123.454117 -259.601679) (xy 123.470003 -259.651878) (xy 123.47804 -259.703914) (xy 123.478544 -259.73024)
			(xy 124.696223 -259.73024) (xy 124.700253 -259.677742) (xy 124.71225 -259.626474) (xy 124.731933 -259.577639)
			(xy 124.758839 -259.53238) (xy 124.792339 -259.491759) (xy 124.831647 -259.456728) (xy 124.875842 -259.428108)
			(xy 124.923887 -259.406569) (xy 124.974658 -259.392617) (xy 125.026963 -259.386579) (xy 125.079577 -259.388596)
			(xy 125.131267 -259.39862) (xy 125.18082 -259.416418) (xy 125.227076 -259.441571) (xy 125.26895 -259.47349)
			(xy 125.305462 -259.511428) (xy 125.335754 -259.554494) (xy 125.359117 -259.601679) (xy 125.375003 -259.651878)
			(xy 125.38304 -259.703914) (xy 125.383544 -259.73024) (xy 125.38304 -259.756566) (xy 125.375003 -259.808602)
			(xy 125.359117 -259.858801) (xy 125.335754 -259.905986) (xy 125.305462 -259.949052) (xy 125.26895 -259.98699)
			(xy 125.227076 -260.018909) (xy 125.18082 -260.044062) (xy 125.131267 -260.06186) (xy 125.079577 -260.071884)
			(xy 125.026963 -260.073901) (xy 124.974658 -260.067863) (xy 124.923887 -260.053911) (xy 124.875842 -260.032372)
			(xy 124.831647 -260.003752) (xy 124.792339 -259.968721) (xy 124.758839 -259.9281) (xy 124.731933 -259.882841)
			(xy 124.71225 -259.834006) (xy 124.700253 -259.782738) (xy 124.696223 -259.73024) (xy 123.478544 -259.73024)
			(xy 123.47804 -259.756566) (xy 123.470003 -259.808602) (xy 123.454117 -259.858801) (xy 123.430754 -259.905986)
			(xy 123.400462 -259.949052) (xy 123.36395 -259.98699) (xy 123.322076 -260.018909) (xy 123.27582 -260.044062)
			(xy 123.226267 -260.06186) (xy 123.174577 -260.071884) (xy 123.121963 -260.073901) (xy 123.069658 -260.067863)
			(xy 123.018887 -260.053911) (xy 122.970842 -260.032372) (xy 122.926647 -260.003752) (xy 122.887339 -259.968721)
			(xy 122.853839 -259.9281) (xy 122.826933 -259.882841) (xy 122.80725 -259.834006) (xy 122.795253 -259.782738)
			(xy 122.791223 -259.73024) (xy 121.55297 -259.73024) (xy 121.552466 -259.756566) (xy 121.544429 -259.808602)
			(xy 121.528543 -259.858801) (xy 121.50518 -259.905986) (xy 121.474888 -259.949052) (xy 121.438376 -259.98699)
			(xy 121.396502 -260.018909) (xy 121.350246 -260.044062) (xy 121.300693 -260.06186) (xy 121.249003 -260.071884)
			(xy 121.196389 -260.073901) (xy 121.144084 -260.067863) (xy 121.093313 -260.053911) (xy 121.045268 -260.032372)
			(xy 121.001073 -260.003752) (xy 120.961765 -259.968721) (xy 120.928265 -259.9281) (xy 120.901359 -259.882841)
			(xy 120.881676 -259.834006) (xy 120.869679 -259.782738) (xy 120.865649 -259.73024) (xy 116.718334 -259.73024)
			(xy 116.718334 -260.280404) (xy 117.096797 -260.280404) (xy 117.100827 -260.227906) (xy 117.112824 -260.176638)
			(xy 117.132507 -260.127803) (xy 117.159413 -260.082544) (xy 117.192913 -260.041923) (xy 117.232221 -260.006892)
			(xy 117.276416 -259.978272) (xy 117.324461 -259.956733) (xy 117.375232 -259.942781) (xy 117.427537 -259.936743)
			(xy 117.480151 -259.93876) (xy 117.531841 -259.948784) (xy 117.581394 -259.966582) (xy 117.62765 -259.991735)
			(xy 117.669524 -260.023654) (xy 117.706036 -260.061592) (xy 117.736328 -260.104658) (xy 117.759691 -260.151843)
			(xy 117.775577 -260.202042) (xy 117.783614 -260.254078) (xy 117.784118 -260.280404) (xy 117.783614 -260.30673)
			(xy 117.775577 -260.358766) (xy 117.759691 -260.408965) (xy 117.736328 -260.45615) (xy 117.706036 -260.499216)
			(xy 117.669524 -260.537154) (xy 117.62765 -260.569073) (xy 117.581394 -260.594226) (xy 117.531841 -260.612024)
			(xy 117.480151 -260.622048) (xy 117.427537 -260.624065) (xy 117.375232 -260.618027) (xy 117.324461 -260.604075)
			(xy 117.276416 -260.582536) (xy 117.232221 -260.553916) (xy 117.192913 -260.518885) (xy 117.159413 -260.478264)
			(xy 117.132507 -260.433005) (xy 117.112824 -260.38417) (xy 117.100827 -260.332902) (xy 117.096797 -260.280404)
			(xy 116.718334 -260.280404) (xy 116.718334 -261.18185) (xy 116.718798 -261.191726) (xy 116.726243 -261.210022)
			(xy 116.732812 -261.21741) (xy 116.733066 -261.217664) (xy 117.0432 -261.527798) (xy 117.043708 -261.528306)
			(xy 117.051085 -261.5349) (xy 117.069384 -261.542374) (xy 117.079268 -261.542784) (xy 117.114574 -261.542784)
			(xy 117.12424 -261.54231) (xy 117.142163 -261.535053) (xy 117.156124 -261.521675) (xy 117.160548 -261.513066)
			(xy 117.174264 -261.483094) (xy 117.17528 -261.46379) (xy 117.172232 -261.454646) (xy 117.16639 -261.43712)
			(xy 117.161818 -261.43077) (xy 117.146617 -261.408739) (xy 117.122509 -261.360953) (xy 117.106112 -261.310003)
			(xy 117.097823 -261.257126) (xy 117.097302 -261.230364) (xy 117.097302 -261.222998) (xy 117.098369 -261.196391)
			(xy 117.107706 -261.143969) (xy 117.125022 -261.093616) (xy 117.149904 -261.046541) (xy 117.181754 -261.00387)
			(xy 117.21981 -260.966627) (xy 117.263158 -260.935705) (xy 117.31076 -260.911845) (xy 117.361475 -260.89562)
			(xy 117.414086 -260.887417) (xy 117.44071 -260.886956) (xy 117.467407 -260.887463) (xy 117.520157 -260.895725)
			(xy 117.570994 -260.912049) (xy 117.618694 -260.936041) (xy 117.662107 -260.967125) (xy 117.700188 -261.00455)
			(xy 117.732021 -261.047417) (xy 117.756839 -261.094692) (xy 117.767572 -261.126224) (xy 121.638834 -261.126224)
			(xy 121.642794 -261.07717) (xy 121.654571 -261.029386) (xy 121.673862 -260.98411) (xy 121.700165 -260.942514)
			(xy 121.7328 -260.905677) (xy 121.770921 -260.874552) (xy 121.813542 -260.849945) (xy 121.859558 -260.832493)
			(xy 121.907777 -260.822649) (xy 121.956952 -260.820668) (xy 122.005807 -260.8266) (xy 122.053078 -260.840292)
			(xy 122.09754 -260.86139) (xy 122.138043 -260.889346) (xy 122.173536 -260.923438) (xy 122.203101 -260.962782)
			(xy 122.225972 -261.006359) (xy 122.241556 -261.05304) (xy 122.249451 -261.101617) (xy 122.249946 -261.126224)
			(xy 123.518942 -261.126224) (xy 123.522902 -261.07717) (xy 123.534679 -261.029386) (xy 123.55397 -260.98411)
			(xy 123.580273 -260.942514) (xy 123.612908 -260.905677) (xy 123.651029 -260.874552) (xy 123.69365 -260.849945)
			(xy 123.739666 -260.832493) (xy 123.787885 -260.822649) (xy 123.83706 -260.820668) (xy 123.885915 -260.8266)
			(xy 123.933186 -260.840292) (xy 123.977648 -260.86139) (xy 124.018151 -260.889346) (xy 124.053644 -260.923438)
			(xy 124.083209 -260.962782) (xy 124.10608 -261.006359) (xy 124.121664 -261.05304) (xy 124.129559 -261.101617)
			(xy 124.130054 -261.126224) (xy 125.39905 -261.126224) (xy 125.40301 -261.07717) (xy 125.414787 -261.029386)
			(xy 125.434078 -260.98411) (xy 125.460381 -260.942514) (xy 125.493016 -260.905677) (xy 125.531137 -260.874552)
			(xy 125.573758 -260.849945) (xy 125.619774 -260.832493) (xy 125.667993 -260.822649) (xy 125.717168 -260.820668)
			(xy 125.766023 -260.8266) (xy 125.813294 -260.840292) (xy 125.857756 -260.86139) (xy 125.898259 -260.889346)
			(xy 125.933752 -260.923438) (xy 125.963317 -260.962782) (xy 125.986188 -261.006359) (xy 126.001772 -261.05304)
			(xy 126.009667 -261.101617) (xy 126.010162 -261.126224) (xy 127.278904 -261.126224) (xy 127.282864 -261.07717)
			(xy 127.294641 -261.029386) (xy 127.313932 -260.98411) (xy 127.340235 -260.942514) (xy 127.37287 -260.905677)
			(xy 127.410991 -260.874552) (xy 127.453612 -260.849945) (xy 127.499628 -260.832493) (xy 127.547847 -260.822649)
			(xy 127.597022 -260.820668) (xy 127.645877 -260.8266) (xy 127.693148 -260.840292) (xy 127.73761 -260.86139)
			(xy 127.778113 -260.889346) (xy 127.813606 -260.923438) (xy 127.843171 -260.962782) (xy 127.866042 -261.006359)
			(xy 127.881626 -261.05304) (xy 127.889521 -261.101617) (xy 127.890016 -261.126224) (xy 128.218958 -261.126224)
			(xy 128.222918 -261.07717) (xy 128.234695 -261.029386) (xy 128.253986 -260.98411) (xy 128.280289 -260.942514)
			(xy 128.312924 -260.905677) (xy 128.351045 -260.874552) (xy 128.393666 -260.849945) (xy 128.439682 -260.832493)
			(xy 128.487901 -260.822649) (xy 128.537076 -260.820668) (xy 128.585931 -260.8266) (xy 128.633202 -260.840292)
			(xy 128.677664 -260.86139) (xy 128.718167 -260.889346) (xy 128.75366 -260.923438) (xy 128.783225 -260.962782)
			(xy 128.806096 -261.006359) (xy 128.82168 -261.05304) (xy 128.829575 -261.101617) (xy 128.83007 -261.126224)
			(xy 129.159012 -261.126224) (xy 129.162972 -261.07717) (xy 129.174749 -261.029386) (xy 129.19404 -260.98411)
			(xy 129.220343 -260.942514) (xy 129.252978 -260.905677) (xy 129.291099 -260.874552) (xy 129.33372 -260.849945)
			(xy 129.379736 -260.832493) (xy 129.427955 -260.822649) (xy 129.47713 -260.820668) (xy 129.525985 -260.8266)
			(xy 129.573256 -260.840292) (xy 129.617718 -260.86139) (xy 129.658221 -260.889346) (xy 129.693714 -260.923438)
			(xy 129.723279 -260.962782) (xy 129.74615 -261.006359) (xy 129.761734 -261.05304) (xy 129.769629 -261.101617)
			(xy 129.770124 -261.126224) (xy 129.769629 -261.150831) (xy 129.761734 -261.199408) (xy 129.74615 -261.246089)
			(xy 129.723279 -261.289666) (xy 129.693714 -261.32901) (xy 129.658221 -261.363102) (xy 129.617718 -261.391058)
			(xy 129.573256 -261.412156) (xy 129.525985 -261.425848) (xy 129.47713 -261.43178) (xy 129.427955 -261.429799)
			(xy 129.379736 -261.419955) (xy 129.33372 -261.402503) (xy 129.291099 -261.377896) (xy 129.252978 -261.346771)
			(xy 129.220343 -261.309934) (xy 129.19404 -261.268338) (xy 129.174749 -261.223062) (xy 129.162972 -261.175278)
			(xy 129.159012 -261.126224) (xy 128.83007 -261.126224) (xy 128.829575 -261.150831) (xy 128.82168 -261.199408)
			(xy 128.806096 -261.246089) (xy 128.783225 -261.289666) (xy 128.75366 -261.32901) (xy 128.718167 -261.363102)
			(xy 128.677664 -261.391058) (xy 128.633202 -261.412156) (xy 128.585931 -261.425848) (xy 128.537076 -261.43178)
			(xy 128.487901 -261.429799) (xy 128.439682 -261.419955) (xy 128.393666 -261.402503) (xy 128.351045 -261.377896)
			(xy 128.312924 -261.346771) (xy 128.280289 -261.309934) (xy 128.253986 -261.268338) (xy 128.234695 -261.223062)
			(xy 128.222918 -261.175278) (xy 128.218958 -261.126224) (xy 127.890016 -261.126224) (xy 127.889521 -261.150831)
			(xy 127.881626 -261.199408) (xy 127.866042 -261.246089) (xy 127.843171 -261.289666) (xy 127.813606 -261.32901)
			(xy 127.778113 -261.363102) (xy 127.73761 -261.391058) (xy 127.693148 -261.412156) (xy 127.645877 -261.425848)
			(xy 127.597022 -261.43178) (xy 127.547847 -261.429799) (xy 127.499628 -261.419955) (xy 127.453612 -261.402503)
			(xy 127.410991 -261.377896) (xy 127.37287 -261.346771) (xy 127.340235 -261.309934) (xy 127.313932 -261.268338)
			(xy 127.294641 -261.223062) (xy 127.282864 -261.175278) (xy 127.278904 -261.126224) (xy 126.010162 -261.126224)
			(xy 126.009667 -261.150831) (xy 126.001772 -261.199408) (xy 125.986188 -261.246089) (xy 125.963317 -261.289666)
			(xy 125.933752 -261.32901) (xy 125.898259 -261.363102) (xy 125.857756 -261.391058) (xy 125.813294 -261.412156)
			(xy 125.766023 -261.425848) (xy 125.717168 -261.43178) (xy 125.667993 -261.429799) (xy 125.619774 -261.419955)
			(xy 125.573758 -261.402503) (xy 125.531137 -261.377896) (xy 125.493016 -261.346771) (xy 125.460381 -261.309934)
			(xy 125.434078 -261.268338) (xy 125.414787 -261.223062) (xy 125.40301 -261.175278) (xy 125.39905 -261.126224)
			(xy 124.130054 -261.126224) (xy 124.129559 -261.150831) (xy 124.121664 -261.199408) (xy 124.10608 -261.246089)
			(xy 124.083209 -261.289666) (xy 124.053644 -261.32901) (xy 124.018151 -261.363102) (xy 123.977648 -261.391058)
			(xy 123.933186 -261.412156) (xy 123.885915 -261.425848) (xy 123.83706 -261.43178) (xy 123.787885 -261.429799)
			(xy 123.739666 -261.419955) (xy 123.69365 -261.402503) (xy 123.651029 -261.377896) (xy 123.612908 -261.346771)
			(xy 123.580273 -261.309934) (xy 123.55397 -261.268338) (xy 123.534679 -261.223062) (xy 123.522902 -261.175278)
			(xy 123.518942 -261.126224) (xy 122.249946 -261.126224) (xy 122.249451 -261.150831) (xy 122.241556 -261.199408)
			(xy 122.225972 -261.246089) (xy 122.203101 -261.289666) (xy 122.173536 -261.32901) (xy 122.138043 -261.363102)
			(xy 122.09754 -261.391058) (xy 122.053078 -261.412156) (xy 122.005807 -261.425848) (xy 121.956952 -261.43178)
			(xy 121.907777 -261.429799) (xy 121.859558 -261.419955) (xy 121.813542 -261.402503) (xy 121.770921 -261.377896)
			(xy 121.7328 -261.346771) (xy 121.700165 -261.309934) (xy 121.673862 -261.268338) (xy 121.654571 -261.223062)
			(xy 121.642794 -261.175278) (xy 121.638834 -261.126224) (xy 117.767572 -261.126224) (xy 117.774044 -261.145238)
			(xy 117.783221 -261.197837) (xy 117.784118 -261.224522) (xy 117.784118 -261.229602) (xy 117.783618 -261.258217)
			(xy 117.774257 -261.314675) (xy 117.755646 -261.368792) (xy 117.742462 -261.394194) (xy 117.736112 -261.406132)
			(xy 117.736366 -261.433056) (xy 117.786658 -261.517892) (xy 117.791455 -261.525272) (xy 117.805006 -261.536485)
			(xy 117.821552 -261.542453) (xy 117.830346 -261.542784) (xy 118.05793 -261.542784) (xy 118.065361 -261.543092)
			(xy 118.079563 -261.547479) (xy 118.08587 -261.55142) (xy 118.086124 -261.551674) (xy 118.092728 -261.555992)
			(xy 118.099332 -261.558024) (xy 118.103104 -261.559173) (xy 118.110884 -261.560455) (xy 118.114826 -261.560564)
			(xy 119.09171 -261.560564) (xy 119.101553 -261.561088) (xy 119.119733 -261.568656) (xy 119.127016 -261.575296)
			(xy 119.732298 -262.180578) (xy 119.732806 -262.181086) (xy 119.740186 -262.187672) (xy 119.758485 -262.195134)
			(xy 119.768366 -262.195564) (xy 122.041666 -262.195564) (xy 122.054312 -262.194896) (xy 122.076581 -262.182905)
			(xy 122.084084 -262.172704) (xy 122.136662 -262.092694) (xy 122.138948 -262.067802) (xy 122.133868 -262.055864)
			(xy 122.122511 -262.027268) (xy 122.110217 -261.96699) (xy 122.109484 -261.93623) (xy 122.109484 -261.931658)
			(xy 122.11036 -261.90665) (xy 122.119257 -261.857412) (xy 122.136061 -261.810282) (xy 122.160325 -261.766523)
			(xy 122.191399 -261.727306) (xy 122.228451 -261.69368) (xy 122.27049 -261.666544) (xy 122.31639 -261.646626)
			(xy 122.364924 -261.634457) (xy 122.414792 -261.630365) (xy 122.46466 -261.634457) (xy 122.513194 -261.646626)
			(xy 122.559094 -261.666544) (xy 122.601133 -261.69368) (xy 122.638185 -261.727306) (xy 122.669259 -261.766523)
			(xy 122.693523 -261.810282) (xy 122.710327 -261.857412) (xy 122.719224 -261.90665) (xy 122.7201 -261.931658)
			(xy 122.7201 -261.934706) (xy 122.7201 -261.93623) (xy 123.988842 -261.93623) (xy 123.992802 -261.887176)
			(xy 124.004579 -261.839392) (xy 124.02387 -261.794116) (xy 124.050173 -261.75252) (xy 124.082808 -261.715683)
			(xy 124.120929 -261.684558) (xy 124.16355 -261.659951) (xy 124.209566 -261.642499) (xy 124.257785 -261.632655)
			(xy 124.30696 -261.630674) (xy 124.355815 -261.636606) (xy 124.403086 -261.650298) (xy 124.447548 -261.671396)
			(xy 124.488051 -261.699352) (xy 124.523544 -261.733444) (xy 124.553109 -261.772788) (xy 124.57598 -261.816365)
			(xy 124.591564 -261.863046) (xy 124.599459 -261.911623) (xy 124.599954 -261.93623) (xy 125.86895 -261.93623)
			(xy 125.87291 -261.887176) (xy 125.884687 -261.839392) (xy 125.903978 -261.794116) (xy 125.930281 -261.75252)
			(xy 125.962916 -261.715683) (xy 126.001037 -261.684558) (xy 126.043658 -261.659951) (xy 126.089674 -261.642499)
			(xy 126.137893 -261.632655) (xy 126.187068 -261.630674) (xy 126.235923 -261.636606) (xy 126.283194 -261.650298)
			(xy 126.327656 -261.671396) (xy 126.368159 -261.699352) (xy 126.403652 -261.733444) (xy 126.433217 -261.772788)
			(xy 126.456088 -261.816365) (xy 126.471672 -261.863046) (xy 126.479567 -261.911623) (xy 126.480062 -261.93623)
			(xy 127.738627 -261.93623) (xy 127.742722 -261.885502) (xy 127.754901 -261.836088) (xy 127.774849 -261.789268)
			(xy 127.80205 -261.746254) (xy 127.835798 -261.70816) (xy 127.87522 -261.675973) (xy 127.919294 -261.650527)
			(xy 127.96688 -261.63248) (xy 128.016744 -261.6223) (xy 128.067596 -261.620251) (xy 128.118117 -261.626385)
			(xy 128.167001 -261.640545) (xy 128.21298 -261.662362) (xy 128.254864 -261.691272) (xy 128.291568 -261.726527)
			(xy 128.322141 -261.767213) (xy 128.345792 -261.812276) (xy 128.361908 -261.86055) (xy 128.370072 -261.910784)
			(xy 128.370584 -261.93623) (xy 128.688858 -261.93623) (xy 128.692818 -261.887176) (xy 128.704595 -261.839392)
			(xy 128.723886 -261.794116) (xy 128.750189 -261.75252) (xy 128.782824 -261.715683) (xy 128.820945 -261.684558)
			(xy 128.863566 -261.659951) (xy 128.909582 -261.642499) (xy 128.957801 -261.632655) (xy 129.006976 -261.630674)
			(xy 129.055831 -261.636606) (xy 129.103102 -261.650298) (xy 129.147564 -261.671396) (xy 129.188067 -261.699352)
			(xy 129.22356 -261.733444) (xy 129.253125 -261.772788) (xy 129.275996 -261.816365) (xy 129.29158 -261.863046)
			(xy 129.299475 -261.911623) (xy 129.29997 -261.93623) (xy 129.628912 -261.93623) (xy 129.632872 -261.887176)
			(xy 129.644649 -261.839392) (xy 129.66394 -261.794116) (xy 129.690243 -261.75252) (xy 129.722878 -261.715683)
			(xy 129.760999 -261.684558) (xy 129.80362 -261.659951) (xy 129.849636 -261.642499) (xy 129.897855 -261.632655)
			(xy 129.94703 -261.630674) (xy 129.995885 -261.636606) (xy 130.043156 -261.650298) (xy 130.087618 -261.671396)
			(xy 130.128121 -261.699352) (xy 130.163614 -261.733444) (xy 130.193179 -261.772788) (xy 130.21605 -261.816365)
			(xy 130.231634 -261.863046) (xy 130.239529 -261.911623) (xy 130.240024 -261.93623) (xy 130.239529 -261.960837)
			(xy 130.231634 -262.009414) (xy 130.21605 -262.056095) (xy 130.193179 -262.099672) (xy 130.163614 -262.139016)
			(xy 130.128121 -262.173108) (xy 130.087618 -262.201064) (xy 130.043156 -262.222162) (xy 129.995885 -262.235854)
			(xy 129.94703 -262.241786) (xy 129.897855 -262.239805) (xy 129.849636 -262.229961) (xy 129.80362 -262.212509)
			(xy 129.760999 -262.187902) (xy 129.722878 -262.156777) (xy 129.690243 -262.11994) (xy 129.66394 -262.078344)
			(xy 129.644649 -262.033068) (xy 129.632872 -261.985284) (xy 129.628912 -261.93623) (xy 129.29997 -261.93623)
			(xy 129.299475 -261.960837) (xy 129.29158 -262.009414) (xy 129.275996 -262.056095) (xy 129.253125 -262.099672)
			(xy 129.22356 -262.139016) (xy 129.188067 -262.173108) (xy 129.147564 -262.201064) (xy 129.103102 -262.222162)
			(xy 129.055831 -262.235854) (xy 129.006976 -262.241786) (xy 128.957801 -262.239805) (xy 128.909582 -262.229961)
			(xy 128.863566 -262.212509) (xy 128.820945 -262.187902) (xy 128.782824 -262.156777) (xy 128.750189 -262.11994)
			(xy 128.723886 -262.078344) (xy 128.704595 -262.033068) (xy 128.692818 -261.985284) (xy 128.688858 -261.93623)
			(xy 128.370584 -261.93623) (xy 128.370072 -261.961676) (xy 128.361908 -262.01191) (xy 128.345792 -262.060184)
			(xy 128.322141 -262.105247) (xy 128.291568 -262.145933) (xy 128.254864 -262.181188) (xy 128.21298 -262.210098)
			(xy 128.167001 -262.231915) (xy 128.118117 -262.246075) (xy 128.067596 -262.252209) (xy 128.016744 -262.25016)
			(xy 127.96688 -262.23998) (xy 127.919294 -262.221933) (xy 127.87522 -262.196487) (xy 127.835798 -262.1643)
			(xy 127.80205 -262.126206) (xy 127.774849 -262.083192) (xy 127.754901 -262.036372) (xy 127.742722 -261.986958)
			(xy 127.738627 -261.93623) (xy 126.480062 -261.93623) (xy 126.479567 -261.960837) (xy 126.471672 -262.009414)
			(xy 126.456088 -262.056095) (xy 126.433217 -262.099672) (xy 126.403652 -262.139016) (xy 126.368159 -262.173108)
			(xy 126.327656 -262.201064) (xy 126.283194 -262.222162) (xy 126.235923 -262.235854) (xy 126.187068 -262.241786)
			(xy 126.137893 -262.239805) (xy 126.089674 -262.229961) (xy 126.043658 -262.212509) (xy 126.001037 -262.187902)
			(xy 125.962916 -262.156777) (xy 125.930281 -262.11994) (xy 125.903978 -262.078344) (xy 125.884687 -262.033068)
			(xy 125.87291 -261.985284) (xy 125.86895 -261.93623) (xy 124.599954 -261.93623) (xy 124.599459 -261.960837)
			(xy 124.591564 -262.009414) (xy 124.57598 -262.056095) (xy 124.553109 -262.099672) (xy 124.523544 -262.139016)
			(xy 124.488051 -262.173108) (xy 124.447548 -262.201064) (xy 124.403086 -262.222162) (xy 124.355815 -262.235854)
			(xy 124.30696 -262.241786) (xy 124.257785 -262.239805) (xy 124.209566 -262.229961) (xy 124.16355 -262.212509)
			(xy 124.120929 -262.187902) (xy 124.082808 -262.156777) (xy 124.050173 -262.11994) (xy 124.02387 -262.078344)
			(xy 124.004579 -262.033068) (xy 123.992802 -261.985284) (xy 123.988842 -261.93623) (xy 122.7201 -261.93623)
			(xy 122.71934 -261.966988) (xy 122.707062 -262.027266) (xy 122.695716 -262.055864) (xy 122.690636 -262.067802)
			(xy 122.692922 -262.092694) (xy 122.7455 -262.172704) (xy 122.753024 -262.182878) (xy 122.775282 -262.194846)
			(xy 122.787918 -262.195564) (xy 123.40971 -262.195564) (xy 123.419553 -262.196088) (xy 123.437733 -262.203656)
			(xy 123.445016 -262.210296) (xy 123.678188 -262.443468) (xy 123.685136 -262.449851) (xy 123.702352 -262.457529)
			(xy 123.721178 -262.458476) (xy 123.730258 -262.455914) (xy 123.752882 -262.449015) (xy 123.799576 -262.441481)
			(xy 123.823222 -262.440928) (xy 123.828302 -262.440928) (xy 123.85193 -262.44165) (xy 123.898545 -262.449486)
			(xy 123.943395 -262.464413) (xy 123.985408 -262.486075) (xy 124.023581 -262.513953) (xy 124.057001 -262.547382)
			(xy 124.084869 -262.585562) (xy 124.106519 -262.627582) (xy 124.121434 -262.672436) (xy 124.129258 -262.719053)
			(xy 124.130054 -262.74268) (xy 124.130054 -262.74649) (xy 124.129563 -262.770454) (xy 124.122029 -262.817788)
			(xy 124.115068 -262.840724) (xy 124.11246 -262.849798) (xy 124.113403 -262.868642) (xy 124.121093 -262.885871)
			(xy 124.127514 -262.892794) (xy 124.304298 -263.069578) (xy 124.304806 -263.070086) (xy 124.312186 -263.076672)
			(xy 124.330485 -263.084134) (xy 124.340366 -263.084564)
		)
		(stroke
			(width 0)
			(type solid)
		)
		(fill yes)
		(layer "In4.Cu")
		(net "PVDDCR_SOC_P1")
	)
	(gr_poly
		(pts
			(xy 260.00837 -218.309444) (xy 260.018433 -218.309007) (xy 260.037014 -218.301268) (xy 260.044438 -218.294458)
			(xy 262.166862 -216.172034) (xy 262.173702 -216.164634) (xy 262.181419 -216.146035) (xy 262.181848 -216.135966)
			(xy 262.181848 -200.399904) (xy 262.182272 -200.389835) (xy 262.189991 -200.371234) (xy 262.196834 -200.363836)
			(xy 265.172952 -197.387718) (xy 265.180572 -197.367652) (xy 265.17981 -197.35673) (xy 265.179302 -197.33514)
			(xy 265.179747 -197.308793) (xy 265.187241 -197.256634) (xy 265.202083 -197.206073) (xy 265.223969 -197.158139)
			(xy 265.252456 -197.113808) (xy 265.286961 -197.073982) (xy 265.326784 -197.039474) (xy 265.371112 -197.010984)
			(xy 265.419045 -196.989093) (xy 265.469605 -196.974248) (xy 265.521763 -196.966749) (xy 265.54811 -196.966332)
			(xy 265.576113 -196.966853) (xy 265.631476 -196.975321) (xy 265.684922 -196.992061) (xy 265.735223 -197.016689)
			(xy 265.781223 -197.048637) (xy 265.821864 -197.087173) (xy 265.856213 -197.131409) (xy 265.88348 -197.18033)
			(xy 265.903038 -197.23281) (xy 265.914437 -197.287644) (xy 265.91641 -197.315582) (xy 265.917426 -197.335902)
			(xy 265.946636 -197.363588) (xy 269.122652 -197.363588) (xy 269.151862 -197.335394) (xy 269.152878 -197.31482)
			(xy 269.154541 -197.284928) (xy 269.164151 -197.225834) (xy 269.180807 -197.168328) (xy 269.204267 -197.113245)
			(xy 269.23419 -197.061389) (xy 269.270139 -197.013513) (xy 269.311591 -196.970315) (xy 269.357944 -196.932422)
			(xy 269.383002 -196.91604) (xy 269.393162 -196.90969) (xy 269.405354 -196.889878) (xy 269.415006 -196.785738)
			(xy 269.406624 -196.763894) (xy 269.397734 -196.755766) (xy 269.379413 -196.738245) (xy 269.347265 -196.699047)
			(xy 269.32079 -196.655815) (xy 269.300488 -196.609363) (xy 269.286742 -196.560568) (xy 269.27981 -196.510349)
			(xy 269.27937 -196.485002) (xy 269.279886 -196.457402) (xy 269.288113 -196.402819) (xy 269.304383 -196.350072)
			(xy 269.328333 -196.30034) (xy 269.359428 -196.254732) (xy 269.396973 -196.214268) (xy 269.44013 -196.179851)
			(xy 269.487934 -196.152252) (xy 269.539318 -196.132085) (xy 269.593133 -196.119802) (xy 269.648178 -196.115677)
			(xy 269.703223 -196.119802) (xy 269.757038 -196.132085) (xy 269.808422 -196.152252) (xy 269.856226 -196.179851)
			(xy 269.899383 -196.214268) (xy 269.936928 -196.254732) (xy 269.968023 -196.30034) (xy 269.991973 -196.350072)
			(xy 270.008243 -196.402819) (xy 270.01647 -196.457402) (xy 270.016986 -196.485002) (xy 270.016566 -196.51035)
			(xy 270.009625 -196.56057) (xy 269.995874 -196.609366) (xy 269.975573 -196.65582) (xy 269.949103 -196.699057)
			(xy 269.916962 -196.738264) (xy 269.898622 -196.755766) (xy 269.889732 -196.763894) (xy 269.88135 -196.785738)
			(xy 269.891002 -196.889878) (xy 269.903194 -196.90969) (xy 269.913354 -196.91604) (xy 269.938408 -196.932432)
			(xy 269.984771 -196.970314) (xy 270.026233 -197.013507) (xy 270.062189 -197.06138) (xy 270.092115 -197.113236)
			(xy 270.115576 -197.16832) (xy 270.13223 -197.225829) (xy 270.141834 -197.284926) (xy 270.143478 -197.31482)
			(xy 270.144494 -197.335394) (xy 270.173704 -197.363588) (xy 272.693638 -197.363588) (xy 272.722848 -197.335902)
			(xy 272.723864 -197.315582) (xy 272.725748 -197.288976) (xy 272.736219 -197.236678) (xy 272.754114 -197.186433)
			(xy 272.77906 -197.139289) (xy 272.810536 -197.096231) (xy 272.847887 -197.058156) (xy 272.890332 -197.025858)
			(xy 272.936987 -197.00001) (xy 272.986879 -196.981153) (xy 273.038967 -196.969679) (xy 273.092164 -196.965828)
			(xy 273.145361 -196.969679) (xy 273.197449 -196.981153) (xy 273.247341 -197.00001) (xy 273.293996 -197.025858)
			(xy 273.336441 -197.058156) (xy 273.373792 -197.096231) (xy 273.405268 -197.139289) (xy 273.430214 -197.186433)
			(xy 273.448109 -197.236678) (xy 273.45858 -197.288976) (xy 273.460464 -197.315582) (xy 273.46148 -197.335902)
			(xy 273.49069 -197.363588) (xy 276.666706 -197.363588) (xy 276.695916 -197.335394) (xy 276.696932 -197.31482)
			(xy 276.698595 -197.284928) (xy 276.708206 -197.225836) (xy 276.724864 -197.168331) (xy 276.748325 -197.113251)
			(xy 276.778249 -197.061397) (xy 276.8142 -197.013524) (xy 276.855655 -196.970329) (xy 276.90201 -196.93244)
			(xy 276.927056 -196.91604) (xy 276.937216 -196.90969) (xy 276.949408 -196.889878) (xy 276.95906 -196.785738)
			(xy 276.950678 -196.763894) (xy 276.941788 -196.755766) (xy 276.923464 -196.738246) (xy 276.891312 -196.69905)
			(xy 276.864833 -196.655818) (xy 276.844528 -196.609366) (xy 276.83078 -196.56057) (xy 276.823847 -196.51035)
			(xy 276.823424 -196.485002) (xy 276.82394 -196.457402) (xy 276.832167 -196.402819) (xy 276.848437 -196.350072)
			(xy 276.872387 -196.30034) (xy 276.903482 -196.254732) (xy 276.941027 -196.214268) (xy 276.984184 -196.179851)
			(xy 277.031988 -196.152252) (xy 277.083372 -196.132085) (xy 277.137187 -196.119802) (xy 277.192232 -196.115677)
			(xy 277.247277 -196.119802) (xy 277.301092 -196.132085) (xy 277.352476 -196.152252) (xy 277.40028 -196.179851)
			(xy 277.443437 -196.214268) (xy 277.480982 -196.254732) (xy 277.512077 -196.30034) (xy 277.536027 -196.350072)
			(xy 277.552297 -196.402819) (xy 277.560524 -196.457402) (xy 277.56104 -196.485002) (xy 277.56062 -196.51035)
			(xy 277.553678 -196.560568) (xy 277.539926 -196.609364) (xy 277.519623 -196.655816) (xy 277.49315 -196.699051)
			(xy 277.461008 -196.738255) (xy 277.442676 -196.755766) (xy 277.433786 -196.763894) (xy 277.425404 -196.785738)
			(xy 277.435056 -196.889878) (xy 277.447248 -196.90969) (xy 277.457408 -196.91604) (xy 277.482459 -196.932433)
			(xy 277.528818 -196.970318) (xy 277.570276 -197.013512) (xy 277.606228 -197.061386) (xy 277.636151 -197.113242)
			(xy 277.659609 -197.168325) (xy 277.67626 -197.225833) (xy 277.685863 -197.284928) (xy 277.687532 -197.31482)
			(xy 277.688548 -197.335394) (xy 277.717758 -197.363588) (xy 280.237438 -197.363588) (xy 280.266648 -197.335902)
			(xy 280.267664 -197.315582) (xy 280.269548 -197.288976) (xy 280.280019 -197.236678) (xy 280.297914 -197.186433)
			(xy 280.32286 -197.139289) (xy 280.354336 -197.096231) (xy 280.391687 -197.058156) (xy 280.434132 -197.025858)
			(xy 280.480787 -197.00001) (xy 280.530679 -196.981153) (xy 280.582767 -196.969679) (xy 280.635964 -196.965828)
			(xy 280.689161 -196.969679) (xy 280.741249 -196.981153) (xy 280.791141 -197.00001) (xy 280.837796 -197.025858)
			(xy 280.880241 -197.058156) (xy 280.917592 -197.096231) (xy 280.949068 -197.139289) (xy 280.974014 -197.186433)
			(xy 280.991909 -197.236678) (xy 281.00238 -197.288976) (xy 281.004264 -197.315582) (xy 281.00528 -197.335902)
			(xy 281.03449 -197.363588) (xy 284.125416 -197.363588) (xy 284.15488 -197.33514) (xy 284.155642 -197.314566)
			(xy 284.157361 -197.280107) (xy 284.167964 -197.211931) (xy 284.186569 -197.14549) (xy 284.212914 -197.081722)
			(xy 284.246629 -197.021524) (xy 284.287238 -196.965744) (xy 284.33417 -196.915169) (xy 284.386762 -196.870509)
			(xy 284.41523 -196.851016) (xy 284.42412 -196.845174) (xy 284.435296 -196.827902) (xy 284.451552 -196.734176)
			(xy 284.44698 -196.71411) (xy 284.440376 -196.705474) (xy 284.423175 -196.681432) (xy 284.395846 -196.629017)
			(xy 284.377229 -196.572913) (xy 284.3678 -196.514558) (xy 284.367224 -196.485002) (xy 284.36774 -196.457402)
			(xy 284.375967 -196.402819) (xy 284.392237 -196.350072) (xy 284.416187 -196.30034) (xy 284.447282 -196.254732)
			(xy 284.484827 -196.214268) (xy 284.527984 -196.179851) (xy 284.575788 -196.152252) (xy 284.627172 -196.132085)
			(xy 284.680987 -196.119802) (xy 284.736032 -196.115677) (xy 284.791077 -196.119802) (xy 284.844892 -196.132085)
			(xy 284.896276 -196.152252) (xy 284.94408 -196.179851) (xy 284.987237 -196.214268) (xy 285.024782 -196.254732)
			(xy 285.055877 -196.30034) (xy 285.079827 -196.350072) (xy 285.096097 -196.402819) (xy 285.104324 -196.457402)
			(xy 285.10484 -196.485002) (xy 285.104256 -196.514558) (xy 285.094828 -196.572912) (xy 285.076214 -196.629016)
			(xy 285.04889 -196.681433) (xy 285.031688 -196.705474) (xy 285.025084 -196.71411) (xy 285.020512 -196.734176)
			(xy 285.036768 -196.827902) (xy 285.047944 -196.845174) (xy 285.056834 -196.851016) (xy 285.080882 -196.867359)
			(xy 285.125922 -196.904135) (xy 285.14675 -196.924422) (xy 285.189168 -196.96684) (xy 285.196534 -196.97368)
			(xy 285.215067 -196.981422) (xy 285.235151 -196.981422) (xy 285.253684 -196.97368) (xy 285.26105 -196.96684)
			(xy 285.267146 -196.960744) (xy 285.270956 -196.952616) (xy 285.285614 -196.922653) (xy 285.320809 -196.865986)
			(xy 285.362262 -196.813722) (xy 285.38551 -196.789802) (xy 285.548578 -196.626734) (xy 285.571939 -196.604005)
			(xy 285.622909 -196.563376) (xy 285.678109 -196.528712) (xy 285.736845 -196.50045) (xy 285.798377 -196.478944)
			(xy 285.86193 -196.464466) (xy 285.926705 -196.457198) (xy 285.959296 -196.456808) (xy 286.189674 -196.456808)
			(xy 286.223329 -196.457265) (xy 286.290194 -196.464989) (xy 286.355719 -196.480383) (xy 286.38754 -196.491352)
			(xy 286.397885 -196.494637) (xy 286.419513 -196.493079) (xy 286.43856 -196.482716) (xy 286.445452 -196.474334)
			(xy 286.457773 -196.458231) (xy 286.484341 -196.427596) (xy 286.498538 -196.41312) (xy 286.661606 -196.250052)
			(xy 286.684959 -196.227304) (xy 286.735917 -196.186636) (xy 286.79111 -196.151934) (xy 286.849844 -196.123633)
			(xy 286.911379 -196.10209) (xy 286.974939 -196.087577) (xy 287.039726 -196.080275) (xy 287.072324 -196.079872)
			(xy 287.302702 -196.079872) (xy 287.335299 -196.080312) (xy 287.400082 -196.087614) (xy 287.463641 -196.102125)
			(xy 287.525174 -196.123663) (xy 287.583908 -196.151956) (xy 287.639104 -196.18665) (xy 287.690067 -196.227306)
			(xy 287.71342 -196.250052) (xy 287.876488 -196.41312) (xy 287.899234 -196.436474) (xy 287.939898 -196.487433)
			(xy 287.974597 -196.542627) (xy 288.002894 -196.601361) (xy 288.024434 -196.662895) (xy 288.038945 -196.726455)
			(xy 288.046244 -196.79124) (xy 288.046668 -196.823838) (xy 288.046668 -196.92366) (xy 288.04708 -196.933689)
			(xy 288.054742 -196.952225) (xy 288.068914 -196.966418) (xy 288.08744 -196.974106) (xy 288.097468 -196.97446)
			(xy 288.102294 -196.97446) (xy 288.107374 -196.973444) (xy 288.122614 -196.970904) (xy 288.141156 -196.967856)
			(xy 288.16554 -196.939408) (xy 288.16554 -196.491098) (xy 288.165986 -196.45851) (xy 288.17326 -196.393743)
			(xy 288.187741 -196.330197) (xy 288.209245 -196.268672) (xy 288.237502 -196.209941) (xy 288.272156 -196.154743)
			(xy 288.312773 -196.103772) (xy 288.335466 -196.08038) (xy 288.498534 -195.917312) (xy 288.521888 -195.894566)
			(xy 288.572848 -195.853904) (xy 288.628042 -195.819206) (xy 288.686776 -195.79091) (xy 288.74831 -195.769372)
			(xy 288.81187 -195.754863) (xy 288.876655 -195.747565) (xy 288.909252 -195.747132) (xy 289.13963 -195.747132)
			(xy 289.172226 -195.747574) (xy 289.237009 -195.754878) (xy 289.300566 -195.769391) (xy 289.362098 -195.790929)
			(xy 289.420831 -195.819223) (xy 289.476026 -195.853917) (xy 289.526989 -195.894573) (xy 289.550348 -195.917312)
			(xy 289.713416 -196.08038) (xy 289.736162 -196.103733) (xy 289.776825 -196.154692) (xy 289.811523 -196.209887)
			(xy 289.839818 -196.268621) (xy 289.861354 -196.330155) (xy 289.87586 -196.393716) (xy 289.883154 -196.458501)
			(xy 289.883596 -196.491098) (xy 289.883596 -196.75602) (xy 289.883954 -196.766051) (xy 289.891552 -196.784613)
			(xy 289.905724 -196.798806) (xy 289.914838 -196.80301) (xy 289.929316 -196.809106) (xy 289.959034 -196.80301)
			(xy 290.262564 -196.49948) (xy 290.285917 -196.476733) (xy 290.336876 -196.436069) (xy 290.39207 -196.40137)
			(xy 290.450804 -196.373074) (xy 290.512339 -196.351536) (xy 290.575899 -196.337028) (xy 290.640684 -196.329733)
			(xy 290.673282 -196.3293) (xy 290.754816 -196.3293) (xy 290.764822 -196.328809) (xy 290.783308 -196.321147)
			(xy 290.797456 -196.306994) (xy 290.805112 -196.288506) (xy 290.805616 -196.2785) (xy 290.805616 -196.267578)
			(xy 290.796472 -196.247766) (xy 290.788344 -196.240654) (xy 290.76553 -196.219924) (xy 290.724571 -196.173854)
			(xy 290.689479 -196.123173) (xy 290.660766 -196.068623) (xy 290.638854 -196.011005) (xy 290.624063 -195.951161)
			(xy 290.61661 -195.889968) (xy 290.616132 -195.859146) (xy 290.61667 -195.825989) (xy 290.625293 -195.760238)
			(xy 290.642386 -195.696164) (xy 290.667658 -195.634854) (xy 290.700683 -195.577348) (xy 290.740899 -195.52462)
			(xy 290.787625 -195.477564) (xy 290.81349 -195.45681) (xy 290.822348 -195.449223) (xy 290.832647 -195.428324)
			(xy 290.833302 -195.416678) (xy 290.833302 -195.336414) (xy 290.832731 -195.324749) (xy 290.822401 -195.303832)
			(xy 290.81349 -195.296282) (xy 290.787598 -195.275562) (xy 290.740877 -195.228499) (xy 290.700669 -195.175764)
			(xy 290.667654 -195.118251) (xy 290.642391 -195.056936) (xy 290.62531 -194.992858) (xy 290.6167 -194.927104)
			(xy 290.616132 -194.893946) (xy 290.616681 -194.86017) (xy 290.625617 -194.793211) (xy 290.643336 -194.728024)
			(xy 290.669528 -194.665756) (xy 290.703732 -194.607502) (xy 290.745345 -194.554288) (xy 290.793635 -194.507051)
			(xy 290.847753 -194.466621) (xy 290.87699 -194.4497) (xy 290.888166 -194.443604) (xy 290.901882 -194.422522)
			(xy 290.91128 -194.313556) (xy 290.901628 -194.290188) (xy 290.891722 -194.282314) (xy 290.870872 -194.264703)
			(xy 290.834091 -194.224383) (xy 290.803655 -194.179081) (xy 290.78023 -194.129788) (xy 290.764328 -194.07758)
			(xy 290.756296 -194.023598) (xy 290.755832 -193.99631) (xy 290.756348 -193.96871) (xy 290.764575 -193.914127)
			(xy 290.780845 -193.86138) (xy 290.804795 -193.811648) (xy 290.83589 -193.76604) (xy 290.873435 -193.725576)
			(xy 290.916592 -193.691159) (xy 290.964396 -193.66356) (xy 291.01578 -193.643393) (xy 291.069595 -193.63111)
			(xy 291.12464 -193.626985) (xy 291.179685 -193.63111) (xy 291.2335 -193.643393) (xy 291.284884 -193.66356)
			(xy 291.332688 -193.691159) (xy 291.375845 -193.725576) (xy 291.41339 -193.76604) (xy 291.444485 -193.811648)
			(xy 291.468435 -193.86138) (xy 291.484705 -193.914127) (xy 291.492932 -193.96871) (xy 291.493448 -193.99631)
			(xy 291.492956 -194.023597) (xy 291.484918 -194.077576) (xy 291.469018 -194.129782) (xy 291.445603 -194.179077)
			(xy 291.415183 -194.224387) (xy 291.378423 -194.264723) (xy 291.357558 -194.282314) (xy 291.347652 -194.290188)
			(xy 291.338 -194.313556) (xy 291.347398 -194.422522) (xy 291.361114 -194.443604) (xy 291.37229 -194.4497)
			(xy 291.401512 -194.466642) (xy 291.455619 -194.507078) (xy 291.503901 -194.554317) (xy 291.545507 -194.607529)
			(xy 291.579707 -194.665778) (xy 291.6059 -194.72804) (xy 291.623624 -194.79322) (xy 291.632569 -194.860172)
			(xy 291.633148 -194.893946) (xy 291.632611 -194.927104) (xy 291.62399 -194.992857) (xy 291.6069 -195.056934)
			(xy 291.58163 -195.118247) (xy 291.54861 -195.175757) (xy 291.508398 -195.228491) (xy 291.461676 -195.275554)
			(xy 291.43579 -195.296282) (xy 291.426934 -195.30387) (xy 291.416635 -195.324768) (xy 291.415978 -195.336414)
			(xy 291.415978 -195.416678) (xy 291.416547 -195.428345) (xy 291.426872 -195.449267) (xy 291.43579 -195.45681)
			(xy 291.461684 -195.477529) (xy 291.508406 -195.524591) (xy 291.548617 -195.577326) (xy 291.581635 -195.634839)
			(xy 291.606899 -195.696154) (xy 291.623982 -195.760233) (xy 291.632593 -195.825988) (xy 291.633148 -195.859146)
			(xy 291.632619 -195.892159) (xy 291.624068 -195.95763) (xy 291.607115 -196.021443) (xy 291.582046 -196.082526)
			(xy 291.549283 -196.139851) (xy 291.52977 -196.166486) (xy 291.521134 -196.177916) (xy 291.51834 -196.206872)
			(xy 291.56533 -196.301106) (xy 291.569914 -196.309343) (xy 291.583826 -196.322038) (xy 291.60138 -196.328864)
			(xy 291.610796 -196.3293) (xy 291.914834 -196.3293) (xy 291.923788 -196.32895) (xy 291.940608 -196.322799)
			(xy 291.954299 -196.311255) (xy 291.95903 -196.303646) (xy 291.973157 -196.279639) (xy 292.00751 -196.235795)
			(xy 292.04807 -196.197618) (xy 292.093911 -196.165978) (xy 292.143991 -196.141596) (xy 292.19717 -196.125026)
			(xy 292.252236 -196.116645) (xy 292.307936 -196.116645) (xy 292.363002 -196.125026) (xy 292.416181 -196.141596)
			(xy 292.466261 -196.165978) (xy 292.512102 -196.197618) (xy 292.552662 -196.235795) (xy 292.587015 -196.279639)
			(xy 292.601142 -196.303646) (xy 292.605873 -196.311258) (xy 292.619553 -196.322819) (xy 292.636382 -196.328952)
			(xy 292.645338 -196.3293) (xy 293.498778 -196.3293) (xy 293.531376 -196.329739) (xy 293.596161 -196.337037)
			(xy 293.659722 -196.351545) (xy 293.721259 -196.373078) (xy 293.779997 -196.401368) (xy 293.835197 -196.436057)
			(xy 293.886166 -196.476709) (xy 293.909496 -196.49948) (xy 294.574468 -197.164452) (xy 294.581878 -197.171136)
			(xy 294.600314 -197.178721) (xy 294.610282 -197.179184) (xy 295.35882 -197.179184) (xy 295.367775 -197.178836)
			(xy 295.384596 -197.172687) (xy 295.398289 -197.161142) (xy 295.403016 -197.15353) (xy 295.417164 -197.12955)
			(xy 295.451547 -197.085761) (xy 295.49212 -197.047637) (xy 295.537963 -197.016043) (xy 295.588032 -196.991697)
			(xy 295.641192 -196.975153) (xy 295.696235 -196.966786) (xy 295.751909 -196.966786) (xy 295.806952 -196.975153)
			(xy 295.860112 -196.991697) (xy 295.910181 -197.016043) (xy 295.956024 -197.047637) (xy 295.996597 -197.085761)
			(xy 296.03098 -197.12955) (xy 296.045128 -197.15353) (xy 296.049858 -197.161145) (xy 296.063536 -197.172714)
			(xy 296.080366 -197.178854) (xy 296.089324 -197.179184) (xy 297.085258 -197.179184) (xy 297.095221 -197.178699)
			(xy 297.113646 -197.171112) (xy 297.121072 -197.164452) (xy 297.786044 -196.49948) (xy 297.809397 -196.476732)
			(xy 297.860355 -196.436066) (xy 297.915549 -196.401366) (xy 297.974283 -196.373067) (xy 298.035818 -196.351527)
			(xy 298.099378 -196.337017) (xy 298.164164 -196.32972) (xy 298.196762 -196.3293) (xy 298.298616 -196.3293)
			(xy 298.308622 -196.328809) (xy 298.327108 -196.321147) (xy 298.341256 -196.306994) (xy 298.348912 -196.288506)
			(xy 298.349416 -196.2785) (xy 298.349416 -196.267578) (xy 298.340272 -196.247766) (xy 298.332144 -196.240654)
			(xy 298.30933 -196.219924) (xy 298.268371 -196.173854) (xy 298.233279 -196.123173) (xy 298.204566 -196.068623)
			(xy 298.182654 -196.011005) (xy 298.167863 -195.951161) (xy 298.16041 -195.889968) (xy 298.159932 -195.859146)
			(xy 298.16047 -195.825989) (xy 298.169093 -195.760238) (xy 298.186186 -195.696164) (xy 298.211458 -195.634854)
			(xy 298.244483 -195.577348) (xy 298.284699 -195.52462) (xy 298.331425 -195.477564) (xy 298.35729 -195.45681)
			(xy 298.366148 -195.449223) (xy 298.376447 -195.428324) (xy 298.377102 -195.416678) (xy 298.377102 -195.336414)
			(xy 298.376531 -195.324749) (xy 298.366201 -195.303832) (xy 298.35729 -195.296282) (xy 298.331398 -195.275562)
			(xy 298.284677 -195.228499) (xy 298.244469 -195.175764) (xy 298.211454 -195.118251) (xy 298.186191 -195.056936)
			(xy 298.16911 -194.992858) (xy 298.1605 -194.927104) (xy 298.159932 -194.893946) (xy 298.160481 -194.86017)
			(xy 298.169417 -194.793211) (xy 298.187136 -194.728024) (xy 298.213328 -194.665756) (xy 298.247532 -194.607502)
			(xy 298.289145 -194.554288) (xy 298.337435 -194.507051) (xy 298.391553 -194.466621) (xy 298.42079 -194.4497)
			(xy 298.431966 -194.443604) (xy 298.445682 -194.422522) (xy 298.45508 -194.313556) (xy 298.445428 -194.290188)
			(xy 298.435522 -194.282314) (xy 298.414672 -194.264703) (xy 298.377891 -194.224383) (xy 298.347455 -194.179081)
			(xy 298.32403 -194.129788) (xy 298.308128 -194.07758) (xy 298.300096 -194.023598) (xy 298.299632 -193.99631)
			(xy 298.300148 -193.96871) (xy 298.308375 -193.914127) (xy 298.324645 -193.86138) (xy 298.348595 -193.811648)
			(xy 298.37969 -193.76604) (xy 298.417235 -193.725576) (xy 298.460392 -193.691159) (xy 298.508196 -193.66356)
			(xy 298.55958 -193.643393) (xy 298.613395 -193.63111) (xy 298.66844 -193.626985) (xy 298.723485 -193.63111)
			(xy 298.7773 -193.643393) (xy 298.828684 -193.66356) (xy 298.876488 -193.691159) (xy 298.919645 -193.725576)
			(xy 298.95719 -193.76604) (xy 298.988285 -193.811648) (xy 299.012235 -193.86138) (xy 299.028505 -193.914127)
			(xy 299.036732 -193.96871) (xy 299.037248 -193.99631) (xy 299.036756 -194.023597) (xy 299.028718 -194.077576)
			(xy 299.012818 -194.129782) (xy 298.989403 -194.179077) (xy 298.958983 -194.224387) (xy 298.922223 -194.264723)
			(xy 298.901358 -194.282314) (xy 298.891452 -194.290188) (xy 298.8818 -194.313556) (xy 298.891198 -194.422522)
			(xy 298.904914 -194.443604) (xy 298.91609 -194.4497) (xy 298.945312 -194.466642) (xy 298.999419 -194.507078)
			(xy 299.047701 -194.554317) (xy 299.089307 -194.607529) (xy 299.123507 -194.665778) (xy 299.1497 -194.72804)
			(xy 299.167424 -194.79322) (xy 299.176369 -194.860172) (xy 299.176948 -194.893946) (xy 299.176411 -194.927104)
			(xy 299.16779 -194.992857) (xy 299.1507 -195.056934) (xy 299.12543 -195.118247) (xy 299.09241 -195.175757)
			(xy 299.052198 -195.228491) (xy 299.005476 -195.275554) (xy 298.97959 -195.296282) (xy 298.970734 -195.30387)
			(xy 298.960435 -195.324768) (xy 298.959778 -195.336414) (xy 298.959778 -195.416678) (xy 298.960347 -195.428345)
			(xy 298.970672 -195.449267) (xy 298.97959 -195.45681) (xy 299.005484 -195.477529) (xy 299.052206 -195.524591)
			(xy 299.092417 -195.577326) (xy 299.125435 -195.634839) (xy 299.150699 -195.696154) (xy 299.167782 -195.760233)
			(xy 299.176393 -195.825988) (xy 299.176948 -195.859146) (xy 299.176419 -195.892159) (xy 299.167868 -195.95763)
			(xy 299.150915 -196.021443) (xy 299.125846 -196.082526) (xy 299.093083 -196.139851) (xy 299.07357 -196.166486)
			(xy 299.064934 -196.177916) (xy 299.06214 -196.206872) (xy 299.10913 -196.301106) (xy 299.113714 -196.309343)
			(xy 299.127626 -196.322038) (xy 299.14518 -196.328864) (xy 299.154596 -196.3293) (xy 299.458888 -196.3293)
			(xy 299.467837 -196.328942) (xy 299.484643 -196.322779) (xy 299.498319 -196.311231) (xy 299.503084 -196.303646)
			(xy 299.517211 -196.279639) (xy 299.551564 -196.235795) (xy 299.592124 -196.197618) (xy 299.637965 -196.165978)
			(xy 299.688045 -196.141596) (xy 299.741224 -196.125026) (xy 299.79629 -196.116645) (xy 299.85199 -196.116645)
			(xy 299.907056 -196.125026) (xy 299.960235 -196.141596) (xy 300.010315 -196.165978) (xy 300.056156 -196.197618)
			(xy 300.096716 -196.235795) (xy 300.131069 -196.279639) (xy 300.145196 -196.303646) (xy 300.149925 -196.311263)
			(xy 300.163603 -196.322837) (xy 300.180433 -196.328985) (xy 300.189392 -196.3293) (xy 301.174658 -196.3293)
			(xy 301.207254 -196.329743) (xy 301.272035 -196.33705) (xy 301.335591 -196.351565) (xy 301.397122 -196.373105)
			(xy 301.455854 -196.401399) (xy 301.511048 -196.436093) (xy 301.56201 -196.476748) (xy 301.570494 -196.485002)
			(xy 306.998893 -196.485002) (xy 307.002828 -196.431231) (xy 307.014551 -196.378607) (xy 307.033811 -196.32825)
			(xy 307.060197 -196.281233) (xy 307.093149 -196.23856) (xy 307.131962 -196.201139) (xy 307.17581 -196.169769)
			(xy 307.223758 -196.145117) (xy 307.274785 -196.127709) (xy 307.327803 -196.117916) (xy 307.381682 -196.115947)
			(xy 307.435273 -196.121844) (xy 307.487434 -196.13548) (xy 307.537054 -196.156567) (xy 307.539989 -196.158358)
			(xy 308.073296 -196.158358) (xy 308.07737 -196.09489) (xy 308.089528 -196.032465) (xy 308.109568 -195.972106)
			(xy 308.137162 -195.914806) (xy 308.171858 -195.861505) (xy 308.213084 -195.813078) (xy 308.260164 -195.770321)
			(xy 308.312326 -195.733935) (xy 308.368713 -195.704518) (xy 308.428398 -195.682553) (xy 308.490402 -195.668401)
			(xy 308.553706 -195.662295) (xy 308.617272 -195.664333) (xy 308.680055 -195.674483) (xy 308.741025 -195.692579)
			(xy 308.79918 -195.718322) (xy 308.853566 -195.751291) (xy 308.903289 -195.790944) (xy 308.947534 -195.83663)
			(xy 308.985573 -195.887599) (xy 309.016782 -195.943013) (xy 309.040648 -196.001964) (xy 309.05678 -196.063482)
			(xy 309.064913 -196.126559) (xy 309.065422 -196.158358) (xy 309.064913 -196.190157) (xy 309.05678 -196.253234)
			(xy 309.040648 -196.314752) (xy 309.016782 -196.373703) (xy 308.985573 -196.429117) (xy 308.947534 -196.480086)
			(xy 308.903289 -196.525772) (xy 308.853566 -196.565425) (xy 308.79918 -196.598394) (xy 308.741025 -196.624137)
			(xy 308.680055 -196.642233) (xy 308.617272 -196.652383) (xy 308.553706 -196.654421) (xy 308.490402 -196.648315)
			(xy 308.428398 -196.634163) (xy 308.368713 -196.612198) (xy 308.312326 -196.582781) (xy 308.260164 -196.546395)
			(xy 308.213084 -196.503638) (xy 308.171858 -196.455211) (xy 308.137162 -196.40191) (xy 308.109568 -196.34461)
			(xy 308.089528 -196.284251) (xy 308.07737 -196.221826) (xy 308.073296 -196.158358) (xy 307.539989 -196.158358)
			(xy 307.583075 -196.184653) (xy 307.624517 -196.219141) (xy 307.660495 -196.259295) (xy 307.690243 -196.304259)
			(xy 307.713128 -196.353076) (xy 307.72866 -196.404705) (xy 307.73651 -196.458045) (xy 307.737002 -196.485002)
			(xy 307.73651 -196.511959) (xy 307.72866 -196.565299) (xy 307.713128 -196.616928) (xy 307.690243 -196.665745)
			(xy 307.660495 -196.710709) (xy 307.624517 -196.750863) (xy 307.583075 -196.785351) (xy 307.537054 -196.813437)
			(xy 307.487434 -196.834524) (xy 307.435273 -196.84816) (xy 307.381682 -196.854057) (xy 307.327803 -196.852088)
			(xy 307.274785 -196.842295) (xy 307.223758 -196.824887) (xy 307.17581 -196.800235) (xy 307.131962 -196.768865)
			(xy 307.093149 -196.731444) (xy 307.060197 -196.688771) (xy 307.033811 -196.641754) (xy 307.014551 -196.591397)
			(xy 307.002828 -196.538773) (xy 306.998893 -196.485002) (xy 301.570494 -196.485002) (xy 301.585376 -196.49948)
			(xy 302.250348 -197.164452) (xy 302.257757 -197.171139) (xy 302.276193 -197.178731) (xy 302.286162 -197.179184)
			(xy 302.902874 -197.179184) (xy 302.911824 -197.178828) (xy 302.928632 -197.172667) (xy 302.942309 -197.161118)
			(xy 302.94707 -197.15353) (xy 302.961218 -197.12955) (xy 302.995601 -197.085761) (xy 303.036174 -197.047637)
			(xy 303.082017 -197.016043) (xy 303.132086 -196.991697) (xy 303.185246 -196.975153) (xy 303.240289 -196.966786)
			(xy 303.295963 -196.966786) (xy 303.351006 -196.975153) (xy 303.404166 -196.991697) (xy 303.454235 -197.016043)
			(xy 303.500078 -197.047637) (xy 303.540651 -197.085761) (xy 303.575034 -197.12955) (xy 303.589182 -197.15353)
			(xy 303.593914 -197.161139) (xy 303.607595 -197.172693) (xy 303.624423 -197.178816) (xy 303.633378 -197.179184)
			(xy 307.698394 -197.179184) (xy 307.73092 -197.179649) (xy 307.795563 -197.186943) (xy 307.858985 -197.201418)
			(xy 307.920392 -197.222894) (xy 307.979012 -197.251099) (xy 308.034112 -197.285682) (xy 308.085 -197.326207)
			(xy 308.10835 -197.348856) (xy 308.11576 -197.355542) (xy 308.134195 -197.363133) (xy 308.144164 -197.363588)
			(xy 312.390028 -197.363588) (xy 312.400096 -197.363159) (xy 312.418692 -197.355437) (xy 312.426096 -197.348602)
			(xy 312.950606 -196.824092) (xy 312.958185 -196.815572) (xy 312.965702 -196.794076) (xy 312.965084 -196.78269)
			(xy 312.954924 -196.692012) (xy 312.942732 -196.672708) (xy 312.932826 -196.666358) (xy 312.905907 -196.648861)
			(xy 312.856279 -196.608126) (xy 312.812172 -196.56147) (xy 312.774287 -196.509634) (xy 312.743227 -196.453443)
			(xy 312.719484 -196.393789) (xy 312.703438 -196.331622) (xy 312.695342 -196.26793) (xy 312.694828 -196.235828)
			(xy 312.695331 -196.203506) (xy 312.703524 -196.139383) (xy 312.719782 -196.076817) (xy 312.743841 -196.016817)
			(xy 312.775314 -195.960352) (xy 312.813693 -195.908333) (xy 312.858358 -195.8616) (xy 312.908588 -195.820909)
			(xy 312.963572 -195.786914) (xy 312.99277 -195.77304) (xy 313.00547 -195.767198) (xy 313.021218 -195.7451)
			(xy 313.030362 -195.6435) (xy 313.030878 -195.634581) (xy 313.026363 -195.617306) (xy 313.016153 -195.602659)
			(xy 313.009026 -195.597272) (xy 309.497984 -193.14541) (xy 309.4878 -193.139068) (xy 309.464088 -193.13563)
			(xy 309.452518 -193.138806) (xy 309.363618 -193.168778) (xy 309.3466 -193.18605) (xy 309.343044 -193.19748)
			(xy 309.329324 -193.238422) (xy 309.294913 -193.317622) (xy 309.25288 -193.393055) (xy 309.203631 -193.463987)
			(xy 309.147645 -193.529732) (xy 309.085464 -193.589651) (xy 309.017691 -193.643165) (xy 308.981602 -193.666872)
			(xy 308.974177 -193.672107) (xy 308.963313 -193.68665) (xy 308.958193 -193.704067) (xy 308.959459 -193.722177)
			(xy 308.962806 -193.730626) (xy 308.976763 -193.762888) (xy 308.996451 -193.830366) (xy 309.006395 -193.89995)
			(xy 309.007002 -193.935096) (xy 309.006494 -193.967197) (xy 308.998202 -194.030863) (xy 308.981756 -194.092923)
			(xy 308.957433 -194.15234) (xy 308.925638 -194.208118) (xy 308.886906 -194.259321) (xy 308.864762 -194.282568)
			(xy 308.85765 -194.289934) (xy 308.850284 -194.30873) (xy 308.851554 -194.40144) (xy 308.859682 -194.419982)
			(xy 308.867048 -194.427094) (xy 308.890734 -194.450554) (xy 308.932238 -194.502724) (xy 308.966375 -194.559987)
			(xy 308.992529 -194.621308) (xy 309.010228 -194.685581) (xy 309.019152 -194.751647) (xy 309.019702 -194.78498)
			(xy 309.019213 -194.816143) (xy 309.011401 -194.877977) (xy 308.995901 -194.938345) (xy 308.972958 -194.996293)
			(xy 308.942932 -195.05091) (xy 308.906298 -195.101332) (xy 308.863633 -195.146766) (xy 308.815611 -195.186494)
			(xy 308.762987 -195.219889) (xy 308.706593 -195.246426) (xy 308.647318 -195.265686) (xy 308.586097 -195.277365)
			(xy 308.523894 -195.281278) (xy 308.461691 -195.277365) (xy 308.40047 -195.265686) (xy 308.341195 -195.246426)
			(xy 308.284801 -195.219889) (xy 308.232177 -195.186494) (xy 308.184155 -195.146766) (xy 308.14149 -195.101332)
			(xy 308.104856 -195.05091) (xy 308.07483 -194.996293) (xy 308.051887 -194.938345) (xy 308.036387 -194.877977)
			(xy 308.028575 -194.816143) (xy 308.028086 -194.78498) (xy 308.028596 -194.752879) (xy 308.03689 -194.689215)
			(xy 308.053338 -194.627156) (xy 308.077663 -194.567741) (xy 308.109459 -194.511965) (xy 308.148191 -194.460763)
			(xy 308.170326 -194.437508) (xy 308.177438 -194.430142) (xy 308.184804 -194.411346) (xy 308.183534 -194.318636)
			(xy 308.175406 -194.300094) (xy 308.16804 -194.292982) (xy 308.144351 -194.269524) (xy 308.10284 -194.217355)
			(xy 308.068695 -194.160093) (xy 308.042532 -194.098772) (xy 308.024824 -194.034498) (xy 308.01589 -193.96843)
			(xy 308.015386 -193.935096) (xy 308.015996 -193.900422) (xy 308.025651 -193.83175) (xy 308.044759 -193.765087)
			(xy 308.058312 -193.733166) (xy 308.061703 -193.724716) (xy 308.062906 -193.706562) (xy 308.057699 -193.689129)
			(xy 308.046738 -193.674607) (xy 308.039262 -193.669412) (xy 308.005613 -193.64758) (xy 307.942038 -193.598662)
			(xy 307.8832 -193.544139) (xy 307.829591 -193.484467) (xy 307.781659 -193.420145) (xy 307.739805 -193.351713)
			(xy 307.704381 -193.279742) (xy 307.675682 -193.204835) (xy 307.653948 -193.127618) (xy 307.639362 -193.048739)
			(xy 307.632045 -192.968856) (xy 307.631592 -192.928748) (xy 307.632037 -192.888997) (xy 307.639233 -192.809821)
			(xy 307.653571 -192.731623) (xy 307.674933 -192.655045) (xy 307.703143 -192.580716) (xy 307.737969 -192.509248)
			(xy 307.779125 -192.441228) (xy 307.826273 -192.377215) (xy 307.879025 -192.317735) (xy 307.90769 -192.290192)
			(xy 307.91912 -192.27927) (xy 307.925724 -192.249044) (xy 307.885084 -192.146682) (xy 307.880971 -192.137412)
			(xy 307.866855 -192.122873) (xy 307.848223 -192.114908) (xy 307.838094 -192.114424) (xy 306.682902 -192.114424)
			(xy 306.672832 -192.114847) (xy 306.654229 -192.122564) (xy 306.646834 -192.12941) (xy 306.588922 -192.18783)
			(xy 306.581302 -192.206372) (xy 306.581302 -192.216532) (xy 306.581302 -192.21831) (xy 306.580786 -192.24591)
			(xy 306.572559 -192.300493) (xy 306.556289 -192.35324) (xy 306.532339 -192.402973) (xy 306.501244 -192.44858)
			(xy 306.463699 -192.489044) (xy 306.420542 -192.523461) (xy 306.372738 -192.55106) (xy 306.321354 -192.571227)
			(xy 306.267539 -192.58351) (xy 306.212494 -192.587635) (xy 306.157449 -192.58351) (xy 306.103634 -192.571227)
			(xy 306.05225 -192.55106) (xy 306.004446 -192.523461) (xy 305.961289 -192.489044) (xy 305.923744 -192.44858)
			(xy 305.892649 -192.402973) (xy 305.868699 -192.35324) (xy 305.852429 -192.300493) (xy 305.844202 -192.24591)
			(xy 305.843686 -192.21831) (xy 305.843686 -192.206372) (xy 305.836066 -192.18783) (xy 305.778154 -192.12941)
			(xy 305.770753 -192.12257) (xy 305.752155 -192.11485) (xy 305.742086 -192.114424) (xy 304.894234 -192.114424)
			(xy 304.88417 -192.11486) (xy 304.865585 -192.122594) (xy 304.858166 -192.12941) (xy 304.800254 -192.18783)
			(xy 304.792634 -192.206372) (xy 304.792634 -192.216532) (xy 304.792634 -192.21831) (xy 304.792118 -192.24591)
			(xy 304.783891 -192.300493) (xy 304.767621 -192.35324) (xy 304.743671 -192.402973) (xy 304.712576 -192.44858)
			(xy 304.675031 -192.489044) (xy 304.631874 -192.523461) (xy 304.58407 -192.55106) (xy 304.532686 -192.571227)
			(xy 304.478871 -192.58351) (xy 304.423826 -192.587635) (xy 304.368781 -192.58351) (xy 304.314966 -192.571227)
			(xy 304.263582 -192.55106) (xy 304.215778 -192.523461) (xy 304.172621 -192.489044) (xy 304.135076 -192.44858)
			(xy 304.103981 -192.402973) (xy 304.080031 -192.35324) (xy 304.063761 -192.300493) (xy 304.055534 -192.24591)
			(xy 304.055018 -192.21831) (xy 304.055018 -192.206372) (xy 304.047398 -192.18783) (xy 303.989486 -192.12941)
			(xy 303.982087 -192.122565) (xy 303.963489 -192.114834) (xy 303.953418 -192.114424) (xy 303.7332 -192.114424)
			(xy 303.726088 -192.114424) (xy 303.104042 -192.108836) (xy 303.093819 -192.109242) (xy 303.074948 -192.117099)
			(xy 303.067466 -192.124076) (xy 303.009046 -192.183512) (xy 303.001426 -192.202562) (xy 303.00168 -192.212976)
			(xy 303.001934 -192.235074) (xy 303.001444 -192.276801) (xy 302.993493 -192.359874) (xy 302.97768 -192.441815)
			(xy 302.954147 -192.521882) (xy 302.923109 -192.599349) (xy 302.904398 -192.636648) (xy 302.89942 -192.647811)
			(xy 302.899427 -192.672217) (xy 302.904398 -192.683384) (xy 302.923076 -192.720698) (xy 302.954095 -192.798166)
			(xy 302.977619 -192.878231) (xy 302.993435 -192.960167) (xy 303.0014 -193.043234) (xy 303.001934 -193.084958)
			(xy 303.001419 -193.127344) (xy 302.993233 -193.21172) (xy 302.976943 -193.294912) (xy 302.952701 -193.376144)
			(xy 302.920734 -193.454657) (xy 302.881339 -193.529719) (xy 302.834884 -193.600629) (xy 302.781804 -193.666726)
			(xy 302.722593 -193.727392) (xy 302.657804 -193.78206) (xy 302.62322 -193.806572) (xy 302.615583 -193.81233)
			(xy 302.604919 -193.828191) (xy 302.600796 -193.846853) (xy 302.601884 -193.856356) (xy 302.604838 -193.875907)
			(xy 302.608019 -193.915324) (xy 302.608234 -193.935096) (xy 302.607774 -193.965786) (xy 302.603978 -193.996305)
			(xy 303.927495 -193.996305) (xy 303.931342 -193.934627) (xy 303.942824 -193.873905) (xy 303.961763 -193.815081)
			(xy 303.987865 -193.759067) (xy 304.020726 -193.706731) (xy 304.059837 -193.658884) (xy 304.10459 -193.616269)
			(xy 304.154293 -193.579545) (xy 304.181002 -193.564002) (xy 304.192178 -193.557906) (xy 304.20564 -193.53657)
			(xy 304.214276 -193.427096) (xy 304.20437 -193.403982) (xy 304.19421 -193.396108) (xy 304.172876 -193.378506)
			(xy 304.135213 -193.338004) (xy 304.104025 -193.292329) (xy 304.080012 -193.242507) (xy 304.063712 -193.189657)
			(xy 304.055491 -193.134964) (xy 304.055018 -193.10731) (xy 304.055534 -193.07971) (xy 304.063761 -193.025127)
			(xy 304.080031 -192.97238) (xy 304.103981 -192.922648) (xy 304.135076 -192.87704) (xy 304.172621 -192.836576)
			(xy 304.215778 -192.802159) (xy 304.263582 -192.77456) (xy 304.314966 -192.754393) (xy 304.368781 -192.74211)
			(xy 304.423826 -192.737985) (xy 304.478871 -192.74211) (xy 304.532686 -192.754393) (xy 304.58407 -192.77456)
			(xy 304.631874 -192.802159) (xy 304.675031 -192.836576) (xy 304.712576 -192.87704) (xy 304.743671 -192.922648)
			(xy 304.767621 -192.97238) (xy 304.783891 -193.025127) (xy 304.792118 -193.07971) (xy 304.792634 -193.10731)
			(xy 304.792139 -193.134961) (xy 304.7839 -193.189646) (xy 304.767594 -193.242489) (xy 304.743584 -193.292308)
			(xy 304.71241 -193.337986) (xy 304.674768 -193.3785) (xy 304.653442 -193.396108) (xy 304.643282 -193.403982)
			(xy 304.633376 -193.427096) (xy 304.642012 -193.53657) (xy 304.655474 -193.557906) (xy 304.66665 -193.564002)
			(xy 304.693366 -193.579532) (xy 304.743066 -193.61626) (xy 304.787816 -193.658878) (xy 304.826924 -193.706727)
			(xy 304.859783 -193.759065) (xy 304.885883 -193.815081) (xy 304.90482 -193.873905) (xy 304.916301 -193.934627)
			(xy 304.920148 -193.996305) (xy 304.9163 -194.057983) (xy 304.904818 -194.118704) (xy 304.885879 -194.177528)
			(xy 304.859778 -194.233543) (xy 304.826918 -194.28588) (xy 304.78781 -194.333729) (xy 304.743058 -194.376347)
			(xy 304.693358 -194.413073) (xy 304.66665 -194.428618) (xy 304.655474 -194.434714) (xy 304.642012 -194.45605)
			(xy 304.633376 -194.565524) (xy 304.643282 -194.588638) (xy 304.653442 -194.596512) (xy 304.674776 -194.614114)
			(xy 304.712441 -194.654615) (xy 304.74363 -194.700289) (xy 304.767644 -194.750111) (xy 304.783944 -194.802962)
			(xy 304.792162 -194.857656) (xy 304.792634 -194.88531) (xy 304.792118 -194.91291) (xy 304.783891 -194.967493)
			(xy 304.767621 -195.02024) (xy 304.743671 -195.069973) (xy 304.712576 -195.11558) (xy 304.675031 -195.156044)
			(xy 304.631874 -195.190461) (xy 304.58407 -195.21806) (xy 304.532686 -195.238227) (xy 304.478871 -195.25051)
			(xy 304.423826 -195.254635) (xy 304.368781 -195.25051) (xy 304.314966 -195.238227) (xy 304.263582 -195.21806)
			(xy 304.215778 -195.190461) (xy 304.172621 -195.156044) (xy 304.135076 -195.11558) (xy 304.103981 -195.069973)
			(xy 304.080031 -195.02024) (xy 304.063761 -194.967493) (xy 304.055534 -194.91291) (xy 304.055018 -194.88531)
			(xy 304.055508 -194.857658) (xy 304.063745 -194.802972) (xy 304.080051 -194.750128) (xy 304.104062 -194.700309)
			(xy 304.135238 -194.654632) (xy 304.172883 -194.614118) (xy 304.19421 -194.596512) (xy 304.20437 -194.588638)
			(xy 304.214276 -194.565524) (xy 304.20564 -194.45605) (xy 304.192178 -194.434714) (xy 304.181002 -194.428618)
			(xy 304.154301 -194.41306) (xy 304.104598 -194.376338) (xy 304.059844 -194.333723) (xy 304.020732 -194.285877)
			(xy 303.98787 -194.233542) (xy 303.961766 -194.177528) (xy 303.942826 -194.118704) (xy 303.931343 -194.057983)
			(xy 303.927495 -193.996305) (xy 302.603978 -193.996305) (xy 302.600198 -194.026698) (xy 302.585162 -194.086209)
			(xy 302.562894 -194.143408) (xy 302.533737 -194.197422) (xy 302.498135 -194.247423) (xy 302.456634 -194.292648)
			(xy 302.409868 -194.332404) (xy 302.38446 -194.349624) (xy 302.37557 -194.355466) (xy 302.364394 -194.372484)
			(xy 302.347376 -194.465448) (xy 302.351694 -194.485514) (xy 302.358044 -194.49415) (xy 302.375887 -194.519613)
			(xy 302.405774 -194.574135) (xy 302.428607 -194.631968) (xy 302.444028 -194.692202) (xy 302.451794 -194.753892)
			(xy 302.452278 -194.78498) (xy 302.451771 -194.817444) (xy 302.443299 -194.881816) (xy 302.426496 -194.944532)
			(xy 302.40165 -195.004518) (xy 302.369187 -195.060747) (xy 302.329661 -195.112257) (xy 302.28375 -195.158168)
			(xy 302.232238 -195.197692) (xy 302.176009 -195.230154) (xy 302.116022 -195.254999) (xy 302.053306 -195.271801)
			(xy 301.988934 -195.280272) (xy 301.95647 -195.280788) (xy 301.923364 -195.280236) (xy 301.85774 -195.271421)
			(xy 301.793874 -195.253951) (xy 301.7329 -195.228137) (xy 301.675904 -195.194439) (xy 301.6239 -195.153455)
			(xy 301.577812 -195.105915) (xy 301.55769 -195.07962) (xy 301.550324 -195.069714) (xy 301.528988 -195.059046)
			(xy 301.4218 -195.059808) (xy 301.400718 -195.07073) (xy 301.393352 -195.08089) (xy 301.380571 -195.098366)
			(xy 301.352467 -195.131306) (xy 301.337218 -195.146676) (xy 301.329852 -195.154042) (xy 301.322232 -195.172076)
			(xy 301.321216 -195.264024) (xy 301.328582 -195.282566) (xy 301.335694 -195.289932) (xy 301.357518 -195.313114)
			(xy 301.395651 -195.3641) (xy 301.426938 -195.419552) (xy 301.450862 -195.478555) (xy 301.467029 -195.540137)
			(xy 301.469352 -195.558156) (xy 305.687984 -195.558156) (xy 305.688555 -195.524392) (xy 305.697736 -195.457489)
			(xy 305.715909 -195.392451) (xy 305.742737 -195.33048) (xy 305.777725 -195.272721) (xy 305.820225 -195.220243)
			(xy 305.844448 -195.196714) (xy 305.85156 -195.189856) (xy 305.859942 -195.171822) (xy 305.864006 -195.081144)
			(xy 305.857402 -195.062348) (xy 305.850544 -195.054982) (xy 305.830338 -195.031623) (xy 305.795112 -194.980888)
			(xy 305.766289 -194.926261) (xy 305.744291 -194.868546) (xy 305.729444 -194.808593) (xy 305.721966 -194.747282)
			(xy 305.721512 -194.7164) (xy 305.721967 -194.685796) (xy 305.729321 -194.625032) (xy 305.74391 -194.565589)
			(xy 305.765524 -194.508325) (xy 305.79385 -194.454067) (xy 305.828481 -194.403598) (xy 305.868914 -194.357648)
			(xy 305.891438 -194.336924) (xy 305.89855 -194.330828) (xy 305.906932 -194.314826) (xy 305.917346 -194.229482)
			(xy 305.913028 -194.211956) (xy 305.907694 -194.204082) (xy 305.892591 -194.180979) (xy 305.868679 -194.131233)
			(xy 305.85243 -194.078485) (xy 305.844206 -194.023907) (xy 305.843686 -193.99631) (xy 305.844202 -193.96871)
			(xy 305.852429 -193.914127) (xy 305.868699 -193.86138) (xy 305.892649 -193.811648) (xy 305.923744 -193.76604)
			(xy 305.961289 -193.725576) (xy 306.004446 -193.691159) (xy 306.05225 -193.66356) (xy 306.103634 -193.643393)
			(xy 306.157449 -193.63111) (xy 306.212494 -193.626985) (xy 306.267539 -193.63111) (xy 306.321354 -193.643393)
			(xy 306.372738 -193.66356) (xy 306.420542 -193.691159) (xy 306.463699 -193.725576) (xy 306.501244 -193.76604)
			(xy 306.532339 -193.811648) (xy 306.556289 -193.86138) (xy 306.572559 -193.914127) (xy 306.580786 -193.96871)
			(xy 306.581302 -193.99631) (xy 306.580849 -194.021645) (xy 306.573903 -194.071837) (xy 306.560143 -194.120603)
			(xy 306.539829 -194.167023) (xy 306.526946 -194.188842) (xy 306.52212 -194.19697) (xy 306.518564 -194.21475)
			(xy 306.533296 -194.299332) (xy 306.54244 -194.31508) (xy 306.549806 -194.320922) (xy 306.57465 -194.341679)
			(xy 306.619404 -194.388458) (xy 306.657862 -194.440538) (xy 306.689402 -194.497075) (xy 306.713514 -194.557157)
			(xy 306.729808 -194.619813) (xy 306.738022 -194.68403) (xy 306.738528 -194.7164) (xy 306.738104 -194.746865)
			(xy 306.730828 -194.80736) (xy 306.71638 -194.866552) (xy 306.694967 -194.923596) (xy 306.666894 -194.977674)
			(xy 306.632565 -195.028013) (xy 306.59247 -195.073892) (xy 306.570126 -195.094606) (xy 306.562506 -195.10121)
			(xy 306.55387 -195.11899) (xy 306.548028 -195.209668) (xy 306.554124 -195.228464) (xy 306.560728 -195.236084)
			(xy 306.579409 -195.258561) (xy 306.61189 -195.307151) (xy 306.638432 -195.359224) (xy 306.658666 -195.414058)
			(xy 306.672311 -195.47089) (xy 306.679178 -195.528932) (xy 306.6796 -195.558156) (xy 306.679111 -195.589319)
			(xy 306.671299 -195.651153) (xy 306.655799 -195.711521) (xy 306.632856 -195.769469) (xy 306.60283 -195.824086)
			(xy 306.566196 -195.874508) (xy 306.523531 -195.919942) (xy 306.475509 -195.95967) (xy 306.422885 -195.993065)
			(xy 306.366491 -196.019602) (xy 306.307216 -196.038862) (xy 306.245995 -196.050541) (xy 306.183792 -196.054454)
			(xy 306.121589 -196.050541) (xy 306.060368 -196.038862) (xy 306.001093 -196.019602) (xy 305.944699 -195.993065)
			(xy 305.892075 -195.95967) (xy 305.844053 -195.919942) (xy 305.801388 -195.874508) (xy 305.764754 -195.824086)
			(xy 305.734728 -195.769469) (xy 305.711785 -195.711521) (xy 305.696285 -195.651153) (xy 305.688473 -195.589319)
			(xy 305.687984 -195.558156) (xy 301.469352 -195.558156) (xy 301.475171 -195.603283) (xy 301.475648 -195.635118)
			(xy 301.475159 -195.666281) (xy 301.467347 -195.728115) (xy 301.451847 -195.788483) (xy 301.428904 -195.846431)
			(xy 301.398878 -195.901048) (xy 301.362244 -195.95147) (xy 301.319579 -195.996904) (xy 301.271557 -196.036632)
			(xy 301.218933 -196.070027) (xy 301.162539 -196.096564) (xy 301.103264 -196.115824) (xy 301.042043 -196.127503)
			(xy 300.97984 -196.131416) (xy 300.917637 -196.127503) (xy 300.856416 -196.115824) (xy 300.797141 -196.096564)
			(xy 300.740747 -196.070027) (xy 300.688123 -196.036632) (xy 300.640101 -195.996904) (xy 300.597436 -195.95147)
			(xy 300.560802 -195.901048) (xy 300.530776 -195.846431) (xy 300.507833 -195.788483) (xy 300.492333 -195.728115)
			(xy 300.484521 -195.666281) (xy 300.484032 -195.635118) (xy 300.484527 -195.603286) (xy 300.492687 -195.540147)
			(xy 300.508863 -195.478573) (xy 300.532788 -195.419575) (xy 300.564069 -195.364126) (xy 300.60219 -195.313137)
			(xy 300.623986 -195.289932) (xy 300.631098 -195.282566) (xy 300.638464 -195.264024) (xy 300.637448 -195.172076)
			(xy 300.629828 -195.154042) (xy 300.622462 -195.146676) (xy 300.598974 -195.122715) (xy 300.557857 -195.069691)
			(xy 300.524068 -195.011722) (xy 300.498193 -194.949814) (xy 300.480681 -194.885041) (xy 300.471837 -194.818529)
			(xy 300.471332 -194.78498) (xy 300.471847 -194.752059) (xy 300.480338 -194.686767) (xy 300.497186 -194.623117)
			(xy 300.522112 -194.562176) (xy 300.554697 -194.504962) (xy 300.594395 -194.452435) (xy 300.617128 -194.428618)
			(xy 300.62424 -194.421252) (xy 300.631606 -194.402964) (xy 300.631352 -194.311016) (xy 300.623732 -194.292728)
			(xy 300.616366 -194.285616) (xy 300.593812 -194.26228) (xy 300.554337 -194.210768) (xy 300.521915 -194.154548)
			(xy 300.497102 -194.094581) (xy 300.480321 -194.03189) (xy 300.471858 -193.967545) (xy 300.471332 -193.935096)
			(xy 300.47184 -193.902633) (xy 300.480315 -193.838264) (xy 300.49712 -193.775551) (xy 300.521968 -193.715569)
			(xy 300.554432 -193.659343) (xy 300.593958 -193.607836) (xy 300.639869 -193.561929) (xy 300.69138 -193.522408)
			(xy 300.747608 -193.489948) (xy 300.807593 -193.465106) (xy 300.870307 -193.448307) (xy 300.934677 -193.439837)
			(xy 300.96714 -193.439288) (xy 300.999192 -193.439791) (xy 301.062761 -193.448056) (xy 301.124732 -193.464458)
			(xy 301.154592 -193.476118) (xy 301.168308 -193.481706) (xy 301.197264 -193.476372) (xy 301.286672 -193.393822)
			(xy 301.294292 -193.365374) (xy 301.28972 -193.35115) (xy 301.277224 -193.310269) (xy 301.25929 -193.22668)
			(xy 301.253906 -193.184272) (xy 301.252636 -193.17335) (xy 301.242222 -193.155316) (xy 301.164752 -193.09842)
			(xy 301.144178 -193.093848) (xy 301.133764 -193.09588) (xy 301.092515 -193.103364) (xy 301.009059 -193.111376)
			(xy 300.96714 -193.111882) (xy 300.924089 -193.111373) (xy 300.838403 -193.102937) (xy 300.753956 -193.086142)
			(xy 300.671561 -193.061151) (xy 300.592014 -193.028204) (xy 300.516078 -192.987618) (xy 300.444487 -192.939784)
			(xy 300.37793 -192.885163) (xy 300.317047 -192.824281) (xy 300.262424 -192.757724) (xy 300.214589 -192.686134)
			(xy 300.174002 -192.610199) (xy 300.141054 -192.530652) (xy 300.116061 -192.448258) (xy 300.099265 -192.363811)
			(xy 300.090828 -192.278124) (xy 300.090332 -192.235074) (xy 300.091602 -192.187322) (xy 300.09211 -192.176654)
			(xy 300.085252 -192.15735) (xy 300.027594 -192.096136) (xy 300.020197 -192.088949) (xy 300.001317 -192.080695)
			(xy 299.991018 -192.080134) (xy 299.137578 -192.07226) (xy 299.126909 -192.07276) (xy 299.107354 -192.081289)
			(xy 299.099732 -192.08877) (xy 299.041312 -192.15227) (xy 299.034454 -192.17259) (xy 299.03547 -192.183512)
			(xy 299.037248 -192.21831) (xy 299.036732 -192.24591) (xy 299.028505 -192.300493) (xy 299.012235 -192.35324)
			(xy 298.988285 -192.402973) (xy 298.95719 -192.44858) (xy 298.919645 -192.489044) (xy 298.876488 -192.523461)
			(xy 298.828684 -192.55106) (xy 298.7773 -192.571227) (xy 298.723485 -192.58351) (xy 298.66844 -192.587635)
			(xy 298.613395 -192.58351) (xy 298.55958 -192.571227) (xy 298.508196 -192.55106) (xy 298.460392 -192.523461)
			(xy 298.417235 -192.489044) (xy 298.37969 -192.44858) (xy 298.348595 -192.402973) (xy 298.324645 -192.35324)
			(xy 298.308375 -192.300493) (xy 298.300148 -192.24591) (xy 298.299632 -192.21831) (xy 298.299679 -192.207874)
			(xy 298.300821 -192.187033) (xy 298.301918 -192.176654) (xy 298.303188 -192.165732) (xy 298.296838 -192.145412)
			(xy 298.239688 -192.080642) (xy 298.232171 -192.073067) (xy 298.212748 -192.064283) (xy 298.202096 -192.063624)
			(xy 297.347132 -192.05575) (xy 297.336189 -192.056108) (xy 297.31618 -192.064939) (xy 297.308524 -192.072768)
			(xy 297.250358 -192.138554) (xy 297.244008 -192.159382) (xy 297.245532 -192.170558) (xy 297.246967 -192.182444)
			(xy 297.24849 -192.206338) (xy 297.24858 -192.21831) (xy 297.248064 -192.24591) (xy 297.239837 -192.300493)
			(xy 297.223567 -192.35324) (xy 297.199617 -192.402973) (xy 297.168522 -192.44858) (xy 297.130977 -192.489044)
			(xy 297.08782 -192.523461) (xy 297.040016 -192.55106) (xy 296.988632 -192.571227) (xy 296.934817 -192.58351)
			(xy 296.879772 -192.587635) (xy 296.824727 -192.58351) (xy 296.770912 -192.571227) (xy 296.719528 -192.55106)
			(xy 296.671724 -192.523461) (xy 296.628567 -192.489044) (xy 296.591022 -192.44858) (xy 296.559927 -192.402973)
			(xy 296.535977 -192.35324) (xy 296.519707 -192.300493) (xy 296.51148 -192.24591) (xy 296.510964 -192.21831)
			(xy 296.511089 -192.204606) (xy 296.513124 -192.177272) (xy 296.515028 -192.1637) (xy 296.516806 -192.152778)
			(xy 296.51071 -192.131696) (xy 296.45356 -192.064894) (xy 296.446088 -192.056955) (xy 296.426345 -192.047758)
			(xy 296.41546 -192.047114) (xy 295.555924 -192.03924) (xy 295.54519 -192.039701) (xy 295.525498 -192.048231)
			(xy 295.517824 -192.05575) (xy 295.459404 -192.119504) (xy 295.4528 -192.13957) (xy 295.453816 -192.150492)
			(xy 295.455726 -192.171585) (xy 295.457758 -192.213895) (xy 295.45788 -192.235074) (xy 295.45739 -192.2768)
			(xy 295.449439 -192.359874) (xy 295.433624 -192.441815) (xy 295.410091 -192.521881) (xy 295.37905 -192.599346)
			(xy 295.360344 -192.636648) (xy 295.35537 -192.647812) (xy 295.355377 -192.672216) (xy 295.360344 -192.683384)
			(xy 295.379023 -192.720697) (xy 295.410044 -192.798166) (xy 295.433569 -192.87823) (xy 295.449386 -192.960166)
			(xy 295.457352 -193.043234) (xy 295.45788 -193.084958) (xy 295.457365 -193.127344) (xy 295.449179 -193.211719)
			(xy 295.432888 -193.29491) (xy 295.408645 -193.37614) (xy 295.376676 -193.454652) (xy 295.33728 -193.529713)
			(xy 295.290824 -193.600621) (xy 295.237741 -193.666715) (xy 295.178528 -193.727378) (xy 295.113737 -193.782043)
			(xy 295.079166 -193.806572) (xy 295.071524 -193.812327) (xy 295.060849 -193.828187) (xy 295.056722 -193.846854)
			(xy 295.05783 -193.856356) (xy 295.060784 -193.875907) (xy 295.063964 -193.915324) (xy 295.06418 -193.935096)
			(xy 295.06369 -193.96693) (xy 295.059899 -193.996305) (xy 296.383469 -193.996305) (xy 296.387315 -193.934629)
			(xy 296.398795 -193.87391) (xy 296.417732 -193.815087) (xy 296.443831 -193.759074) (xy 296.476689 -193.706738)
			(xy 296.515795 -193.65889) (xy 296.560544 -193.616273) (xy 296.610241 -193.579547) (xy 296.636948 -193.564002)
			(xy 296.648124 -193.557906) (xy 296.661586 -193.53657) (xy 296.670222 -193.427096) (xy 296.660316 -193.403982)
			(xy 296.650156 -193.396108) (xy 296.628831 -193.378495) (xy 296.591166 -193.337997) (xy 296.559976 -193.292325)
			(xy 296.53596 -193.242505) (xy 296.519658 -193.189655) (xy 296.511437 -193.134964) (xy 296.510964 -193.10731)
			(xy 296.51148 -193.07971) (xy 296.519707 -193.025127) (xy 296.535977 -192.97238) (xy 296.559927 -192.922648)
			(xy 296.591022 -192.87704) (xy 296.628567 -192.836576) (xy 296.671724 -192.802159) (xy 296.719528 -192.77456)
			(xy 296.770912 -192.754393) (xy 296.824727 -192.74211) (xy 296.879772 -192.737985) (xy 296.934817 -192.74211)
			(xy 296.988632 -192.754393) (xy 297.040016 -192.77456) (xy 297.08782 -192.802159) (xy 297.130977 -192.836576)
			(xy 297.168522 -192.87704) (xy 297.199617 -192.922648) (xy 297.223567 -192.97238) (xy 297.239837 -193.025127)
			(xy 297.248064 -193.07971) (xy 297.24858 -193.10731) (xy 297.248105 -193.134962) (xy 297.239865 -193.189649)
			(xy 297.223556 -193.242494) (xy 297.199543 -193.292312) (xy 297.168363 -193.33799) (xy 297.130717 -193.378502)
			(xy 297.109388 -193.396108) (xy 297.099228 -193.403982) (xy 297.089322 -193.427096) (xy 297.097958 -193.53657)
			(xy 297.11142 -193.557906) (xy 297.122596 -193.564002) (xy 297.149315 -193.57953) (xy 297.199019 -193.616255)
			(xy 297.243774 -193.658872) (xy 297.282886 -193.70672) (xy 297.315749 -193.759059) (xy 297.341852 -193.815075)
			(xy 297.360792 -193.873901) (xy 297.372274 -193.934625) (xy 297.376121 -193.996305) (xy 297.372273 -194.057985)
			(xy 297.36079 -194.118708) (xy 297.341849 -194.177534) (xy 297.315744 -194.23355) (xy 297.282881 -194.285888)
			(xy 297.243768 -194.333735) (xy 297.199011 -194.376351) (xy 297.149306 -194.413075) (xy 297.122596 -194.428618)
			(xy 297.11142 -194.434714) (xy 297.097958 -194.45605) (xy 297.089322 -194.565524) (xy 297.099228 -194.588638)
			(xy 297.109388 -194.596512) (xy 297.130732 -194.614103) (xy 297.168393 -194.654607) (xy 297.19958 -194.700284)
			(xy 297.223592 -194.750108) (xy 297.23989 -194.802961) (xy 297.248108 -194.857655) (xy 297.24858 -194.88531)
			(xy 297.248064 -194.91291) (xy 297.239837 -194.967493) (xy 297.223567 -195.02024) (xy 297.199617 -195.069973)
			(xy 297.168522 -195.11558) (xy 297.130977 -195.156044) (xy 297.08782 -195.190461) (xy 297.040016 -195.21806)
			(xy 296.988632 -195.238227) (xy 296.934817 -195.25051) (xy 296.879772 -195.254635) (xy 296.824727 -195.25051)
			(xy 296.770912 -195.238227) (xy 296.719528 -195.21806) (xy 296.671724 -195.190461) (xy 296.628567 -195.156044)
			(xy 296.591022 -195.11558) (xy 296.559927 -195.069973) (xy 296.535977 -195.02024) (xy 296.519707 -194.967493)
			(xy 296.51148 -194.91291) (xy 296.510964 -194.88531) (xy 296.511474 -194.857659) (xy 296.51971 -194.802975)
			(xy 296.536013 -194.750132) (xy 296.56002 -194.700314) (xy 296.591192 -194.654635) (xy 296.628831 -194.61412)
			(xy 296.650156 -194.596512) (xy 296.660316 -194.588638) (xy 296.670222 -194.565524) (xy 296.661586 -194.45605)
			(xy 296.648124 -194.434714) (xy 296.636948 -194.428618) (xy 296.61025 -194.413058) (xy 296.560551 -194.376333)
			(xy 296.515802 -194.333717) (xy 296.476695 -194.28587) (xy 296.443836 -194.233535) (xy 296.417736 -194.177522)
			(xy 296.398798 -194.1187) (xy 296.387316 -194.05798) (xy 296.383469 -193.996305) (xy 295.059899 -193.996305)
			(xy 295.05554 -194.030074) (xy 295.039373 -194.091656) (xy 295.015456 -194.150661) (xy 294.984182 -194.206119)
			(xy 294.946065 -194.257116) (xy 294.924226 -194.280282) (xy 294.917114 -194.287648) (xy 294.909748 -194.305936)
			(xy 294.910764 -194.397884) (xy 294.918638 -194.416172) (xy 294.92575 -194.423284) (xy 294.949234 -194.447247)
			(xy 294.990344 -194.500272) (xy 295.024125 -194.558243) (xy 295.049992 -194.620151) (xy 295.067496 -194.684922)
			(xy 295.076332 -194.751433) (xy 295.07688 -194.78498) (xy 295.076378 -194.816941) (xy 295.068367 -194.880359)
			(xy 295.05247 -194.942273) (xy 295.028938 -195.001706) (xy 294.998144 -195.057721) (xy 294.960571 -195.109436)
			(xy 294.916814 -195.156033) (xy 294.867561 -195.196778) (xy 294.81359 -195.231029) (xy 294.755751 -195.258246)
			(xy 294.694958 -195.277999) (xy 294.632168 -195.289977) (xy 294.568372 -195.293991) (xy 294.504576 -195.289977)
			(xy 294.441786 -195.277999) (xy 294.380993 -195.258246) (xy 294.323154 -195.231029) (xy 294.269183 -195.196778)
			(xy 294.21993 -195.156033) (xy 294.176173 -195.109436) (xy 294.1386 -195.057721) (xy 294.107806 -195.001706)
			(xy 294.084274 -194.942273) (xy 294.068377 -194.880359) (xy 294.060366 -194.816941) (xy 294.059864 -194.78498)
			(xy 294.060398 -194.75143) (xy 294.069217 -194.684913) (xy 294.086712 -194.620135) (xy 294.112579 -194.558223)
			(xy 294.146368 -194.500252) (xy 294.187492 -194.447232) (xy 294.210994 -194.423284) (xy 294.218106 -194.416172)
			(xy 294.22598 -194.397884) (xy 294.226996 -194.305936) (xy 294.21963 -194.287648) (xy 294.212518 -194.280282)
			(xy 294.190693 -194.2571) (xy 294.152557 -194.206115) (xy 294.121268 -194.150664) (xy 294.097342 -194.091661)
			(xy 294.081173 -194.030078) (xy 294.073028 -193.966931) (xy 294.072564 -193.935096) (xy 294.072852 -193.911647)
			(xy 294.077308 -193.86496) (xy 294.081454 -193.841878) (xy 294.082883 -193.832389) (xy 294.07936 -193.813539)
			(xy 294.069148 -193.79731) (xy 294.061642 -193.791332) (xy 294.038699 -193.774185) (xy 293.994851 -193.737323)
			(xy 293.974012 -193.717672) (xy 293.966675 -193.71129) (xy 293.948625 -193.704098) (xy 293.929195 -193.704133)
			(xy 293.911172 -193.711389) (xy 293.897138 -193.724826) (xy 293.889106 -193.742518) (xy 293.888228 -193.761928)
			(xy 293.890954 -193.771266) (xy 293.899815 -193.79766) (xy 293.912245 -193.851933) (xy 293.918516 -193.907257)
			(xy 293.918894 -193.935096) (xy 293.91845 -193.965219) (xy 293.911147 -194.025022) (xy 293.896648 -194.083498)
			(xy 293.875168 -194.139785) (xy 293.847022 -194.193053) (xy 293.812627 -194.242517) (xy 293.79291 -194.265296)
			(xy 293.786306 -194.272662) (xy 293.779702 -194.29095) (xy 293.78275 -194.380866) (xy 293.79037 -194.398646)
			(xy 293.797482 -194.405504) (xy 293.821188 -194.429502) (xy 293.862705 -194.482666) (xy 293.896831 -194.540853)
			(xy 293.922966 -194.603039) (xy 293.940652 -194.668135) (xy 293.949578 -194.734996) (xy 293.950136 -194.768724)
			(xy 293.949716 -194.798416) (xy 293.942799 -194.857396) (xy 293.929062 -194.91517) (xy 293.908693 -194.970951)
			(xy 293.881967 -195.023981) (xy 293.849249 -195.07354) (xy 293.810983 -195.118951) (xy 293.789608 -195.139564)
			(xy 293.781988 -195.146676) (xy 293.77386 -195.165472) (xy 293.772082 -195.258944) (xy 293.779956 -195.277994)
			(xy 293.787068 -195.28536) (xy 293.809541 -195.308662) (xy 293.848872 -195.360084) (xy 293.881174 -195.416189)
			(xy 293.905896 -195.476021) (xy 293.922619 -195.538562) (xy 293.931058 -195.602749) (xy 293.931594 -195.635118)
			(xy 293.931105 -195.666281) (xy 293.923293 -195.728115) (xy 293.907793 -195.788483) (xy 293.88485 -195.846431)
			(xy 293.854824 -195.901048) (xy 293.81819 -195.95147) (xy 293.775525 -195.996904) (xy 293.727503 -196.036632)
			(xy 293.674879 -196.070027) (xy 293.618485 -196.096564) (xy 293.55921 -196.115824) (xy 293.497989 -196.127503)
			(xy 293.435786 -196.131416) (xy 293.373583 -196.127503) (xy 293.312362 -196.115824) (xy 293.253087 -196.096564)
			(xy 293.196693 -196.070027) (xy 293.144069 -196.036632) (xy 293.096047 -195.996904) (xy 293.053382 -195.95147)
			(xy 293.016748 -195.901048) (xy 292.986722 -195.846431) (xy 292.963779 -195.788483) (xy 292.948279 -195.728115)
			(xy 292.940467 -195.666281) (xy 292.939978 -195.635118) (xy 292.940497 -195.602185) (xy 292.949182 -195.536896)
			(xy 292.966443 -195.473333) (xy 292.991973 -195.412617) (xy 293.025323 -195.35582) (xy 293.065905 -195.303943)
			(xy 293.089076 -195.280534) (xy 293.096442 -195.273422) (xy 293.10457 -195.254372) (xy 293.104062 -195.1609)
			(xy 293.096188 -195.14185) (xy 293.088568 -195.134738) (xy 293.064431 -195.110699) (xy 293.022154 -195.057283)
			(xy 292.987391 -194.998699) (xy 292.960764 -194.935997) (xy 292.942752 -194.8703) (xy 292.933676 -194.802785)
			(xy 292.93312 -194.768724) (xy 292.933611 -194.736896) (xy 292.941547 -194.673736) (xy 292.957299 -194.612059)
			(xy 292.980621 -194.552828) (xy 293.011148 -194.496969) (xy 293.048404 -194.445353) (xy 293.069772 -194.42176)
			(xy 293.07663 -194.414394) (xy 293.083742 -194.39636) (xy 293.082726 -194.306444) (xy 293.07536 -194.288664)
			(xy 293.068248 -194.281552) (xy 293.046278 -194.258318) (xy 293.007877 -194.207187) (xy 292.976364 -194.151547)
			(xy 292.95226 -194.092318) (xy 292.935965 -194.030484) (xy 292.92775 -193.967069) (xy 292.927278 -193.935096)
			(xy 292.927809 -193.902634) (xy 292.936284 -193.838264) (xy 292.953088 -193.775552) (xy 292.977933 -193.715569)
			(xy 293.010395 -193.659343) (xy 293.049918 -193.607834) (xy 293.095827 -193.561925) (xy 293.147334 -193.522401)
			(xy 293.20356 -193.489938) (xy 293.263543 -193.465091) (xy 293.326255 -193.448286) (xy 293.390624 -193.43981)
			(xy 293.423086 -193.439288) (xy 293.455139 -193.439787) (xy 293.51871 -193.448046) (xy 293.580684 -193.464442)
			(xy 293.610538 -193.476118) (xy 293.624254 -193.481706) (xy 293.65321 -193.476372) (xy 293.742618 -193.393822)
			(xy 293.750238 -193.365374) (xy 293.745666 -193.35115) (xy 293.733169 -193.310269) (xy 293.715234 -193.22668)
			(xy 293.709852 -193.184272) (xy 293.708582 -193.17335) (xy 293.698168 -193.155316) (xy 293.620698 -193.09842)
			(xy 293.600124 -193.093848) (xy 293.58971 -193.09588) (xy 293.548461 -193.103366) (xy 293.465006 -193.111383)
			(xy 293.423086 -193.111882) (xy 293.380037 -193.11137) (xy 293.294354 -193.10293) (xy 293.209911 -193.086131)
			(xy 293.127522 -193.061137) (xy 293.047978 -193.028187) (xy 292.972048 -192.9876) (xy 292.900461 -192.939765)
			(xy 292.833908 -192.885144) (xy 292.77303 -192.824262) (xy 292.718411 -192.757706) (xy 292.67058 -192.686118)
			(xy 292.629996 -192.610185) (xy 292.59705 -192.530641) (xy 292.572059 -192.44825) (xy 292.555265 -192.363806)
			(xy 292.546828 -192.278123) (xy 292.546278 -192.235074) (xy 292.546468 -192.207441) (xy 292.549897 -192.152281)
			(xy 292.553136 -192.124838) (xy 292.55466 -192.113916) (xy 292.54831 -192.093596) (xy 292.49116 -192.028064)
			(xy 292.483707 -192.020233) (xy 292.464107 -192.011159) (xy 292.453314 -192.010538) (xy 291.581586 -192.002664)
			(xy 291.569924 -192.003126) (xy 291.548892 -192.013188) (xy 291.5412 -192.021968) (xy 291.48405 -192.094358)
			(xy 291.479224 -192.117218) (xy 291.482272 -192.128902) (xy 291.487401 -192.150897) (xy 291.49288 -192.195727)
			(xy 291.493194 -192.21831) (xy 291.492678 -192.24591) (xy 291.484451 -192.300493) (xy 291.468181 -192.35324)
			(xy 291.444231 -192.402973) (xy 291.413136 -192.44858) (xy 291.375591 -192.489044) (xy 291.332434 -192.523461)
			(xy 291.28463 -192.55106) (xy 291.233246 -192.571227) (xy 291.179431 -192.58351) (xy 291.124386 -192.587635)
			(xy 291.069341 -192.58351) (xy 291.015526 -192.571227) (xy 290.964142 -192.55106) (xy 290.916338 -192.523461)
			(xy 290.873181 -192.489044) (xy 290.835636 -192.44858) (xy 290.804541 -192.402973) (xy 290.780591 -192.35324)
			(xy 290.764321 -192.300493) (xy 290.756094 -192.24591) (xy 290.755578 -192.21831) (xy 290.755968 -192.194019)
			(xy 290.762341 -192.145856) (xy 290.768278 -192.122298) (xy 290.771326 -192.110614) (xy 290.767008 -192.087754)
			(xy 290.711128 -192.014348) (xy 290.703631 -192.005451) (xy 290.682863 -191.995015) (xy 290.67125 -191.994282)
			(xy 289.7886 -191.986154) (xy 289.776709 -191.986652) (xy 289.755365 -191.997112) (xy 289.747706 -192.00622)
			(xy 289.691064 -192.080642) (xy 289.686746 -192.104264) (xy 289.690048 -192.115948) (xy 289.696821 -192.140994)
			(xy 289.70409 -192.192368) (xy 289.704526 -192.21831) (xy 289.70401 -192.24591) (xy 289.695783 -192.300493)
			(xy 289.679513 -192.35324) (xy 289.655563 -192.402973) (xy 289.624468 -192.44858) (xy 289.586923 -192.489044)
			(xy 289.543766 -192.523461) (xy 289.495962 -192.55106) (xy 289.444578 -192.571227) (xy 289.390763 -192.58351)
			(xy 289.335718 -192.587635) (xy 289.280673 -192.58351) (xy 289.226858 -192.571227) (xy 289.175474 -192.55106)
			(xy 289.12767 -192.523461) (xy 289.084513 -192.489044) (xy 289.046968 -192.44858) (xy 289.015873 -192.402973)
			(xy 288.991923 -192.35324) (xy 288.975653 -192.300493) (xy 288.967426 -192.24591) (xy 288.96691 -192.21831)
			(xy 288.967454 -192.190643) (xy 288.975746 -192.135932) (xy 288.98342 -192.109344) (xy 288.986976 -192.097914)
			(xy 288.982912 -192.074038) (xy 288.927794 -191.9986) (xy 288.920241 -191.989376) (xy 288.899052 -191.978513)
			(xy 288.887154 -191.977772) (xy 288.002472 -191.969644) (xy 287.991327 -191.970109) (xy 287.971053 -191.979347)
			(xy 287.963356 -191.987424) (xy 287.905444 -192.055242) (xy 287.899602 -192.077086) (xy 287.90138 -192.088262)
			(xy 287.907205 -192.124685) (xy 287.913439 -192.19819) (xy 287.913826 -192.235074) (xy 287.913336 -192.276801)
			(xy 287.905385 -192.359874) (xy 287.889572 -192.441815) (xy 287.866039 -192.521882) (xy 287.835 -192.599348)
			(xy 287.81629 -192.636648) (xy 287.811313 -192.647811) (xy 287.811319 -192.672217) (xy 287.81629 -192.683384)
			(xy 287.834968 -192.720697) (xy 287.865987 -192.798166) (xy 287.889512 -192.878231) (xy 287.905328 -192.960167)
			(xy 287.913293 -193.043234) (xy 287.913826 -193.084958) (xy 287.913311 -193.127344) (xy 287.905125 -193.21172)
			(xy 287.888835 -193.294911) (xy 287.864593 -193.376143) (xy 287.832625 -193.454656) (xy 287.79323 -193.529718)
			(xy 287.746775 -193.600628) (xy 287.693694 -193.666724) (xy 287.634483 -193.72739) (xy 287.569694 -193.782058)
			(xy 287.535112 -193.806572) (xy 287.527476 -193.812331) (xy 287.516813 -193.828191) (xy 287.512691 -193.846853)
			(xy 287.513776 -193.856356) (xy 287.51673 -193.875907) (xy 287.519911 -193.915324) (xy 287.520126 -193.935096)
			(xy 287.519636 -193.96693) (xy 287.515844 -193.996305) (xy 288.839391 -193.996305) (xy 288.843238 -193.934627)
			(xy 288.85472 -193.873906) (xy 288.873658 -193.815082) (xy 288.89976 -193.759068) (xy 288.932621 -193.706732)
			(xy 288.971731 -193.658885) (xy 289.016484 -193.616269) (xy 289.066185 -193.579545) (xy 289.092894 -193.564002)
			(xy 289.10407 -193.557906) (xy 289.117532 -193.53657) (xy 289.126168 -193.427096) (xy 289.116262 -193.403982)
			(xy 289.106102 -193.396108) (xy 289.084766 -193.378508) (xy 289.047104 -193.338006) (xy 289.015916 -193.29233)
			(xy 288.991903 -193.242508) (xy 288.975603 -193.189657) (xy 288.967383 -193.134964) (xy 288.96691 -193.10731)
			(xy 288.967426 -193.07971) (xy 288.975653 -193.025127) (xy 288.991923 -192.97238) (xy 289.015873 -192.922648)
			(xy 289.046968 -192.87704) (xy 289.084513 -192.836576) (xy 289.12767 -192.802159) (xy 289.175474 -192.77456)
			(xy 289.226858 -192.754393) (xy 289.280673 -192.74211) (xy 289.335718 -192.737985) (xy 289.390763 -192.74211)
			(xy 289.444578 -192.754393) (xy 289.495962 -192.77456) (xy 289.543766 -192.802159) (xy 289.586923 -192.836576)
			(xy 289.624468 -192.87704) (xy 289.655563 -192.922648) (xy 289.679513 -192.97238) (xy 289.695783 -193.025127)
			(xy 289.70401 -193.07971) (xy 289.704526 -193.10731) (xy 289.704034 -193.134961) (xy 289.695795 -193.189647)
			(xy 289.679488 -193.24249) (xy 289.655478 -193.292308) (xy 289.624303 -193.337986) (xy 289.58666 -193.378501)
			(xy 289.565334 -193.396108) (xy 289.555174 -193.403982) (xy 289.545268 -193.427096) (xy 289.553904 -193.53657)
			(xy 289.567366 -193.557906) (xy 289.578542 -193.564002) (xy 289.605258 -193.579532) (xy 289.654959 -193.616259)
			(xy 289.69971 -193.658877) (xy 289.738818 -193.706726) (xy 289.771678 -193.759064) (xy 289.797778 -193.81508)
			(xy 289.816716 -193.873905) (xy 289.828197 -193.934627) (xy 289.832044 -193.996305) (xy 289.828196 -194.057983)
			(xy 289.816714 -194.118705) (xy 289.797775 -194.177529) (xy 289.771673 -194.233544) (xy 289.738813 -194.285882)
			(xy 289.699703 -194.33373) (xy 289.654951 -194.376347) (xy 289.60525 -194.413073) (xy 289.578542 -194.428618)
			(xy 289.567366 -194.434714) (xy 289.553904 -194.45605) (xy 289.545268 -194.565524) (xy 289.555174 -194.588638)
			(xy 289.565334 -194.596512) (xy 289.586666 -194.614116) (xy 289.624331 -194.654616) (xy 289.655521 -194.70029)
			(xy 289.679536 -194.750112) (xy 289.695835 -194.802963) (xy 289.704054 -194.857656) (xy 289.704526 -194.88531)
			(xy 289.70401 -194.91291) (xy 289.695783 -194.967493) (xy 289.679513 -195.02024) (xy 289.655563 -195.069973)
			(xy 289.624468 -195.11558) (xy 289.586923 -195.156044) (xy 289.543766 -195.190461) (xy 289.495962 -195.21806)
			(xy 289.444578 -195.238227) (xy 289.390763 -195.25051) (xy 289.335718 -195.254635) (xy 289.280673 -195.25051)
			(xy 289.226858 -195.238227) (xy 289.175474 -195.21806) (xy 289.12767 -195.190461) (xy 289.084513 -195.156044)
			(xy 289.046968 -195.11558) (xy 289.015873 -195.069973) (xy 288.991923 -195.02024) (xy 288.975653 -194.967493)
			(xy 288.967426 -194.91291) (xy 288.96691 -194.88531) (xy 288.967403 -194.857659) (xy 288.97564 -194.802973)
			(xy 288.991946 -194.750129) (xy 289.015955 -194.70031) (xy 289.047131 -194.654632) (xy 289.084775 -194.614119)
			(xy 289.106102 -194.596512) (xy 289.116262 -194.588638) (xy 289.126168 -194.565524) (xy 289.117532 -194.45605)
			(xy 289.10407 -194.434714) (xy 289.092894 -194.428618) (xy 289.066194 -194.41306) (xy 289.016491 -194.376337)
			(xy 288.971737 -194.333722) (xy 288.932627 -194.285876) (xy 288.899765 -194.23354) (xy 288.873662 -194.177527)
			(xy 288.854722 -194.118703) (xy 288.843239 -194.057982) (xy 288.839391 -193.996305) (xy 287.515844 -193.996305)
			(xy 287.511485 -194.030073) (xy 287.495317 -194.091654) (xy 287.471398 -194.150657) (xy 287.440121 -194.206113)
			(xy 287.402002 -194.257107) (xy 287.380172 -194.280282) (xy 287.37306 -194.287648) (xy 287.365694 -194.305936)
			(xy 287.36671 -194.397884) (xy 287.374584 -194.416172) (xy 287.381696 -194.423284) (xy 287.405179 -194.447247)
			(xy 287.446285 -194.500274) (xy 287.480063 -194.558245) (xy 287.505928 -194.620153) (xy 287.52343 -194.684924)
			(xy 287.532265 -194.751433) (xy 287.532826 -194.78498) (xy 287.532324 -194.816941) (xy 287.524313 -194.880359)
			(xy 287.508416 -194.942273) (xy 287.484884 -195.001706) (xy 287.45409 -195.057721) (xy 287.416517 -195.109436)
			(xy 287.37276 -195.156033) (xy 287.323507 -195.196778) (xy 287.269536 -195.231029) (xy 287.211697 -195.258246)
			(xy 287.150904 -195.277999) (xy 287.088114 -195.289977) (xy 287.024318 -195.293991) (xy 286.960522 -195.289977)
			(xy 286.897732 -195.277999) (xy 286.836939 -195.258246) (xy 286.7791 -195.231029) (xy 286.725129 -195.196778)
			(xy 286.675876 -195.156033) (xy 286.632119 -195.109436) (xy 286.594546 -195.057721) (xy 286.563752 -195.001706)
			(xy 286.54022 -194.942273) (xy 286.524323 -194.880359) (xy 286.516312 -194.816941) (xy 286.51581 -194.78498)
			(xy 286.516343 -194.75143) (xy 286.525161 -194.684912) (xy 286.542655 -194.620133) (xy 286.56852 -194.558218)
			(xy 286.602307 -194.500246) (xy 286.643428 -194.447222) (xy 286.66694 -194.423284) (xy 286.674052 -194.416172)
			(xy 286.681926 -194.397884) (xy 286.682942 -194.305936) (xy 286.675576 -194.287648) (xy 286.668464 -194.280282)
			(xy 286.646641 -194.257099) (xy 286.608509 -194.206113) (xy 286.577224 -194.150661) (xy 286.5533 -194.091658)
			(xy 286.537133 -194.030076) (xy 286.528989 -193.96693) (xy 286.52851 -193.935096) (xy 286.528798 -193.911647)
			(xy 286.533253 -193.86496) (xy 286.5374 -193.841878) (xy 286.538829 -193.83239) (xy 286.535304 -193.813543)
			(xy 286.525085 -193.79732) (xy 286.517588 -193.791332) (xy 286.494644 -193.774186) (xy 286.450794 -193.737326)
			(xy 286.429958 -193.717672) (xy 286.422617 -193.71128) (xy 286.404554 -193.704071) (xy 286.385105 -193.704098)
			(xy 286.367062 -193.711357) (xy 286.353013 -193.724806) (xy 286.344974 -193.742515) (xy 286.344098 -193.761944)
			(xy 286.3469 -193.771266) (xy 286.35576 -193.79766) (xy 286.368189 -193.851933) (xy 286.37446 -193.907257)
			(xy 286.37484 -193.935096) (xy 286.374332 -193.967198) (xy 286.366041 -194.030863) (xy 286.349596 -194.092925)
			(xy 286.325274 -194.152343) (xy 286.293481 -194.208122) (xy 286.254751 -194.259328) (xy 286.2326 -194.282568)
			(xy 286.225488 -194.289934) (xy 286.218122 -194.30873) (xy 286.219392 -194.40144) (xy 286.22752 -194.419982)
			(xy 286.234886 -194.427094) (xy 286.25857 -194.450554) (xy 286.300071 -194.502726) (xy 286.334205 -194.559989)
			(xy 286.360357 -194.62131) (xy 286.378055 -194.685583) (xy 286.386979 -194.751648) (xy 286.38754 -194.78498)
			(xy 286.387017 -194.817701) (xy 286.378417 -194.882574) (xy 286.361362 -194.945754) (xy 286.336149 -195.006143)
			(xy 286.303216 -195.062693) (xy 286.263134 -195.114423) (xy 286.24022 -195.137786) (xy 286.232854 -195.144898)
			(xy 286.22498 -195.163694) (xy 286.22498 -195.256404) (xy 286.232854 -195.2752) (xy 286.24022 -195.282312)
			(xy 286.263126 -195.305685) (xy 286.303222 -195.357407) (xy 286.336167 -195.413953) (xy 286.36139 -195.474341)
			(xy 286.378452 -195.537521) (xy 286.387056 -195.602396) (xy 286.38754 -195.635118) (xy 286.387051 -195.666281)
			(xy 286.379239 -195.728115) (xy 286.363739 -195.788483) (xy 286.340796 -195.846431) (xy 286.31077 -195.901048)
			(xy 286.274136 -195.95147) (xy 286.231471 -195.996904) (xy 286.183449 -196.036632) (xy 286.130825 -196.070027)
			(xy 286.074431 -196.096564) (xy 286.015156 -196.115824) (xy 285.953935 -196.127503) (xy 285.891732 -196.131416)
			(xy 285.829529 -196.127503) (xy 285.768308 -196.115824) (xy 285.709033 -196.096564) (xy 285.652639 -196.070027)
			(xy 285.600015 -196.036632) (xy 285.551993 -195.996904) (xy 285.509328 -195.95147) (xy 285.472694 -195.901048)
			(xy 285.442668 -195.846431) (xy 285.419725 -195.788483) (xy 285.404225 -195.728115) (xy 285.396413 -195.666281)
			(xy 285.395924 -195.635118) (xy 285.396446 -195.602397) (xy 285.405047 -195.537523) (xy 285.422101 -195.474343)
			(xy 285.447312 -195.413953) (xy 285.480244 -195.357401) (xy 285.520324 -195.305669) (xy 285.543244 -195.282312)
			(xy 285.55061 -195.2752) (xy 285.558484 -195.256404) (xy 285.558484 -195.163694) (xy 285.55061 -195.144898)
			(xy 285.543244 -195.137786) (xy 285.520339 -195.114412) (xy 285.480247 -195.062689) (xy 285.447304 -195.006143)
			(xy 285.422083 -194.945755) (xy 285.405023 -194.882576) (xy 285.39642 -194.817701) (xy 285.395924 -194.78498)
			(xy 285.396434 -194.752879) (xy 285.404729 -194.689216) (xy 285.421177 -194.627158) (xy 285.445504 -194.567744)
			(xy 285.477301 -194.511969) (xy 285.516036 -194.46077) (xy 285.538164 -194.437508) (xy 285.545276 -194.430142)
			(xy 285.552642 -194.411346) (xy 285.551372 -194.318636) (xy 285.543244 -194.300094) (xy 285.535878 -194.292982)
			(xy 285.512191 -194.269522) (xy 285.470685 -194.217352) (xy 285.436544 -194.16009) (xy 285.410385 -194.098769)
			(xy 285.392679 -194.034496) (xy 285.383746 -193.96843) (xy 285.383224 -193.935096) (xy 285.383732 -193.902633)
			(xy 285.392207 -193.838263) (xy 285.409012 -193.77555) (xy 285.43386 -193.715567) (xy 285.466324 -193.659341)
			(xy 285.50585 -193.607834) (xy 285.551761 -193.561926) (xy 285.603271 -193.522404) (xy 285.6595 -193.489944)
			(xy 285.719484 -193.465101) (xy 285.782199 -193.4483) (xy 285.846569 -193.43983) (xy 285.879032 -193.439288)
			(xy 285.911084 -193.43979) (xy 285.974654 -193.448055) (xy 286.036625 -193.464455) (xy 286.066484 -193.476118)
			(xy 286.0802 -193.481706) (xy 286.109156 -193.476372) (xy 286.198564 -193.393822) (xy 286.206184 -193.365374)
			(xy 286.201612 -193.35115) (xy 286.189115 -193.310269) (xy 286.171179 -193.226681) (xy 286.165798 -193.184272)
			(xy 286.164528 -193.17335) (xy 286.154114 -193.155316) (xy 286.076644 -193.09842) (xy 286.05607 -193.093848)
			(xy 286.045656 -193.09588) (xy 286.004407 -193.103363) (xy 285.920951 -193.111375) (xy 285.879032 -193.111882)
			(xy 285.835982 -193.111372) (xy 285.750296 -193.102936) (xy 285.665849 -193.086141) (xy 285.583455 -193.061149)
			(xy 285.503908 -193.028201) (xy 285.427974 -192.987615) (xy 285.356383 -192.939781) (xy 285.289826 -192.88516)
			(xy 285.228944 -192.824278) (xy 285.174322 -192.757721) (xy 285.126488 -192.686131) (xy 285.085901 -192.610197)
			(xy 285.052953 -192.53065) (xy 285.027961 -192.448257) (xy 285.011165 -192.36381) (xy 285.002728 -192.278124)
			(xy 285.002224 -192.235074) (xy 285.002727 -192.191668) (xy 285.01125 -192.105275) (xy 285.019242 -192.062608)
			(xy 285.021528 -192.051432) (xy 285.016194 -192.029588) (xy 284.959552 -191.959992) (xy 284.952031 -191.951684)
			(xy 284.931873 -191.941954) (xy 284.92069 -191.941196) (xy 284.014164 -191.932814) (xy 284.005744 -191.933031)
			(xy 283.989772 -191.938346) (xy 283.976408 -191.948581) (xy 283.971492 -191.95542) (xy 283.917136 -192.0367)
			(xy 283.914596 -192.0621) (xy 283.919676 -192.074038) (xy 283.928997 -192.096935) (xy 283.942113 -192.1446)
			(xy 283.948729 -192.193592) (xy 283.94914 -192.21831) (xy 283.948624 -192.24591) (xy 283.940397 -192.300493)
			(xy 283.924127 -192.35324) (xy 283.900177 -192.402973) (xy 283.869082 -192.44858) (xy 283.831537 -192.489044)
			(xy 283.78838 -192.523461) (xy 283.740576 -192.55106) (xy 283.689192 -192.571227) (xy 283.635377 -192.58351)
			(xy 283.580332 -192.587635) (xy 283.525287 -192.58351) (xy 283.471472 -192.571227) (xy 283.420088 -192.55106)
			(xy 283.372284 -192.523461) (xy 283.329127 -192.489044) (xy 283.291582 -192.44858) (xy 283.260487 -192.402973)
			(xy 283.236537 -192.35324) (xy 283.220267 -192.300493) (xy 283.21204 -192.24591) (xy 283.211524 -192.21831)
			(xy 283.21196 -192.192487) (xy 283.219161 -192.141346) (xy 283.23341 -192.091704) (xy 283.243528 -192.067942)
			(xy 283.248862 -192.056004) (xy 283.247084 -192.030604) (xy 283.193998 -191.948308) (xy 283.186585 -191.938044)
			(xy 283.164467 -191.925789) (xy 283.151834 -191.92494) (xy 282.21813 -191.916304) (xy 282.209553 -191.916535)
			(xy 282.193309 -191.922028) (xy 282.179812 -191.932604) (xy 282.17495 -191.939672) (xy 282.121356 -192.023238)
			(xy 282.119578 -192.049146) (xy 282.12542 -192.061084) (xy 282.136512 -192.085792) (xy 282.152139 -192.137647)
			(xy 282.160008 -192.19123) (xy 282.160472 -192.21831) (xy 282.159956 -192.24591) (xy 282.151729 -192.300493)
			(xy 282.135459 -192.35324) (xy 282.111509 -192.402973) (xy 282.080414 -192.44858) (xy 282.042869 -192.489044)
			(xy 281.999712 -192.523461) (xy 281.951908 -192.55106) (xy 281.900524 -192.571227) (xy 281.846709 -192.58351)
			(xy 281.791664 -192.587635) (xy 281.736619 -192.58351) (xy 281.682804 -192.571227) (xy 281.63142 -192.55106)
			(xy 281.583616 -192.523461) (xy 281.540459 -192.489044) (xy 281.502914 -192.44858) (xy 281.471819 -192.402973)
			(xy 281.447869 -192.35324) (xy 281.431599 -192.300493) (xy 281.423372 -192.24591) (xy 281.422856 -192.21831)
			(xy 281.42339 -192.190098) (xy 281.431975 -192.134332) (xy 281.448947 -192.080521) (xy 281.460956 -192.054988)
			(xy 281.466798 -192.04305) (xy 281.465782 -192.017396) (xy 281.413712 -191.93256) (xy 281.408906 -191.925433)
			(xy 281.395547 -191.914632) (xy 281.379373 -191.908843) (xy 281.370786 -191.90843) (xy 280.44394 -191.899794)
			(xy 280.43234 -191.900296) (xy 280.411435 -191.910344) (xy 280.403808 -191.919098) (xy 280.346404 -191.991488)
			(xy 280.341578 -192.014094) (xy 280.344372 -192.025778) (xy 280.35245 -192.06007) (xy 280.363741 -192.129617)
			(xy 280.36941 -192.199845) (xy 280.369772 -192.235074) (xy 280.369282 -192.2768) (xy 280.361331 -192.359874)
			(xy 280.345516 -192.441815) (xy 280.321982 -192.521881) (xy 280.290942 -192.599346) (xy 280.272236 -192.636648)
			(xy 280.267255 -192.647811) (xy 280.267262 -192.672217) (xy 280.272236 -192.683384) (xy 280.290915 -192.720697)
			(xy 280.321936 -192.798166) (xy 280.345462 -192.87823) (xy 280.361279 -192.960166) (xy 280.369245 -193.043234)
			(xy 280.369772 -193.084958) (xy 280.369257 -193.127344) (xy 280.361071 -193.211718) (xy 280.34478 -193.294909)
			(xy 280.320537 -193.37614) (xy 280.288568 -193.454652) (xy 280.249171 -193.529712) (xy 280.202715 -193.60062)
			(xy 280.149632 -193.666713) (xy 280.090419 -193.727376) (xy 280.025627 -193.782041) (xy 279.991058 -193.806572)
			(xy 279.983417 -193.812328) (xy 279.972744 -193.828188) (xy 279.968618 -193.846853) (xy 279.969722 -193.856356)
			(xy 279.972676 -193.875907) (xy 279.975857 -193.915324) (xy 279.976072 -193.935096) (xy 279.975582 -193.96693)
			(xy 279.971791 -193.996305) (xy 281.295365 -193.996305) (xy 281.299211 -193.93463) (xy 281.310691 -193.87391)
			(xy 281.329628 -193.815088) (xy 281.355726 -193.759075) (xy 281.388583 -193.706739) (xy 281.427689 -193.658891)
			(xy 281.472437 -193.616274) (xy 281.522134 -193.579547) (xy 281.54884 -193.564002) (xy 281.560016 -193.557906)
			(xy 281.573478 -193.53657) (xy 281.582114 -193.427096) (xy 281.572208 -193.403982) (xy 281.562048 -193.396108)
			(xy 281.540721 -193.378497) (xy 281.503057 -193.337998) (xy 281.471867 -193.292325) (xy 281.447852 -193.242505)
			(xy 281.43155 -193.189656) (xy 281.423329 -193.134964) (xy 281.422856 -193.10731) (xy 281.423372 -193.07971)
			(xy 281.431599 -193.025127) (xy 281.447869 -192.97238) (xy 281.471819 -192.922648) (xy 281.502914 -192.87704)
			(xy 281.540459 -192.836576) (xy 281.583616 -192.802159) (xy 281.63142 -192.77456) (xy 281.682804 -192.754393)
			(xy 281.736619 -192.74211) (xy 281.791664 -192.737985) (xy 281.846709 -192.74211) (xy 281.900524 -192.754393)
			(xy 281.951908 -192.77456) (xy 281.999712 -192.802159) (xy 282.042869 -192.836576) (xy 282.080414 -192.87704)
			(xy 282.111509 -192.922648) (xy 282.135459 -192.97238) (xy 282.151729 -193.025127) (xy 282.159956 -193.07971)
			(xy 282.160472 -193.10731) (xy 282.16 -193.134962) (xy 282.15176 -193.189649) (xy 282.13545 -193.242494)
			(xy 282.111436 -193.292313) (xy 282.080257 -193.33799) (xy 282.042609 -193.378502) (xy 282.02128 -193.396108)
			(xy 282.01112 -193.403982) (xy 282.001214 -193.427096) (xy 282.00985 -193.53657) (xy 282.023312 -193.557906)
			(xy 282.034488 -193.564002) (xy 282.061207 -193.57953) (xy 282.110912 -193.616254) (xy 282.155668 -193.658871)
			(xy 282.194781 -193.706719) (xy 282.227644 -193.759058) (xy 282.253748 -193.815074) (xy 282.272688 -193.8739)
			(xy 282.28417 -193.934625) (xy 282.288017 -193.996305) (xy 282.284169 -194.057985) (xy 282.272685 -194.118709)
			(xy 282.253744 -194.177535) (xy 282.227639 -194.233551) (xy 282.194775 -194.285889) (xy 282.155661 -194.333736)
			(xy 282.110905 -194.376352) (xy 282.061199 -194.413075) (xy 282.034488 -194.428618) (xy 282.023312 -194.434714)
			(xy 282.00985 -194.45605) (xy 282.001214 -194.565524) (xy 282.01112 -194.588638) (xy 282.02128 -194.596512)
			(xy 282.042622 -194.614105) (xy 282.080284 -194.654609) (xy 282.111472 -194.700285) (xy 282.135484 -194.750109)
			(xy 282.151782 -194.802961) (xy 282.16 -194.857655) (xy 282.160472 -194.88531) (xy 282.159956 -194.91291)
			(xy 282.151729 -194.967493) (xy 282.135459 -195.02024) (xy 282.111509 -195.069973) (xy 282.080414 -195.11558)
			(xy 282.042869 -195.156044) (xy 281.999712 -195.190461) (xy 281.951908 -195.21806) (xy 281.900524 -195.238227)
			(xy 281.846709 -195.25051) (xy 281.791664 -195.254635) (xy 281.736619 -195.25051) (xy 281.682804 -195.238227)
			(xy 281.63142 -195.21806) (xy 281.583616 -195.190461) (xy 281.540459 -195.156044) (xy 281.502914 -195.11558)
			(xy 281.471819 -195.069973) (xy 281.447869 -195.02024) (xy 281.431599 -194.967493) (xy 281.423372 -194.91291)
			(xy 281.422856 -194.88531) (xy 281.423369 -194.85766) (xy 281.431604 -194.802976) (xy 281.447908 -194.750133)
			(xy 281.471914 -194.700314) (xy 281.503085 -194.654636) (xy 281.540724 -194.61412) (xy 281.562048 -194.596512)
			(xy 281.572208 -194.588638) (xy 281.582114 -194.565524) (xy 281.573478 -194.45605) (xy 281.560016 -194.434714)
			(xy 281.54884 -194.428618) (xy 281.522142 -194.413058) (xy 281.472444 -194.376332) (xy 281.427695 -194.333716)
			(xy 281.388589 -194.285869) (xy 281.355731 -194.233534) (xy 281.329631 -194.177521) (xy 281.310694 -194.118699)
			(xy 281.299212 -194.05798) (xy 281.295365 -193.996305) (xy 279.971791 -193.996305) (xy 279.967432 -194.030074)
			(xy 279.951265 -194.091655) (xy 279.927347 -194.15066) (xy 279.896073 -194.206118) (xy 279.857956 -194.257115)
			(xy 279.836118 -194.280282) (xy 279.829006 -194.287648) (xy 279.82164 -194.305936) (xy 279.822656 -194.397884)
			(xy 279.83053 -194.416172) (xy 279.837642 -194.423284) (xy 279.861127 -194.447246) (xy 279.902237 -194.500272)
			(xy 279.936019 -194.558242) (xy 279.961886 -194.62015) (xy 279.97939 -194.684922) (xy 279.988227 -194.751433)
			(xy 279.988772 -194.78498) (xy 279.98827 -194.816941) (xy 279.980259 -194.880359) (xy 279.964362 -194.942273)
			(xy 279.94083 -195.001706) (xy 279.910036 -195.057721) (xy 279.872463 -195.109436) (xy 279.828706 -195.156033)
			(xy 279.779453 -195.196778) (xy 279.725482 -195.231029) (xy 279.667643 -195.258246) (xy 279.60685 -195.277999)
			(xy 279.54406 -195.289977) (xy 279.480264 -195.293991) (xy 279.416468 -195.289977) (xy 279.353678 -195.277999)
			(xy 279.292885 -195.258246) (xy 279.235046 -195.231029) (xy 279.181075 -195.196778) (xy 279.131822 -195.156033)
			(xy 279.088065 -195.109436) (xy 279.050492 -195.057721) (xy 279.019698 -195.001706) (xy 278.996166 -194.942273)
			(xy 278.980269 -194.880359) (xy 278.972258 -194.816941) (xy 278.971756 -194.78498) (xy 278.972289 -194.75143)
			(xy 278.981108 -194.684913) (xy 278.998603 -194.620135) (xy 279.02447 -194.558222) (xy 279.058259 -194.500251)
			(xy 279.099382 -194.44723) (xy 279.122886 -194.423284) (xy 279.129998 -194.416172) (xy 279.137872 -194.397884)
			(xy 279.138888 -194.305936) (xy 279.131522 -194.287648) (xy 279.12441 -194.280282) (xy 279.102586 -194.2571)
			(xy 279.06445 -194.206115) (xy 279.033161 -194.150663) (xy 279.009236 -194.09166) (xy 278.993067 -194.030078)
			(xy 278.984923 -193.966931) (xy 278.984456 -193.935096) (xy 278.984744 -193.911647) (xy 278.9892 -193.86496)
			(xy 278.993346 -193.841878) (xy 278.994775 -193.832389) (xy 278.991252 -193.81354) (xy 278.981039 -193.797311)
			(xy 278.973534 -193.791332) (xy 278.950736 -193.774291) (xy 278.907144 -193.737683) (xy 278.886412 -193.71818)
			(xy 278.879092 -193.711777) (xy 278.86106 -193.704534) (xy 278.841628 -193.704517) (xy 278.823584 -193.711728)
			(xy 278.809516 -193.725133) (xy 278.801442 -193.742808) (xy 278.800522 -193.762219) (xy 278.803354 -193.77152)
			(xy 278.812143 -193.797885) (xy 278.824474 -193.852077) (xy 278.830673 -193.907307) (xy 278.83104 -193.935096)
			(xy 278.830532 -193.967198) (xy 278.822241 -194.030863) (xy 278.805796 -194.092925) (xy 278.781474 -194.152343)
			(xy 278.749681 -194.208122) (xy 278.710951 -194.259328) (xy 278.6888 -194.282568) (xy 278.681688 -194.289934)
			(xy 278.674322 -194.30873) (xy 278.675592 -194.40144) (xy 278.68372 -194.419982) (xy 278.691086 -194.427094)
			(xy 278.71477 -194.450554) (xy 278.756271 -194.502726) (xy 278.790405 -194.559989) (xy 278.816557 -194.62131)
			(xy 278.834255 -194.685583) (xy 278.843179 -194.751648) (xy 278.84374 -194.78498) (xy 278.843217 -194.817701)
			(xy 278.834617 -194.882574) (xy 278.817562 -194.945754) (xy 278.792349 -195.006143) (xy 278.759416 -195.062693)
			(xy 278.719334 -195.114423) (xy 278.69642 -195.137786) (xy 278.689054 -195.144898) (xy 278.68118 -195.163694)
			(xy 278.68118 -195.256404) (xy 278.689054 -195.2752) (xy 278.69642 -195.282312) (xy 278.719326 -195.305685)
			(xy 278.759422 -195.357407) (xy 278.792367 -195.413953) (xy 278.81759 -195.474341) (xy 278.834652 -195.537521)
			(xy 278.843256 -195.602396) (xy 278.84374 -195.635118) (xy 278.843251 -195.666281) (xy 278.835439 -195.728115)
			(xy 278.819939 -195.788483) (xy 278.796996 -195.846431) (xy 278.790006 -195.859146) (xy 283.072078 -195.859146)
			(xy 283.072623 -195.825987) (xy 283.081235 -195.760231) (xy 283.098318 -195.696152) (xy 283.123584 -195.634837)
			(xy 283.156603 -195.577324) (xy 283.196816 -195.52459) (xy 283.243541 -195.477528) (xy 283.269436 -195.45681)
			(xy 283.278359 -195.449272) (xy 283.28868 -195.428346) (xy 283.289248 -195.416678) (xy 283.289248 -195.336414)
			(xy 283.288617 -195.324764) (xy 283.278303 -195.303864) (xy 283.269436 -195.296282) (xy 283.243555 -195.275547)
			(xy 283.196832 -195.228486) (xy 283.156619 -195.175754) (xy 283.123598 -195.118244) (xy 283.098327 -195.056932)
			(xy 283.081237 -194.992857) (xy 283.072615 -194.927104) (xy 283.072078 -194.893946) (xy 283.072644 -194.860172)
			(xy 283.081589 -194.793218) (xy 283.099314 -194.728037) (xy 283.125508 -194.665774) (xy 283.15971 -194.607525)
			(xy 283.201319 -194.554313) (xy 283.249603 -194.507075) (xy 283.303713 -194.466641) (xy 283.332936 -194.4497)
			(xy 283.344112 -194.443604) (xy 283.357828 -194.422522) (xy 283.367226 -194.313556) (xy 283.357574 -194.290188)
			(xy 283.347668 -194.282314) (xy 283.326808 -194.264717) (xy 283.290047 -194.224383) (xy 283.259626 -194.179075)
			(xy 283.23621 -194.12978) (xy 283.220309 -194.077575) (xy 283.21227 -194.023597) (xy 283.211778 -193.99631)
			(xy 283.212294 -193.96871) (xy 283.220521 -193.914127) (xy 283.236791 -193.86138) (xy 283.260741 -193.811648)
			(xy 283.291836 -193.76604) (xy 283.329381 -193.725576) (xy 283.372538 -193.691159) (xy 283.420342 -193.66356)
			(xy 283.471726 -193.643393) (xy 283.525541 -193.63111) (xy 283.580586 -193.626985) (xy 283.635631 -193.63111)
			(xy 283.689446 -193.643393) (xy 283.74083 -193.66356) (xy 283.788634 -193.691159) (xy 283.831791 -193.725576)
			(xy 283.869336 -193.76604) (xy 283.900431 -193.811648) (xy 283.924381 -193.86138) (xy 283.940651 -193.914127)
			(xy 283.948878 -193.96871) (xy 283.949394 -193.99631) (xy 283.948957 -194.023599) (xy 283.940923 -194.077584)
			(xy 283.925017 -194.129793) (xy 283.901588 -194.179087) (xy 283.871146 -194.224388) (xy 283.834358 -194.264705)
			(xy 283.813504 -194.282314) (xy 283.803598 -194.290188) (xy 283.793946 -194.313556) (xy 283.803344 -194.422522)
			(xy 283.81706 -194.443604) (xy 283.828236 -194.4497) (xy 283.857479 -194.46661) (xy 283.911596 -194.507043)
			(xy 283.959885 -194.554282) (xy 284.001497 -194.607498) (xy 284.0357 -194.665753) (xy 284.061891 -194.728022)
			(xy 284.07961 -194.79321) (xy 284.088545 -194.860169) (xy 284.089094 -194.893946) (xy 284.088554 -194.927105)
			(xy 284.079942 -194.992861) (xy 284.062859 -195.056941) (xy 284.037592 -195.118257) (xy 284.004572 -195.17577)
			(xy 283.964358 -195.228504) (xy 283.917631 -195.275564) (xy 283.891736 -195.296282) (xy 283.882812 -195.303819)
			(xy 283.872492 -195.324746) (xy 283.871924 -195.336414) (xy 283.871924 -195.416678) (xy 283.872569 -195.428326)
			(xy 283.882875 -195.449225) (xy 283.891736 -195.45681) (xy 283.917607 -195.477557) (xy 283.964331 -195.524615)
			(xy 284.004546 -195.577345) (xy 284.037569 -195.634852) (xy 284.062841 -195.696163) (xy 284.079933 -195.760237)
			(xy 284.088556 -195.825989) (xy 284.089094 -195.859146) (xy 284.088592 -195.891107) (xy 284.080581 -195.954525)
			(xy 284.064684 -196.016439) (xy 284.041152 -196.075872) (xy 284.010358 -196.131887) (xy 283.972785 -196.183602)
			(xy 283.929028 -196.230199) (xy 283.879775 -196.270944) (xy 283.825804 -196.305195) (xy 283.767965 -196.332412)
			(xy 283.707172 -196.352165) (xy 283.644382 -196.364143) (xy 283.580586 -196.368157) (xy 283.51679 -196.364143)
			(xy 283.454 -196.352165) (xy 283.393207 -196.332412) (xy 283.335368 -196.305195) (xy 283.281397 -196.270944)
			(xy 283.232144 -196.230199) (xy 283.188387 -196.183602) (xy 283.150814 -196.131887) (xy 283.12002 -196.075872)
			(xy 283.096488 -196.016439) (xy 283.080591 -195.954525) (xy 283.07258 -195.891107) (xy 283.072078 -195.859146)
			(xy 278.790006 -195.859146) (xy 278.76697 -195.901048) (xy 278.730336 -195.95147) (xy 278.687671 -195.996904)
			(xy 278.639649 -196.036632) (xy 278.587025 -196.070027) (xy 278.530631 -196.096564) (xy 278.471356 -196.115824)
			(xy 278.410135 -196.127503) (xy 278.347932 -196.131416) (xy 278.285729 -196.127503) (xy 278.224508 -196.115824)
			(xy 278.165233 -196.096564) (xy 278.108839 -196.070027) (xy 278.056215 -196.036632) (xy 278.008193 -195.996904)
			(xy 277.965528 -195.95147) (xy 277.928894 -195.901048) (xy 277.898868 -195.846431) (xy 277.875925 -195.788483)
			(xy 277.860425 -195.728115) (xy 277.852613 -195.666281) (xy 277.852124 -195.635118) (xy 277.852646 -195.602397)
			(xy 277.861247 -195.537523) (xy 277.878301 -195.474343) (xy 277.903512 -195.413953) (xy 277.936444 -195.357401)
			(xy 277.976524 -195.305669) (xy 277.999444 -195.282312) (xy 278.00681 -195.2752) (xy 278.014684 -195.256404)
			(xy 278.014684 -195.163694) (xy 278.00681 -195.144898) (xy 277.999444 -195.137786) (xy 277.976539 -195.114412)
			(xy 277.936447 -195.062689) (xy 277.903504 -195.006143) (xy 277.878283 -194.945755) (xy 277.861223 -194.882576)
			(xy 277.85262 -194.817701) (xy 277.852124 -194.78498) (xy 277.852634 -194.752879) (xy 277.860929 -194.689216)
			(xy 277.877377 -194.627158) (xy 277.901704 -194.567744) (xy 277.933501 -194.511969) (xy 277.972236 -194.46077)
			(xy 277.994364 -194.437508) (xy 278.001476 -194.430142) (xy 278.008842 -194.411346) (xy 278.007572 -194.318636)
			(xy 277.999444 -194.300094) (xy 277.992078 -194.292982) (xy 277.968391 -194.269522) (xy 277.926885 -194.217352)
			(xy 277.892744 -194.16009) (xy 277.866585 -194.098769) (xy 277.848879 -194.034496) (xy 277.839946 -193.96843)
			(xy 277.839424 -193.935096) (xy 277.839932 -193.902633) (xy 277.848407 -193.838263) (xy 277.865212 -193.77555)
			(xy 277.89006 -193.715567) (xy 277.922524 -193.659341) (xy 277.96205 -193.607834) (xy 278.007961 -193.561926)
			(xy 278.059471 -193.522404) (xy 278.1157 -193.489944) (xy 278.175684 -193.465101) (xy 278.238399 -193.4483)
			(xy 278.302769 -193.43983) (xy 278.335232 -193.439288) (xy 278.367232 -193.439776) (xy 278.430704 -193.447984)
			(xy 278.492594 -193.464283) (xy 278.52243 -193.475864) (xy 278.5364 -193.481706) (xy 278.564848 -193.476372)
			(xy 278.65451 -193.393568) (xy 278.66213 -193.365374) (xy 278.657558 -193.35115) (xy 278.645061 -193.310269)
			(xy 278.627126 -193.22668) (xy 278.621744 -193.184272) (xy 278.620474 -193.173604) (xy 278.61006 -193.155316)
			(xy 278.53259 -193.09842) (xy 278.51227 -193.093848) (xy 278.501602 -193.09588) (xy 278.460414 -193.103339)
			(xy 278.377087 -193.111354) (xy 278.335232 -193.111882) (xy 278.292182 -193.111372) (xy 278.206496 -193.102936)
			(xy 278.122049 -193.086141) (xy 278.039655 -193.061149) (xy 277.960108 -193.028201) (xy 277.884174 -192.987615)
			(xy 277.812583 -192.939781) (xy 277.746026 -192.88516) (xy 277.685144 -192.824278) (xy 277.630522 -192.757721)
			(xy 277.582688 -192.686131) (xy 277.542101 -192.610197) (xy 277.509153 -192.53065) (xy 277.484161 -192.448257)
			(xy 277.467365 -192.36381) (xy 277.458928 -192.278124) (xy 277.458424 -192.235074) (xy 277.458873 -192.19551)
			(xy 277.466027 -192.116706) (xy 277.480255 -192.038868) (xy 277.490428 -192.000632) (xy 277.49373 -191.988948)
			(xy 277.489158 -191.966088) (xy 277.433532 -191.89192) (xy 277.425991 -191.882971) (xy 277.405084 -191.872514)
			(xy 277.3934 -191.871854) (xy 276.433534 -191.862964) (xy 276.424398 -191.863247) (xy 276.407225 -191.869469)
			(xy 276.393322 -191.881315) (xy 276.388576 -191.889126) (xy 276.338538 -191.97955) (xy 276.339554 -192.00749)
			(xy 276.347174 -192.019428) (xy 276.360938 -192.041804) (xy 276.382686 -192.089623) (xy 276.397433 -192.140042)
			(xy 276.40488 -192.192044) (xy 276.40534 -192.21831) (xy 276.404824 -192.24591) (xy 276.396597 -192.300493)
			(xy 276.380327 -192.35324) (xy 276.356377 -192.402973) (xy 276.325282 -192.44858) (xy 276.287737 -192.489044)
			(xy 276.24458 -192.523461) (xy 276.196776 -192.55106) (xy 276.145392 -192.571227) (xy 276.091577 -192.58351)
			(xy 276.036532 -192.587635) (xy 275.981487 -192.58351) (xy 275.927672 -192.571227) (xy 275.876288 -192.55106)
			(xy 275.828484 -192.523461) (xy 275.785327 -192.489044) (xy 275.747782 -192.44858) (xy 275.716687 -192.402973)
			(xy 275.692737 -192.35324) (xy 275.676467 -192.300493) (xy 275.66824 -192.24591) (xy 275.667724 -192.21831)
			(xy 275.668203 -192.19117) (xy 275.67615 -192.137474) (xy 275.691874 -192.08552) (xy 275.715036 -192.036429)
			(xy 275.7297 -192.013586) (xy 275.737574 -192.001902) (xy 275.738844 -191.974216) (xy 275.690584 -191.882776)
			(xy 275.685992 -191.874855) (xy 275.672338 -191.862678) (xy 275.655277 -191.856072) (xy 275.646134 -191.855598)
			(xy 274.63369 -191.846454) (xy 274.624373 -191.846779) (xy 274.606916 -191.853276) (xy 274.59294 -191.865588)
			(xy 274.588224 -191.873632) (xy 274.539456 -191.966342) (xy 274.541234 -191.994536) (xy 274.549616 -192.00622)
			(xy 274.565413 -192.029655) (xy 274.590459 -192.080316) (xy 274.607493 -192.134201) (xy 274.616118 -192.190053)
			(xy 274.616672 -192.21831) (xy 274.616156 -192.24591) (xy 274.607929 -192.300493) (xy 274.591659 -192.35324)
			(xy 274.567709 -192.402973) (xy 274.536614 -192.44858) (xy 274.499069 -192.489044) (xy 274.455912 -192.523461)
			(xy 274.408108 -192.55106) (xy 274.356724 -192.571227) (xy 274.302909 -192.58351) (xy 274.247864 -192.587635)
			(xy 274.192819 -192.58351) (xy 274.139004 -192.571227) (xy 274.08762 -192.55106) (xy 274.039816 -192.523461)
			(xy 273.996659 -192.489044) (xy 273.959114 -192.44858) (xy 273.928019 -192.402973) (xy 273.904069 -192.35324)
			(xy 273.887799 -192.300493) (xy 273.879572 -192.24591) (xy 273.879056 -192.21831) (xy 273.879602 -192.18923)
			(xy 273.888728 -192.131789) (xy 273.906755 -192.076493) (xy 273.933238 -192.024711) (xy 273.949922 -192.000886)
			(xy 273.958558 -191.989202) (xy 273.960844 -191.961008) (xy 273.913854 -191.867282) (xy 273.909314 -191.859137)
			(xy 273.895558 -191.846573) (xy 273.878209 -191.839783) (xy 273.868896 -191.839342) (xy 272.880328 -191.830198)
			(xy 272.868216 -191.830749) (xy 272.846591 -191.841631) (xy 272.838926 -191.851026) (xy 272.782792 -191.92748)
			(xy 272.778982 -191.95161) (xy 272.782792 -191.963294) (xy 272.79651 -192.007274) (xy 272.815721 -192.097382)
			(xy 272.825376 -192.189008) (xy 272.825972 -192.235074) (xy 272.825482 -192.2768) (xy 272.817531 -192.359874)
			(xy 272.801716 -192.441815) (xy 272.778182 -192.521881) (xy 272.747142 -192.599346) (xy 272.728436 -192.636648)
			(xy 272.723455 -192.647811) (xy 272.723462 -192.672217) (xy 272.728436 -192.683384) (xy 272.747115 -192.720697)
			(xy 272.778136 -192.798166) (xy 272.801662 -192.87823) (xy 272.817479 -192.960166) (xy 272.825445 -193.043234)
			(xy 272.825972 -193.084958) (xy 272.825457 -193.127344) (xy 272.817271 -193.211718) (xy 272.80098 -193.294909)
			(xy 272.776737 -193.37614) (xy 272.744768 -193.454652) (xy 272.705371 -193.529712) (xy 272.658915 -193.60062)
			(xy 272.605832 -193.666713) (xy 272.546619 -193.727376) (xy 272.481827 -193.782041) (xy 272.447258 -193.806572)
			(xy 272.439617 -193.812328) (xy 272.428944 -193.828188) (xy 272.424818 -193.846853) (xy 272.425922 -193.856356)
			(xy 272.428876 -193.875907) (xy 272.432057 -193.915324) (xy 272.432272 -193.935096) (xy 272.431782 -193.96693)
			(xy 272.427991 -193.996305) (xy 273.751565 -193.996305) (xy 273.755411 -193.93463) (xy 273.766891 -193.87391)
			(xy 273.785828 -193.815088) (xy 273.811926 -193.759075) (xy 273.844783 -193.706739) (xy 273.883889 -193.658891)
			(xy 273.928637 -193.616274) (xy 273.978334 -193.579547) (xy 274.00504 -193.564002) (xy 274.016216 -193.557906)
			(xy 274.029678 -193.53657) (xy 274.038314 -193.427096) (xy 274.028408 -193.403982) (xy 274.018248 -193.396108)
			(xy 273.996921 -193.378497) (xy 273.959257 -193.337998) (xy 273.928067 -193.292325) (xy 273.904052 -193.242505)
			(xy 273.88775 -193.189656) (xy 273.879529 -193.134964) (xy 273.879056 -193.10731) (xy 273.879572 -193.07971)
			(xy 273.887799 -193.025127) (xy 273.904069 -192.97238) (xy 273.928019 -192.922648) (xy 273.959114 -192.87704)
			(xy 273.996659 -192.836576) (xy 274.039816 -192.802159) (xy 274.08762 -192.77456) (xy 274.139004 -192.754393)
			(xy 274.192819 -192.74211) (xy 274.247864 -192.737985) (xy 274.302909 -192.74211) (xy 274.356724 -192.754393)
			(xy 274.408108 -192.77456) (xy 274.455912 -192.802159) (xy 274.499069 -192.836576) (xy 274.536614 -192.87704)
			(xy 274.567709 -192.922648) (xy 274.591659 -192.97238) (xy 274.607929 -193.025127) (xy 274.616156 -193.07971)
			(xy 274.616672 -193.10731) (xy 274.6162 -193.134962) (xy 274.60796 -193.189649) (xy 274.59165 -193.242494)
			(xy 274.567636 -193.292313) (xy 274.536457 -193.33799) (xy 274.498809 -193.378502) (xy 274.47748 -193.396108)
			(xy 274.46732 -193.403982) (xy 274.457414 -193.427096) (xy 274.46605 -193.53657) (xy 274.479512 -193.557906)
			(xy 274.490688 -193.564002) (xy 274.517407 -193.57953) (xy 274.567112 -193.616254) (xy 274.611868 -193.658871)
			(xy 274.650981 -193.706719) (xy 274.683844 -193.759058) (xy 274.709948 -193.815074) (xy 274.728888 -193.8739)
			(xy 274.74037 -193.934625) (xy 274.744217 -193.996305) (xy 274.740369 -194.057985) (xy 274.728885 -194.118709)
			(xy 274.709944 -194.177535) (xy 274.683839 -194.233551) (xy 274.650975 -194.285889) (xy 274.611861 -194.333736)
			(xy 274.567105 -194.376352) (xy 274.517399 -194.413075) (xy 274.490688 -194.428618) (xy 274.479512 -194.434714)
			(xy 274.46605 -194.45605) (xy 274.457414 -194.565524) (xy 274.46732 -194.588638) (xy 274.47748 -194.596512)
			(xy 274.498822 -194.614105) (xy 274.536484 -194.654609) (xy 274.567672 -194.700285) (xy 274.591684 -194.750109)
			(xy 274.607982 -194.802961) (xy 274.6162 -194.857655) (xy 274.616672 -194.88531) (xy 274.616156 -194.91291)
			(xy 274.607929 -194.967493) (xy 274.591659 -195.02024) (xy 274.567709 -195.069973) (xy 274.536614 -195.11558)
			(xy 274.499069 -195.156044) (xy 274.455912 -195.190461) (xy 274.408108 -195.21806) (xy 274.356724 -195.238227)
			(xy 274.302909 -195.25051) (xy 274.247864 -195.254635) (xy 274.192819 -195.25051) (xy 274.139004 -195.238227)
			(xy 274.08762 -195.21806) (xy 274.039816 -195.190461) (xy 273.996659 -195.156044) (xy 273.959114 -195.11558)
			(xy 273.928019 -195.069973) (xy 273.904069 -195.02024) (xy 273.887799 -194.967493) (xy 273.879572 -194.91291)
			(xy 273.879056 -194.88531) (xy 273.879569 -194.85766) (xy 273.887804 -194.802976) (xy 273.904108 -194.750133)
			(xy 273.928114 -194.700314) (xy 273.959285 -194.654636) (xy 273.996924 -194.61412) (xy 274.018248 -194.596512)
			(xy 274.028408 -194.588638) (xy 274.038314 -194.565524) (xy 274.029678 -194.45605) (xy 274.016216 -194.434714)
			(xy 274.00504 -194.428618) (xy 273.978342 -194.413058) (xy 273.928644 -194.376332) (xy 273.883895 -194.333716)
			(xy 273.844789 -194.285869) (xy 273.811931 -194.233534) (xy 273.785831 -194.177521) (xy 273.766894 -194.118699)
			(xy 273.755412 -194.05798) (xy 273.751565 -193.996305) (xy 272.427991 -193.996305) (xy 272.423632 -194.030074)
			(xy 272.407465 -194.091655) (xy 272.383547 -194.15066) (xy 272.352273 -194.206118) (xy 272.314156 -194.257115)
			(xy 272.292318 -194.280282) (xy 272.285206 -194.287648) (xy 272.27784 -194.305936) (xy 272.278856 -194.397884)
			(xy 272.28673 -194.416172) (xy 272.293842 -194.423284) (xy 272.317327 -194.447246) (xy 272.358437 -194.500272)
			(xy 272.392219 -194.558242) (xy 272.418086 -194.62015) (xy 272.43559 -194.684922) (xy 272.444427 -194.751433)
			(xy 272.444972 -194.78498) (xy 272.44447 -194.816941) (xy 272.436459 -194.880359) (xy 272.420562 -194.942273)
			(xy 272.39703 -195.001706) (xy 272.366236 -195.057721) (xy 272.328663 -195.109436) (xy 272.284906 -195.156033)
			(xy 272.235653 -195.196778) (xy 272.181682 -195.231029) (xy 272.123843 -195.258246) (xy 272.06305 -195.277999)
			(xy 272.00026 -195.289977) (xy 271.936464 -195.293991) (xy 271.872668 -195.289977) (xy 271.809878 -195.277999)
			(xy 271.749085 -195.258246) (xy 271.691246 -195.231029) (xy 271.637275 -195.196778) (xy 271.588022 -195.156033)
			(xy 271.544265 -195.109436) (xy 271.506692 -195.057721) (xy 271.475898 -195.001706) (xy 271.452366 -194.942273)
			(xy 271.436469 -194.880359) (xy 271.428458 -194.816941) (xy 271.427956 -194.78498) (xy 271.428489 -194.75143)
			(xy 271.437308 -194.684913) (xy 271.454803 -194.620135) (xy 271.48067 -194.558222) (xy 271.514459 -194.500251)
			(xy 271.555582 -194.44723) (xy 271.579086 -194.423284) (xy 271.586198 -194.416172) (xy 271.594072 -194.397884)
			(xy 271.595088 -194.305936) (xy 271.587722 -194.287648) (xy 271.58061 -194.280282) (xy 271.558786 -194.2571)
			(xy 271.52065 -194.206115) (xy 271.489361 -194.150663) (xy 271.465436 -194.09166) (xy 271.449267 -194.030078)
			(xy 271.441123 -193.966931) (xy 271.440656 -193.935096) (xy 271.440944 -193.911647) (xy 271.4454 -193.86496)
			(xy 271.449546 -193.841878) (xy 271.450975 -193.832389) (xy 271.447452 -193.81354) (xy 271.437239 -193.797311)
			(xy 271.429734 -193.791332) (xy 271.406791 -193.774184) (xy 271.362943 -193.737323) (xy 271.342104 -193.717672)
			(xy 271.334767 -193.711292) (xy 271.31672 -193.704103) (xy 271.297294 -193.704139) (xy 271.279273 -193.711395)
			(xy 271.265242 -193.72483) (xy 271.257212 -193.742519) (xy 271.256333 -193.761925) (xy 271.259046 -193.771266)
			(xy 271.267907 -193.79766) (xy 271.280337 -193.851933) (xy 271.286609 -193.907257) (xy 271.286986 -193.935096)
			(xy 271.286478 -193.967197) (xy 271.278186 -194.030862) (xy 271.26174 -194.092923) (xy 271.237415 -194.152339)
			(xy 271.20562 -194.208116) (xy 271.166887 -194.259319) (xy 271.144746 -194.282568) (xy 271.137634 -194.289934)
			(xy 271.130268 -194.30873) (xy 271.131538 -194.40144) (xy 271.139666 -194.419982) (xy 271.147032 -194.427094)
			(xy 271.170714 -194.450555) (xy 271.212212 -194.502728) (xy 271.246343 -194.559992) (xy 271.272492 -194.621313)
			(xy 271.290188 -194.685585) (xy 271.29911 -194.751648) (xy 271.299686 -194.78498) (xy 271.299164 -194.817701)
			(xy 271.290564 -194.882575) (xy 271.27351 -194.945756) (xy 271.248299 -195.006146) (xy 271.215368 -195.062699)
			(xy 271.175289 -195.114431) (xy 271.152366 -195.137786) (xy 271.145 -195.144898) (xy 271.137126 -195.163694)
			(xy 271.137126 -195.256404) (xy 271.145 -195.2752) (xy 271.152366 -195.282312) (xy 271.17527 -195.305686)
			(xy 271.215363 -195.357409) (xy 271.248305 -195.413956) (xy 271.273525 -195.474343) (xy 271.290585 -195.537523)
			(xy 271.299188 -195.602397) (xy 271.299686 -195.635118) (xy 271.299197 -195.666281) (xy 271.291385 -195.728115)
			(xy 271.275885 -195.788483) (xy 271.252942 -195.846431) (xy 271.245952 -195.859146) (xy 275.528024 -195.859146)
			(xy 275.52859 -195.825988) (xy 275.5372 -195.760234) (xy 275.554282 -195.696156) (xy 275.579545 -195.634841)
			(xy 275.612561 -195.577328) (xy 275.652769 -195.524593) (xy 275.69949 -195.47753) (xy 275.725382 -195.45681)
			(xy 275.734295 -195.449262) (xy 275.744624 -195.428344) (xy 275.745194 -195.416678) (xy 275.745194 -195.336414)
			(xy 275.744547 -195.324767) (xy 275.734242 -195.303868) (xy 275.725382 -195.296282) (xy 275.699511 -195.275535)
			(xy 275.652786 -195.228477) (xy 275.612571 -195.175748) (xy 275.579547 -195.11824) (xy 275.554275 -195.05693)
			(xy 275.537183 -194.992855) (xy 275.528561 -194.927103) (xy 275.528024 -194.893946) (xy 275.528618 -194.860173)
			(xy 275.537561 -194.793222) (xy 275.555285 -194.728043) (xy 275.581476 -194.665781) (xy 275.615674 -194.607532)
			(xy 275.657278 -194.55432) (xy 275.705557 -194.50708) (xy 275.759661 -194.466643) (xy 275.788882 -194.4497)
			(xy 275.800058 -194.443604) (xy 275.813774 -194.422522) (xy 275.823172 -194.313556) (xy 275.81352 -194.290188)
			(xy 275.803614 -194.282314) (xy 275.782764 -194.264706) (xy 275.745999 -194.224376) (xy 275.715576 -194.17907)
			(xy 275.692158 -194.129778) (xy 275.676256 -194.077573) (xy 275.668216 -194.023596) (xy 275.667724 -193.99631)
			(xy 275.66824 -193.96871) (xy 275.676467 -193.914127) (xy 275.692737 -193.86138) (xy 275.716687 -193.811648)
			(xy 275.747782 -193.76604) (xy 275.785327 -193.725576) (xy 275.828484 -193.691159) (xy 275.876288 -193.66356)
			(xy 275.927672 -193.643393) (xy 275.981487 -193.63111) (xy 276.036532 -193.626985) (xy 276.091577 -193.63111)
			(xy 276.145392 -193.643393) (xy 276.196776 -193.66356) (xy 276.24458 -193.691159) (xy 276.287737 -193.725576)
			(xy 276.325282 -193.76604) (xy 276.356377 -193.811648) (xy 276.380327 -193.86138) (xy 276.396597 -193.914127)
			(xy 276.404824 -193.96871) (xy 276.40534 -193.99631) (xy 276.404886 -194.023599) (xy 276.396853 -194.077581)
			(xy 276.38095 -194.12979) (xy 276.357523 -194.179084) (xy 276.327085 -194.224385) (xy 276.290302 -194.264704)
			(xy 276.26945 -194.282314) (xy 276.259544 -194.290188) (xy 276.249892 -194.313556) (xy 276.25929 -194.422522)
			(xy 276.273006 -194.443604) (xy 276.284182 -194.4497) (xy 276.313412 -194.466632) (xy 276.367532 -194.507059)
			(xy 276.415823 -194.554295) (xy 276.457437 -194.607506) (xy 276.491642 -194.665759) (xy 276.517835 -194.728026)
			(xy 276.535555 -194.793212) (xy 276.544491 -194.86017) (xy 276.54504 -194.893946) (xy 276.544483 -194.927104)
			(xy 276.535872 -194.992859) (xy 276.51879 -195.056938) (xy 276.493526 -195.118253) (xy 276.460509 -195.175766)
			(xy 276.420298 -195.228501) (xy 276.373576 -195.275563) (xy 276.347682 -195.296282) (xy 276.338766 -195.303827)
			(xy 276.32844 -195.324748) (xy 276.32787 -195.336414) (xy 276.32787 -195.416678) (xy 276.328499 -195.428328)
			(xy 276.338814 -195.449228) (xy 276.347682 -195.45681) (xy 276.373563 -195.477545) (xy 276.420285 -195.524606)
			(xy 276.460497 -195.577339) (xy 276.493519 -195.634848) (xy 276.518789 -195.69616) (xy 276.53588 -195.760236)
			(xy 276.544502 -195.825988) (xy 276.54504 -195.859146) (xy 276.544538 -195.891107) (xy 276.536527 -195.954525)
			(xy 276.52063 -196.016439) (xy 276.497098 -196.075872) (xy 276.466304 -196.131887) (xy 276.428731 -196.183602)
			(xy 276.384974 -196.230199) (xy 276.335721 -196.270944) (xy 276.28175 -196.305195) (xy 276.223911 -196.332412)
			(xy 276.163118 -196.352165) (xy 276.100328 -196.364143) (xy 276.036532 -196.368157) (xy 275.972736 -196.364143)
			(xy 275.909946 -196.352165) (xy 275.849153 -196.332412) (xy 275.791314 -196.305195) (xy 275.737343 -196.270944)
			(xy 275.68809 -196.230199) (xy 275.644333 -196.183602) (xy 275.60676 -196.131887) (xy 275.575966 -196.075872)
			(xy 275.552434 -196.016439) (xy 275.536537 -195.954525) (xy 275.528526 -195.891107) (xy 275.528024 -195.859146)
			(xy 271.245952 -195.859146) (xy 271.222916 -195.901048) (xy 271.186282 -195.95147) (xy 271.143617 -195.996904)
			(xy 271.095595 -196.036632) (xy 271.042971 -196.070027) (xy 270.986577 -196.096564) (xy 270.927302 -196.115824)
			(xy 270.866081 -196.127503) (xy 270.803878 -196.131416) (xy 270.741675 -196.127503) (xy 270.680454 -196.115824)
			(xy 270.621179 -196.096564) (xy 270.564785 -196.070027) (xy 270.512161 -196.036632) (xy 270.464139 -195.996904)
			(xy 270.421474 -195.95147) (xy 270.38484 -195.901048) (xy 270.354814 -195.846431) (xy 270.331871 -195.788483)
			(xy 270.316371 -195.728115) (xy 270.308559 -195.666281) (xy 270.30807 -195.635118) (xy 270.308593 -195.602398)
			(xy 270.317194 -195.537524) (xy 270.334249 -195.474345) (xy 270.359462 -195.413956) (xy 270.392396 -195.357407)
			(xy 270.432479 -195.305678) (xy 270.45539 -195.282312) (xy 270.462756 -195.2752) (xy 270.47063 -195.256404)
			(xy 270.47063 -195.163694) (xy 270.462756 -195.144898) (xy 270.45539 -195.137786) (xy 270.432488 -195.114411)
			(xy 270.392399 -195.062687) (xy 270.35946 -195.00614) (xy 270.334242 -194.945752) (xy 270.317184 -194.882574)
			(xy 270.308582 -194.817701) (xy 270.30807 -194.78498) (xy 270.30858 -194.752879) (xy 270.316874 -194.689215)
			(xy 270.333321 -194.627155) (xy 270.357646 -194.56774) (xy 270.389441 -194.511963) (xy 270.428173 -194.460761)
			(xy 270.45031 -194.437508) (xy 270.457422 -194.430142) (xy 270.464788 -194.411346) (xy 270.463518 -194.318636)
			(xy 270.45539 -194.300094) (xy 270.448024 -194.292982) (xy 270.424335 -194.269523) (xy 270.382826 -194.217354)
			(xy 270.348682 -194.160092) (xy 270.32252 -194.098771) (xy 270.304813 -194.034497) (xy 270.295879 -193.96843)
			(xy 270.29537 -193.935096) (xy 270.295901 -193.902633) (xy 270.304376 -193.838264) (xy 270.321179 -193.775551)
			(xy 270.346025 -193.715568) (xy 270.378487 -193.659341) (xy 270.41801 -193.607832) (xy 270.463918 -193.561922)
			(xy 270.515426 -193.522397) (xy 270.571652 -193.489933) (xy 270.631634 -193.465085) (xy 270.694346 -193.448279)
			(xy 270.758715 -193.439802) (xy 270.791178 -193.439288) (xy 270.823231 -193.439787) (xy 270.886803 -193.448045)
			(xy 270.948777 -193.464439) (xy 270.97863 -193.476118) (xy 270.992346 -193.481706) (xy 271.021302 -193.476372)
			(xy 271.11071 -193.393822) (xy 271.11833 -193.365374) (xy 271.113758 -193.35115) (xy 271.101261 -193.310269)
			(xy 271.083326 -193.22668) (xy 271.077944 -193.184272) (xy 271.076674 -193.17335) (xy 271.06626 -193.155316)
			(xy 270.98879 -193.09842) (xy 270.968216 -193.093848) (xy 270.957802 -193.09588) (xy 270.916553 -193.103365)
			(xy 270.833098 -193.111382) (xy 270.791178 -193.111882) (xy 270.748129 -193.11137) (xy 270.662447 -193.102928)
			(xy 270.578005 -193.08613) (xy 270.495616 -193.061135) (xy 270.416073 -193.028185) (xy 270.340143 -192.987597)
			(xy 270.268558 -192.939762) (xy 270.202005 -192.885141) (xy 270.141127 -192.824259) (xy 270.086509 -192.757704)
			(xy 270.038678 -192.686115) (xy 269.998095 -192.610183) (xy 269.965149 -192.530639) (xy 269.940159 -192.448249)
			(xy 269.923364 -192.363805) (xy 269.914928 -192.278123) (xy 269.91437 -192.235074) (xy 269.915039 -192.186504)
			(xy 269.925796 -192.08996) (xy 269.947142 -191.995194) (xy 269.962376 -191.94907) (xy 269.96644 -191.937386)
			(xy 269.962884 -191.913256) (xy 269.907512 -191.835786) (xy 269.899941 -191.826329) (xy 269.878457 -191.815208)
			(xy 269.866364 -191.81445) (xy 268.852904 -191.81445) (xy 268.843287 -191.814863) (xy 268.825407 -191.821952)
			(xy 268.8114 -191.835134) (xy 268.80693 -191.84366) (xy 268.761718 -191.940688) (xy 268.765528 -191.969898)
			(xy 268.77518 -191.981328) (xy 268.791367 -192.00135) (xy 268.818618 -192.045032) (xy 268.83953 -192.09208)
			(xy 268.853696 -192.141579) (xy 268.86084 -192.192567) (xy 268.861286 -192.21831) (xy 268.86077 -192.24591)
			(xy 268.852543 -192.300493) (xy 268.836273 -192.35324) (xy 268.812323 -192.402973) (xy 268.781228 -192.44858)
			(xy 268.743683 -192.489044) (xy 268.700526 -192.523461) (xy 268.652722 -192.55106) (xy 268.601338 -192.571227)
			(xy 268.547523 -192.58351) (xy 268.492478 -192.587635) (xy 268.437433 -192.58351) (xy 268.383618 -192.571227)
			(xy 268.332234 -192.55106) (xy 268.28443 -192.523461) (xy 268.241273 -192.489044) (xy 268.203728 -192.44858)
			(xy 268.172633 -192.402973) (xy 268.148683 -192.35324) (xy 268.132413 -192.300493) (xy 268.124186 -192.24591)
			(xy 268.12367 -192.21831) (xy 268.124116 -192.192567) (xy 268.131267 -192.14158) (xy 268.145434 -192.092082)
			(xy 268.166339 -192.045031) (xy 268.193579 -192.001341) (xy 268.209776 -191.981328) (xy 268.219428 -191.969898)
			(xy 268.223238 -191.940688) (xy 268.178026 -191.84366) (xy 268.173562 -191.835131) (xy 268.159548 -191.821956)
			(xy 268.141669 -191.814861) (xy 268.132052 -191.81445) (xy 267.064236 -191.81445) (xy 267.054616 -191.814857)
			(xy 267.036726 -191.82194) (xy 267.02271 -191.83512) (xy 267.018262 -191.84366) (xy 266.97305 -191.940688)
			(xy 266.97686 -191.969898) (xy 266.986512 -191.981328) (xy 267.002698 -192.00135) (xy 267.029947 -192.045034)
			(xy 267.050857 -192.092082) (xy 267.065021 -192.14158) (xy 267.072165 -192.192567) (xy 267.072618 -192.21831)
			(xy 267.072102 -192.24591) (xy 267.063875 -192.300493) (xy 267.047605 -192.35324) (xy 267.023655 -192.402973)
			(xy 266.99256 -192.44858) (xy 266.955015 -192.489044) (xy 266.911858 -192.523461) (xy 266.864054 -192.55106)
			(xy 266.81267 -192.571227) (xy 266.758855 -192.58351) (xy 266.70381 -192.587635) (xy 266.648765 -192.58351)
			(xy 266.59495 -192.571227) (xy 266.543566 -192.55106) (xy 266.495762 -192.523461) (xy 266.452605 -192.489044)
			(xy 266.41506 -192.44858) (xy 266.383965 -192.402973) (xy 266.360015 -192.35324) (xy 266.343745 -192.300493)
			(xy 266.335518 -192.24591) (xy 266.335002 -192.21831) (xy 266.335448 -192.192567) (xy 266.342598 -192.141579)
			(xy 266.356762 -192.092079) (xy 266.377665 -192.045026) (xy 266.404901 -192.001333) (xy 266.421108 -191.981328)
			(xy 266.43076 -191.969898) (xy 266.43457 -191.940688) (xy 266.389358 -191.84366) (xy 266.384891 -191.835139)
			(xy 266.370873 -191.821982) (xy 266.352997 -191.81491) (xy 266.343384 -191.81445) (xy 265.329924 -191.81445)
			(xy 265.317831 -191.815192) (xy 265.296356 -191.826334) (xy 265.288776 -191.835786) (xy 265.233404 -191.913256)
			(xy 265.229848 -191.937386) (xy 265.233912 -191.94907) (xy 265.249153 -191.995193) (xy 265.27052 -192.089956)
			(xy 265.281265 -192.186503) (xy 265.281918 -192.235074) (xy 265.281428 -192.276801) (xy 265.273477 -192.359874)
			(xy 265.257663 -192.441815) (xy 265.23413 -192.521882) (xy 265.203091 -192.599348) (xy 265.184382 -192.636648)
			(xy 265.179405 -192.647812) (xy 265.179412 -192.672217) (xy 265.184382 -192.683384) (xy 265.20306 -192.720697)
			(xy 265.23408 -192.798166) (xy 265.257604 -192.87823) (xy 265.27342 -192.960166) (xy 265.281385 -193.043234)
			(xy 265.281918 -193.084958) (xy 265.281403 -193.127344) (xy 265.273217 -193.211719) (xy 265.256927 -193.294911)
			(xy 265.232685 -193.376143) (xy 265.200717 -193.454656) (xy 265.161321 -193.529717) (xy 265.114866 -193.600627)
			(xy 265.061785 -193.666723) (xy 265.002573 -193.727388) (xy 264.937784 -193.782055) (xy 264.903204 -193.806572)
			(xy 264.895569 -193.812331) (xy 264.884908 -193.828192) (xy 264.880787 -193.846853) (xy 264.881868 -193.856356)
			(xy 264.884822 -193.875907) (xy 264.888003 -193.915324) (xy 264.888218 -193.935096) (xy 264.887728 -193.96693)
			(xy 264.883936 -193.996305) (xy 266.207487 -193.996305) (xy 266.211334 -193.934628) (xy 266.222815 -193.873907)
			(xy 266.241754 -193.815083) (xy 266.267855 -193.759069) (xy 266.300715 -193.706733) (xy 266.339825 -193.658886)
			(xy 266.384577 -193.61627) (xy 266.434278 -193.579546) (xy 266.460986 -193.564002) (xy 266.472162 -193.557906)
			(xy 266.485624 -193.53657) (xy 266.49426 -193.427096) (xy 266.484354 -193.403982) (xy 266.474194 -193.396108)
			(xy 266.452877 -193.378485) (xy 266.41521 -193.33799) (xy 266.384018 -193.29232) (xy 266.36 -193.242502)
			(xy 266.343698 -193.189654) (xy 266.335476 -193.134963) (xy 266.335002 -193.10731) (xy 266.335518 -193.07971)
			(xy 266.343745 -193.025127) (xy 266.360015 -192.97238) (xy 266.383965 -192.922648) (xy 266.41506 -192.87704)
			(xy 266.452605 -192.836576) (xy 266.495762 -192.802159) (xy 266.543566 -192.77456) (xy 266.59495 -192.754393)
			(xy 266.648765 -192.74211) (xy 266.70381 -192.737985) (xy 266.758855 -192.74211) (xy 266.81267 -192.754393)
			(xy 266.864054 -192.77456) (xy 266.911858 -192.802159) (xy 266.955015 -192.836576) (xy 266.99256 -192.87704)
			(xy 267.023655 -192.922648) (xy 267.047605 -192.97238) (xy 267.063875 -193.025127) (xy 267.072102 -193.07971)
			(xy 267.072618 -193.10731) (xy 267.072129 -193.134961) (xy 267.06389 -193.189647) (xy 267.047582 -193.242491)
			(xy 267.023572 -193.292309) (xy 266.992396 -193.337987) (xy 266.954753 -193.378501) (xy 266.933426 -193.396108)
			(xy 266.923266 -193.403982) (xy 266.91336 -193.427096) (xy 266.921996 -193.53657) (xy 266.935458 -193.557906)
			(xy 266.946634 -193.564002) (xy 266.973351 -193.579532) (xy 267.023052 -193.616258) (xy 267.067804 -193.658876)
			(xy 267.106913 -193.706725) (xy 267.139773 -193.759063) (xy 267.165874 -193.815079) (xy 267.184812 -193.873904)
			(xy 267.196293 -193.934626) (xy 267.20014 -193.996305) (xy 267.196292 -194.057983) (xy 267.18481 -194.118706)
			(xy 267.16587 -194.17753) (xy 267.139768 -194.233545) (xy 267.106907 -194.285883) (xy 267.067797 -194.333731)
			(xy 267.023044 -194.376348) (xy 266.973343 -194.413074) (xy 266.946634 -194.428618) (xy 266.935458 -194.434714)
			(xy 266.921996 -194.45605) (xy 266.91336 -194.565524) (xy 266.923266 -194.588638) (xy 266.933426 -194.596512)
			(xy 266.954756 -194.614119) (xy 266.992422 -194.654618) (xy 267.023612 -194.700291) (xy 267.047627 -194.750112)
			(xy 267.063927 -194.802963) (xy 267.072146 -194.857656) (xy 267.072618 -194.88531) (xy 267.072102 -194.91291)
			(xy 267.063875 -194.967493) (xy 267.047605 -195.02024) (xy 267.023655 -195.069973) (xy 266.99256 -195.11558)
			(xy 266.955015 -195.156044) (xy 266.911858 -195.190461) (xy 266.864054 -195.21806) (xy 266.81267 -195.238227)
			(xy 266.758855 -195.25051) (xy 266.70381 -195.254635) (xy 266.648765 -195.25051) (xy 266.59495 -195.238227)
			(xy 266.543566 -195.21806) (xy 266.495762 -195.190461) (xy 266.452605 -195.156044) (xy 266.41506 -195.11558)
			(xy 266.383965 -195.069973) (xy 266.360015 -195.02024) (xy 266.343745 -194.967493) (xy 266.335518 -194.91291)
			(xy 266.335002 -194.88531) (xy 266.335498 -194.857659) (xy 266.343734 -194.802973) (xy 266.36004 -194.750129)
			(xy 266.384049 -194.700311) (xy 266.415224 -194.654633) (xy 266.452867 -194.614119) (xy 266.474194 -194.596512)
			(xy 266.484354 -194.588638) (xy 266.49426 -194.565524) (xy 266.485624 -194.45605) (xy 266.472162 -194.434714)
			(xy 266.460986 -194.428618) (xy 266.434286 -194.41306) (xy 266.384584 -194.376336) (xy 266.339831 -194.333721)
			(xy 266.300721 -194.285875) (xy 266.26786 -194.233539) (xy 266.241757 -194.177526) (xy 266.222818 -194.118703)
			(xy 266.211335 -194.057982) (xy 266.207487 -193.996305) (xy 264.883936 -193.996305) (xy 264.879577 -194.030073)
			(xy 264.863409 -194.091653) (xy 264.839489 -194.150657) (xy 264.808212 -194.206112) (xy 264.770093 -194.257106)
			(xy 264.748264 -194.280282) (xy 264.741152 -194.287648) (xy 264.733786 -194.305936) (xy 264.734802 -194.397884)
			(xy 264.742676 -194.416172) (xy 264.749788 -194.423284) (xy 264.773271 -194.447247) (xy 264.814378 -194.500274)
			(xy 264.848157 -194.558245) (xy 264.874022 -194.620153) (xy 264.891524 -194.684924) (xy 264.90036 -194.751433)
			(xy 264.900918 -194.78498) (xy 264.900416 -194.816941) (xy 264.892405 -194.880359) (xy 264.876508 -194.942273)
			(xy 264.852976 -195.001706) (xy 264.822182 -195.057721) (xy 264.784609 -195.109436) (xy 264.740852 -195.156033)
			(xy 264.691599 -195.196778) (xy 264.637628 -195.231029) (xy 264.579789 -195.258246) (xy 264.518996 -195.277999)
			(xy 264.456206 -195.289977) (xy 264.39241 -195.293991) (xy 264.328614 -195.289977) (xy 264.265824 -195.277999)
			(xy 264.205031 -195.258246) (xy 264.147192 -195.231029) (xy 264.093221 -195.196778) (xy 264.043968 -195.156033)
			(xy 264.000211 -195.109436) (xy 263.962638 -195.057721) (xy 263.931844 -195.001706) (xy 263.908312 -194.942273)
			(xy 263.892415 -194.880359) (xy 263.884404 -194.816941) (xy 263.883902 -194.78498) (xy 263.884435 -194.75143)
			(xy 263.893253 -194.684912) (xy 263.910747 -194.620132) (xy 263.936612 -194.558218) (xy 263.970398 -194.500245)
			(xy 264.011518 -194.447221) (xy 264.035032 -194.423284) (xy 264.042144 -194.416172) (xy 264.050018 -194.397884)
			(xy 264.051034 -194.305936) (xy 264.043668 -194.287648) (xy 264.036556 -194.280282) (xy 264.014734 -194.257099)
			(xy 263.976602 -194.206112) (xy 263.945317 -194.150661) (xy 263.921394 -194.091657) (xy 263.905227 -194.030076)
			(xy 263.897084 -193.96693) (xy 263.896602 -193.935096) (xy 263.89689 -193.911647) (xy 263.901345 -193.86496)
			(xy 263.905492 -193.841878) (xy 263.90692 -193.832388) (xy 263.9034 -193.813537) (xy 263.893193 -193.797302)
			(xy 263.88568 -193.791332) (xy 263.852875 -193.766611) (xy 263.791538 -193.711966) (xy 263.735581 -193.651825)
			(xy 263.685493 -193.586713) (xy 263.641715 -193.517202) (xy 263.60463 -193.443901) (xy 263.574563 -193.367454)
			(xy 263.551778 -193.288529) (xy 263.536474 -193.207819) (xy 263.528786 -193.126032) (xy 263.528302 -193.084958)
			(xy 263.52879 -193.043231) (xy 263.536739 -192.960157) (xy 263.55255 -192.878214) (xy 263.576081 -192.798147)
			(xy 263.607118 -192.720679) (xy 263.625838 -192.683384) (xy 263.630821 -192.67222) (xy 263.630828 -192.647808)
			(xy 263.625838 -192.636648) (xy 263.607158 -192.599335) (xy 263.576135 -192.521867) (xy 263.552607 -192.441803)
			(xy 263.536788 -192.359866) (xy 263.528819 -192.276798) (xy 263.528302 -192.235074) (xy 263.528971 -192.186504)
			(xy 263.539727 -192.08996) (xy 263.561072 -191.995193) (xy 263.576308 -191.94907) (xy 263.580372 -191.937386)
			(xy 263.576816 -191.913256) (xy 263.521444 -191.835786) (xy 263.513875 -191.826323) (xy 263.492392 -191.815189)
			(xy 263.480296 -191.81445) (xy 263.43229 -191.81445) (xy 263.42228 -191.814939) (xy 263.403783 -191.822599)
			(xy 263.389621 -191.836749) (xy 263.381947 -191.85524) (xy 263.38149 -191.86525) (xy 263.38149 -191.872616)
			(xy 263.383522 -191.879982) (xy 263.393576 -191.915721) (xy 263.404418 -191.989166) (xy 263.405112 -192.026286)
			(xy 263.40461 -192.058247) (xy 263.396599 -192.121665) (xy 263.380702 -192.183579) (xy 263.35717 -192.243012)
			(xy 263.326376 -192.299027) (xy 263.288803 -192.350742) (xy 263.245046 -192.397339) (xy 263.195793 -192.438084)
			(xy 263.141822 -192.472335) (xy 263.083983 -192.499552) (xy 263.02319 -192.519305) (xy 262.9604 -192.531283)
			(xy 262.896604 -192.535297) (xy 262.832808 -192.531283) (xy 262.770018 -192.519305) (xy 262.709225 -192.499552)
			(xy 262.651386 -192.472335) (xy 262.597415 -192.438084) (xy 262.548162 -192.397339) (xy 262.504405 -192.350742)
			(xy 262.466832 -192.299027) (xy 262.436038 -192.243012) (xy 262.412506 -192.183579) (xy 262.396609 -192.121665)
			(xy 262.388598 -192.058247) (xy 262.388096 -192.026286) (xy 262.388238 -192.010304) (xy 262.390272 -191.978403)
			(xy 262.39216 -191.962532) (xy 262.393684 -191.950594) (xy 262.385556 -191.927734) (xy 262.317484 -191.862964)
			(xy 262.308427 -191.855209) (xy 262.285633 -191.848319) (xy 262.273796 -191.849756) (xy 256.33807 -192.896236)
			(xy 256.317496 -192.913254) (xy 256.31267 -192.9257) (xy 256.306295 -192.941776) (xy 256.291033 -192.972814)
			(xy 256.28219 -192.987676) (xy 256.278146 -192.994935) (xy 256.274501 -193.011137) (xy 256.275078 -193.019426)
			(xy 256.278126 -193.04889) (xy 256.27936 -193.057284) (xy 256.286616 -193.07261) (xy 256.29235 -193.078862)
			(xy 256.314688 -193.102641) (xy 256.353716 -193.154923) (xy 256.385734 -193.211769) (xy 256.410218 -193.272244)
			(xy 256.426763 -193.335354) (xy 256.435099 -193.400062) (xy 256.435606 -193.432684) (xy 256.435028 -193.467639)
			(xy 256.425461 -193.536893) (xy 256.406504 -193.604184) (xy 256.378514 -193.668248) (xy 256.342018 -193.727876)
			(xy 256.32029 -193.755264) (xy 256.315059 -193.762283) (xy 256.309223 -193.778775) (xy 256.30886 -193.787522)
			(xy 256.30886 -193.941446) (xy 256.309173 -193.950202) (xy 256.31502 -193.966704) (xy 256.32029 -193.973704)
			(xy 256.342006 -194.001102) (xy 256.378513 -194.060724) (xy 256.406509 -194.124784) (xy 256.425468 -194.192075)
			(xy 256.435032 -194.261328) (xy 256.435606 -194.296284) (xy 256.435027 -194.330837) (xy 256.42567 -194.399308)
			(xy 256.407126 -194.46588) (xy 256.395581 -194.492626) (xy 259.966714 -194.492626) (xy 259.967307 -194.457671)
			(xy 259.976866 -194.388418) (xy 259.99582 -194.321127) (xy 260.023812 -194.257067) (xy 260.060316 -194.197444)
			(xy 260.08203 -194.170046) (xy 260.087285 -194.163036) (xy 260.09314 -194.146542) (xy 260.09346 -194.137788)
			(xy 260.09346 -193.856864) (xy 260.09312 -193.848115) (xy 260.087268 -193.831623) (xy 260.08203 -193.824606)
			(xy 260.060324 -193.797201) (xy 260.023824 -193.737578) (xy 259.99583 -193.673519) (xy 259.976868 -193.606231)
			(xy 259.967295 -193.53698) (xy 259.966714 -193.502026) (xy 259.967192 -193.469875) (xy 259.975289 -193.406086)
			(xy 259.99137 -193.343828) (xy 260.015177 -193.284097) (xy 260.046331 -193.227847) (xy 260.084332 -193.175976)
			(xy 260.128575 -193.129316) (xy 260.15315 -193.10858) (xy 260.16077 -193.10223) (xy 260.170168 -193.085212)
			(xy 260.18109 -192.99555) (xy 260.17601 -192.977008) (xy 260.169914 -192.96888) (xy 260.152013 -192.94394)
			(xy 260.12355 -192.889553) (xy 260.104155 -192.831312) (xy 260.094329 -192.770719) (xy 260.093714 -192.740026)
			(xy 260.0942 -192.712775) (xy 260.101956 -192.658827) (xy 260.117311 -192.606532) (xy 260.139953 -192.556955)
			(xy 260.169419 -192.511105) (xy 260.20511 -192.469914) (xy 260.246301 -192.434223) (xy 260.292151 -192.404757)
			(xy 260.341728 -192.382115) (xy 260.394023 -192.36676) (xy 260.447971 -192.359004) (xy 260.502473 -192.359004)
			(xy 260.556421 -192.36676) (xy 260.608716 -192.382115) (xy 260.658293 -192.404757) (xy 260.704143 -192.434223)
			(xy 260.745334 -192.469914) (xy 260.781025 -192.511105) (xy 260.810491 -192.556955) (xy 260.833133 -192.606532)
			(xy 260.848488 -192.658827) (xy 260.856244 -192.712775) (xy 260.85673 -192.740026) (xy 260.856137 -192.77072)
			(xy 260.846309 -192.831316) (xy 260.826911 -192.889559) (xy 260.798442 -192.943947) (xy 260.78053 -192.96888)
			(xy 260.774434 -192.977008) (xy 260.769354 -192.99555) (xy 260.780276 -193.085212) (xy 260.789674 -193.10223)
			(xy 260.797294 -193.10858) (xy 260.82186 -193.129323) (xy 260.866085 -193.175995) (xy 260.904074 -193.227869)
			(xy 260.935221 -193.284118) (xy 260.959029 -193.343844) (xy 260.975119 -193.406095) (xy 260.983233 -193.469878)
			(xy 260.98373 -193.502026) (xy 260.983157 -193.536981) (xy 260.973592 -193.606235) (xy 260.954632 -193.673526)
			(xy 260.926636 -193.737586) (xy 260.890129 -193.797208) (xy 260.868414 -193.824606) (xy 260.863142 -193.831605)
			(xy 260.857296 -193.848108) (xy 260.856984 -193.856864) (xy 260.856984 -194.137788) (xy 260.857357 -194.146534)
			(xy 260.863188 -194.163025) (xy 260.868414 -194.170046) (xy 260.890104 -194.197462) (xy 260.926605 -194.257084)
			(xy 260.954602 -194.32114) (xy 260.973568 -194.388425) (xy 260.983146 -194.457673) (xy 260.98373 -194.492626)
			(xy 260.983238 -194.524776) (xy 260.975146 -194.588566) (xy 260.959069 -194.650824) (xy 260.935264 -194.710556)
			(xy 260.904113 -194.766807) (xy 260.866112 -194.818677) (xy 260.821869 -194.865337) (xy 260.797294 -194.886072)
			(xy 260.789674 -194.892422) (xy 260.780276 -194.90944) (xy 260.769354 -194.999102) (xy 260.774434 -195.017644)
			(xy 260.78053 -195.025772) (xy 260.798446 -195.050701) (xy 260.826908 -195.105091) (xy 260.846299 -195.163336)
			(xy 260.856119 -195.223932) (xy 260.85673 -195.254626) (xy 260.856244 -195.281877) (xy 260.848488 -195.335825)
			(xy 260.833133 -195.38812) (xy 260.810491 -195.437697) (xy 260.781025 -195.483547) (xy 260.745334 -195.524738)
			(xy 260.704143 -195.560429) (xy 260.658293 -195.589895) (xy 260.608716 -195.612537) (xy 260.556421 -195.627892)
			(xy 260.502473 -195.635648) (xy 260.447971 -195.635648) (xy 260.394023 -195.627892) (xy 260.341728 -195.612537)
			(xy 260.292151 -195.589895) (xy 260.246301 -195.560429) (xy 260.20511 -195.524738) (xy 260.169419 -195.483547)
			(xy 260.139953 -195.437697) (xy 260.117311 -195.38812) (xy 260.101956 -195.335825) (xy 260.0942 -195.281877)
			(xy 260.093714 -195.254626) (xy 260.094345 -195.223934) (xy 260.104163 -195.163339) (xy 260.123551 -195.105097)
			(xy 260.152008 -195.050707) (xy 260.169914 -195.025772) (xy 260.17601 -195.017644) (xy 260.18109 -194.999102)
			(xy 260.170168 -194.90944) (xy 260.16077 -194.892422) (xy 260.15315 -194.886072) (xy 260.12857 -194.865344)
			(xy 260.084344 -194.818671) (xy 260.046355 -194.766795) (xy 260.015209 -194.710544) (xy 259.991404 -194.650814)
			(xy 259.975318 -194.58856) (xy 259.967208 -194.524775) (xy 259.966714 -194.492626) (xy 256.395581 -194.492626)
			(xy 256.379738 -194.529328) (xy 256.344009 -194.588481) (xy 256.300598 -194.642251) (xy 256.27584 -194.666362)
			(xy 256.269994 -194.67241) (xy 256.262228 -194.687318) (xy 256.2606 -194.695572) (xy 256.256028 -194.724782)
			(xy 256.255156 -194.73304) (xy 256.258148 -194.749362) (xy 256.26187 -194.756786) (xy 256.276575 -194.785047)
			(xy 256.297409 -194.845247) (xy 256.30797 -194.908068) (xy 256.308606 -194.93992) (xy 256.308133 -194.96729)
			(xy 256.300307 -195.021466) (xy 256.284818 -195.073969) (xy 256.261984 -195.123718) (xy 256.232274 -195.169693)
			(xy 256.214626 -195.190618) (xy 256.20853 -195.19773) (xy 256.20218 -195.214748) (xy 256.20218 -195.300092)
			(xy 256.20853 -195.31711) (xy 256.214626 -195.324222) (xy 256.232266 -195.345154) (xy 256.261987 -195.391122)
			(xy 256.284826 -195.440869) (xy 256.300312 -195.493372) (xy 256.308127 -195.54755) (xy 256.308606 -195.57492)
			(xy 256.308194 -195.600194) (xy 256.301514 -195.6503) (xy 256.288274 -195.699084) (xy 256.268706 -195.745692)
			(xy 256.256282 -195.767706) (xy 256.250877 -195.778086) (xy 256.249214 -195.801402) (xy 256.258062 -195.823038)
			(xy 256.266442 -195.831206) (xy 256.288874 -195.851914) (xy 256.329136 -195.897808) (xy 256.363613 -195.948193)
			(xy 256.391809 -196.002343) (xy 256.413319 -196.05948) (xy 256.427832 -196.118782) (xy 256.43514 -196.179394)
			(xy 256.435606 -196.20992) (xy 256.435026 -196.244875) (xy 256.425454 -196.314125) (xy 256.406493 -196.381414)
			(xy 256.3785 -196.445474) (xy 256.35135 -196.489828) (xy 262.672322 -196.489828) (xy 262.672753 -196.463763)
			(xy 262.679871 -196.412121) (xy 262.693951 -196.361927) (xy 262.714732 -196.314118) (xy 262.741825 -196.269581)
			(xy 262.774728 -196.229146) (xy 262.812828 -196.193565) (xy 262.833866 -196.17817) (xy 262.842502 -196.172074)
			(xy 262.85317 -196.154548) (xy 262.866632 -196.06006) (xy 262.861298 -196.040248) (xy 262.854694 -196.031866)
			(xy 262.833823 -196.004756) (xy 262.798753 -195.94601) (xy 262.77188 -195.883091) (xy 262.753689 -195.817136)
			(xy 262.744509 -195.749337) (xy 262.74395 -195.715128) (xy 262.744452 -195.683167) (xy 262.752463 -195.619749)
			(xy 262.76836 -195.557835) (xy 262.791892 -195.498402) (xy 262.822686 -195.442387) (xy 262.860259 -195.390672)
			(xy 262.904016 -195.344075) (xy 262.953269 -195.30333) (xy 263.00724 -195.269079) (xy 263.065079 -195.241862)
			(xy 263.125872 -195.222109) (xy 263.188662 -195.210131) (xy 263.252458 -195.206118) (xy 263.316254 -195.210131)
			(xy 263.379044 -195.222109) (xy 263.439837 -195.241862) (xy 263.497676 -195.269079) (xy 263.551647 -195.30333)
			(xy 263.6009 -195.344075) (xy 263.644657 -195.390672) (xy 263.68223 -195.442387) (xy 263.713024 -195.498402)
			(xy 263.736556 -195.557835) (xy 263.752453 -195.619749) (xy 263.760464 -195.683167) (xy 263.760966 -195.715128)
			(xy 263.760427 -195.748321) (xy 263.751807 -195.814146) (xy 263.739801 -195.859146) (xy 267.98397 -195.859146)
			(xy 267.984518 -195.825987) (xy 267.99313 -195.760232) (xy 268.010213 -195.696153) (xy 268.035478 -195.634837)
			(xy 268.068497 -195.577325) (xy 268.108709 -195.52459) (xy 268.155434 -195.477528) (xy 268.181328 -195.45681)
			(xy 268.190249 -195.44927) (xy 268.200572 -195.428346) (xy 268.20114 -195.416678) (xy 268.20114 -195.336414)
			(xy 268.200511 -195.324764) (xy 268.190196 -195.303864) (xy 268.181328 -195.296282) (xy 268.155446 -195.275549)
			(xy 268.108723 -195.228488) (xy 268.06851 -195.175755) (xy 268.035489 -195.118245) (xy 268.010219 -195.056933)
			(xy 267.993129 -194.992857) (xy 267.984507 -194.927104) (xy 267.98397 -194.893946) (xy 267.98454 -194.860172)
			(xy 267.993485 -194.793219) (xy 268.01121 -194.728038) (xy 268.037403 -194.665775) (xy 268.071605 -194.607526)
			(xy 268.113213 -194.554314) (xy 268.161496 -194.507076) (xy 268.215605 -194.466641) (xy 268.244828 -194.4497)
			(xy 268.256004 -194.443604) (xy 268.26972 -194.422522) (xy 268.279118 -194.313556) (xy 268.269466 -194.290188)
			(xy 268.25956 -194.282314) (xy 268.238699 -194.264719) (xy 268.201937 -194.224384) (xy 268.171517 -194.179076)
			(xy 268.148101 -194.129781) (xy 268.132201 -194.077575) (xy 268.124162 -194.023597) (xy 268.12367 -193.99631)
			(xy 268.124186 -193.96871) (xy 268.132413 -193.914127) (xy 268.148683 -193.86138) (xy 268.172633 -193.811648)
			(xy 268.203728 -193.76604) (xy 268.241273 -193.725576) (xy 268.28443 -193.691159) (xy 268.332234 -193.66356)
			(xy 268.383618 -193.643393) (xy 268.437433 -193.63111) (xy 268.492478 -193.626985) (xy 268.547523 -193.63111)
			(xy 268.601338 -193.643393) (xy 268.652722 -193.66356) (xy 268.700526 -193.691159) (xy 268.743683 -193.725576)
			(xy 268.781228 -193.76604) (xy 268.812323 -193.811648) (xy 268.836273 -193.86138) (xy 268.852543 -193.914127)
			(xy 268.86077 -193.96871) (xy 268.861286 -193.99631) (xy 268.860815 -194.023598) (xy 268.852784 -194.077579)
			(xy 268.836882 -194.129787) (xy 268.813459 -194.17908) (xy 268.783025 -194.224382) (xy 268.746245 -194.264703)
			(xy 268.725396 -194.282314) (xy 268.71549 -194.290188) (xy 268.705838 -194.313556) (xy 268.715236 -194.422522)
			(xy 268.728952 -194.443604) (xy 268.740128 -194.4497) (xy 268.769369 -194.466614) (xy 268.823486 -194.507046)
			(xy 268.871776 -194.554285) (xy 268.913388 -194.607499) (xy 268.947591 -194.665754) (xy 268.973782 -194.728022)
			(xy 268.991502 -194.79321) (xy 269.000437 -194.860169) (xy 269.000986 -194.893946) (xy 269.000449 -194.927105)
			(xy 268.991837 -194.992862) (xy 268.974753 -195.056942) (xy 268.949487 -195.118258) (xy 268.916466 -195.17577)
			(xy 268.876251 -195.228504) (xy 268.829524 -195.275564) (xy 268.803628 -195.296282) (xy 268.794703 -195.303818)
			(xy 268.784384 -195.324746) (xy 268.783816 -195.336414) (xy 268.783816 -195.416678) (xy 268.784464 -195.428325)
			(xy 268.794768 -195.449224) (xy 268.803628 -195.45681) (xy 268.829497 -195.477559) (xy 268.876222 -195.524617)
			(xy 268.916437 -195.577346) (xy 268.949461 -195.634853) (xy 268.974733 -195.696163) (xy 268.991825 -195.760237)
			(xy 269.000448 -195.825989) (xy 269.000986 -195.859146) (xy 269.000484 -195.891107) (xy 268.992473 -195.954525)
			(xy 268.976576 -196.016439) (xy 268.953044 -196.075872) (xy 268.92225 -196.131887) (xy 268.884677 -196.183602)
			(xy 268.84092 -196.230199) (xy 268.791667 -196.270944) (xy 268.737696 -196.305195) (xy 268.679857 -196.332412)
			(xy 268.619064 -196.352165) (xy 268.556274 -196.364143) (xy 268.492478 -196.368157) (xy 268.428682 -196.364143)
			(xy 268.365892 -196.352165) (xy 268.305099 -196.332412) (xy 268.24726 -196.305195) (xy 268.193289 -196.270944)
			(xy 268.144036 -196.230199) (xy 268.100279 -196.183602) (xy 268.062706 -196.131887) (xy 268.031912 -196.075872)
			(xy 268.00838 -196.016439) (xy 267.992483 -195.954525) (xy 267.984472 -195.891107) (xy 267.98397 -195.859146)
			(xy 263.739801 -195.859146) (xy 263.734693 -195.878289) (xy 263.709374 -195.939657) (xy 263.676282 -195.997208)
			(xy 263.63598 -196.049962) (xy 263.589154 -196.09702) (xy 263.5366 -196.137582) (xy 263.479214 -196.170959)
			(xy 263.4488 -196.184266) (xy 263.438894 -196.18833) (xy 263.42467 -196.203062) (xy 263.390888 -196.29247)
			(xy 263.391904 -196.31279) (xy 263.39673 -196.322442) (xy 263.402862 -196.335421) (xy 263.413416 -196.362117)
			(xy 263.417812 -196.375782) (xy 263.421622 -196.387466) (xy 263.43864 -196.404992) (xy 263.54024 -196.43852)
			(xy 263.56437 -196.434964) (xy 263.574276 -196.427598) (xy 263.60036 -196.409333) (xy 263.656236 -196.37879)
			(xy 263.71549 -196.355463) (xy 263.777192 -196.33972) (xy 263.840378 -196.331807) (xy 263.872218 -196.331332)
			(xy 263.904181 -196.331755) (xy 263.967602 -196.339769) (xy 264.029519 -196.355669) (xy 264.088955 -196.379203)
			(xy 264.144973 -196.410001) (xy 264.196689 -196.447576) (xy 264.243288 -196.491337) (xy 264.284035 -196.540593)
			(xy 264.318287 -196.594568) (xy 264.345505 -196.65241) (xy 264.365258 -196.713207) (xy 264.377237 -196.776)
			(xy 264.381251 -196.8398) (xy 264.377237 -196.9036) (xy 264.365258 -196.966393) (xy 264.345505 -197.02719)
			(xy 264.318287 -197.085032) (xy 264.284035 -197.139007) (xy 264.243288 -197.188263) (xy 264.196689 -197.232024)
			(xy 264.144973 -197.269599) (xy 264.088955 -197.300397) (xy 264.029519 -197.323931) (xy 263.967602 -197.339831)
			(xy 263.904181 -197.347845) (xy 263.872218 -197.348348) (xy 263.839063 -197.347871) (xy 263.773317 -197.33923)
			(xy 263.709252 -197.322118) (xy 263.647954 -197.296825) (xy 263.590463 -197.263781) (xy 263.537755 -197.223545)
			(xy 263.490722 -197.176801) (xy 263.450162 -197.12434) (xy 263.416765 -197.067054) (xy 263.391095 -197.005913)
			(xy 263.373589 -196.941955) (xy 263.368536 -196.909182) (xy 263.366758 -196.89699) (xy 263.352788 -196.876924)
			(xy 263.2583 -196.826886) (xy 263.233916 -196.826378) (xy 263.22274 -196.831966) (xy 263.196324 -196.844361)
			(xy 263.140673 -196.861896) (xy 263.083004 -196.870777) (xy 263.05383 -196.871336) (xy 263.026579 -196.870817)
			(xy 262.972632 -196.863065) (xy 262.920337 -196.847714) (xy 262.870758 -196.825077) (xy 262.824907 -196.795615)
			(xy 262.783714 -196.759927) (xy 262.74802 -196.71874) (xy 262.718551 -196.672893) (xy 262.695906 -196.623318)
			(xy 262.680548 -196.571025) (xy 262.672787 -196.517079) (xy 262.672322 -196.489828) (xy 256.35135 -196.489828)
			(xy 256.342002 -196.5051) (xy 256.32029 -196.5325) (xy 256.315049 -196.539516) (xy 256.309193 -196.556008)
			(xy 256.30886 -196.564758) (xy 256.30886 -196.718682) (xy 256.309179 -196.727436) (xy 256.315035 -196.74393)
			(xy 256.32029 -196.75094) (xy 256.342004 -196.778338) (xy 256.378506 -196.837961) (xy 256.406499 -196.902022)
			(xy 256.425453 -196.969312) (xy 256.435012 -197.038565) (xy 256.435606 -197.07352) (xy 256.435153 -197.104046)
			(xy 256.427841 -197.164658) (xy 256.413323 -197.223958) (xy 256.39181 -197.281094) (xy 256.363611 -197.335243)
			(xy 256.329131 -197.385625) (xy 256.288866 -197.431517) (xy 256.266442 -197.452234) (xy 256.258119 -197.460441)
			(xy 256.249315 -197.482068) (xy 256.250894 -197.505364) (xy 256.256282 -197.515734) (xy 256.268711 -197.537746)
			(xy 256.288289 -197.584352) (xy 256.301535 -197.633137) (xy 256.308215 -197.683244) (xy 256.308606 -197.70852)
			(xy 256.308133 -197.73589) (xy 256.300307 -197.790066) (xy 256.284818 -197.842569) (xy 256.261984 -197.892318)
			(xy 256.232274 -197.938293) (xy 256.214626 -197.959218) (xy 256.20853 -197.96633) (xy 256.20218 -197.983348)
			(xy 256.20218 -198.068692) (xy 256.20853 -198.08571) (xy 256.214626 -198.092822) (xy 256.232266 -198.113754)
			(xy 256.261987 -198.159722) (xy 256.284826 -198.209469) (xy 256.300312 -198.261972) (xy 256.308127 -198.31615)
			(xy 256.308606 -198.34352) (xy 256.308194 -198.368794) (xy 256.301514 -198.4189) (xy 256.288274 -198.467684)
			(xy 256.268706 -198.514292) (xy 256.256282 -198.536306) (xy 256.252233 -198.543896) (xy 256.248986 -198.560776)
			(xy 256.249932 -198.569326) (xy 256.25425 -198.599044) (xy 256.255893 -198.60758) (xy 256.264066 -198.622909)
			(xy 256.270252 -198.629016) (xy 256.292224 -198.649695) (xy 256.331616 -198.6954) (xy 256.365323 -198.745445)
			(xy 256.392872 -198.799126) (xy 256.413876 -198.855691) (xy 256.42804 -198.914343) (xy 256.435164 -198.974259)
			(xy 256.435606 -199.004428) (xy 256.435025 -199.039382) (xy 256.425452 -199.108633) (xy 256.40649 -199.175921)
			(xy 256.378497 -199.23998) (xy 256.341998 -199.299605) (xy 256.32029 -199.327008) (xy 256.31505 -199.334025)
			(xy 256.309197 -199.350516) (xy 256.30886 -199.359266) (xy 256.30886 -199.51319) (xy 256.309181 -199.521943)
			(xy 256.315038 -199.538436) (xy 256.32029 -199.545448) (xy 256.342003 -199.572847) (xy 256.378505 -199.632469)
			(xy 256.406496 -199.69653) (xy 256.425449 -199.763821) (xy 256.435007 -199.833073) (xy 256.435606 -199.868028)
			(xy 256.435158 -199.898196) (xy 256.42802 -199.958107) (xy 256.413848 -200.016754) (xy 256.392841 -200.073314)
			(xy 256.365293 -200.126993) (xy 256.331591 -200.177038) (xy 256.292208 -200.222746) (xy 256.270252 -200.24344)
			(xy 256.264072 -200.249551) (xy 256.255898 -200.264877) (xy 256.25425 -200.273412) (xy 256.249932 -200.30313)
			(xy 256.249018 -200.311679) (xy 256.252259 -200.328552) (xy 256.256282 -200.33615) (xy 256.26871 -200.358163)
			(xy 256.288286 -200.404768) (xy 256.30153 -200.453553) (xy 256.308208 -200.503661) (xy 256.308606 -200.528936)
			(xy 256.308132 -200.556305) (xy 256.300303 -200.610481) (xy 256.284813 -200.662982) (xy 256.261977 -200.71273)
			(xy 256.232267 -200.758703) (xy 256.214626 -200.779634) (xy 256.20853 -200.786746) (xy 256.20218 -200.803764)
			(xy 256.20218 -200.889108) (xy 256.20853 -200.906126) (xy 256.214626 -200.913238) (xy 256.232265 -200.934171)
			(xy 256.261984 -200.980139) (xy 256.284821 -201.029886) (xy 256.300305 -201.082389) (xy 256.308117 -201.136567)
			(xy 256.308606 -201.163936) (xy 256.308193 -201.18921) (xy 256.301511 -201.239315) (xy 256.28827 -201.288098)
			(xy 256.2687 -201.334705) (xy 256.256282 -201.356722) (xy 256.250881 -201.367101) (xy 256.249224 -201.390413)
			(xy 256.258076 -201.412042) (xy 256.266442 -201.420222) (xy 256.288874 -201.44093) (xy 256.329134 -201.486825)
			(xy 256.36361 -201.53721) (xy 256.391804 -201.59136) (xy 256.413311 -201.648497) (xy 256.427823 -201.707798)
			(xy 256.435129 -201.768411) (xy 256.435606 -201.798936) (xy 256.435025 -201.83389) (xy 256.425451 -201.90314)
			(xy 256.406488 -201.970428) (xy 256.378493 -202.034486) (xy 256.341994 -202.09411) (xy 256.32029 -202.121516)
			(xy 256.315052 -202.128533) (xy 256.3092 -202.145025) (xy 256.30886 -202.153774) (xy 256.30886 -202.307698)
			(xy 256.309182 -202.316451) (xy 256.315042 -202.332942) (xy 256.32029 -202.339956) (xy 256.342008 -202.367353)
			(xy 256.378521 -202.426974) (xy 256.406524 -202.491034) (xy 256.425489 -202.558325) (xy 256.435059 -202.62758)
			(xy 256.435606 -202.662536) (xy 256.435152 -202.693061) (xy 256.427838 -202.753672) (xy 256.413319 -202.812972)
			(xy 256.391805 -202.870106) (xy 256.363604 -202.924253) (xy 256.329124 -202.974635) (xy 256.288858 -203.020525)
			(xy 256.266442 -203.04125) (xy 256.258123 -203.049458) (xy 256.249325 -203.071082) (xy 256.25091 -203.094374)
			(xy 256.256282 -203.10475) (xy 256.26871 -203.126763) (xy 256.288286 -203.173368) (xy 256.30153 -203.222153)
			(xy 256.308208 -203.272261) (xy 256.308606 -203.297536) (xy 256.308132 -203.324905) (xy 256.300303 -203.379081)
			(xy 256.284813 -203.431582) (xy 256.261977 -203.48133) (xy 256.232267 -203.527303) (xy 256.214626 -203.548234)
			(xy 256.20853 -203.555346) (xy 256.20218 -203.572364) (xy 256.20218 -203.657708) (xy 256.20853 -203.674726)
			(xy 256.214626 -203.681838) (xy 256.232265 -203.702771) (xy 256.261984 -203.748739) (xy 256.284821 -203.798486)
			(xy 256.300305 -203.850989) (xy 256.308117 -203.905167) (xy 256.308606 -203.932536) (xy 256.307993 -203.964391)
			(xy 256.297451 -204.02722) (xy 256.276601 -204.08742) (xy 256.26187 -204.11567) (xy 256.258138 -204.123088)
			(xy 256.255168 -204.139414) (xy 256.256028 -204.147674) (xy 256.2606 -204.176884) (xy 256.262163 -204.185157)
			(xy 256.269953 -204.200074) (xy 256.27584 -204.206094) (xy 256.30059 -204.230212) (xy 256.344005 -204.28398)
			(xy 256.379739 -204.343132) (xy 256.407132 -204.406577) (xy 256.425681 -204.473149) (xy 256.435044 -204.541619)
			(xy 256.435606 -204.576172) (xy 256.435022 -204.611125) (xy 256.425444 -204.680373) (xy 256.406477 -204.747658)
			(xy 256.378479 -204.811713) (xy 256.341978 -204.871334) (xy 256.32029 -204.898752) (xy 256.315057 -204.905771)
			(xy 256.309217 -204.922262) (xy 256.30886 -204.93101) (xy 256.30886 -205.084934) (xy 256.309171 -205.093691)
			(xy 256.315015 -205.110196) (xy 256.32029 -205.117192) (xy 256.342006 -205.14459) (xy 256.378515 -205.204211)
			(xy 256.406513 -205.268271) (xy 256.425474 -205.335562) (xy 256.435039 -205.404816) (xy 256.435606 -205.439772)
			(xy 256.435028 -205.474326) (xy 256.425672 -205.542797) (xy 256.40713 -205.60937) (xy 256.379742 -205.672819)
			(xy 256.344014 -205.731974) (xy 256.300603 -205.785745) (xy 256.27584 -205.80985) (xy 256.269993 -205.815898)
			(xy 256.262223 -205.830805) (xy 256.2606 -205.83906) (xy 256.256028 -205.86827) (xy 256.255154 -205.876528)
			(xy 256.258143 -205.892852) (xy 256.26187 -205.900274) (xy 256.276576 -205.928535) (xy 256.297411 -205.988735)
			(xy 256.307974 -206.051556) (xy 256.308606 -206.083408) (xy 256.308134 -206.110778) (xy 256.300309 -206.164956)
			(xy 256.284821 -206.217459) (xy 256.261989 -206.267209) (xy 256.23228 -206.313186) (xy 256.214626 -206.334106)
			(xy 256.20853 -206.341218) (xy 256.20218 -206.358236) (xy 256.20218 -206.44358) (xy 256.20853 -206.460598)
			(xy 256.214626 -206.46771) (xy 256.232266 -206.488642) (xy 256.261989 -206.534609) (xy 256.284829 -206.584356)
			(xy 256.300317 -206.636859) (xy 256.308134 -206.691038) (xy 256.308606 -206.718408) (xy 256.308195 -206.743683)
			(xy 256.301517 -206.793789) (xy 256.288278 -206.842574) (xy 256.268711 -206.889183) (xy 256.256282 -206.911194)
			(xy 256.250874 -206.921574) (xy 256.249206 -206.944894) (xy 256.258053 -206.966534) (xy 256.266442 -206.974694)
			(xy 256.288875 -206.995402) (xy 256.329138 -207.041295) (xy 256.363616 -207.09168) (xy 256.391814 -207.14583)
			(xy 256.413324 -207.202967) (xy 256.427838 -207.262269) (xy 256.435148 -207.322882) (xy 256.435606 -207.353408)
			(xy 256.435027 -207.388363) (xy 256.425456 -207.457615) (xy 256.406496 -207.524904) (xy 256.378504 -207.588965)
			(xy 256.342007 -207.648592) (xy 256.32029 -207.675988) (xy 256.315048 -207.683004) (xy 256.309187 -207.699495)
			(xy 256.30886 -207.708246) (xy 256.30886 -207.86217) (xy 256.309177 -207.870925) (xy 256.31503 -207.887422)
			(xy 256.32029 -207.894428) (xy 256.342005 -207.921826) (xy 256.378509 -207.981449) (xy 256.406502 -208.045509)
			(xy 256.425458 -208.1128) (xy 256.435019 -208.182053) (xy 256.435606 -208.217008) (xy 256.435154 -208.247534)
			(xy 256.427843 -208.308147) (xy 256.413327 -208.367448) (xy 256.391814 -208.424585) (xy 256.363616 -208.478734)
			(xy 256.329136 -208.529118) (xy 256.288872 -208.575011) (xy 256.266442 -208.595722) (xy 256.258138 -208.603931)
			(xy 256.24937 -208.625546) (xy 256.25098 -208.648816) (xy 256.256282 -208.659222) (xy 256.268712 -208.681234)
			(xy 256.288291 -208.72784) (xy 256.301538 -208.776624) (xy 256.30822 -208.826732) (xy 256.308606 -208.852008)
			(xy 256.308134 -208.879378) (xy 256.300309 -208.933556) (xy 256.284821 -208.986059) (xy 256.261989 -209.035809)
			(xy 256.23228 -209.081786) (xy 256.214626 -209.102706) (xy 256.20853 -209.109818) (xy 256.20218 -209.126836)
			(xy 256.20218 -209.21218) (xy 256.20853 -209.229198) (xy 256.214626 -209.23631) (xy 256.232266 -209.257242)
			(xy 256.261989 -209.303209) (xy 256.284829 -209.352956) (xy 256.300317 -209.405459) (xy 256.308134 -209.459638)
			(xy 256.308606 -209.487008) (xy 256.308195 -209.512283) (xy 256.301517 -209.562389) (xy 256.288278 -209.611174)
			(xy 256.268711 -209.657783) (xy 256.256282 -209.679794) (xy 256.252231 -209.687383) (xy 256.24898 -209.704265)
			(xy 256.249932 -209.712814) (xy 256.25425 -209.742532) (xy 256.255891 -209.751069) (xy 256.264062 -209.766401)
			(xy 256.270252 -209.772504) (xy 256.292224 -209.793182) (xy 256.331617 -209.838887) (xy 256.365326 -209.888932)
			(xy 256.392876 -209.942614) (xy 256.413882 -209.999178) (xy 256.428047 -210.05783) (xy 256.435172 -210.117747)
			(xy 256.435606 -210.147916) (xy 256.435026 -210.182871) (xy 256.425455 -210.252122) (xy 256.406494 -210.319411)
			(xy 256.378501 -210.383471) (xy 256.342003 -210.443097) (xy 256.32029 -210.470496) (xy 256.315049 -210.477512)
			(xy 256.309191 -210.494004) (xy 256.30886 -210.502754) (xy 256.30886 -210.656678) (xy 256.309179 -210.665432)
			(xy 256.315033 -210.681928) (xy 256.32029 -210.688936) (xy 256.342004 -210.716334) (xy 256.378507 -210.775957)
			(xy 256.4065 -210.840017) (xy 256.425455 -210.907308) (xy 256.435014 -210.976561) (xy 256.435606 -211.011516)
			(xy 256.435158 -211.041684) (xy 256.428022 -211.101596) (xy 256.413851 -211.160244) (xy 256.392845 -211.216805)
			(xy 256.365298 -211.270485) (xy 256.331596 -211.320531) (xy 256.292214 -211.36624) (xy 256.270252 -211.386928)
			(xy 256.26407 -211.393039) (xy 256.255893 -211.408364) (xy 256.25425 -211.4169) (xy 256.249932 -211.446618)
			(xy 256.249016 -211.455167) (xy 256.252253 -211.472043) (xy 256.256282 -211.479638) (xy 256.268711 -211.50165)
			(xy 256.288289 -211.548256) (xy 256.301534 -211.597041) (xy 256.308213 -211.647149) (xy 256.308606 -211.672424)
			(xy 256.308133 -211.699793) (xy 256.300306 -211.75397) (xy 256.284816 -211.806472) (xy 256.261982 -211.856221)
			(xy 256.232272 -211.902196) (xy 256.214626 -211.923122) (xy 256.20853 -211.930234) (xy 256.20218 -211.947252)
			(xy 256.20218 -212.032596) (xy 256.20853 -212.049614) (xy 256.214626 -212.056726) (xy 256.232265 -212.077658)
			(xy 256.261986 -212.123626) (xy 256.284825 -212.173373) (xy 256.30031 -212.225876) (xy 256.308124 -212.280054)
			(xy 256.308606 -212.307424) (xy 256.308194 -212.332698) (xy 256.301514 -212.382804) (xy 256.288273 -212.431588)
			(xy 256.268705 -212.478195) (xy 256.256282 -212.50021) (xy 256.250878 -212.51059) (xy 256.249217 -212.533905)
			(xy 256.258066 -212.555539) (xy 256.266442 -212.56371) (xy 256.288874 -212.584418) (xy 256.329136 -212.630312)
			(xy 256.363613 -212.680697) (xy 256.391808 -212.734847) (xy 256.413317 -212.791984) (xy 256.427829 -212.851286)
			(xy 256.435137 -212.911898) (xy 256.435606 -212.942424) (xy 256.435025 -212.977379) (xy 256.425453 -213.046629)
			(xy 256.406492 -213.113918) (xy 256.378498 -213.177977) (xy 256.342 -213.237602) (xy 256.32029 -213.265004)
			(xy 256.31505 -213.27202) (xy 256.309195 -213.288512) (xy 256.30886 -213.297262) (xy 256.30886 -213.451186)
			(xy 256.30918 -213.45994) (xy 256.315037 -213.476433) (xy 256.32029 -213.483444) (xy 256.342004 -213.510842)
			(xy 256.378506 -213.570465) (xy 256.406497 -213.634526) (xy 256.425451 -213.701817) (xy 256.43501 -213.771069)
			(xy 256.435606 -213.806024) (xy 256.435153 -213.83655) (xy 256.42784 -213.897161) (xy 256.413322 -213.956462)
			(xy 256.391809 -214.013597) (xy 256.363609 -214.067745) (xy 256.329129 -214.118128) (xy 256.288864 -214.164019)
			(xy 256.266442 -214.184738) (xy 256.25812 -214.192945) (xy 256.249318 -214.214571) (xy 256.250898 -214.237867)
			(xy 256.256282 -214.248238) (xy 256.268711 -214.27025) (xy 256.288289 -214.316856) (xy 256.301534 -214.365641)
			(xy 256.308213 -214.415749) (xy 256.308606 -214.441024) (xy 256.30812 -214.468275) (xy 256.300364 -214.522223)
			(xy 256.285009 -214.574518) (xy 256.262367 -214.624095) (xy 256.232901 -214.669945) (xy 256.19721 -214.711136)
			(xy 256.156019 -214.746827) (xy 256.110169 -214.776293) (xy 256.060592 -214.798935) (xy 256.008297 -214.81429)
			(xy 255.954349 -214.822046) (xy 255.899847 -214.822046) (xy 255.845899 -214.81429) (xy 255.793604 -214.798935)
			(xy 255.744027 -214.776293) (xy 255.698177 -214.746827) (xy 255.656986 -214.711136) (xy 255.621295 -214.669945)
			(xy 255.591829 -214.624095) (xy 255.569187 -214.574518) (xy 255.553832 -214.522223) (xy 255.546076 -214.468275)
			(xy 255.54559 -214.441024) (xy 255.545999 -214.415749) (xy 255.552673 -214.365641) (xy 255.565908 -214.316854)
			(xy 255.585472 -214.270242) (xy 255.597914 -214.248238) (xy 255.60333 -214.237856) (xy 255.60501 -214.214528)
			(xy 255.59617 -214.192875) (xy 255.587754 -214.184738) (xy 255.56532 -214.164031) (xy 255.525054 -214.118138)
			(xy 255.490573 -214.067754) (xy 255.462373 -214.013604) (xy 255.440859 -213.956466) (xy 255.426341 -213.897164)
			(xy 255.419028 -213.836551) (xy 255.41859 -213.806024) (xy 255.419167 -213.771068) (xy 255.428734 -213.701815)
			(xy 255.44769 -213.634522) (xy 255.475679 -213.570458) (xy 255.512174 -213.510828) (xy 255.533906 -213.483444)
			(xy 255.53913 -213.476422) (xy 255.544958 -213.459931) (xy 255.545336 -213.451186) (xy 255.545336 -213.297262)
			(xy 255.545024 -213.288505) (xy 255.539179 -213.272002) (xy 255.533906 -213.265004) (xy 255.51219 -213.237606)
			(xy 255.475682 -213.177984) (xy 255.447685 -213.113924) (xy 255.428725 -213.046633) (xy 255.41916 -212.97738)
			(xy 255.41859 -212.942424) (xy 255.41904 -212.911897) (xy 255.426348 -212.851282) (xy 255.440861 -212.791979)
			(xy 255.46237 -212.734839) (xy 255.490567 -212.680687) (xy 255.525045 -212.6303) (xy 255.565308 -212.584404)
			(xy 255.587754 -212.56371) (xy 255.596065 -212.555502) (xy 255.604847 -212.533882) (xy 255.603248 -212.510602)
			(xy 255.597914 -212.50021) (xy 255.585489 -212.478197) (xy 255.565917 -212.43159) (xy 255.552679 -212.382805)
			(xy 255.546006 -212.332699) (xy 255.54559 -212.307424) (xy 255.546067 -212.280056) (xy 255.5539 -212.225883)
			(xy 255.569396 -212.173385) (xy 255.592234 -212.123641) (xy 255.621947 -212.077671) (xy 255.63957 -212.056726)
			(xy 255.645666 -212.049614) (xy 255.652016 -212.032596) (xy 255.652016 -211.947252) (xy 255.645666 -211.930234)
			(xy 255.63957 -211.923122) (xy 255.621928 -211.90219) (xy 255.592202 -211.856224) (xy 255.569357 -211.806477)
			(xy 255.553865 -211.753974) (xy 255.546044 -211.699795) (xy 255.54559 -211.672424) (xy 255.545999 -211.647149)
			(xy 255.552673 -211.597041) (xy 255.565908 -211.548254) (xy 255.585472 -211.501642) (xy 255.597914 -211.479638)
			(xy 255.601954 -211.472047) (xy 255.605184 -211.455169) (xy 255.604264 -211.446618) (xy 255.599946 -211.4169)
			(xy 255.598295 -211.408368) (xy 255.59011 -211.393052) (xy 255.583944 -211.386928) (xy 255.561971 -211.36625)
			(xy 255.522575 -211.320546) (xy 255.488863 -211.270502) (xy 255.46131 -211.21682) (xy 255.440301 -211.160256)
			(xy 255.426133 -211.101603) (xy 255.419003 -211.041686) (xy 255.41859 -211.011516) (xy 255.419168 -210.976561)
			(xy 255.428735 -210.907307) (xy 255.447692 -210.840016) (xy 255.475682 -210.775952) (xy 255.512177 -210.716323)
			(xy 255.533906 -210.688936) (xy 255.539129 -210.681914) (xy 255.544954 -210.665423) (xy 255.545336 -210.656678)
			(xy 255.545336 -210.502754) (xy 255.545023 -210.493998) (xy 255.539176 -210.477496) (xy 255.533906 -210.470496)
			(xy 255.51219 -210.443098) (xy 255.475684 -210.383476) (xy 255.447687 -210.319416) (xy 255.428728 -210.252125)
			(xy 255.419165 -210.182871) (xy 255.41859 -210.147916) (xy 255.419036 -210.117747) (xy 255.426169 -210.057833)
			(xy 255.440336 -209.999183) (xy 255.46134 -209.94262) (xy 255.488885 -209.888937) (xy 255.522585 -209.838888)
			(xy 255.561966 -209.793175) (xy 255.583944 -209.772504) (xy 255.59013 -209.766395) (xy 255.598317 -209.751072)
			(xy 255.599946 -209.742532) (xy 255.604264 -209.712814) (xy 255.605169 -209.704268) (xy 255.601912 -209.687403)
			(xy 255.597914 -209.679794) (xy 255.585489 -209.657781) (xy 255.56592 -209.611174) (xy 255.552684 -209.562389)
			(xy 255.546013 -209.512282) (xy 255.54559 -209.487008) (xy 255.546061 -209.459638) (xy 255.553884 -209.405459)
			(xy 255.56937 -209.352954) (xy 255.592201 -209.303202) (xy 255.621908 -209.257224) (xy 255.63957 -209.23631)
			(xy 255.645666 -209.229198) (xy 255.652016 -209.21218) (xy 255.652016 -209.126836) (xy 255.645666 -209.109818)
			(xy 255.63957 -209.102706) (xy 255.621929 -209.081774) (xy 255.592204 -209.035807) (xy 255.569362 -208.98606)
			(xy 255.553873 -208.933557) (xy 255.546054 -208.879378) (xy 255.54559 -208.852008) (xy 255.546 -208.826733)
			(xy 255.552676 -208.776626) (xy 255.565913 -208.72784) (xy 255.585478 -208.68123) (xy 255.597914 -208.659222)
			(xy 255.603326 -208.648841) (xy 255.605 -208.625517) (xy 255.596157 -208.60387) (xy 255.587754 -208.595722)
			(xy 255.565321 -208.575014) (xy 255.525056 -208.529121) (xy 255.490577 -208.478737) (xy 255.462378 -208.424586)
			(xy 255.440866 -208.367449) (xy 255.42635 -208.308148) (xy 255.419039 -208.247534) (xy 255.41859 -208.217008)
			(xy 255.419168 -208.182053) (xy 255.428737 -208.1128) (xy 255.447695 -208.045509) (xy 255.475685 -207.981446)
			(xy 255.512181 -207.921818) (xy 255.533906 -207.894428) (xy 255.539128 -207.887406) (xy 255.54495 -207.870915)
			(xy 255.545336 -207.86217) (xy 255.545336 -207.708246) (xy 255.545021 -207.69949) (xy 255.539172 -207.68299)
			(xy 255.533906 -207.675988) (xy 255.512191 -207.64859) (xy 255.475685 -207.588968) (xy 255.44769 -207.524908)
			(xy 255.428732 -207.457617) (xy 255.419169 -207.388363) (xy 255.41859 -207.353408) (xy 255.419041 -207.322882)
			(xy 255.426351 -207.262268) (xy 255.440865 -207.202965) (xy 255.462376 -207.145827) (xy 255.490573 -207.091676)
			(xy 255.525052 -207.04129) (xy 255.565315 -206.995396) (xy 255.587754 -206.974694) (xy 255.596062 -206.966486)
			(xy 255.604837 -206.944868) (xy 255.603233 -206.921593) (xy 255.597914 -206.911194) (xy 255.585489 -206.889181)
			(xy 255.56592 -206.842574) (xy 255.552684 -206.793789) (xy 255.546013 -206.743682) (xy 255.54559 -206.718408)
			(xy 255.546061 -206.691038) (xy 255.553884 -206.636859) (xy 255.56937 -206.584354) (xy 255.592201 -206.534602)
			(xy 255.621908 -206.488624) (xy 255.63957 -206.46771) (xy 255.645666 -206.460598) (xy 255.652016 -206.44358)
			(xy 255.652016 -206.358236) (xy 255.645666 -206.341218) (xy 255.63957 -206.334106) (xy 255.621929 -206.313174)
			(xy 255.592204 -206.267207) (xy 255.569362 -206.21746) (xy 255.553873 -206.164957) (xy 255.546054 -206.110778)
			(xy 255.54559 -206.083408) (xy 255.546208 -206.051555) (xy 255.556758 -205.988729) (xy 255.577615 -205.928534)
			(xy 255.592326 -205.900274) (xy 255.596065 -205.892857) (xy 255.599049 -205.876529) (xy 255.598168 -205.86827)
			(xy 255.593596 -205.83906) (xy 255.592039 -205.830783) (xy 255.584257 -205.815858) (xy 255.578356 -205.80985)
			(xy 255.553609 -205.785731) (xy 255.5102 -205.731961) (xy 255.474474 -205.672809) (xy 255.447087 -205.609363)
			(xy 255.428546 -205.542792) (xy 255.419191 -205.474324) (xy 255.41859 -205.439772) (xy 255.419171 -205.404818)
			(xy 255.428744 -205.335567) (xy 255.447705 -205.268279) (xy 255.475699 -205.204219) (xy 255.512198 -205.144595)
			(xy 255.533906 -205.117192) (xy 255.539137 -205.110172) (xy 255.54498 -205.093681) (xy 255.545336 -205.084934)
			(xy 255.545336 -204.93101) (xy 255.545015 -204.922257) (xy 255.539157 -204.905764) (xy 255.533906 -204.898752)
			(xy 255.512193 -204.871353) (xy 255.475691 -204.81173) (xy 255.4477 -204.74767) (xy 255.428747 -204.680379)
			(xy 255.41919 -204.611127) (xy 255.41859 -204.576172) (xy 255.419172 -204.54162) (xy 255.428534 -204.473152)
			(xy 255.447082 -204.406584) (xy 255.474474 -204.34314) (xy 255.510206 -204.283991) (xy 255.553619 -204.230225)
			(xy 255.578356 -204.206094) (xy 255.584209 -204.200049) (xy 255.591992 -204.185144) (xy 255.593596 -204.176884)
			(xy 255.598168 -204.147674) (xy 255.599049 -204.139414) (xy 255.596073 -204.123083) (xy 255.592326 -204.11567)
			(xy 255.577624 -204.087408) (xy 255.556799 -204.027208) (xy 255.546245 -203.964387) (xy 255.54559 -203.932536)
			(xy 255.546066 -203.905168) (xy 255.553898 -203.850994) (xy 255.569392 -203.798495) (xy 255.592229 -203.74875)
			(xy 255.621942 -203.702779) (xy 255.63957 -203.681838) (xy 255.645666 -203.674726) (xy 255.652016 -203.657708)
			(xy 255.652016 -203.572364) (xy 255.645666 -203.555346) (xy 255.63957 -203.548234) (xy 255.621927 -203.527303)
			(xy 255.592199 -203.481336) (xy 255.569354 -203.43159) (xy 255.55386 -203.379087) (xy 255.546037 -203.324907)
			(xy 255.54559 -203.297536) (xy 255.545998 -203.27226) (xy 255.552671 -203.222152) (xy 255.565905 -203.173364)
			(xy 255.585467 -203.126752) (xy 255.597914 -203.10475) (xy 255.603309 -203.094372) (xy 255.604955 -203.071068)
			(xy 255.596097 -203.04945) (xy 255.587754 -203.04125) (xy 255.565319 -203.020543) (xy 255.525053 -202.97465)
			(xy 255.49057 -202.924266) (xy 255.462368 -202.870116) (xy 255.440853 -202.812979) (xy 255.426334 -202.753677)
			(xy 255.419019 -202.693063) (xy 255.41859 -202.662536) (xy 255.419173 -202.627582) (xy 255.428751 -202.558334)
			(xy 255.447716 -202.491049) (xy 255.475713 -202.426992) (xy 255.512214 -202.367371) (xy 255.533906 -202.339956)
			(xy 255.539132 -202.332935) (xy 255.544964 -202.316444) (xy 255.545336 -202.307698) (xy 255.545336 -202.153774)
			(xy 255.545026 -202.145017) (xy 255.539184 -202.12851) (xy 255.533906 -202.121516) (xy 255.512189 -202.094118)
			(xy 255.47568 -202.034497) (xy 255.447681 -201.970437) (xy 255.42872 -201.903146) (xy 255.419153 -201.833892)
			(xy 255.41859 -201.798936) (xy 255.41904 -201.768409) (xy 255.426346 -201.707793) (xy 255.440858 -201.648489)
			(xy 255.462366 -201.591349) (xy 255.490562 -201.537195) (xy 255.525039 -201.486807) (xy 255.565302 -201.44091)
			(xy 255.587754 -201.420222) (xy 255.596068 -201.412014) (xy 255.604855 -201.390393) (xy 255.60326 -201.367109)
			(xy 255.597914 -201.356722) (xy 255.585488 -201.334709) (xy 255.565915 -201.288103) (xy 255.552675 -201.239318)
			(xy 255.546001 -201.189211) (xy 255.54559 -201.163936) (xy 255.546066 -201.136568) (xy 255.553898 -201.082394)
			(xy 255.569392 -201.029895) (xy 255.592229 -200.98015) (xy 255.621942 -200.934179) (xy 255.63957 -200.913238)
			(xy 255.645666 -200.906126) (xy 255.652016 -200.889108) (xy 255.652016 -200.803764) (xy 255.645666 -200.786746)
			(xy 255.63957 -200.779634) (xy 255.621927 -200.758703) (xy 255.592199 -200.712736) (xy 255.569354 -200.66299)
			(xy 255.55386 -200.610487) (xy 255.546037 -200.556307) (xy 255.54559 -200.528936) (xy 255.545998 -200.50366)
			(xy 255.552671 -200.453552) (xy 255.565905 -200.404764) (xy 255.585467 -200.358152) (xy 255.597914 -200.33615)
			(xy 255.601956 -200.328559) (xy 255.60519 -200.311681) (xy 255.604264 -200.30313) (xy 255.599946 -200.273412)
			(xy 255.598297 -200.264879) (xy 255.590114 -200.249561) (xy 255.583944 -200.24344) (xy 255.56197 -200.222762)
			(xy 255.522573 -200.177058) (xy 255.488861 -200.127014) (xy 255.461306 -200.073333) (xy 255.440296 -200.016769)
			(xy 255.426126 -199.958116) (xy 255.418995 -199.898198) (xy 255.41859 -199.868028) (xy 255.419174 -199.833075)
			(xy 255.428752 -199.763827) (xy 255.447719 -199.696542) (xy 255.475716 -199.632486) (xy 255.512218 -199.572866)
			(xy 255.533906 -199.545448) (xy 255.539131 -199.538426) (xy 255.544959 -199.521935) (xy 255.545336 -199.51319)
			(xy 255.545336 -199.359266) (xy 255.545025 -199.350509) (xy 255.539181 -199.334005) (xy 255.533906 -199.327008)
			(xy 255.51219 -199.29961) (xy 255.475682 -199.239989) (xy 255.447684 -199.175929) (xy 255.428723 -199.108637)
			(xy 255.419158 -199.039384) (xy 255.41859 -199.004428) (xy 255.419041 -198.974262) (xy 255.426183 -198.914353)
			(xy 255.440359 -198.855709) (xy 255.46137 -198.799152) (xy 255.48892 -198.745477) (xy 255.522624 -198.695436)
			(xy 255.562009 -198.649731) (xy 255.583944 -198.629016) (xy 255.590132 -198.622908) (xy 255.598322 -198.607585)
			(xy 255.599946 -198.599044) (xy 255.604264 -198.569326) (xy 255.605171 -198.560779) (xy 255.601917 -198.543913)
			(xy 255.597914 -198.536306) (xy 255.585489 -198.514293) (xy 255.565918 -198.467686) (xy 255.55268 -198.418901)
			(xy 255.546008 -198.368795) (xy 255.54559 -198.34352) (xy 255.546067 -198.316152) (xy 255.553901 -198.261979)
			(xy 255.569397 -198.209482) (xy 255.592236 -198.159738) (xy 255.621949 -198.113769) (xy 255.63957 -198.092822)
			(xy 255.645666 -198.08571) (xy 255.652016 -198.068692) (xy 255.652016 -197.983348) (xy 255.645666 -197.96633)
			(xy 255.63957 -197.959218) (xy 255.621928 -197.938286) (xy 255.592202 -197.89232) (xy 255.569359 -197.842573)
			(xy 255.553867 -197.79007) (xy 255.546047 -197.735891) (xy 255.54559 -197.70852) (xy 255.545999 -197.683245)
			(xy 255.552674 -197.633137) (xy 255.56591 -197.58435) (xy 255.585474 -197.537739) (xy 255.597914 -197.515734)
			(xy 255.603329 -197.505353) (xy 255.605008 -197.482026) (xy 255.596166 -197.460374) (xy 255.587754 -197.452234)
			(xy 255.56532 -197.431527) (xy 255.525055 -197.385634) (xy 255.490574 -197.335249) (xy 255.462374 -197.281099)
			(xy 255.44086 -197.223962) (xy 255.426343 -197.16466) (xy 255.41903 -197.104047) (xy 255.41859 -197.07352)
			(xy 255.419168 -197.038564) (xy 255.428735 -196.969311) (xy 255.447691 -196.902019) (xy 255.47568 -196.837955)
			(xy 255.512175 -196.778326) (xy 255.533906 -196.75094) (xy 255.53913 -196.743918) (xy 255.544956 -196.727427)
			(xy 255.545336 -196.718682) (xy 255.545336 -196.564758) (xy 255.545023 -196.556002) (xy 255.539177 -196.539499)
			(xy 255.533906 -196.5325) (xy 255.51219 -196.505102) (xy 255.475683 -196.44548) (xy 255.447686 -196.38142)
			(xy 255.428727 -196.314129) (xy 255.419162 -196.244876) (xy 255.41859 -196.20992) (xy 255.419041 -196.179393)
			(xy 255.426349 -196.118779) (xy 255.440862 -196.059475) (xy 255.462372 -196.002336) (xy 255.490568 -195.948184)
			(xy 255.525046 -195.897798) (xy 255.56531 -195.851902) (xy 255.587754 -195.831206) (xy 255.596064 -195.822998)
			(xy 255.604844 -195.801379) (xy 255.603244 -195.7781) (xy 255.597914 -195.767706) (xy 255.585489 -195.745693)
			(xy 255.565918 -195.699086) (xy 255.55268 -195.650301) (xy 255.546008 -195.600195) (xy 255.54559 -195.57492)
			(xy 255.546067 -195.547552) (xy 255.553901 -195.493379) (xy 255.569397 -195.440882) (xy 255.592236 -195.391138)
			(xy 255.621949 -195.345169) (xy 255.63957 -195.324222) (xy 255.645666 -195.31711) (xy 255.652016 -195.300092)
			(xy 255.652016 -195.214748) (xy 255.645666 -195.19773) (xy 255.63957 -195.190618) (xy 255.621928 -195.169686)
			(xy 255.592202 -195.12372) (xy 255.569359 -195.073973) (xy 255.553867 -195.02147) (xy 255.546047 -194.967291)
			(xy 255.54559 -194.93992) (xy 255.546207 -194.908066) (xy 255.556755 -194.84524) (xy 255.577611 -194.785044)
			(xy 255.592326 -194.756786) (xy 255.596067 -194.74937) (xy 255.599055 -194.73304) (xy 255.598168 -194.724782)
			(xy 255.593596 -194.695572) (xy 255.592041 -194.687295) (xy 255.584261 -194.672367) (xy 255.578356 -194.666362)
			(xy 255.553608 -194.642243) (xy 255.510198 -194.588474) (xy 255.47447 -194.529322) (xy 255.447082 -194.465876)
			(xy 255.428539 -194.399305) (xy 255.419183 -194.330836) (xy 255.41859 -194.296284) (xy 255.41917 -194.261329)
			(xy 255.428741 -194.192078) (xy 255.447702 -194.124789) (xy 255.475694 -194.060728) (xy 255.512192 -194.001102)
			(xy 255.533906 -193.973704) (xy 255.539139 -193.966685) (xy 255.544986 -193.950194) (xy 255.545336 -193.941446)
			(xy 255.545336 -193.787522) (xy 255.545017 -193.778768) (xy 255.539162 -193.762273) (xy 255.533906 -193.755264)
			(xy 255.512192 -193.727866) (xy 255.475689 -193.668243) (xy 255.447697 -193.604182) (xy 255.428742 -193.536892)
			(xy 255.419183 -193.467639) (xy 255.41859 -193.432684) (xy 255.418986 -193.404242) (xy 255.425336 -193.347714)
			(xy 255.437955 -193.292248) (xy 255.456685 -193.238536) (xy 255.468628 -193.21272) (xy 255.474724 -193.199766)
			(xy 255.47193 -193.171826) (xy 255.408684 -193.08826) (xy 255.402719 -193.081106) (xy 255.386909 -193.071285)
			(xy 255.36864 -193.067728) (xy 255.359408 -193.068956) (xy 252.109732 -193.641726) (xy 252.104304 -193.642853)
			(xy 252.094061 -193.647088) (xy 252.089412 -193.650108) (xy 248.72188 -196.008244) (xy 248.715276 -196.013832)
			(xy 245.068344 -199.660764) (xy 245.061503 -199.668164) (xy 245.053785 -199.686763) (xy 245.053358 -199.696832)
			(xy 245.053358 -203.760832) (xy 245.053789 -203.770898) (xy 245.061518 -203.789489) (xy 245.068344 -203.7969)
			(xy 252.077728 -210.806284) (xy 252.084569 -210.813684) (xy 252.092284 -210.832283) (xy 252.092714 -210.842352)
			(xy 252.092714 -216.493852) (xy 252.093147 -216.503918) (xy 252.100876 -216.522507) (xy 252.1077 -216.52992)
			(xy 253.872238 -218.294458) (xy 253.879637 -218.301303) (xy 253.898235 -218.30903) (xy 253.908306 -218.309444)
		)
		(stroke
			(width 0)
			(type solid)
		)
		(fill yes)
		(layer "In4.Cu")
		(net "PVDD11_S3_P0")
	)
	(gr_poly
		(pts
			(xy 353.551998 -404.39086) (xy 353.562067 -404.390436) (xy 353.580669 -404.382718) (xy 353.588066 -404.375874)
			(xy 354.215954 -403.747986) (xy 354.222803 -403.740589) (xy 354.23054 -403.72199) (xy 354.23094 -403.711918)
			(xy 354.23094 -402.61413) (xy 354.215446 -402.589492) (xy 354.201984 -402.583142) (xy 354.178152 -402.571224)
			(xy 354.134319 -402.540935) (xy 354.09591 -402.504009) (xy 354.063919 -402.461401) (xy 354.039175 -402.414215)
			(xy 354.022318 -402.363671) (xy 354.013784 -402.311078) (xy 354.013262 -402.284438) (xy 354.01381 -402.256949)
			(xy 354.022906 -402.202728) (xy 354.040837 -402.150756) (xy 354.06711 -402.102462) (xy 354.08362 -402.080476)
			(xy 354.089462 -402.07311) (xy 354.094796 -402.05533) (xy 354.089462 -401.969224) (xy 354.081842 -401.95246)
			(xy 354.075238 -401.945856) (xy 354.054216 -401.924224) (xy 354.018581 -401.875558) (xy 353.991047 -401.821892)
			(xy 353.972298 -401.764562) (xy 353.962803 -401.704997) (xy 353.962208 -401.674838) (xy 353.962208 -400.811238)
			(xy 353.962651 -400.784879) (xy 353.969906 -400.732664) (xy 353.984283 -400.681946) (xy 354.005509 -400.633691)
			(xy 354.033178 -400.588819) (xy 354.066764 -400.548185) (xy 354.085906 -400.53006) (xy 354.093018 -400.52371)
			(xy 354.101146 -400.506946) (xy 354.109528 -400.420332) (xy 354.104448 -400.402552) (xy 354.09886 -400.394678)
			(xy 354.084702 -400.374833) (xy 354.062215 -400.331585) (xy 354.046897 -400.28531) (xy 354.039138 -400.237186)
			(xy 354.038662 -400.212814) (xy 354.03912 -400.188975) (xy 354.046533 -400.141878) (xy 354.061181 -400.096507)
			(xy 354.082707 -400.053966) (xy 354.110588 -400.015291) (xy 354.144145 -399.981423) (xy 354.182561 -399.953186)
			(xy 354.203508 -399.941796) (xy 354.216208 -399.935192) (xy 354.23094 -399.911062) (xy 354.23094 -398.890236)
			(xy 354.230586 -398.881254) (xy 354.224367 -398.864401) (xy 354.212688 -398.850752) (xy 354.205032 -398.84604)
			(xy 354.115878 -398.795748) (xy 354.0887 -398.796002) (xy 354.076762 -398.803368) (xy 354.052743 -398.817163)
			(xy 354.000947 -398.836773) (xy 353.946466 -398.846739) (xy 353.918774 -398.84731) (xy 353.89352 -398.846786)
			(xy 353.843701 -398.838469) (xy 353.795931 -398.822066) (xy 353.751511 -398.798024) (xy 353.711655 -398.766999)
			(xy 353.677448 -398.729838) (xy 353.649824 -398.687553) (xy 353.629536 -398.641299) (xy 353.617138 -398.592336)
			(xy 353.612967 -398.542) (xy 353.617138 -398.491664) (xy 353.629536 -398.442701) (xy 353.649824 -398.396447)
			(xy 353.677448 -398.354162) (xy 353.711655 -398.317001) (xy 353.751511 -398.285976) (xy 353.795931 -398.261934)
			(xy 353.843701 -398.245531) (xy 353.89352 -398.237214) (xy 353.918774 -398.236694) (xy 353.946467 -398.237269)
			(xy 354.000953 -398.247212) (xy 354.052748 -398.26683) (xy 354.076762 -398.280636) (xy 354.0887 -398.288002)
			(xy 354.115878 -398.288256) (xy 354.205032 -398.237964) (xy 354.212667 -398.23324) (xy 354.224291 -398.21957)
			(xy 354.230511 -398.202739) (xy 354.23094 -398.193768) (xy 354.23094 -397.628364) (xy 354.230741 -397.621698)
			(xy 354.22726 -397.608828) (xy 354.224082 -397.602964) (xy 354.051362 -397.304006) (xy 354.039463 -397.281338)
			(xy 354.022588 -397.233007) (xy 354.014026 -397.182536) (xy 354.013516 -397.15694) (xy 354.013516 -397.156432)
			(xy 354.0136 -397.145087) (xy 354.015256 -397.122457) (xy 354.016818 -397.11122) (xy 354.018088 -397.10233)
			(xy 354.014532 -397.085058) (xy 353.971098 -397.013938) (xy 353.957128 -397.003016) (xy 353.948746 -396.999968)
			(xy 353.926345 -396.991947) (xy 353.884153 -396.969958) (xy 353.845881 -396.941693) (xy 353.812455 -396.907834)
			(xy 353.784683 -396.869203) (xy 353.763238 -396.826732) (xy 353.748637 -396.78145) (xy 353.741235 -396.734451)
			(xy 353.74072 -396.710662) (xy 353.74122 -396.685264) (xy 353.74962 -396.635168) (xy 353.766199 -396.587154)
			(xy 353.790498 -396.542548) (xy 353.821847 -396.50258) (xy 353.840288 -396.48511) (xy 353.84867 -396.47749)
			(xy 353.857306 -396.457424) (xy 353.854512 -396.35811) (xy 353.845114 -396.338552) (xy 353.836224 -396.33144)
			(xy 353.817662 -396.315638) (xy 353.784933 -396.279513) (xy 353.757858 -396.238976) (xy 353.737023 -396.194906)
			(xy 353.72288 -396.148256) (xy 353.715734 -396.100035) (xy 353.71532 -396.075662) (xy 353.715759 -396.051546)
			(xy 353.722765 -396.003826) (xy 353.736623 -395.957628) (xy 353.75704 -395.913931) (xy 353.76993 -395.893544)
			(xy 353.775772 -395.884654) (xy 353.779328 -395.864588) (xy 353.758246 -395.772386) (xy 353.746054 -395.755622)
			(xy 353.737164 -395.750288) (xy 353.716361 -395.737433) (xy 353.678443 -395.706555) (xy 353.645491 -395.670425)
			(xy 353.618226 -395.629831) (xy 353.597244 -395.585662) (xy 353.583002 -395.538881) (xy 353.575813 -395.490512)
			(xy 353.575366 -395.466062) (xy 353.575927 -395.438779) (xy 353.584887 -395.384954) (xy 353.602558 -395.333329)
			(xy 353.628461 -395.285303) (xy 353.661893 -395.242179) (xy 353.681538 -395.223238) (xy 353.688982 -395.215744)
			(xy 353.697518 -395.196449) (xy 353.698048 -395.1859) (xy 353.698048 -395.111224) (xy 353.69746 -395.10069)
			(xy 353.688926 -395.081419) (xy 353.681538 -395.073886) (xy 353.661883 -395.054953) (xy 353.628441 -395.011832)
			(xy 353.602533 -394.963805) (xy 353.584862 -394.912176) (xy 353.575908 -394.858347) (xy 353.575366 -394.831062)
			(xy 353.57562 -394.81887) (xy 353.575874 -394.809218) (xy 353.569778 -394.791184) (xy 353.511104 -394.723874)
			(xy 353.49434 -394.715238) (xy 353.484434 -394.714222) (xy 353.457483 -394.710859) (xy 353.405113 -394.696479)
			(xy 353.355792 -394.673742) (xy 353.310844 -394.64326) (xy 353.271476 -394.605849) (xy 353.238742 -394.562514)
			(xy 353.213521 -394.514417) (xy 353.19649 -394.462847) (xy 353.191826 -394.436092) (xy 353.190556 -394.426694)
			(xy 352.918014 -393.95527) (xy 352.910648 -393.949428) (xy 352.900996 -393.9413) (xy 352.893893 -393.935562)
			(xy 352.876842 -393.929061) (xy 352.867722 -393.9286) (xy 352.495612 -393.9286) (xy 352.486724 -393.92894)
			(xy 352.470025 -393.935032) (xy 352.456428 -393.946483) (xy 352.45167 -393.954) (xy 352.444812 -393.965938)
			(xy 352.444812 -393.992862) (xy 352.519742 -394.122402) (xy 352.527108 -394.128244) (xy 352.545886 -394.144048)
			(xy 352.579018 -394.180256) (xy 352.606438 -394.220961) (xy 352.627543 -394.26527) (xy 352.641872 -394.31221)
			(xy 352.649109 -394.360752) (xy 352.649536 -394.385292) (xy 352.649282 -394.397484) (xy 352.649028 -394.407136)
			(xy 352.655124 -394.42517) (xy 352.713798 -394.49248) (xy 352.730562 -394.501116) (xy 352.740468 -394.502132)
			(xy 352.767238 -394.505456) (xy 352.81927 -394.519676) (xy 352.868305 -394.542151) (xy 352.913044 -394.572285)
			(xy 352.9523 -394.609279) (xy 352.985032 -394.652153) (xy 353.010374 -394.699769) (xy 353.027653 -394.750867)
			(xy 353.036412 -394.804092) (xy 353.036886 -394.831062) (xy 353.036323 -394.858344) (xy 353.027358 -394.912166)
			(xy 353.009683 -394.963787) (xy 352.983775 -395.011807) (xy 352.950339 -395.054925) (xy 352.930714 -395.073886)
			(xy 352.923268 -395.081379) (xy 352.914731 -395.100674) (xy 352.914204 -395.111224) (xy 352.914204 -395.1859)
			(xy 352.914795 -395.196433) (xy 352.923329 -395.215702) (xy 352.930714 -395.223238) (xy 352.95037 -395.24217)
			(xy 352.983814 -395.28529) (xy 353.009722 -395.333317) (xy 353.027392 -395.384947) (xy 353.036344 -395.438777)
			(xy 353.036886 -395.466062) (xy 353.036453 -395.490179) (xy 353.029457 -395.537904) (xy 353.015608 -395.584108)
			(xy 352.995199 -395.627813) (xy 352.982276 -395.64818) (xy 352.976434 -395.65707) (xy 352.972878 -395.677136)
			(xy 352.99396 -395.769338) (xy 353.006152 -395.786102) (xy 353.015042 -395.791436) (xy 353.035843 -395.804292)
			(xy 353.073759 -395.83517) (xy 353.106707 -395.871301) (xy 353.133969 -395.911895) (xy 353.154948 -395.956065)
			(xy 353.169186 -396.002845) (xy 353.176371 -396.051212) (xy 353.17684 -396.075662) (xy 353.176402 -396.100033)
			(xy 353.169246 -396.148246) (xy 353.155098 -396.194888) (xy 353.134263 -396.238952) (xy 353.107192 -396.279485)
			(xy 353.074471 -396.315609) (xy 353.055936 -396.33144) (xy 353.047046 -396.338552) (xy 353.037648 -396.35811)
			(xy 353.034854 -396.457424) (xy 353.04349 -396.47749) (xy 353.051872 -396.48511) (xy 353.070295 -396.502597)
			(xy 353.10164 -396.542564) (xy 353.125939 -396.587167) (xy 353.142523 -396.635175) (xy 353.150934 -396.685266)
			(xy 353.15144 -396.710662) (xy 353.151349 -396.721944) (xy 353.149695 -396.744446) (xy 353.148138 -396.75562)
			(xy 353.146868 -396.764764) (xy 353.15017 -396.782036) (xy 353.193858 -396.853156) (xy 353.207574 -396.864078)
			(xy 353.21621 -396.866872) (xy 353.244339 -396.877147) (xy 353.296266 -396.906957) (xy 353.319334 -396.926054)
			(xy 353.340779 -396.945671) (xy 353.376578 -396.991448) (xy 353.390454 -397.016986) (xy 353.391216 -397.018256)
			(xy 353.783392 -397.696944) (xy 353.7962 -397.720276) (xy 353.814351 -397.770308) (xy 353.823535 -397.822732)
			(xy 353.824032 -397.849344) (xy 353.823558 -397.873334) (xy 353.816047 -397.920721) (xy 353.801216 -397.966351)
			(xy 353.77943 -398.009099) (xy 353.751226 -398.047914) (xy 353.717299 -398.081839) (xy 353.678482 -398.110041)
			(xy 353.635733 -398.131823) (xy 353.590102 -398.146651) (xy 353.542714 -398.15416) (xy 353.518724 -398.154652)
			(xy 353.495195 -398.154211) (xy 353.448697 -398.146978) (xy 353.403859 -398.132695) (xy 353.361745 -398.111699)
			(xy 353.323352 -398.08449) (xy 353.289589 -398.05171) (xy 353.261256 -398.014138) (xy 353.249738 -397.993616)
			(xy 353.249484 -397.993108) (xy 353.248976 -397.992346) (xy 352.848418 -397.298926) (xy 352.837304 -397.276836)
			(xy 352.821579 -397.229956) (xy 352.813609 -397.181155) (xy 352.813112 -397.156432) (xy 352.813263 -397.145083)
			(xy 352.815044 -397.122453) (xy 352.816668 -397.11122) (xy 352.817938 -397.10233) (xy 352.814382 -397.085058)
			(xy 352.770948 -397.013938) (xy 352.757232 -397.002762) (xy 352.748596 -396.999968) (xy 352.726206 -396.991941)
			(xy 352.684037 -396.969943) (xy 352.64579 -396.94167) (xy 352.612391 -396.907808) (xy 352.584648 -396.869175)
			(xy 352.563233 -396.826707) (xy 352.548663 -396.781431) (xy 352.541292 -396.734443) (xy 352.540824 -396.710662)
			(xy 352.541324 -396.685264) (xy 352.549724 -396.635168) (xy 352.566303 -396.587154) (xy 352.590602 -396.542548)
			(xy 352.621952 -396.502581) (xy 352.640392 -396.48511) (xy 352.648774 -396.47749) (xy 352.65741 -396.457424)
			(xy 352.654616 -396.35811) (xy 352.645218 -396.338552) (xy 352.636328 -396.33144) (xy 352.617765 -396.315638)
			(xy 352.585036 -396.279513) (xy 352.557961 -396.238976) (xy 352.537126 -396.194906) (xy 352.522983 -396.148256)
			(xy 352.515836 -396.100036) (xy 352.515424 -396.075662) (xy 352.515863 -396.051546) (xy 352.522869 -396.003826)
			(xy 352.536727 -395.957628) (xy 352.557144 -395.913931) (xy 352.570034 -395.893544) (xy 352.575876 -395.884654)
			(xy 352.579432 -395.864588) (xy 352.55835 -395.772386) (xy 352.546158 -395.755622) (xy 352.537268 -395.750288)
			(xy 352.516465 -395.737433) (xy 352.478546 -395.706556) (xy 352.445594 -395.670425) (xy 352.418329 -395.629832)
			(xy 352.397346 -395.585662) (xy 352.383104 -395.538881) (xy 352.375915 -395.490512) (xy 352.37547 -395.466062)
			(xy 352.376031 -395.438779) (xy 352.384991 -395.384954) (xy 352.402662 -395.333329) (xy 352.428565 -395.285303)
			(xy 352.461998 -395.242179) (xy 352.481642 -395.223238) (xy 352.489098 -395.215749) (xy 352.497651 -395.196453)
			(xy 352.498152 -395.1859) (xy 352.498152 -395.111224) (xy 352.497565 -395.10069) (xy 352.489031 -395.081419)
			(xy 352.481642 -395.073886) (xy 352.461987 -395.054953) (xy 352.428544 -395.011832) (xy 352.402636 -394.963806)
			(xy 352.384965 -394.912177) (xy 352.376011 -394.858347) (xy 352.37547 -394.831062) (xy 352.375724 -394.81887)
			(xy 352.375978 -394.809218) (xy 352.369882 -394.791184) (xy 352.311208 -394.723874) (xy 352.294444 -394.715238)
			(xy 352.284538 -394.714222) (xy 352.257626 -394.71087) (xy 352.205329 -394.696522) (xy 352.156074 -394.673832)
			(xy 352.111183 -394.643408) (xy 352.07186 -394.606065) (xy 352.039158 -394.562806) (xy 352.013954 -394.514789)
			(xy 351.996924 -394.463303) (xy 351.992184 -394.4366) (xy 351.99066 -394.427202) (xy 351.717864 -393.95527)
			(xy 351.710498 -393.949428) (xy 351.700846 -393.9413) (xy 351.693745 -393.935554) (xy 351.676695 -393.929037)
			(xy 351.667572 -393.9286) (xy 351.295716 -393.9286) (xy 351.286828 -393.928939) (xy 351.270127 -393.935031)
			(xy 351.256529 -393.946481) (xy 351.251774 -393.954) (xy 351.244916 -393.965938) (xy 351.244916 -393.992862)
			(xy 351.3201 -394.12291) (xy 351.327212 -394.128752) (xy 351.345943 -394.144532) (xy 351.37899 -394.180678)
			(xy 351.406342 -394.221304) (xy 351.427398 -394.265523) (xy 351.441697 -394.312365) (xy 351.448926 -394.360804)
			(xy 351.449386 -394.385292) (xy 351.449132 -394.397484) (xy 351.448878 -394.407136) (xy 351.454974 -394.42517)
			(xy 351.513648 -394.49248) (xy 351.530412 -394.501116) (xy 351.540318 -394.502132) (xy 351.567085 -394.50546)
			(xy 351.619111 -394.519686) (xy 351.668139 -394.542164) (xy 351.712871 -394.5723) (xy 351.75212 -394.609294)
			(xy 351.784847 -394.652166) (xy 351.810184 -394.69978) (xy 351.827461 -394.750874) (xy 351.836218 -394.804094)
			(xy 351.836736 -394.831062) (xy 351.836173 -394.858344) (xy 351.82721 -394.912167) (xy 351.809536 -394.96379)
			(xy 351.783631 -395.011813) (xy 351.750198 -395.054934) (xy 351.730564 -395.073886) (xy 351.723124 -395.081381)
			(xy 351.714596 -395.100676) (xy 351.714054 -395.111224) (xy 351.714054 -395.1859) (xy 351.714646 -395.196432)
			(xy 351.723187 -395.215696) (xy 351.730564 -395.223238) (xy 351.750217 -395.242172) (xy 351.783656 -395.285293)
			(xy 351.809561 -395.33332) (xy 351.827228 -395.384949) (xy 351.836178 -395.438778) (xy 351.836736 -395.466062)
			(xy 351.836303 -395.49018) (xy 351.829308 -395.537905) (xy 351.815461 -395.58411) (xy 351.795054 -395.627816)
			(xy 351.782126 -395.64818) (xy 351.776284 -395.65707) (xy 351.772728 -395.677136) (xy 351.79381 -395.769338)
			(xy 351.806002 -395.786102) (xy 351.814892 -395.791436) (xy 351.835696 -395.80429) (xy 351.873617 -395.835166)
			(xy 351.90657 -395.871295) (xy 351.933836 -395.911889) (xy 351.954819 -395.95606) (xy 351.969059 -396.002841)
			(xy 351.976245 -396.051211) (xy 351.97669 -396.075662) (xy 351.976253 -396.100033) (xy 351.969097 -396.148247)
			(xy 351.95495 -396.194891) (xy 351.934118 -396.238957) (xy 351.90705 -396.279492) (xy 351.874331 -396.315621)
			(xy 351.855786 -396.33144) (xy 351.846896 -396.338552) (xy 351.837498 -396.35811) (xy 351.834704 -396.457424)
			(xy 351.84334 -396.47749) (xy 351.851722 -396.48511) (xy 351.870143 -396.502599) (xy 351.901482 -396.542567)
			(xy 351.925777 -396.58717) (xy 351.942358 -396.635178) (xy 351.950767 -396.685267) (xy 351.95129 -396.710662)
			(xy 351.951199 -396.721944) (xy 351.949546 -396.744446) (xy 351.947988 -396.75562) (xy 351.946718 -396.76451)
			(xy 351.950274 -396.782036) (xy 351.993708 -396.852902) (xy 352.007424 -396.864078) (xy 352.01606 -396.866872)
			(xy 352.038304 -396.874809) (xy 352.080225 -396.89656) (xy 352.118298 -396.924505) (xy 352.151615 -396.957977)
			(xy 352.179383 -396.996179) (xy 352.190558 -397.016986) (xy 352.191066 -397.018002) (xy 352.583496 -397.696944)
			(xy 352.596304 -397.720276) (xy 352.614454 -397.770308) (xy 352.623639 -397.822732) (xy 352.624136 -397.849344)
			(xy 352.623662 -397.873334) (xy 352.616151 -397.920722) (xy 352.60132 -397.966352) (xy 352.579534 -398.0091)
			(xy 352.551331 -398.047915) (xy 352.517403 -398.081841) (xy 352.478587 -398.110043) (xy 352.435837 -398.131826)
			(xy 352.390206 -398.146654) (xy 352.342818 -398.154163) (xy 352.318828 -398.154652) (xy 352.295299 -398.154212)
			(xy 352.2488 -398.146979) (xy 352.203962 -398.132696) (xy 352.161848 -398.111701) (xy 352.123454 -398.084491)
			(xy 352.08969 -398.051712) (xy 352.061358 -398.014139) (xy 352.049842 -397.993616) (xy 352.049588 -397.993108)
			(xy 352.04908 -397.992346) (xy 351.651316 -397.304006) (xy 351.639385 -397.281345) (xy 351.622438 -397.23302)
			(xy 351.613798 -397.182544) (xy 351.613216 -397.15694) (xy 351.613216 -397.156432) (xy 351.613367 -397.145083)
			(xy 351.615148 -397.122453) (xy 351.616772 -397.11122) (xy 351.618042 -397.10233) (xy 351.614486 -397.085058)
			(xy 351.571052 -397.013938) (xy 351.557082 -397.003016) (xy 351.5487 -396.999968) (xy 351.526296 -396.99195)
			(xy 351.484098 -396.969965) (xy 351.445819 -396.941703) (xy 351.412387 -396.907845) (xy 351.38461 -396.869213)
			(xy 351.36316 -396.82674) (xy 351.348556 -396.781455) (xy 351.341152 -396.734453) (xy 351.340674 -396.710662)
			(xy 351.341173 -396.685264) (xy 351.349573 -396.635167) (xy 351.366149 -396.587151) (xy 351.390446 -396.542542)
			(xy 351.421792 -396.502571) (xy 351.440242 -396.48511) (xy 351.448624 -396.47749) (xy 351.45726 -396.457424)
			(xy 351.454466 -396.35811) (xy 351.445068 -396.338552) (xy 351.436178 -396.33144) (xy 351.417618 -396.315637)
			(xy 351.384893 -396.279509) (xy 351.357822 -396.238972) (xy 351.336991 -396.194902) (xy 351.32285 -396.148253)
			(xy 351.315704 -396.100035) (xy 351.315274 -396.075662) (xy 351.315713 -396.051546) (xy 351.322718 -396.003825)
			(xy 351.336574 -395.957627) (xy 351.356989 -395.913928) (xy 351.369884 -395.893544) (xy 351.375726 -395.884654)
			(xy 351.379282 -395.864588) (xy 351.3582 -395.772386) (xy 351.346008 -395.755622) (xy 351.337118 -395.750288)
			(xy 351.316313 -395.737435) (xy 351.278388 -395.70656) (xy 351.245431 -395.670431) (xy 351.218162 -395.629838)
			(xy 351.197175 -395.585667) (xy 351.182931 -395.538885) (xy 351.175741 -395.490514) (xy 351.17532 -395.466062)
			(xy 351.175881 -395.43878) (xy 351.184842 -395.384956) (xy 351.202515 -395.333332) (xy 351.228421 -395.285309)
			(xy 351.261857 -395.242189) (xy 351.281492 -395.223238) (xy 351.288942 -395.215746) (xy 351.297486 -395.196451)
			(xy 351.298002 -395.1859) (xy 351.298002 -395.111224) (xy 351.297416 -395.100689) (xy 351.288888 -395.081412)
			(xy 351.281492 -395.073886) (xy 351.261834 -395.054955) (xy 351.228387 -395.011835) (xy 351.202474 -394.963809)
			(xy 351.1848 -394.912179) (xy 351.175845 -394.858348) (xy 351.17532 -394.831062) (xy 351.175574 -394.81887)
			(xy 351.175828 -394.809218) (xy 351.169732 -394.791184) (xy 351.111058 -394.723874) (xy 351.094294 -394.715238)
			(xy 351.084388 -394.714222) (xy 351.05744 -394.710856) (xy 351.005075 -394.69647) (xy 350.95576 -394.67373)
			(xy 350.910819 -394.643246) (xy 350.871456 -394.605835) (xy 350.838728 -394.5625) (xy 350.813511 -394.514405)
			(xy 350.796483 -394.462839) (xy 350.79178 -394.436092) (xy 350.79051 -394.426694) (xy 350.517968 -393.95527)
			(xy 350.510602 -393.949428) (xy 350.50095 -393.9413) (xy 350.49385 -393.935553) (xy 350.476799 -393.929035)
			(xy 350.467676 -393.9286) (xy 350.095566 -393.9286) (xy 350.086673 -393.928931) (xy 350.06996 -393.935012)
			(xy 350.056348 -393.946458) (xy 350.051624 -393.954) (xy 350.044766 -393.965938) (xy 350.044766 -393.992862)
			(xy 350.119696 -394.122402) (xy 350.127062 -394.128244) (xy 350.145842 -394.144047) (xy 350.178979 -394.180253)
			(xy 350.206402 -394.220957) (xy 350.227511 -394.265266) (xy 350.241842 -394.312208) (xy 350.249079 -394.360752)
			(xy 350.24949 -394.385292) (xy 350.249236 -394.397484) (xy 350.248982 -394.407136) (xy 350.255078 -394.42517)
			(xy 350.313752 -394.49248) (xy 350.330516 -394.501116) (xy 350.340422 -394.502132) (xy 350.367189 -394.50546)
			(xy 350.419214 -394.519686) (xy 350.468242 -394.542165) (xy 350.512973 -394.572301) (xy 350.552222 -394.609295)
			(xy 350.584948 -394.652167) (xy 350.610285 -394.699781) (xy 350.627561 -394.750875) (xy 350.636318 -394.804094)
			(xy 350.63684 -394.831062) (xy 350.636277 -394.858344) (xy 350.627314 -394.912167) (xy 350.60964 -394.96379)
			(xy 350.583736 -395.011813) (xy 350.550302 -395.054935) (xy 350.530668 -395.073886) (xy 350.523227 -395.081381)
			(xy 350.514699 -395.100676) (xy 350.514158 -395.111224) (xy 350.514158 -395.1859) (xy 350.51475 -395.196432)
			(xy 350.523291 -395.215695) (xy 350.530668 -395.223238) (xy 350.550321 -395.242172) (xy 350.58376 -395.285293)
			(xy 350.609664 -395.333321) (xy 350.627331 -395.384949) (xy 350.636281 -395.438778) (xy 350.63684 -395.466062)
			(xy 350.636407 -395.49018) (xy 350.629412 -395.537905) (xy 350.615565 -395.58411) (xy 350.595159 -395.627816)
			(xy 350.58223 -395.64818) (xy 350.576388 -395.65707) (xy 350.572832 -395.677136) (xy 350.593914 -395.769338)
			(xy 350.606106 -395.786102) (xy 350.614996 -395.791436) (xy 350.6358 -395.80429) (xy 350.67372 -395.835166)
			(xy 350.706673 -395.871296) (xy 350.733939 -395.91189) (xy 350.754921 -395.95606) (xy 350.769161 -396.002842)
			(xy 350.776348 -396.051211) (xy 350.776794 -396.075662) (xy 350.776357 -396.100033) (xy 350.769201 -396.148247)
			(xy 350.755055 -396.194891) (xy 350.734222 -396.238957) (xy 350.707154 -396.279493) (xy 350.674436 -396.315622)
			(xy 350.65589 -396.33144) (xy 350.647 -396.338552) (xy 350.637602 -396.35811) (xy 350.634808 -396.457424)
			(xy 350.643444 -396.47749) (xy 350.651826 -396.48511) (xy 350.670246 -396.502599) (xy 350.701586 -396.542567)
			(xy 350.72588 -396.58717) (xy 350.742461 -396.635178) (xy 350.75087 -396.685267) (xy 350.751394 -396.710662)
			(xy 350.751303 -396.721944) (xy 350.74965 -396.744446) (xy 350.748092 -396.75562) (xy 350.746822 -396.764764)
			(xy 350.750124 -396.782036) (xy 350.793812 -396.853156) (xy 350.807528 -396.864078) (xy 350.816164 -396.866872)
			(xy 350.844295 -396.877143) (xy 350.896227 -396.906948) (xy 350.919288 -396.926054) (xy 350.940736 -396.945669)
			(xy 350.97654 -396.991443) (xy 350.990408 -397.016986) (xy 350.99117 -397.018256) (xy 351.383346 -397.696944)
			(xy 351.396129 -397.720294) (xy 351.41432 -397.770318) (xy 351.423603 -397.822731) (xy 351.42424 -397.849344)
			(xy 351.42379 -397.873348) (xy 351.41627 -397.920765) (xy 351.401422 -397.96642) (xy 351.379613 -398.00919)
			(xy 351.351379 -398.048019) (xy 351.317417 -398.081952) (xy 351.278563 -398.110152) (xy 351.235774 -398.131924)
			(xy 351.190106 -398.146732) (xy 351.142683 -398.15421) (xy 351.118678 -398.154652) (xy 351.095147 -398.154215)
			(xy 351.048644 -398.146989) (xy 351.0038 -398.132711) (xy 350.961679 -398.11172) (xy 350.923279 -398.084512)
			(xy 350.88951 -398.051734) (xy 350.861171 -398.014161) (xy 350.849692 -397.993616) (xy 350.849438 -397.993108)
			(xy 350.84893 -397.992346) (xy 350.448372 -397.298926) (xy 350.437302 -397.276825) (xy 350.421661 -397.229939)
			(xy 350.413767 -397.181146) (xy 350.41332 -397.156432) (xy 350.413404 -397.145087) (xy 350.41506 -397.122457)
			(xy 350.416622 -397.11122) (xy 350.417892 -397.10233) (xy 350.414336 -397.085058) (xy 350.370902 -397.013938)
			(xy 350.357186 -397.002762) (xy 350.34855 -396.999968) (xy 350.326162 -396.991939) (xy 350.283999 -396.969937)
			(xy 350.245758 -396.941662) (xy 350.212364 -396.907798) (xy 350.184626 -396.869166) (xy 350.163214 -396.8267)
			(xy 350.148647 -396.781426) (xy 350.141278 -396.734442) (xy 350.140778 -396.710662) (xy 350.141277 -396.685264)
			(xy 350.149677 -396.635167) (xy 350.166253 -396.587151) (xy 350.19055 -396.542543) (xy 350.221897 -396.502572)
			(xy 350.240346 -396.48511) (xy 350.248728 -396.47749) (xy 350.257364 -396.457424) (xy 350.25457 -396.35811)
			(xy 350.245172 -396.338552) (xy 350.236282 -396.33144) (xy 350.217722 -396.315637) (xy 350.184997 -396.27951)
			(xy 350.157925 -396.238973) (xy 350.137094 -396.194903) (xy 350.122952 -396.148254) (xy 350.115807 -396.100035)
			(xy 350.115378 -396.075662) (xy 350.115817 -396.051546) (xy 350.122822 -396.003825) (xy 350.136679 -395.957627)
			(xy 350.157093 -395.913928) (xy 350.169988 -395.893544) (xy 350.17583 -395.884654) (xy 350.179386 -395.864588)
			(xy 350.158304 -395.772386) (xy 350.146112 -395.755622) (xy 350.137222 -395.750288) (xy 350.116422 -395.737431)
			(xy 350.078508 -395.706551) (xy 350.04556 -395.67042) (xy 350.018299 -395.629826) (xy 349.997319 -395.585657)
			(xy 349.98308 -395.538878) (xy 349.975892 -395.490511) (xy 349.975424 -395.466062) (xy 349.975985 -395.43878)
			(xy 349.984947 -395.384956) (xy 350.00262 -395.333333) (xy 350.028526 -395.28531) (xy 350.061962 -395.24219)
			(xy 350.081596 -395.223238) (xy 350.089045 -395.215746) (xy 350.097589 -395.196451) (xy 350.098106 -395.1859)
			(xy 350.098106 -395.111224) (xy 350.09752 -395.100689) (xy 350.088993 -395.081412) (xy 350.081596 -395.073886)
			(xy 350.061938 -395.054955) (xy 350.02849 -395.011836) (xy 350.002577 -394.963809) (xy 349.984903 -394.912179)
			(xy 349.975947 -394.858348) (xy 349.975424 -394.831062) (xy 349.975678 -394.81887) (xy 349.975932 -394.809218)
			(xy 349.969836 -394.791184) (xy 349.911162 -394.723874) (xy 349.894398 -394.715238) (xy 349.884492 -394.714222)
			(xy 349.857577 -394.710873) (xy 349.805273 -394.696532) (xy 349.756012 -394.673847) (xy 349.711113 -394.643425)
			(xy 349.671783 -394.606083) (xy 349.639074 -394.562822) (xy 349.613866 -394.514802) (xy 349.596833 -394.463312)
			(xy 349.592138 -394.4366) (xy 349.590614 -394.427202) (xy 349.317818 -393.95527) (xy 349.310452 -393.949428)
			(xy 349.3008 -393.9413) (xy 349.293697 -393.935561) (xy 349.276647 -393.929059) (xy 349.267526 -393.9286)
			(xy 348.89567 -393.9286) (xy 348.886777 -393.92893) (xy 348.870063 -393.93501) (xy 348.85645 -393.946457)
			(xy 348.851728 -393.954) (xy 348.84487 -393.965938) (xy 348.84487 -393.992862) (xy 348.9198 -394.122402)
			(xy 348.927166 -394.128244) (xy 348.945946 -394.144047) (xy 348.979082 -394.180253) (xy 349.006505 -394.220957)
			(xy 349.027614 -394.265266) (xy 349.041944 -394.312208) (xy 349.049182 -394.360752) (xy 349.049594 -394.385292)
			(xy 349.04934 -394.397484) (xy 349.049086 -394.407136) (xy 349.055182 -394.42517) (xy 349.113856 -394.49248)
			(xy 349.13062 -394.501116) (xy 349.140272 -394.502132) (xy 349.167042 -394.505456) (xy 349.219073 -394.519677)
			(xy 349.268108 -394.542152) (xy 349.312846 -394.572286) (xy 349.352101 -394.60928) (xy 349.384833 -394.652154)
			(xy 349.410175 -394.69977) (xy 349.427454 -394.750868) (xy 349.436213 -394.804092) (xy 349.43669 -394.831062)
			(xy 349.43618 -394.857049) (xy 349.42805 -394.908384) (xy 349.411989 -394.957814) (xy 349.388393 -395.004124)
			(xy 349.357843 -395.046172) (xy 349.321092 -395.082923) (xy 349.279044 -395.113473) (xy 349.232734 -395.137069)
			(xy 349.183304 -395.15313) (xy 349.131969 -395.16126) (xy 349.079995 -395.16126) (xy 349.02866 -395.15313)
			(xy 348.97923 -395.137069) (xy 348.93292 -395.113473) (xy 348.890872 -395.082923) (xy 348.854121 -395.046172)
			(xy 348.823571 -395.004124) (xy 348.799975 -394.957814) (xy 348.783914 -394.908384) (xy 348.775784 -394.857049)
			(xy 348.775274 -394.831062) (xy 348.775528 -394.81887) (xy 348.775782 -394.809218) (xy 348.769686 -394.791184)
			(xy 348.711012 -394.723874) (xy 348.694248 -394.715238) (xy 348.684596 -394.714222) (xy 348.657681 -394.710874)
			(xy 348.605377 -394.696533) (xy 348.556114 -394.673848) (xy 348.511216 -394.643426) (xy 348.471884 -394.606084)
			(xy 348.439176 -394.562823) (xy 348.413966 -394.514803) (xy 348.396933 -394.463313) (xy 348.392242 -394.4366)
			(xy 348.390718 -394.427202) (xy 348.117922 -393.95527) (xy 348.110556 -393.949428) (xy 348.100904 -393.9413)
			(xy 348.093801 -393.93556) (xy 348.076751 -393.929057) (xy 348.06763 -393.9286) (xy 347.69552 -393.9286)
			(xy 347.686631 -393.928938) (xy 347.66993 -393.935029) (xy 347.656331 -393.946479) (xy 347.651578 -393.954)
			(xy 347.64472 -393.965938) (xy 347.64472 -393.992862) (xy 347.71965 -394.122402) (xy 347.727016 -394.128244)
			(xy 347.745793 -394.144049) (xy 347.778925 -394.180256) (xy 347.806344 -394.220961) (xy 347.827449 -394.26527)
			(xy 347.841777 -394.312211) (xy 347.849014 -394.360753) (xy 347.849444 -394.385292) (xy 347.84919 -394.397484)
			(xy 347.848936 -394.407136) (xy 347.855032 -394.42517) (xy 347.913706 -394.49248) (xy 347.93047 -394.501116)
			(xy 347.940376 -394.502132) (xy 347.967145 -394.505457) (xy 348.019177 -394.519678) (xy 348.068211 -394.542153)
			(xy 348.112948 -394.572287) (xy 348.152203 -394.609281) (xy 348.184935 -394.652155) (xy 348.210276 -394.699771)
			(xy 348.227555 -394.750868) (xy 348.236313 -394.804092) (xy 348.236794 -394.831062) (xy 348.236327 -394.855259)
			(xy 348.229231 -394.903132) (xy 348.215243 -394.949463) (xy 348.194661 -394.993264) (xy 348.181676 -395.013688)
			(xy 348.176926 -395.021659) (xy 348.172906 -395.039757) (xy 348.173802 -395.048994) (xy 348.17812 -395.079982)
			(xy 348.179925 -395.089234) (xy 348.189185 -395.105636) (xy 348.196154 -395.111986) (xy 348.218248 -395.130661)
			(xy 348.25802 -395.172672) (xy 348.29218 -395.219361) (xy 348.320184 -395.269983) (xy 348.341586 -395.32373)
			(xy 348.356043 -395.379745) (xy 348.363326 -395.437136) (xy 348.363794 -395.466062) (xy 348.36319 -395.499382)
			(xy 348.353521 -395.565317) (xy 348.334396 -395.629154) (xy 348.320868 -395.65961) (xy 348.316606 -395.670079)
			(xy 348.31668 -395.692653) (xy 348.326436 -395.713011) (xy 348.334838 -395.72057) (xy 348.357085 -395.739244)
			(xy 348.397148 -395.7813) (xy 348.431569 -395.828087) (xy 348.459796 -395.878851) (xy 348.481373 -395.932779)
			(xy 348.495955 -395.989003) (xy 348.503308 -396.04662) (xy 348.503748 -396.075662) (xy 348.503297 -396.104666)
			(xy 348.495967 -396.16221) (xy 348.481432 -396.218368) (xy 348.459923 -396.272242) (xy 348.431786 -396.32297)
			(xy 348.397471 -396.369741) (xy 348.357526 -396.411805) (xy 348.335346 -396.4305) (xy 348.328234 -396.436088)
			(xy 348.31909 -396.451328) (xy 348.30385 -396.534132) (xy 348.306644 -396.551404) (xy 348.311216 -396.559532)
			(xy 348.323809 -396.582711) (xy 348.341695 -396.632331) (xy 348.350776 -396.684289) (xy 348.351348 -396.710662)
			(xy 348.940628 -396.710662) (xy 348.94115 -396.685407) (xy 348.949463 -396.635585) (xy 348.965864 -396.587811)
			(xy 348.989905 -396.543388) (xy 349.020929 -396.503528) (xy 349.058091 -396.469318) (xy 349.100377 -396.441692)
			(xy 349.146633 -396.421402) (xy 349.195598 -396.409002) (xy 349.245936 -396.404831) (xy 349.296274 -396.409002)
			(xy 349.345239 -396.421402) (xy 349.391495 -396.441692) (xy 349.433781 -396.469318) (xy 349.470943 -396.503528)
			(xy 349.501967 -396.543388) (xy 349.526008 -396.587811) (xy 349.542409 -396.635585) (xy 349.550722 -396.685407)
			(xy 349.551244 -396.710662) (xy 349.551141 -396.721943) (xy 349.549489 -396.744445) (xy 349.547942 -396.75562)
			(xy 349.546672 -396.76451) (xy 349.550228 -396.782036) (xy 349.593662 -396.852902) (xy 349.607378 -396.864078)
			(xy 349.616014 -396.866872) (xy 349.63827 -396.87478) (xy 349.680189 -396.896538) (xy 349.718261 -396.92449)
			(xy 349.751577 -396.957968) (xy 349.779343 -396.996174) (xy 349.790512 -397.016986) (xy 349.79102 -397.018002)
			(xy 350.18345 -397.696944) (xy 350.196257 -397.720285) (xy 350.214484 -397.770304) (xy 350.223751 -397.822726)
			(xy 350.224344 -397.849344) (xy 350.223902 -397.873349) (xy 350.216382 -397.920767) (xy 350.201534 -397.966424)
			(xy 350.179724 -398.009195) (xy 350.15149 -398.048026) (xy 350.117526 -398.08196) (xy 350.078671 -398.110161)
			(xy 350.035882 -398.131934) (xy 349.990212 -398.146743) (xy 349.942788 -398.154222) (xy 349.918782 -398.154652)
			(xy 349.895251 -398.154183) (xy 349.848744 -398.14698) (xy 349.803896 -398.132716) (xy 349.761773 -398.111731)
			(xy 349.723374 -398.084523) (xy 349.689611 -398.051738) (xy 349.661287 -398.014155) (xy 349.649796 -397.993616)
			(xy 349.649542 -397.993108) (xy 349.649034 -397.992346) (xy 349.25127 -397.304006) (xy 349.239395 -397.281329)
			(xy 349.222543 -397.232996) (xy 349.21397 -397.182533) (xy 349.213424 -397.15694) (xy 349.213424 -397.156432)
			(xy 349.213515 -397.145087) (xy 349.21517 -397.122458) (xy 349.216726 -397.11122) (xy 349.217996 -397.10233)
			(xy 349.21444 -397.085058) (xy 349.171006 -397.013938) (xy 349.157036 -397.003016) (xy 349.148654 -396.999968)
			(xy 349.126254 -396.991929) (xy 349.084036 -396.969971) (xy 349.045738 -396.941724) (xy 349.012292 -396.907874)
			(xy 348.984507 -396.86924) (xy 348.963058 -396.826761) (xy 348.948465 -396.781467) (xy 348.941081 -396.734456)
			(xy 348.940628 -396.710662) (xy 348.351348 -396.710662) (xy 348.351257 -396.721944) (xy 348.349604 -396.744446)
			(xy 348.348046 -396.75562) (xy 348.346776 -396.76451) (xy 348.350332 -396.782036) (xy 348.393766 -396.852902)
			(xy 348.407482 -396.864078) (xy 348.416118 -396.866872) (xy 348.438359 -396.874813) (xy 348.480274 -396.896569)
			(xy 348.518341 -396.924518) (xy 348.551652 -396.957992) (xy 348.579415 -396.996194) (xy 348.590616 -397.016986)
			(xy 348.591124 -397.018002) (xy 348.983554 -397.696944) (xy 348.996336 -397.720295) (xy 349.014527 -397.770318)
			(xy 349.02381 -397.822731) (xy 349.024448 -397.849344) (xy 349.023998 -397.873349) (xy 349.016478 -397.920766)
			(xy 349.00163 -397.966422) (xy 348.979821 -398.009192) (xy 348.951588 -398.048022) (xy 348.917625 -398.081955)
			(xy 348.878771 -398.110156) (xy 348.835983 -398.131929) (xy 348.790314 -398.146738) (xy 348.742891 -398.154218)
			(xy 348.718886 -398.154652) (xy 348.695355 -398.154216) (xy 348.648851 -398.146991) (xy 348.604006 -398.132714)
			(xy 348.561884 -398.111723) (xy 348.523483 -398.084516) (xy 348.489713 -398.051737) (xy 348.461374 -398.014164)
			(xy 348.4499 -397.993616) (xy 348.449646 -397.993108) (xy 348.449138 -397.992346) (xy 348.051374 -397.304006)
			(xy 348.039475 -397.281338) (xy 348.022599 -397.233007) (xy 348.014037 -397.182536) (xy 348.013528 -397.15694)
			(xy 348.013528 -397.156432) (xy 348.013612 -397.145087) (xy 348.015268 -397.122457) (xy 348.01683 -397.11122)
			(xy 348.0181 -397.10233) (xy 348.014544 -397.085058) (xy 347.97111 -397.013938) (xy 347.95714 -397.003016)
			(xy 347.948758 -396.999968) (xy 347.926357 -396.991948) (xy 347.884163 -396.96996) (xy 347.84589 -396.941695)
			(xy 347.812462 -396.907837) (xy 347.784689 -396.869205) (xy 347.763243 -396.826734) (xy 347.748641 -396.781451)
			(xy 347.741238 -396.734451) (xy 347.740732 -396.710662) (xy 347.741314 -396.684291) (xy 347.750415 -396.63234)
			(xy 347.768289 -396.582719) (xy 347.780864 -396.559532) (xy 347.785436 -396.551404) (xy 347.78823 -396.534132)
			(xy 347.77299 -396.451328) (xy 347.763846 -396.436088) (xy 347.756734 -396.4305) (xy 347.734545 -396.411815)
			(xy 347.694596 -396.369754) (xy 347.660279 -396.322984) (xy 347.632146 -396.272254) (xy 347.610647 -396.218376)
			(xy 347.596125 -396.162213) (xy 347.588815 -396.104667) (xy 347.588332 -396.075662) (xy 347.588935 -396.042342)
			(xy 347.598601 -395.976406) (xy 347.617723 -395.912568) (xy 347.631258 -395.882114) (xy 347.635525 -395.871643)
			(xy 347.635458 -395.849062) (xy 347.625711 -395.828693) (xy 347.617288 -395.821154) (xy 347.595043 -395.802479)
			(xy 347.554985 -395.760422) (xy 347.52057 -395.713635) (xy 347.49235 -395.662869) (xy 347.47078 -395.608942)
			(xy 347.456206 -395.552718) (xy 347.448863 -395.495103) (xy 347.448378 -395.466062) (xy 347.448823 -395.437136)
			(xy 347.456116 -395.379746) (xy 347.470581 -395.323732) (xy 347.491987 -395.269986) (xy 347.519994 -395.219365)
			(xy 347.554155 -395.172677) (xy 347.593926 -395.130663) (xy 347.616018 -395.111986) (xy 347.623083 -395.105716)
			(xy 347.632355 -395.089274) (xy 347.634052 -395.079982) (xy 347.63837 -395.048994) (xy 347.639318 -395.039756)
			(xy 347.635282 -395.021646) (xy 347.630496 -395.013688) (xy 347.617464 -394.99329) (xy 347.596865 -394.949488)
			(xy 347.58288 -394.903148) (xy 347.575807 -394.855264) (xy 347.575378 -394.831062) (xy 347.575632 -394.81887)
			(xy 347.575886 -394.809218) (xy 347.56979 -394.791184) (xy 347.511116 -394.723874) (xy 347.494352 -394.715238)
			(xy 347.484446 -394.714222) (xy 347.457533 -394.71087) (xy 347.405235 -394.696524) (xy 347.35598 -394.673834)
			(xy 347.311088 -394.64341) (xy 347.271763 -394.606068) (xy 347.23906 -394.562808) (xy 347.213856 -394.514791)
			(xy 347.196826 -394.463304) (xy 347.192092 -394.4366) (xy 347.190568 -394.427202) (xy 346.917772 -393.95527)
			(xy 346.910406 -393.949428) (xy 346.900754 -393.9413) (xy 346.893654 -393.935553) (xy 346.876604 -393.929033)
			(xy 346.86748 -393.9286) (xy 346.495624 -393.9286) (xy 346.486735 -393.928938) (xy 346.470033 -393.935028)
			(xy 346.456432 -393.946477) (xy 346.451682 -393.954) (xy 346.444824 -393.965938) (xy 346.444824 -393.992862)
			(xy 346.519754 -394.122402) (xy 346.52712 -394.128244) (xy 346.545897 -394.144049) (xy 346.579028 -394.180257)
			(xy 346.606447 -394.220962) (xy 346.627552 -394.26527) (xy 346.64188 -394.312211) (xy 346.649116 -394.360753)
			(xy 346.649548 -394.385292) (xy 346.649294 -394.397484) (xy 346.64904 -394.407136) (xy 346.655136 -394.42517)
			(xy 346.71381 -394.49248) (xy 346.730574 -394.501116) (xy 346.740226 -394.502132) (xy 346.766993 -394.50546)
			(xy 346.819018 -394.519687) (xy 346.868045 -394.542166) (xy 346.912775 -394.572302) (xy 346.952023 -394.609296)
			(xy 346.984749 -394.652168) (xy 347.010086 -394.699782) (xy 347.027362 -394.750875) (xy 347.036119 -394.804095)
			(xy 347.036644 -394.831062) (xy 347.036081 -394.858344) (xy 347.027118 -394.912167) (xy 347.009445 -394.96379)
			(xy 346.98354 -395.011814) (xy 346.950107 -395.054936) (xy 346.930472 -395.073886) (xy 346.923031 -395.081381)
			(xy 346.914502 -395.100676) (xy 346.913962 -395.111224) (xy 346.913962 -395.1859) (xy 346.914554 -395.196432)
			(xy 346.923096 -395.215695) (xy 346.930472 -395.223238) (xy 346.950125 -395.242172) (xy 346.983563 -395.285294)
			(xy 347.009467 -395.333321) (xy 347.027134 -395.384949) (xy 347.036083 -395.438778) (xy 347.036644 -395.466062)
			(xy 347.036211 -395.49018) (xy 347.029216 -395.537905) (xy 347.015369 -395.58411) (xy 346.994963 -395.627817)
			(xy 346.982034 -395.64818) (xy 346.976192 -395.65707) (xy 346.972636 -395.677136) (xy 346.993718 -395.769338)
			(xy 347.00591 -395.786102) (xy 347.0148 -395.791436) (xy 347.035603 -395.80429) (xy 347.073523 -395.835166)
			(xy 347.106476 -395.871296) (xy 347.133741 -395.91189) (xy 347.154723 -395.956061) (xy 347.168963 -396.002842)
			(xy 347.17615 -396.051212) (xy 347.176598 -396.075662) (xy 347.176161 -396.100033) (xy 347.169005 -396.148247)
			(xy 347.154859 -396.194892) (xy 347.134027 -396.238958) (xy 347.106959 -396.279494) (xy 347.074241 -396.315623)
			(xy 347.055694 -396.33144) (xy 347.046804 -396.338552) (xy 347.037406 -396.35811) (xy 347.034612 -396.457424)
			(xy 347.043248 -396.47749) (xy 347.05163 -396.48511) (xy 347.07005 -396.502599) (xy 347.101389 -396.542568)
			(xy 347.125683 -396.58717) (xy 347.142264 -396.635178) (xy 347.150673 -396.685267) (xy 347.151198 -396.710662)
			(xy 347.151107 -396.721944) (xy 347.149454 -396.744446) (xy 347.147896 -396.75562) (xy 347.146626 -396.76451)
			(xy 347.150182 -396.782036) (xy 347.193616 -396.852902) (xy 347.207332 -396.864078) (xy 347.215968 -396.866872)
			(xy 347.238212 -396.87481) (xy 347.280132 -396.896562) (xy 347.318203 -396.924507) (xy 347.35152 -396.957979)
			(xy 347.379288 -396.996181) (xy 347.390466 -397.016986) (xy 347.390974 -397.018002) (xy 347.783404 -397.696944)
			(xy 347.796212 -397.720277) (xy 347.814361 -397.770309) (xy 347.823546 -397.822732) (xy 347.824044 -397.849344)
			(xy 347.82357 -397.873334) (xy 347.816059 -397.920722) (xy 347.801228 -397.966353) (xy 347.779443 -398.009102)
			(xy 347.751239 -398.047918) (xy 347.717312 -398.081844) (xy 347.678495 -398.110047) (xy 347.635746 -398.131831)
			(xy 347.590115 -398.146661) (xy 347.542726 -398.154171) (xy 347.518736 -398.154652) (xy 347.495207 -398.154212)
			(xy 347.448707 -398.146981) (xy 347.403868 -398.132698) (xy 347.361753 -398.111704) (xy 347.323358 -398.084495)
			(xy 347.289594 -398.051715) (xy 347.26126 -398.014143) (xy 347.24975 -397.993616) (xy 347.249496 -397.993108)
			(xy 347.248988 -397.992346) (xy 346.851224 -397.304006) (xy 346.839293 -397.281345) (xy 346.822346 -397.23302)
			(xy 346.813705 -397.182544) (xy 346.813124 -397.15694) (xy 346.813124 -397.156432) (xy 346.813275 -397.145083)
			(xy 346.815056 -397.122453) (xy 346.81668 -397.11122) (xy 346.81795 -397.10233) (xy 346.814394 -397.085058)
			(xy 346.77096 -397.013938) (xy 346.75699 -397.003016) (xy 346.748608 -396.999968) (xy 346.726204 -396.99195)
			(xy 346.684004 -396.969967) (xy 346.645725 -396.941704) (xy 346.612292 -396.907847) (xy 346.584514 -396.869215)
			(xy 346.563063 -396.826742) (xy 346.548459 -396.781456) (xy 346.541055 -396.734453) (xy 346.540582 -396.710662)
			(xy 346.541081 -396.685264) (xy 346.549481 -396.635167) (xy 346.566058 -396.587152) (xy 346.590355 -396.542543)
			(xy 346.621702 -396.502573) (xy 346.64015 -396.48511) (xy 346.648532 -396.47749) (xy 346.657168 -396.457424)
			(xy 346.654374 -396.35811) (xy 346.644976 -396.338552) (xy 346.636086 -396.33144) (xy 346.617526 -396.315637)
			(xy 346.5848 -396.27951) (xy 346.557729 -396.238973) (xy 346.536897 -396.194903) (xy 346.522755 -396.148254)
			(xy 346.51561 -396.100035) (xy 346.515182 -396.075662) (xy 346.515621 -396.051546) (xy 346.522626 -396.003825)
			(xy 346.536483 -395.957627) (xy 346.556897 -395.913928) (xy 346.569792 -395.893544) (xy 346.575634 -395.884654)
			(xy 346.57919 -395.864588) (xy 346.558108 -395.772386) (xy 346.545916 -395.755622) (xy 346.537026 -395.750288)
			(xy 346.516225 -395.737431) (xy 346.478311 -395.706552) (xy 346.445363 -395.67042) (xy 346.418101 -395.629827)
			(xy 346.397121 -395.585658) (xy 346.382882 -395.538879) (xy 346.375694 -395.490511) (xy 346.375228 -395.466062)
			(xy 346.375789 -395.43878) (xy 346.384751 -395.384956) (xy 346.402424 -395.333333) (xy 346.42833 -395.28531)
			(xy 346.461766 -395.24219) (xy 346.4814 -395.223238) (xy 346.488849 -395.215746) (xy 346.497392 -395.196451)
			(xy 346.49791 -395.1859) (xy 346.49791 -395.111224) (xy 346.497324 -395.100688) (xy 346.488797 -395.081411)
			(xy 346.4814 -395.073886) (xy 346.461742 -395.054955) (xy 346.428294 -395.011836) (xy 346.40238 -394.963809)
			(xy 346.384706 -394.912179) (xy 346.37575 -394.858348) (xy 346.375228 -394.831062) (xy 346.375482 -394.81887)
			(xy 346.375736 -394.809218) (xy 346.36964 -394.791184) (xy 346.310966 -394.723874) (xy 346.294202 -394.715238)
			(xy 346.28455 -394.714222) (xy 346.257637 -394.71087) (xy 346.205339 -394.696524) (xy 346.156083 -394.673835)
			(xy 346.11119 -394.643412) (xy 346.071865 -394.606069) (xy 346.039161 -394.562809) (xy 346.013956 -394.514792)
			(xy 345.996926 -394.463305) (xy 345.992196 -394.4366) (xy 345.990672 -394.427202) (xy 345.717876 -393.95527)
			(xy 345.71051 -393.949428) (xy 345.700858 -393.9413) (xy 345.693758 -393.935552) (xy 345.676708 -393.929031)
			(xy 345.667584 -393.9286) (xy 345.295728 -393.9286) (xy 345.286838 -393.928937) (xy 345.270135 -393.935026)
			(xy 345.256534 -393.946476) (xy 345.251786 -393.954) (xy 345.244928 -393.965938) (xy 345.244928 -393.992862)
			(xy 345.320112 -394.12291) (xy 345.327224 -394.128752) (xy 345.345954 -394.144533) (xy 345.379001 -394.180678)
			(xy 345.406351 -394.221305) (xy 345.427406 -394.265524) (xy 345.441705 -394.312365) (xy 345.448934 -394.360804)
			(xy 345.449398 -394.385292) (xy 345.449144 -394.397484) (xy 345.44889 -394.407136) (xy 345.454986 -394.42517)
			(xy 345.51366 -394.49248) (xy 345.530424 -394.501116) (xy 345.54033 -394.502132) (xy 345.567096 -394.50546)
			(xy 345.619121 -394.519688) (xy 345.668147 -394.542167) (xy 345.712877 -394.572303) (xy 345.752125 -394.609298)
			(xy 345.784851 -394.652169) (xy 345.810187 -394.699783) (xy 345.827462 -394.750876) (xy 345.836219 -394.804095)
			(xy 345.836748 -394.831062) (xy 345.836185 -394.858344) (xy 345.827222 -394.912167) (xy 345.809549 -394.963791)
			(xy 345.783645 -395.011814) (xy 345.750212 -395.054937) (xy 345.730576 -395.073886) (xy 345.723134 -395.081381)
			(xy 345.714604 -395.100676) (xy 345.714066 -395.111224) (xy 345.714066 -395.1859) (xy 345.714658 -395.196431)
			(xy 345.7232 -395.215694) (xy 345.730576 -395.223238) (xy 345.750229 -395.242172) (xy 345.783666 -395.285294)
			(xy 345.80957 -395.333321) (xy 345.827236 -395.38495) (xy 345.836186 -395.438778) (xy 345.836748 -395.466062)
			(xy 345.836315 -395.490179) (xy 345.829318 -395.537904) (xy 345.815468 -395.584107) (xy 345.795057 -395.62781)
			(xy 345.782138 -395.64818) (xy 345.776296 -395.65707) (xy 345.77274 -395.677136) (xy 345.793822 -395.769338)
			(xy 345.806014 -395.786102) (xy 345.814904 -395.791436) (xy 345.835707 -395.80429) (xy 345.873627 -395.835167)
			(xy 345.906579 -395.871297) (xy 345.933844 -395.911891) (xy 345.954826 -395.956061) (xy 345.969065 -396.002842)
			(xy 345.976252 -396.051212) (xy 345.976702 -396.075662) (xy 345.976264 -396.100032) (xy 345.969108 -396.148244)
			(xy 345.954958 -396.194886) (xy 345.934122 -396.238948) (xy 345.907049 -396.279479) (xy 345.874325 -396.315601)
			(xy 345.855798 -396.33144) (xy 345.846908 -396.338552) (xy 345.83751 -396.35811) (xy 345.834716 -396.457424)
			(xy 345.843352 -396.47749) (xy 345.851734 -396.48511) (xy 345.870154 -396.502599) (xy 345.901492 -396.542568)
			(xy 345.925786 -396.587171) (xy 345.942366 -396.635178) (xy 345.950776 -396.685267) (xy 345.951302 -396.710662)
			(xy 345.951211 -396.721944) (xy 345.949558 -396.744446) (xy 345.948 -396.75562) (xy 345.94673 -396.76451)
			(xy 345.950286 -396.782036) (xy 345.99372 -396.852902) (xy 346.007436 -396.864078) (xy 346.016072 -396.866872)
			(xy 346.038316 -396.87481) (xy 346.080235 -396.896562) (xy 346.118306 -396.924508) (xy 346.151623 -396.95798)
			(xy 346.17939 -396.996182) (xy 346.19057 -397.016986) (xy 346.191078 -397.018002) (xy 346.583508 -397.696944)
			(xy 346.596316 -397.720277) (xy 346.614465 -397.770309) (xy 346.623649 -397.822732) (xy 346.624148 -397.849344)
			(xy 346.623674 -397.873334) (xy 346.616163 -397.920723) (xy 346.601332 -397.966354) (xy 346.579547 -398.009103)
			(xy 346.551343 -398.047919) (xy 346.517416 -398.081846) (xy 346.4786 -398.110049) (xy 346.43585 -398.131834)
			(xy 346.390219 -398.146664) (xy 346.34283 -398.154174) (xy 346.31884 -398.154652) (xy 346.295311 -398.154213)
			(xy 346.248811 -398.146981) (xy 346.203971 -398.132699) (xy 346.161855 -398.111705) (xy 346.12346 -398.084496)
			(xy 346.089695 -398.051717) (xy 346.061361 -398.014145) (xy 346.049854 -397.993616) (xy 346.0496 -397.993108)
			(xy 346.049092 -397.992346) (xy 345.651328 -397.304006) (xy 345.639396 -397.281345) (xy 345.622449 -397.23302)
			(xy 345.613809 -397.182544) (xy 345.613228 -397.15694) (xy 345.613228 -397.156432) (xy 345.613379 -397.145083)
			(xy 345.61516 -397.122453) (xy 345.616784 -397.11122) (xy 345.618054 -397.10233) (xy 345.614498 -397.085058)
			(xy 345.571064 -397.013938) (xy 345.557094 -397.003016) (xy 345.548712 -396.999968) (xy 345.526308 -396.991951)
			(xy 345.484108 -396.969967) (xy 345.445828 -396.941705) (xy 345.412394 -396.907848) (xy 345.384616 -396.869215)
			(xy 345.363165 -396.826742) (xy 345.34856 -396.781456) (xy 345.341156 -396.734453) (xy 345.340686 -396.710662)
			(xy 345.341185 -396.685264) (xy 345.349585 -396.635167) (xy 345.366162 -396.587152) (xy 345.390459 -396.542544)
			(xy 345.421807 -396.502574) (xy 345.440254 -396.48511) (xy 345.448636 -396.47749) (xy 345.457272 -396.457424)
			(xy 345.454478 -396.35811) (xy 345.44508 -396.338552) (xy 345.43619 -396.33144) (xy 345.417629 -396.315637)
			(xy 345.384904 -396.27951) (xy 345.357832 -396.238973) (xy 345.336999 -396.194903) (xy 345.322858 -396.148254)
			(xy 345.315712 -396.100035) (xy 345.315286 -396.075662) (xy 345.315725 -396.051546) (xy 345.32273 -396.003826)
			(xy 345.336587 -395.957627) (xy 345.357002 -395.913928) (xy 345.369896 -395.893544) (xy 345.375738 -395.884654)
			(xy 345.379294 -395.864588) (xy 345.358212 -395.772386) (xy 345.34602 -395.755622) (xy 345.33713 -395.750288)
			(xy 345.316329 -395.737432) (xy 345.278414 -395.706552) (xy 345.245466 -395.670421) (xy 345.218204 -395.629827)
			(xy 345.197224 -395.585658) (xy 345.182984 -395.538879) (xy 345.175796 -395.490511) (xy 345.175332 -395.466062)
			(xy 345.175893 -395.438779) (xy 345.184852 -395.384953) (xy 345.202522 -395.333327) (xy 345.228423 -395.285299)
			(xy 345.261853 -395.242172) (xy 345.281504 -395.223238) (xy 345.288952 -395.215746) (xy 345.297494 -395.196451)
			(xy 345.298014 -395.1859) (xy 345.298014 -395.111224) (xy 345.297428 -395.100688) (xy 345.288902 -395.08141)
			(xy 345.281504 -395.073886) (xy 345.261846 -395.054955) (xy 345.228397 -395.011836) (xy 345.202483 -394.96381)
			(xy 345.184809 -394.91218) (xy 345.175853 -394.858348) (xy 345.175332 -394.831062) (xy 345.175586 -394.81887)
			(xy 345.17584 -394.809218) (xy 345.169744 -394.791184) (xy 345.11107 -394.723874) (xy 345.094306 -394.715238)
			(xy 345.0844 -394.714222) (xy 345.057451 -394.710857) (xy 345.005085 -394.696472) (xy 344.955769 -394.673733)
			(xy 344.910826 -394.64325) (xy 344.871461 -394.605839) (xy 344.838731 -394.562504) (xy 344.813514 -394.514408)
			(xy 344.796485 -394.462841) (xy 344.791792 -394.436092) (xy 344.790522 -394.426694) (xy 344.51798 -393.95527)
			(xy 344.510614 -393.949428) (xy 344.500962 -393.9413) (xy 344.493862 -393.935552) (xy 344.476812 -393.929029)
			(xy 344.467688 -393.9286) (xy 344.095578 -393.9286) (xy 344.086684 -393.928929) (xy 344.069968 -393.935007)
			(xy 344.056353 -393.946453) (xy 344.051636 -393.954) (xy 344.044778 -393.965938) (xy 344.044778 -393.992862)
			(xy 344.119708 -394.122402) (xy 344.127074 -394.128244) (xy 344.145853 -394.144047) (xy 344.178989 -394.180254)
			(xy 344.206411 -394.220958) (xy 344.227519 -394.265267) (xy 344.241849 -394.312208) (xy 344.249087 -394.360752)
			(xy 344.249502 -394.385292) (xy 344.249248 -394.397484) (xy 344.248994 -394.407136) (xy 344.25509 -394.42517)
			(xy 344.313764 -394.49248) (xy 344.330528 -394.501116) (xy 344.340434 -394.502132) (xy 344.3672 -394.505461)
			(xy 344.419224 -394.519689) (xy 344.46825 -394.542168) (xy 344.512979 -394.572305) (xy 344.552227 -394.609299)
			(xy 344.584952 -394.65217) (xy 344.610288 -394.699783) (xy 344.627563 -394.750876) (xy 344.636319 -394.804095)
			(xy 344.636852 -394.831062) (xy 344.636289 -394.858344) (xy 344.627326 -394.912168) (xy 344.609653 -394.963791)
			(xy 344.583749 -395.011815) (xy 344.550317 -395.054937) (xy 344.53068 -395.073886) (xy 344.523238 -395.081381)
			(xy 344.514707 -395.100675) (xy 344.51417 -395.111224) (xy 344.51417 -395.1859) (xy 344.51476 -395.196434)
			(xy 344.52329 -395.215707) (xy 344.53068 -395.223238) (xy 344.550332 -395.242172) (xy 344.58377 -395.285294)
			(xy 344.609673 -395.333321) (xy 344.627339 -395.38495) (xy 344.636289 -395.438778) (xy 344.636852 -395.466062)
			(xy 344.636419 -395.490179) (xy 344.629422 -395.537904) (xy 344.615572 -395.584107) (xy 344.595161 -395.627811)
			(xy 344.582242 -395.64818) (xy 344.5764 -395.65707) (xy 344.572844 -395.677136) (xy 344.593926 -395.769338)
			(xy 344.606118 -395.786102) (xy 344.615008 -395.791436) (xy 344.635811 -395.80429) (xy 344.67373 -395.835167)
			(xy 344.706682 -395.871297) (xy 344.733947 -395.911891) (xy 344.754928 -395.956061) (xy 344.769167 -396.002842)
			(xy 344.776354 -396.051212) (xy 344.776806 -396.075662) (xy 344.776368 -396.100032) (xy 344.769212 -396.148245)
			(xy 344.755062 -396.194886) (xy 344.734226 -396.238949) (xy 344.707153 -396.279479) (xy 344.67443 -396.315601)
			(xy 344.655902 -396.33144) (xy 344.647012 -396.338552) (xy 344.637614 -396.35811) (xy 344.63482 -396.457424)
			(xy 344.643456 -396.47749) (xy 344.651838 -396.48511) (xy 344.670258 -396.502599) (xy 344.701596 -396.542568)
			(xy 344.72589 -396.587171) (xy 344.742469 -396.635178) (xy 344.750878 -396.685267) (xy 344.751406 -396.710662)
			(xy 344.751315 -396.721944) (xy 344.749662 -396.744446) (xy 344.748104 -396.75562) (xy 344.746834 -396.764764)
			(xy 344.750136 -396.782036) (xy 344.793824 -396.853156) (xy 344.80754 -396.864078) (xy 344.816176 -396.866872)
			(xy 344.844306 -396.877144) (xy 344.896238 -396.90695) (xy 344.9193 -396.926054) (xy 344.940747 -396.94567)
			(xy 344.97655 -396.991445) (xy 344.99042 -397.016986) (xy 344.991182 -397.018256) (xy 345.383358 -397.696944)
			(xy 345.39614 -397.720295) (xy 345.414331 -397.770318) (xy 345.423613 -397.822731) (xy 345.424252 -397.849344)
			(xy 345.423802 -397.873349) (xy 345.416282 -397.920766) (xy 345.401434 -397.966422) (xy 345.379625 -398.009193)
			(xy 345.351392 -398.048023) (xy 345.31743 -398.081957) (xy 345.278576 -398.110158) (xy 345.235787 -398.131932)
			(xy 345.190119 -398.146741) (xy 345.142695 -398.154221) (xy 345.11869 -398.154652) (xy 345.095159 -398.154216)
			(xy 345.048654 -398.146992) (xy 345.003809 -398.132715) (xy 344.961687 -398.111724) (xy 344.923285 -398.084518)
			(xy 344.889514 -398.051739) (xy 344.861175 -398.014166) (xy 344.849704 -397.993616) (xy 344.84945 -397.993108)
			(xy 344.848942 -397.992346) (xy 344.448384 -397.298926) (xy 344.437313 -397.276826) (xy 344.421672 -397.229939)
			(xy 344.413778 -397.181146) (xy 344.413332 -397.156432) (xy 344.413416 -397.145087) (xy 344.415072 -397.122457)
			(xy 344.416634 -397.11122) (xy 344.417904 -397.10233) (xy 344.414348 -397.085058) (xy 344.370914 -397.013938)
			(xy 344.357198 -397.002762) (xy 344.348562 -396.999968) (xy 344.326174 -396.99194) (xy 344.284009 -396.969938)
			(xy 344.245766 -396.941664) (xy 344.212371 -396.907801) (xy 344.184631 -396.869168) (xy 344.163219 -396.826701)
			(xy 344.148651 -396.781427) (xy 344.141281 -396.734442) (xy 344.14079 -396.710662) (xy 344.14129 -396.685264)
			(xy 344.149689 -396.635167) (xy 344.166267 -396.587152) (xy 344.190564 -396.542544) (xy 344.221912 -396.502575)
			(xy 344.240358 -396.48511) (xy 344.24874 -396.47749) (xy 344.257376 -396.457424) (xy 344.254582 -396.35811)
			(xy 344.245184 -396.338552) (xy 344.236294 -396.33144) (xy 344.217733 -396.315637) (xy 344.185007 -396.279511)
			(xy 344.157935 -396.238974) (xy 344.137102 -396.194904) (xy 344.12296 -396.148254) (xy 344.115815 -396.100035)
			(xy 344.11539 -396.075662) (xy 344.115829 -396.051546) (xy 344.122834 -396.003826) (xy 344.136691 -395.957627)
			(xy 344.157106 -395.913929) (xy 344.17 -395.893544) (xy 344.175842 -395.884654) (xy 344.179398 -395.864588)
			(xy 344.158316 -395.772386) (xy 344.146124 -395.755622) (xy 344.137234 -395.750288) (xy 344.116433 -395.737432)
			(xy 344.078518 -395.706553) (xy 344.045569 -395.670421) (xy 344.018306 -395.629828) (xy 343.997326 -395.585659)
			(xy 343.983086 -395.538879) (xy 343.975898 -395.490512) (xy 343.975436 -395.466062) (xy 343.975997 -395.438779)
			(xy 343.984956 -395.384953) (xy 344.002626 -395.333327) (xy 344.028527 -395.2853) (xy 344.061958 -395.242173)
			(xy 344.081608 -395.223238) (xy 344.089056 -395.215745) (xy 344.097597 -395.196451) (xy 344.098118 -395.1859)
			(xy 344.098118 -395.111224) (xy 344.097532 -395.100688) (xy 344.089006 -395.08141) (xy 344.081608 -395.073886)
			(xy 344.061955 -395.054952) (xy 344.028515 -395.01183) (xy 344.00261 -394.963803) (xy 343.98494 -394.912175)
			(xy 343.975987 -394.858346) (xy 343.975436 -394.831062) (xy 343.97569 -394.81887) (xy 343.975944 -394.809218)
			(xy 343.969848 -394.791184) (xy 343.911174 -394.723874) (xy 343.89441 -394.715238) (xy 343.884504 -394.714222)
			(xy 343.857588 -394.710874) (xy 343.805283 -394.696535) (xy 343.75602 -394.67385) (xy 343.71112 -394.643429)
			(xy 343.671788 -394.606086) (xy 343.639078 -394.562825) (xy 343.613868 -394.514805) (xy 343.596834 -394.463314)
			(xy 343.59215 -394.4366) (xy 343.590626 -394.427202) (xy 343.31783 -393.95527) (xy 343.310464 -393.949428)
			(xy 343.300812 -393.9413) (xy 343.29371 -393.935559) (xy 343.276659 -393.929053) (xy 343.267538 -393.9286)
			(xy 342.895682 -393.9286) (xy 342.886788 -393.928928) (xy 342.87007 -393.935006) (xy 342.856454 -393.946451)
			(xy 342.85174 -393.954) (xy 342.844882 -393.965938) (xy 342.844882 -393.992862) (xy 342.919812 -394.122402)
			(xy 342.927178 -394.128244) (xy 342.945957 -394.144047) (xy 342.979092 -394.180254) (xy 343.006515 -394.220958)
			(xy 343.027622 -394.265267) (xy 343.041952 -394.312209) (xy 343.04919 -394.360752) (xy 343.049606 -394.385292)
			(xy 343.049352 -394.397484) (xy 343.049098 -394.407136) (xy 343.055194 -394.42517) (xy 343.113868 -394.49248)
			(xy 343.130632 -394.501116) (xy 343.140284 -394.502132) (xy 343.167053 -394.505457) (xy 343.219083 -394.519679)
			(xy 343.268116 -394.542155) (xy 343.312852 -394.57229) (xy 343.352106 -394.609284) (xy 343.384837 -394.652157)
			(xy 343.410177 -394.699773) (xy 343.427456 -394.750869) (xy 343.436214 -394.804093) (xy 343.436702 -394.831062)
			(xy 343.436139 -394.858344) (xy 343.427175 -394.912166) (xy 343.4095 -394.963788) (xy 343.383593 -395.011809)
			(xy 343.350157 -395.054928) (xy 343.33053 -395.073886) (xy 343.323082 -395.081378) (xy 343.314543 -395.100673)
			(xy 343.31402 -395.111224) (xy 343.31402 -395.1859) (xy 343.314611 -395.196433) (xy 343.323147 -395.2157)
			(xy 343.33053 -395.223238) (xy 343.350185 -395.242171) (xy 343.383627 -395.285291) (xy 343.409535 -395.333318)
			(xy 343.427204 -395.384947) (xy 343.436155 -395.438777) (xy 343.436702 -395.466062) (xy 343.436269 -395.49018)
			(xy 343.429273 -395.537905) (xy 343.415425 -395.584109) (xy 343.395017 -395.627814) (xy 343.382092 -395.64818)
			(xy 343.37625 -395.65707) (xy 343.372694 -395.677136) (xy 343.393776 -395.769338) (xy 343.405968 -395.786102)
			(xy 343.414858 -395.791436) (xy 343.435658 -395.804292) (xy 343.473572 -395.835172) (xy 343.506519 -395.871303)
			(xy 343.533779 -395.911897) (xy 343.554757 -395.956067) (xy 343.568994 -396.002846) (xy 343.576179 -396.051213)
			(xy 343.576656 -396.075662) (xy 343.576218 -396.100033) (xy 343.569063 -396.148246) (xy 343.554915 -396.194889)
			(xy 343.534081 -396.238954) (xy 343.507011 -396.279487) (xy 343.47429 -396.315613) (xy 343.455752 -396.33144)
			(xy 343.446862 -396.338552) (xy 343.437464 -396.35811) (xy 343.43467 -396.457424) (xy 343.443306 -396.47749)
			(xy 343.451688 -396.48511) (xy 343.47011 -396.502598) (xy 343.501453 -396.542565) (xy 343.525751 -396.587168)
			(xy 343.542334 -396.635176) (xy 343.550744 -396.685266) (xy 343.551256 -396.710662) (xy 343.551165 -396.721944)
			(xy 343.549512 -396.744446) (xy 343.547954 -396.75562) (xy 343.546684 -396.76451) (xy 343.55024 -396.782036)
			(xy 343.593674 -396.852902) (xy 343.60739 -396.864078) (xy 343.616026 -396.866872) (xy 343.638267 -396.874813)
			(xy 343.680181 -396.89657) (xy 343.718247 -396.924519) (xy 343.751557 -396.957994) (xy 343.779319 -396.996196)
			(xy 343.790524 -397.016986) (xy 343.791032 -397.018002) (xy 344.183462 -397.696944) (xy 344.196244 -397.720295)
			(xy 344.214434 -397.770318) (xy 344.223717 -397.822731) (xy 344.224356 -397.849344) (xy 344.223906 -397.873349)
			(xy 344.216386 -397.920766) (xy 344.201538 -397.966423) (xy 344.179729 -398.009193) (xy 344.151496 -398.048024)
			(xy 344.117534 -398.081959) (xy 344.07868 -398.11016) (xy 344.035892 -398.131934) (xy 343.990223 -398.146744)
			(xy 343.942799 -398.154225) (xy 343.918794 -398.154652) (xy 343.895266 -398.154209) (xy 343.848771 -398.146972)
			(xy 343.803937 -398.132685) (xy 343.761826 -398.111688) (xy 343.723436 -398.084477) (xy 343.689677 -398.051697)
			(xy 343.661348 -398.014125) (xy 343.649808 -397.993616) (xy 343.649554 -397.993108) (xy 343.649046 -397.992346)
			(xy 343.251282 -397.304006) (xy 343.239383 -397.281338) (xy 343.222506 -397.233007) (xy 343.213944 -397.182536)
			(xy 343.213436 -397.15694) (xy 343.213436 -397.156432) (xy 343.21352 -397.145087) (xy 343.215176 -397.122457)
			(xy 343.216738 -397.11122) (xy 343.218008 -397.10233) (xy 343.214452 -397.085058) (xy 343.171018 -397.013938)
			(xy 343.157048 -397.003016) (xy 343.148666 -396.999968) (xy 343.126264 -396.991948) (xy 343.08407 -396.969961)
			(xy 343.045795 -396.941696) (xy 343.012367 -396.907839) (xy 342.984593 -396.869207) (xy 342.963146 -396.826735)
			(xy 342.948544 -396.781452) (xy 342.941141 -396.734451) (xy 342.94064 -396.710662) (xy 342.94114 -396.685264)
			(xy 342.949541 -396.635169) (xy 342.96612 -396.587156) (xy 342.99042 -396.54255) (xy 343.021771 -396.502584)
			(xy 343.040208 -396.48511) (xy 343.04859 -396.47749) (xy 343.057226 -396.457424) (xy 343.054432 -396.35811)
			(xy 343.045034 -396.338552) (xy 343.036144 -396.33144) (xy 343.017581 -396.315639) (xy 342.98485 -396.279514)
			(xy 342.957773 -396.238978) (xy 342.936938 -396.194907) (xy 342.922793 -396.148257) (xy 342.915647 -396.100036)
			(xy 342.91524 -396.075662) (xy 342.915679 -396.051546) (xy 342.922685 -396.003826) (xy 342.936544 -395.957629)
			(xy 342.956962 -395.913932) (xy 342.96985 -395.893544) (xy 342.975692 -395.884654) (xy 342.979248 -395.864588)
			(xy 342.958166 -395.772386) (xy 342.945974 -395.755622) (xy 342.937084 -395.750288) (xy 342.91628 -395.737434)
			(xy 342.87836 -395.706557) (xy 342.845406 -395.670427) (xy 342.818139 -395.629834) (xy 342.797155 -395.585664)
			(xy 342.782913 -395.538882) (xy 342.775723 -395.490513) (xy 342.775286 -395.466062) (xy 342.775847 -395.438779)
			(xy 342.784808 -395.384955) (xy 342.802479 -395.33333) (xy 342.828383 -395.285305) (xy 342.861817 -395.242182)
			(xy 342.881458 -395.223238) (xy 342.888912 -395.215748) (xy 342.897462 -395.196453) (xy 342.897968 -395.1859)
			(xy 342.897968 -395.111224) (xy 342.897381 -395.10069) (xy 342.888849 -395.081417) (xy 342.881458 -395.073886)
			(xy 342.861802 -395.054954) (xy 342.828358 -395.011833) (xy 342.802448 -394.963807) (xy 342.784776 -394.912177)
			(xy 342.775822 -394.858347) (xy 342.775286 -394.831062) (xy 342.77554 -394.81887) (xy 342.775794 -394.809218)
			(xy 342.769698 -394.791184) (xy 342.711024 -394.723874) (xy 342.69426 -394.715238) (xy 342.684608 -394.714222)
			(xy 342.657692 -394.710875) (xy 342.605386 -394.696535) (xy 342.556123 -394.673851) (xy 342.511222 -394.64343)
			(xy 342.471889 -394.606088) (xy 342.439179 -394.562826) (xy 342.413969 -394.514806) (xy 342.396935 -394.463315)
			(xy 342.392254 -394.4366) (xy 342.39073 -394.427202) (xy 342.117934 -393.95527) (xy 342.110568 -393.949428)
			(xy 342.100916 -393.9413) (xy 342.093814 -393.935559) (xy 342.076763 -393.929051) (xy 342.067642 -393.9286)
			(xy 341.695532 -393.9286) (xy 341.686642 -393.928937) (xy 341.669938 -393.935025) (xy 341.656335 -393.946474)
			(xy 341.65159 -393.954) (xy 341.644732 -393.965938) (xy 341.644732 -393.992862) (xy 341.719662 -394.122402)
			(xy 341.727028 -394.128244) (xy 341.745805 -394.144049) (xy 341.778935 -394.180257) (xy 341.806353 -394.220962)
			(xy 341.827457 -394.265271) (xy 341.841785 -394.312211) (xy 341.849021 -394.360753) (xy 341.849456 -394.385292)
			(xy 341.849202 -394.397484) (xy 341.848948 -394.407136) (xy 341.855044 -394.42517) (xy 341.913718 -394.49248)
			(xy 341.930482 -394.501116) (xy 341.940388 -394.502132) (xy 341.967157 -394.505457) (xy 342.019186 -394.51968)
			(xy 342.068219 -394.542156) (xy 342.112955 -394.572291) (xy 342.152208 -394.609285) (xy 342.184938 -394.652158)
			(xy 342.210278 -394.699774) (xy 342.227556 -394.75087) (xy 342.236314 -394.804093) (xy 342.236806 -394.831062)
			(xy 342.236339 -394.855259) (xy 342.229243 -394.903132) (xy 342.215255 -394.949463) (xy 342.194674 -394.993265)
			(xy 342.181688 -395.013688) (xy 342.176937 -395.021658) (xy 342.172916 -395.039757) (xy 342.173814 -395.048994)
			(xy 342.178132 -395.079982) (xy 342.179938 -395.089234) (xy 342.189199 -395.105634) (xy 342.196166 -395.111986)
			(xy 342.218264 -395.130659) (xy 342.258043 -395.172667) (xy 342.29221 -395.219354) (xy 342.320219 -395.269976)
			(xy 342.341625 -395.323724) (xy 342.356085 -395.379741) (xy 342.36337 -395.437135) (xy 342.363806 -395.466062)
			(xy 342.363202 -395.499382) (xy 342.353533 -395.565317) (xy 342.334409 -395.629154) (xy 342.32088 -395.65961)
			(xy 342.316617 -395.670079) (xy 342.316691 -395.692653) (xy 342.326448 -395.713009) (xy 342.33485 -395.72057)
			(xy 342.357096 -395.739245) (xy 342.397159 -395.781301) (xy 342.431579 -395.828088) (xy 342.459804 -395.878852)
			(xy 342.481381 -395.93278) (xy 342.495963 -395.989003) (xy 342.503315 -396.04662) (xy 342.50376 -396.075662)
			(xy 342.503309 -396.104666) (xy 342.495978 -396.162208) (xy 342.48144 -396.218364) (xy 342.459929 -396.272235)
			(xy 342.431789 -396.32296) (xy 342.397469 -396.369725) (xy 342.35752 -396.411784) (xy 342.335358 -396.4305)
			(xy 342.328246 -396.436088) (xy 342.319102 -396.451328) (xy 342.303862 -396.534132) (xy 342.306656 -396.551404)
			(xy 342.311228 -396.559532) (xy 342.323824 -396.58271) (xy 342.341715 -396.63233) (xy 342.350799 -396.684289)
			(xy 342.35136 -396.710662) (xy 342.351269 -396.721944) (xy 342.349616 -396.744446) (xy 342.348058 -396.75562)
			(xy 342.346788 -396.76451) (xy 342.350344 -396.782036) (xy 342.393778 -396.852902) (xy 342.407494 -396.864078)
			(xy 342.41613 -396.866872) (xy 342.438371 -396.874813) (xy 342.480284 -396.896571) (xy 342.51835 -396.92452)
			(xy 342.55166 -396.957995) (xy 342.579421 -396.996197) (xy 342.590628 -397.016986) (xy 342.591136 -397.018002)
			(xy 342.983566 -397.696944) (xy 342.996348 -397.720295) (xy 343.014538 -397.770318) (xy 343.02382 -397.822731)
			(xy 343.02446 -397.849344) (xy 343.024009 -397.873346) (xy 343.016489 -397.920758) (xy 343.001641 -397.966408)
			(xy 342.97983 -398.009172) (xy 342.951595 -398.047995) (xy 342.917631 -398.08192) (xy 342.878777 -398.110111)
			(xy 342.835988 -398.131873) (xy 342.790321 -398.14667) (xy 342.742901 -398.154137) (xy 342.718898 -398.154652)
			(xy 342.69537 -398.154209) (xy 342.648874 -398.146973) (xy 342.60404 -398.132687) (xy 342.561929 -398.111689)
			(xy 342.523538 -398.084479) (xy 342.489779 -398.051699) (xy 342.461449 -398.014126) (xy 342.449912 -397.993616)
			(xy 342.449658 -397.993108) (xy 342.44915 -397.992346) (xy 342.051386 -397.304006) (xy 342.039487 -397.281338)
			(xy 342.02261 -397.233007) (xy 342.014048 -397.182536) (xy 342.01354 -397.15694) (xy 342.01354 -397.156432)
			(xy 342.013624 -397.145087) (xy 342.01528 -397.122457) (xy 342.016842 -397.11122) (xy 342.018112 -397.10233)
			(xy 342.014556 -397.085058) (xy 341.971122 -397.013938) (xy 341.957152 -397.003016) (xy 341.94877 -396.999968)
			(xy 341.926368 -396.991948) (xy 341.884173 -396.969961) (xy 341.845898 -396.941697) (xy 341.812469 -396.907839)
			(xy 341.784695 -396.869207) (xy 341.763247 -396.826736) (xy 341.748645 -396.781452) (xy 341.741242 -396.734452)
			(xy 341.740744 -396.710662) (xy 341.741326 -396.684291) (xy 341.750427 -396.63234) (xy 341.768302 -396.582719)
			(xy 341.780876 -396.559532) (xy 341.785448 -396.551404) (xy 341.788242 -396.534132) (xy 341.773002 -396.451328)
			(xy 341.763858 -396.436088) (xy 341.756746 -396.4305) (xy 341.734557 -396.411815) (xy 341.694606 -396.369755)
			(xy 341.660289 -396.322985) (xy 341.632155 -396.272255) (xy 341.610655 -396.218376) (xy 341.596133 -396.162214)
			(xy 341.588822 -396.104667) (xy 341.588344 -396.075662) (xy 341.588947 -396.042342) (xy 341.598613 -395.976406)
			(xy 341.617736 -395.912568) (xy 341.63127 -395.882114) (xy 341.635536 -395.871643) (xy 341.635469 -395.849062)
			(xy 341.625724 -395.828692) (xy 341.6173 -395.821154) (xy 341.595055 -395.802479) (xy 341.554996 -395.760423)
			(xy 341.520579 -395.713636) (xy 341.492359 -395.66287) (xy 341.470788 -395.608942) (xy 341.456214 -395.552719)
			(xy 341.44887 -395.495103) (xy 341.44839 -395.466062) (xy 341.448835 -395.437136) (xy 341.456128 -395.379746)
			(xy 341.470593 -395.323732) (xy 341.492 -395.269987) (xy 341.520007 -395.219367) (xy 341.554169 -395.172679)
			(xy 341.59394 -395.130666) (xy 341.61603 -395.111986) (xy 341.623105 -395.105722) (xy 341.632393 -395.089281)
			(xy 341.634064 -395.079982) (xy 341.638382 -395.048994) (xy 341.63933 -395.039756) (xy 341.635295 -395.021646)
			(xy 341.630508 -395.013688) (xy 341.617475 -394.99329) (xy 341.596876 -394.949488) (xy 341.58289 -394.903149)
			(xy 341.575817 -394.855264) (xy 341.57539 -394.831062) (xy 341.575644 -394.81887) (xy 341.575898 -394.809218)
			(xy 341.569802 -394.791184) (xy 341.511128 -394.723874) (xy 341.494364 -394.715238) (xy 341.484458 -394.714222)
			(xy 341.457545 -394.710871) (xy 341.405245 -394.696526) (xy 341.355988 -394.673837) (xy 341.311095 -394.643414)
			(xy 341.271768 -394.606072) (xy 341.239064 -394.562812) (xy 341.213858 -394.514794) (xy 341.196827 -394.463306)
			(xy 341.192104 -394.4366) (xy 341.19058 -394.427202) (xy 340.917784 -393.95527) (xy 340.910418 -393.949428)
			(xy 340.900766 -393.9413) (xy 340.893666 -393.935551) (xy 340.876616 -393.929027) (xy 340.867492 -393.9286)
			(xy 340.495636 -393.9286) (xy 340.486746 -393.928936) (xy 340.47004 -393.935023) (xy 340.456437 -393.946472)
			(xy 340.451694 -393.954) (xy 340.444836 -393.965938) (xy 340.444836 -393.992862) (xy 340.519766 -394.122402)
			(xy 340.527132 -394.128244) (xy 340.545909 -394.144049) (xy 340.579038 -394.180258) (xy 340.606456 -394.220963)
			(xy 340.62756 -394.265271) (xy 340.641888 -394.312211) (xy 340.649124 -394.360753) (xy 340.64956 -394.385292)
			(xy 340.649306 -394.397484) (xy 340.649052 -394.407136) (xy 340.655148 -394.42517) (xy 340.713822 -394.49248)
			(xy 340.730586 -394.501116) (xy 340.740238 -394.502132) (xy 340.76701 -394.505454) (xy 340.819046 -394.519671)
			(xy 340.868085 -394.542143) (xy 340.912828 -394.572276) (xy 340.952087 -394.60927) (xy 340.984823 -394.652144)
			(xy 341.010168 -394.699763) (xy 341.027449 -394.750863) (xy 341.036209 -394.80409) (xy 341.036656 -394.831062)
			(xy 341.036146 -394.857049) (xy 341.028016 -394.908384) (xy 341.011955 -394.957814) (xy 340.988359 -395.004124)
			(xy 340.957809 -395.046172) (xy 340.921058 -395.082923) (xy 340.87901 -395.113473) (xy 340.8327 -395.137069)
			(xy 340.78327 -395.15313) (xy 340.731935 -395.16126) (xy 340.679961 -395.16126) (xy 340.628626 -395.15313)
			(xy 340.579196 -395.137069) (xy 340.532886 -395.113473) (xy 340.490838 -395.082923) (xy 340.454087 -395.046172)
			(xy 340.423537 -395.004124) (xy 340.399941 -394.957814) (xy 340.38388 -394.908384) (xy 340.37575 -394.857049)
			(xy 340.37524 -394.831062) (xy 340.375494 -394.81887) (xy 340.375748 -394.809218) (xy 340.369652 -394.791184)
			(xy 340.310978 -394.723874) (xy 340.294214 -394.715238) (xy 340.284562 -394.714222) (xy 340.257649 -394.710871)
			(xy 340.205349 -394.696527) (xy 340.156091 -394.673839) (xy 340.111197 -394.643415) (xy 340.07187 -394.606073)
			(xy 340.039165 -394.562813) (xy 340.013959 -394.514795) (xy 339.996928 -394.463307) (xy 339.992208 -394.4366)
			(xy 339.990684 -394.427202) (xy 339.717888 -393.95527) (xy 339.710522 -393.949428) (xy 339.70087 -393.9413)
			(xy 339.69377 -393.935551) (xy 339.67672 -393.929025) (xy 339.667596 -393.9286) (xy 339.29574 -393.9286)
			(xy 339.286849 -393.928935) (xy 339.270143 -393.935022) (xy 339.256538 -393.94647) (xy 339.251798 -393.954)
			(xy 339.24494 -393.965938) (xy 339.24494 -393.992862) (xy 339.320124 -394.12291) (xy 339.327236 -394.128752)
			(xy 339.345965 -394.144533) (xy 339.379011 -394.180679) (xy 339.40636 -394.221306) (xy 339.427415 -394.265525)
			(xy 339.441713 -394.312366) (xy 339.448941 -394.360805) (xy 339.44941 -394.385292) (xy 339.449156 -394.397484)
			(xy 339.448902 -394.407136) (xy 339.454998 -394.42517) (xy 339.513672 -394.49248) (xy 339.530436 -394.501116)
			(xy 339.540342 -394.502132) (xy 339.567113 -394.505454) (xy 339.619149 -394.519671) (xy 339.668188 -394.542144)
			(xy 339.71293 -394.572277) (xy 339.752189 -394.609271) (xy 339.784925 -394.652145) (xy 339.810269 -394.699764)
			(xy 339.82755 -394.750864) (xy 339.83631 -394.804091) (xy 339.83676 -394.831062) (xy 339.836197 -394.858344)
			(xy 339.827234 -394.912168) (xy 339.809562 -394.963791) (xy 339.783658 -395.011816) (xy 339.750226 -395.054939)
			(xy 339.730588 -395.073886) (xy 339.723145 -395.08138) (xy 339.714613 -395.100675) (xy 339.714078 -395.111224)
			(xy 339.714078 -395.1859) (xy 339.714668 -395.196434) (xy 339.723199 -395.215706) (xy 339.730588 -395.223238)
			(xy 339.75024 -395.242172) (xy 339.783677 -395.285295) (xy 339.809579 -395.333322) (xy 339.827245 -395.38495)
			(xy 339.836194 -395.438778) (xy 339.83676 -395.466062) (xy 339.836327 -395.490179) (xy 339.82933 -395.537904)
			(xy 339.81548 -395.584107) (xy 339.79507 -395.627811) (xy 339.78215 -395.64818) (xy 339.776308 -395.65707)
			(xy 339.772752 -395.677136) (xy 339.793834 -395.769338) (xy 339.806026 -395.786102) (xy 339.814916 -395.791436)
			(xy 339.835719 -395.804291) (xy 339.873637 -395.835168) (xy 339.906588 -395.871298) (xy 339.933852 -395.911892)
			(xy 339.954833 -395.956062) (xy 339.969072 -396.002843) (xy 339.976258 -396.051212) (xy 339.976714 -396.075662)
			(xy 339.976276 -396.100032) (xy 339.96912 -396.148245) (xy 339.954971 -396.194887) (xy 339.934135 -396.238949)
			(xy 339.907063 -396.27948) (xy 339.87434 -396.315603) (xy 339.85581 -396.33144) (xy 339.84692 -396.338552)
			(xy 339.837522 -396.35811) (xy 339.834728 -396.457424) (xy 339.843364 -396.47749) (xy 339.851746 -396.48511)
			(xy 339.870165 -396.502599) (xy 339.901503 -396.542569) (xy 339.925796 -396.587171) (xy 339.942375 -396.635179)
			(xy 339.950784 -396.685267) (xy 339.951314 -396.710662) (xy 340.540594 -396.710662) (xy 340.541116 -396.685407)
			(xy 340.549429 -396.635585) (xy 340.56583 -396.587811) (xy 340.589871 -396.543388) (xy 340.620895 -396.503528)
			(xy 340.658057 -396.469318) (xy 340.700343 -396.441692) (xy 340.746599 -396.421402) (xy 340.795564 -396.409002)
			(xy 340.845902 -396.404831) (xy 340.89624 -396.409002) (xy 340.945205 -396.421402) (xy 340.991461 -396.441692)
			(xy 341.033747 -396.469318) (xy 341.070909 -396.503528) (xy 341.101933 -396.543388) (xy 341.125974 -396.587811)
			(xy 341.142375 -396.635585) (xy 341.150688 -396.685407) (xy 341.15121 -396.710662) (xy 341.151106 -396.721943)
			(xy 341.149455 -396.744445) (xy 341.147908 -396.75562) (xy 341.146638 -396.76451) (xy 341.150194 -396.782036)
			(xy 341.193628 -396.852902) (xy 341.207344 -396.864078) (xy 341.21598 -396.866872) (xy 341.23823 -396.874796)
			(xy 341.28015 -396.89655) (xy 341.318223 -396.924497) (xy 341.35154 -396.957972) (xy 341.379308 -396.996176)
			(xy 341.390478 -397.016986) (xy 341.390986 -397.018002) (xy 341.783416 -397.696944) (xy 341.79615 -397.720309)
			(xy 341.814265 -397.770337) (xy 341.823474 -397.822741) (xy 341.824056 -397.849344) (xy 341.823578 -397.873334)
			(xy 341.816067 -397.920723) (xy 341.801236 -397.966353) (xy 341.779452 -398.009103) (xy 341.751249 -398.047919)
			(xy 341.717322 -398.081846) (xy 341.678506 -398.11005) (xy 341.635757 -398.131835) (xy 341.590127 -398.146666)
			(xy 341.542738 -398.154178) (xy 341.518748 -398.154652) (xy 341.495216 -398.154211) (xy 341.448708 -398.147002)
			(xy 341.40386 -398.132734) (xy 341.361736 -398.111744) (xy 341.323337 -398.084532) (xy 341.289576 -398.051743)
			(xy 341.261253 -398.014156) (xy 341.249762 -397.993616) (xy 341.249508 -397.993108) (xy 341.249 -397.992346)
			(xy 340.851236 -397.304006) (xy 340.839323 -397.281336) (xy 340.822384 -397.233012) (xy 340.813724 -397.182542)
			(xy 340.813136 -397.15694) (xy 340.813136 -397.156432) (xy 340.813293 -397.145083) (xy 340.81507 -397.122453)
			(xy 340.816692 -397.11122) (xy 340.817962 -397.10233) (xy 340.814406 -397.085058) (xy 340.770972 -397.013938)
			(xy 340.757002 -397.003016) (xy 340.74862 -396.999968) (xy 340.726213 -396.991948) (xy 340.683995 -396.969986)
			(xy 340.645699 -396.941735) (xy 340.612254 -396.907882) (xy 340.584471 -396.869246) (xy 340.563022 -396.826765)
			(xy 340.54843 -396.781469) (xy 340.541047 -396.734456) (xy 340.540594 -396.710662) (xy 339.951314 -396.710662)
			(xy 339.951223 -396.721944) (xy 339.94957 -396.744446) (xy 339.948012 -396.75562) (xy 339.946742 -396.76451)
			(xy 339.950298 -396.782036) (xy 339.993732 -396.852902) (xy 340.007448 -396.864078) (xy 340.016084 -396.866872)
			(xy 340.038327 -396.874811) (xy 340.080245 -396.896564) (xy 340.118315 -396.92451) (xy 340.15163 -396.957983)
			(xy 340.179396 -396.996185) (xy 340.190582 -397.016986) (xy 340.19109 -397.018002) (xy 340.58352 -397.696944)
			(xy 340.596327 -397.720277) (xy 340.614476 -397.770309) (xy 340.62366 -397.822732) (xy 340.62416 -397.849344)
			(xy 340.62371 -397.873334) (xy 340.616198 -397.920721) (xy 340.601365 -397.96635) (xy 340.579577 -398.009096)
			(xy 340.551369 -398.047908) (xy 340.517438 -398.081829) (xy 340.478618 -398.110025) (xy 340.435864 -398.1318)
			(xy 340.390231 -398.14662) (xy 340.342842 -398.154118) (xy 340.318852 -398.154652) (xy 340.295322 -398.154213)
			(xy 340.248821 -398.146984) (xy 340.203981 -398.132703) (xy 340.161863 -398.11171) (xy 340.123466 -398.084501)
			(xy 340.0897 -398.051723) (xy 340.061364 -398.01415) (xy 340.049866 -397.993616) (xy 340.049612 -397.993108)
			(xy 340.049104 -397.992346) (xy 339.65134 -397.304006) (xy 339.639408 -397.281345) (xy 339.62246 -397.23302)
			(xy 339.613819 -397.182544) (xy 339.61324 -397.15694) (xy 339.61324 -397.156432) (xy 339.613391 -397.145083)
			(xy 339.615172 -397.122453) (xy 339.616796 -397.11122) (xy 339.618066 -397.10233) (xy 339.61451 -397.085058)
			(xy 339.571076 -397.013938) (xy 339.557106 -397.003016) (xy 339.548724 -396.999968) (xy 339.526319 -396.991951)
			(xy 339.484118 -396.969969) (xy 339.445836 -396.941707) (xy 339.412401 -396.90785) (xy 339.384621 -396.869218)
			(xy 339.36317 -396.826744) (xy 339.348564 -396.781457) (xy 339.34116 -396.734454) (xy 339.340698 -396.710662)
			(xy 339.341198 -396.685264) (xy 339.349598 -396.635167) (xy 339.366175 -396.587153) (xy 339.390473 -396.542545)
			(xy 339.421821 -396.502576) (xy 339.440266 -396.48511) (xy 339.448648 -396.47749) (xy 339.457284 -396.457424)
			(xy 339.45449 -396.35811) (xy 339.445092 -396.338552) (xy 339.436202 -396.33144) (xy 339.417641 -396.315638)
			(xy 339.384914 -396.279511) (xy 339.357841 -396.238974) (xy 339.337008 -396.194904) (xy 339.322865 -396.148255)
			(xy 339.31572 -396.100035) (xy 339.315298 -396.075662) (xy 339.315737 -396.051546) (xy 339.322742 -396.003826)
			(xy 339.3366 -395.957627) (xy 339.357015 -395.913929) (xy 339.369908 -395.893544) (xy 339.37575 -395.884654)
			(xy 339.379306 -395.864588) (xy 339.358224 -395.772386) (xy 339.346032 -395.755622) (xy 339.337142 -395.750288)
			(xy 339.31634 -395.737432) (xy 339.278424 -395.706553) (xy 339.245475 -395.670422) (xy 339.218212 -395.629829)
			(xy 339.197231 -395.585659) (xy 339.18299 -395.53888) (xy 339.175802 -395.490512) (xy 339.175344 -395.466062)
			(xy 339.175905 -395.438779) (xy 339.184865 -395.384953) (xy 339.202535 -395.333327) (xy 339.228436 -395.285301)
			(xy 339.261867 -395.242175) (xy 339.281516 -395.223238) (xy 339.288963 -395.215745) (xy 339.297503 -395.19645)
			(xy 339.298026 -395.1859) (xy 339.298026 -395.111224) (xy 339.297441 -395.100688) (xy 339.288916 -395.081409)
			(xy 339.281516 -395.073886) (xy 339.261862 -395.054952) (xy 339.228422 -395.011831) (xy 339.202516 -394.963804)
			(xy 339.184846 -394.912175) (xy 339.175893 -394.858346) (xy 339.175344 -394.831062) (xy 339.175598 -394.81887)
			(xy 339.175852 -394.809218) (xy 339.169756 -394.791184) (xy 339.111082 -394.723874) (xy 339.094318 -394.715238)
			(xy 339.084412 -394.714222) (xy 339.057462 -394.710857) (xy 339.005094 -394.696475) (xy 338.955777 -394.673737)
			(xy 338.910832 -394.643253) (xy 338.871466 -394.605842) (xy 338.838735 -394.562508) (xy 338.813516 -394.514411)
			(xy 338.796487 -394.462843) (xy 338.791804 -394.436092) (xy 338.790534 -394.426694) (xy 338.517992 -393.95527)
			(xy 338.510626 -393.949428) (xy 338.500974 -393.9413) (xy 338.493875 -393.93555) (xy 338.476825 -393.929023)
			(xy 338.4677 -393.9286) (xy 338.09559 -393.9286) (xy 338.086695 -393.928927) (xy 338.069976 -393.935003)
			(xy 338.056357 -393.946448) (xy 338.051648 -393.954) (xy 338.04479 -393.965938) (xy 338.04479 -393.992862)
			(xy 338.11972 -394.122402) (xy 338.127086 -394.128244) (xy 338.145865 -394.144048) (xy 338.178999 -394.180254)
			(xy 338.206421 -394.220959) (xy 338.227528 -394.265268) (xy 338.241857 -394.312209) (xy 338.249095 -394.360752)
			(xy 338.249514 -394.385292) (xy 338.24926 -394.397484) (xy 338.249006 -394.407136) (xy 338.255102 -394.42517)
			(xy 338.313776 -394.49248) (xy 338.33054 -394.501116) (xy 338.340446 -394.502132) (xy 338.367217 -394.505454)
			(xy 338.419252 -394.519672) (xy 338.46829 -394.542145) (xy 338.513032 -394.572278) (xy 338.552291 -394.609272)
			(xy 338.585026 -394.652147) (xy 338.61037 -394.699765) (xy 338.62765 -394.750864) (xy 338.63641 -394.804091)
			(xy 338.636864 -394.831062) (xy 338.636301 -394.858344) (xy 338.627338 -394.912168) (xy 338.609666 -394.963792)
			(xy 338.583763 -395.011816) (xy 338.550331 -395.05494) (xy 338.530692 -395.073886) (xy 338.523248 -395.08138)
			(xy 338.514716 -395.100675) (xy 338.514182 -395.111224) (xy 338.514182 -395.1859) (xy 338.514772 -395.196434)
			(xy 338.523304 -395.215705) (xy 338.530692 -395.223238) (xy 338.550344 -395.242172) (xy 338.58378 -395.285295)
			(xy 338.609682 -395.333322) (xy 338.627348 -395.38495) (xy 338.636297 -395.438778) (xy 338.636864 -395.466062)
			(xy 338.636431 -395.490179) (xy 338.629434 -395.537904) (xy 338.615584 -395.584108) (xy 338.595174 -395.627811)
			(xy 338.582254 -395.64818) (xy 338.576412 -395.65707) (xy 338.572856 -395.677136) (xy 338.593938 -395.769338)
			(xy 338.60613 -395.786102) (xy 338.61502 -395.791436) (xy 338.635822 -395.804291) (xy 338.67374 -395.835168)
			(xy 338.706691 -395.871299) (xy 338.733954 -395.911893) (xy 338.754935 -395.956063) (xy 338.769174 -396.002843)
			(xy 338.77636 -396.051212) (xy 338.776818 -396.075662) (xy 338.77638 -396.100032) (xy 338.769224 -396.148245)
			(xy 338.755075 -396.194887) (xy 338.734239 -396.23895) (xy 338.707167 -396.279481) (xy 338.674444 -396.315604)
			(xy 338.655914 -396.33144) (xy 338.647024 -396.338552) (xy 338.637626 -396.35811) (xy 338.634832 -396.457424)
			(xy 338.643468 -396.47749) (xy 338.65185 -396.48511) (xy 338.670269 -396.502599) (xy 338.701606 -396.542569)
			(xy 338.725899 -396.587172) (xy 338.742478 -396.635179) (xy 338.750886 -396.685267) (xy 338.751418 -396.710662)
			(xy 338.751327 -396.721944) (xy 338.749674 -396.744446) (xy 338.748116 -396.75562) (xy 338.746846 -396.764764)
			(xy 338.750148 -396.782036) (xy 338.793836 -396.853156) (xy 338.807552 -396.864078) (xy 338.816188 -396.866872)
			(xy 338.844318 -396.877145) (xy 338.896248 -396.906952) (xy 338.919312 -396.926054) (xy 338.940758 -396.94567)
			(xy 338.97656 -396.991446) (xy 338.990432 -397.016986) (xy 338.991194 -397.018256) (xy 339.38337 -397.696944)
			(xy 339.396152 -397.720295) (xy 339.414341 -397.770319) (xy 339.423624 -397.822731) (xy 339.424264 -397.849344)
			(xy 339.423813 -397.873346) (xy 339.416293 -397.920758) (xy 339.401445 -397.966409) (xy 339.379634 -398.009173)
			(xy 339.351399 -398.047996) (xy 339.317436 -398.081922) (xy 339.278581 -398.110113) (xy 339.235793 -398.131876)
			(xy 339.190125 -398.146673) (xy 339.142705 -398.15414) (xy 339.118702 -398.154652) (xy 339.095174 -398.15421)
			(xy 339.048678 -398.146974) (xy 339.003843 -398.132688) (xy 338.961731 -398.111691) (xy 338.92334 -398.08448)
			(xy 338.88958 -398.051701) (xy 338.86125 -398.014128) (xy 338.849716 -397.993616) (xy 338.849462 -397.993108)
			(xy 338.848954 -397.992346) (xy 338.448396 -397.298926) (xy 338.437328 -397.276825) (xy 338.421691 -397.229938)
			(xy 338.413799 -397.181146) (xy 338.413344 -397.156432) (xy 338.413428 -397.145087) (xy 338.415084 -397.122457)
			(xy 338.416646 -397.11122) (xy 338.417916 -397.10233) (xy 338.41436 -397.085058) (xy 338.370926 -397.013938)
			(xy 338.35721 -397.002762) (xy 338.348574 -396.999968) (xy 338.326185 -396.99194) (xy 338.284019 -396.96994)
			(xy 338.245774 -396.941666) (xy 338.212378 -396.907803) (xy 338.184637 -396.869171) (xy 338.163224 -396.826703)
			(xy 338.148656 -396.781429) (xy 338.141285 -396.734442) (xy 338.140802 -396.710662) (xy 338.141302 -396.685264)
			(xy 338.149702 -396.635168) (xy 338.166279 -396.587153) (xy 338.190578 -396.542546) (xy 338.221926 -396.502577)
			(xy 338.24037 -396.48511) (xy 338.248752 -396.47749) (xy 338.257388 -396.457424) (xy 338.254594 -396.35811)
			(xy 338.245196 -396.338552) (xy 338.236306 -396.33144) (xy 338.217745 -396.315638) (xy 338.185017 -396.279511)
			(xy 338.157944 -396.238974) (xy 338.137111 -396.194904) (xy 338.122968 -396.148255) (xy 338.115822 -396.100035)
			(xy 338.115402 -396.075662) (xy 338.115841 -396.051546) (xy 338.122846 -396.003826) (xy 338.136704 -395.957627)
			(xy 338.15712 -395.91393) (xy 338.170012 -395.893544) (xy 338.175854 -395.884654) (xy 338.17941 -395.864588)
			(xy 338.158328 -395.772386) (xy 338.146136 -395.755622) (xy 338.137246 -395.750288) (xy 338.116444 -395.737432)
			(xy 338.078528 -395.706554) (xy 338.045578 -395.670423) (xy 338.018314 -395.629829) (xy 337.997333 -395.58566)
			(xy 337.983092 -395.53888) (xy 337.975904 -395.490512) (xy 337.975448 -395.466062) (xy 337.976009 -395.438779)
			(xy 337.984969 -395.384953) (xy 338.002639 -395.333328) (xy 338.028541 -395.285301) (xy 338.061972 -395.242175)
			(xy 338.08162 -395.223238) (xy 338.089066 -395.215745) (xy 338.097606 -395.19645) (xy 338.09813 -395.1859)
			(xy 338.09813 -395.111224) (xy 338.097545 -395.100688) (xy 338.08902 -395.081408) (xy 338.08162 -395.073886)
			(xy 338.061966 -395.054953) (xy 338.028526 -395.011831) (xy 338.002619 -394.963804) (xy 337.984949 -394.912176)
			(xy 337.975996 -394.858346) (xy 337.975448 -394.831062) (xy 337.975702 -394.81887) (xy 337.975956 -394.809218)
			(xy 337.96986 -394.791184) (xy 337.911186 -394.723874) (xy 337.894422 -394.715238) (xy 337.884516 -394.714222)
			(xy 337.8576 -394.710875) (xy 337.805293 -394.696537) (xy 337.756028 -394.673853) (xy 337.711127 -394.643432)
			(xy 337.671793 -394.60609) (xy 337.639082 -394.562829) (xy 337.613871 -394.514808) (xy 337.596836 -394.463317)
			(xy 337.592162 -394.4366) (xy 337.590638 -394.427202) (xy 337.317842 -393.95527) (xy 337.310476 -393.949428)
			(xy 337.300824 -393.9413) (xy 337.293722 -393.935558) (xy 337.276672 -393.929048) (xy 337.26755 -393.9286)
			(xy 336.939382 -393.9286) (xy 336.929313 -393.929027) (xy 336.910714 -393.936746) (xy 336.903314 -393.943586)
			(xy 336.875882 -393.971018) (xy 336.868349 -393.979292) (xy 336.860662 -394.000277) (xy 336.86263 -394.022539)
			(xy 336.867754 -394.032486) (xy 336.919824 -394.122402) (xy 336.92719 -394.128244) (xy 336.945969 -394.144048)
			(xy 336.979103 -394.180255) (xy 337.006524 -394.220959) (xy 337.027631 -394.265268) (xy 337.04196 -394.312209)
			(xy 337.049197 -394.360752) (xy 337.049618 -394.385292) (xy 337.049364 -394.397484) (xy 337.04911 -394.407136)
			(xy 337.055206 -394.42517) (xy 337.11388 -394.49248) (xy 337.130644 -394.501116) (xy 337.140296 -394.502132)
			(xy 337.167064 -394.505458) (xy 337.219093 -394.519681) (xy 337.268124 -394.542158) (xy 337.312859 -394.572293)
			(xy 337.352111 -394.609287) (xy 337.384841 -394.65216) (xy 337.41018 -394.699775) (xy 337.427457 -394.750871)
			(xy 337.436215 -394.804093) (xy 337.436714 -394.831062) (xy 337.436151 -394.858344) (xy 337.427187 -394.912166)
			(xy 337.409513 -394.963788) (xy 337.383607 -395.01181) (xy 337.350172 -395.05493) (xy 337.330542 -395.073886)
			(xy 337.323092 -395.081377) (xy 337.314551 -395.100673) (xy 337.314032 -395.111224) (xy 337.314032 -395.1859)
			(xy 337.314624 -395.196432) (xy 337.323161 -395.215698) (xy 337.330542 -395.223238) (xy 337.350196 -395.242171)
			(xy 337.383638 -395.285292) (xy 337.409544 -395.333319) (xy 337.427212 -395.384948) (xy 337.436163 -395.438778)
			(xy 337.436714 -395.466062) (xy 337.436281 -395.49018) (xy 337.429285 -395.537905) (xy 337.415437 -395.584109)
			(xy 337.39503 -395.627815) (xy 337.382104 -395.64818) (xy 337.376262 -395.65707) (xy 337.372706 -395.677136)
			(xy 337.393788 -395.769338) (xy 337.40598 -395.786102) (xy 337.41487 -395.791436) (xy 337.43567 -395.804293)
			(xy 337.473582 -395.835173) (xy 337.506528 -395.871305) (xy 337.533787 -395.911899) (xy 337.554764 -395.956068)
			(xy 337.569001 -396.002847) (xy 337.576185 -396.051213) (xy 337.576668 -396.075662) (xy 337.57623 -396.100033)
			(xy 337.569075 -396.148246) (xy 337.554927 -396.19489) (xy 337.534094 -396.238955) (xy 337.507024 -396.279489)
			(xy 337.474305 -396.315616) (xy 337.455764 -396.33144) (xy 337.446874 -396.338552) (xy 337.437476 -396.35811)
			(xy 337.434682 -396.457424) (xy 337.443318 -396.47749) (xy 337.4517 -396.48511) (xy 337.470122 -396.502598)
			(xy 337.501464 -396.542566) (xy 337.52576 -396.587168) (xy 337.542342 -396.635177) (xy 337.550753 -396.685267)
			(xy 337.551268 -396.710662) (xy 337.551177 -396.721944) (xy 337.549524 -396.744446) (xy 337.547966 -396.75562)
			(xy 337.546696 -396.76451) (xy 337.550252 -396.782036) (xy 337.593686 -396.852902) (xy 337.607402 -396.864078)
			(xy 337.616038 -396.866872) (xy 337.638283 -396.874808) (xy 337.680206 -396.896557) (xy 337.718281 -396.9245)
			(xy 337.751601 -396.957972) (xy 337.779372 -396.996173) (xy 337.790536 -397.016986) (xy 337.791044 -397.018002)
			(xy 338.183474 -397.696944) (xy 338.196256 -397.720295) (xy 338.214445 -397.770319) (xy 338.223727 -397.822731)
			(xy 338.224368 -397.849344) (xy 338.223917 -397.873346) (xy 338.216397 -397.920759) (xy 338.201549 -397.96641)
			(xy 338.179738 -398.009174) (xy 338.151503 -398.047997) (xy 338.11754 -398.081923) (xy 338.078685 -398.110115)
			(xy 338.035897 -398.131878) (xy 337.99023 -398.146676) (xy 337.942809 -398.154144) (xy 337.918806 -398.154652)
			(xy 337.895278 -398.15421) (xy 337.848781 -398.146974) (xy 337.803946 -398.132689) (xy 337.761834 -398.111692)
			(xy 337.723443 -398.084482) (xy 337.689682 -398.051702) (xy 337.661352 -398.01413) (xy 337.64982 -397.993616)
			(xy 337.649566 -397.993108) (xy 337.649058 -397.992346) (xy 337.251294 -397.304006) (xy 337.239394 -397.281338)
			(xy 337.222517 -397.233008) (xy 337.213955 -397.182536) (xy 337.213448 -397.15694) (xy 337.213448 -397.156432)
			(xy 337.213532 -397.145087) (xy 337.215188 -397.122457) (xy 337.21675 -397.11122) (xy 337.21802 -397.10233)
			(xy 337.214464 -397.085058) (xy 337.17103 -397.013938) (xy 337.15706 -397.003016) (xy 337.148678 -396.999968)
			(xy 337.126276 -396.991949) (xy 337.08408 -396.969962) (xy 337.045804 -396.941699) (xy 337.012374 -396.907841)
			(xy 336.984599 -396.869209) (xy 336.963151 -396.826737) (xy 336.948548 -396.781453) (xy 336.941145 -396.734452)
			(xy 336.940652 -396.710662) (xy 336.941151 -396.685263) (xy 336.94955 -396.635166) (xy 336.966126 -396.58715)
			(xy 336.990421 -396.54254) (xy 337.021766 -396.502567) (xy 337.04022 -396.48511) (xy 337.048602 -396.47749)
			(xy 337.057238 -396.457424) (xy 337.054444 -396.35811) (xy 337.045046 -396.338552) (xy 337.036156 -396.33144)
			(xy 337.017592 -396.315639) (xy 336.98486 -396.279515) (xy 336.957783 -396.238978) (xy 336.936946 -396.194908)
			(xy 336.922801 -396.148257) (xy 336.915654 -396.100036) (xy 336.915252 -396.075662) (xy 336.915691 -396.051546)
			(xy 336.922697 -396.003827) (xy 336.936557 -395.957629) (xy 336.956975 -395.913933) (xy 336.969862 -395.893544)
			(xy 336.975704 -395.884654) (xy 336.97926 -395.864588) (xy 336.958178 -395.772386) (xy 336.945986 -395.755622)
			(xy 336.937096 -395.750288) (xy 336.916292 -395.737434) (xy 336.87837 -395.706558) (xy 336.845415 -395.670429)
			(xy 336.818147 -395.629835) (xy 336.797162 -395.585665) (xy 336.782919 -395.538883) (xy 336.77573 -395.490513)
			(xy 336.775298 -395.466062) (xy 336.775859 -395.438779) (xy 336.78482 -395.384955) (xy 336.802492 -395.333331)
			(xy 336.828397 -395.285307) (xy 336.861831 -395.242185) (xy 336.88147 -395.223238) (xy 336.888922 -395.215748)
			(xy 336.89747 -395.196452) (xy 336.89798 -395.1859) (xy 336.89798 -395.111224) (xy 336.897393 -395.100689)
			(xy 336.888863 -395.081415) (xy 336.88147 -395.073886) (xy 336.861814 -395.054954) (xy 336.828368 -395.011834)
			(xy 336.802457 -394.963807) (xy 336.784785 -394.912178) (xy 336.77583 -394.858347) (xy 336.775298 -394.831062)
			(xy 336.775552 -394.81887) (xy 336.775806 -394.809218) (xy 336.76971 -394.791184) (xy 336.711036 -394.723874)
			(xy 336.694272 -394.715238) (xy 336.68462 -394.714222) (xy 336.659563 -394.711123) (xy 336.610729 -394.698312)
			(xy 336.564404 -394.67824) (xy 336.52166 -394.651373) (xy 336.502248 -394.635228) (xy 336.490818 -394.625322)
			(xy 336.461608 -394.621004) (xy 336.363818 -394.665708) (xy 336.355162 -394.670132) (xy 336.34176 -394.68419)
			(xy 336.334548 -394.702224) (xy 336.3341 -394.711936) (xy 336.3341 -395.906498) (xy 336.336894 -395.918182)
			(xy 336.339688 -395.92377) (xy 336.351347 -395.947376) (xy 336.36786 -395.997366) (xy 336.37625 -396.049339)
			(xy 336.376772 -396.075662) (xy 336.376241 -396.101984) (xy 336.367856 -396.153957) (xy 336.351339 -396.203945)
			(xy 336.339688 -396.227554) (xy 336.336894 -396.233142) (xy 336.3341 -396.244826) (xy 336.3341 -396.609062)
			(xy 336.33664 -396.616682) (xy 336.343534 -396.639562) (xy 336.350933 -396.68677) (xy 336.351372 -396.710662)
			(xy 336.351281 -396.721944) (xy 336.349628 -396.744446) (xy 336.34807 -396.75562) (xy 336.3468 -396.76451)
			(xy 336.350356 -396.782036) (xy 336.39379 -396.852902) (xy 336.407506 -396.864078) (xy 336.416142 -396.866872)
			(xy 336.438387 -396.874808) (xy 336.480309 -396.896558) (xy 336.518384 -396.924501) (xy 336.551704 -396.957973)
			(xy 336.579474 -396.996174) (xy 336.59064 -397.016986) (xy 336.591148 -397.018002) (xy 336.983578 -397.696944)
			(xy 336.99636 -397.720295) (xy 337.014549 -397.770319) (xy 337.023831 -397.822731) (xy 337.024472 -397.849344)
			(xy 337.024021 -397.873347) (xy 337.016501 -397.920759) (xy 337.001653 -397.96641) (xy 336.979842 -398.009175)
			(xy 336.951608 -398.047999) (xy 336.917644 -398.081925) (xy 336.878789 -398.110117) (xy 336.836001 -398.131881)
			(xy 336.790334 -398.146679) (xy 336.742913 -398.154148) (xy 336.71891 -398.154652) (xy 336.695382 -398.15421)
			(xy 336.648885 -398.146975) (xy 336.604049 -398.13269) (xy 336.561936 -398.111694) (xy 336.523545 -398.084484)
			(xy 336.489783 -398.051704) (xy 336.461453 -398.014132) (xy 336.449924 -397.993616) (xy 336.44967 -397.993108)
			(xy 336.449162 -397.992346) (xy 336.428842 -397.957294) (xy 336.422778 -397.94794) (xy 336.404527 -397.935184)
			(xy 336.382594 -397.931341) (xy 336.371692 -397.933672) (xy 336.354928 -397.93799) (xy 336.3341 -397.965168)
			(xy 336.3341 -398.542002) (xy 336.812902 -398.542002) (xy 336.816862 -398.492948) (xy 336.828639 -398.445164)
			(xy 336.84793 -398.399888) (xy 336.874233 -398.358292) (xy 336.906868 -398.321455) (xy 336.944989 -398.29033)
			(xy 336.98761 -398.265723) (xy 337.033626 -398.248271) (xy 337.081845 -398.238427) (xy 337.13102 -398.236446)
			(xy 337.179875 -398.242378) (xy 337.227146 -398.25607) (xy 337.271608 -398.277168) (xy 337.312111 -398.305124)
			(xy 337.347604 -398.339216) (xy 337.377169 -398.37856) (xy 337.40004 -398.422137) (xy 337.415624 -398.468818)
			(xy 337.423519 -398.517395) (xy 337.424014 -398.542002) (xy 338.013052 -398.542002) (xy 338.017012 -398.492948)
			(xy 338.028789 -398.445164) (xy 338.04808 -398.399888) (xy 338.074383 -398.358292) (xy 338.107018 -398.321455)
			(xy 338.145139 -398.29033) (xy 338.18776 -398.265723) (xy 338.233776 -398.248271) (xy 338.281995 -398.238427)
			(xy 338.33117 -398.236446) (xy 338.380025 -398.242378) (xy 338.427296 -398.25607) (xy 338.471758 -398.277168)
			(xy 338.512261 -398.305124) (xy 338.547754 -398.339216) (xy 338.577319 -398.37856) (xy 338.60019 -398.422137)
			(xy 338.615774 -398.468818) (xy 338.623669 -398.517395) (xy 338.624164 -398.542002) (xy 339.212948 -398.542002)
			(xy 339.216908 -398.492948) (xy 339.228685 -398.445164) (xy 339.247976 -398.399888) (xy 339.274279 -398.358292)
			(xy 339.306914 -398.321455) (xy 339.345035 -398.29033) (xy 339.387656 -398.265723) (xy 339.433672 -398.248271)
			(xy 339.481891 -398.238427) (xy 339.531066 -398.236446) (xy 339.579921 -398.242378) (xy 339.627192 -398.25607)
			(xy 339.671654 -398.277168) (xy 339.712157 -398.305124) (xy 339.74765 -398.339216) (xy 339.777215 -398.37856)
			(xy 339.800086 -398.422137) (xy 339.81567 -398.468818) (xy 339.823565 -398.517395) (xy 339.82406 -398.542002)
			(xy 340.413098 -398.542002) (xy 340.417058 -398.492948) (xy 340.428835 -398.445164) (xy 340.448126 -398.399888)
			(xy 340.474429 -398.358292) (xy 340.507064 -398.321455) (xy 340.545185 -398.29033) (xy 340.587806 -398.265723)
			(xy 340.633822 -398.248271) (xy 340.682041 -398.238427) (xy 340.731216 -398.236446) (xy 340.780071 -398.242378)
			(xy 340.827342 -398.25607) (xy 340.871804 -398.277168) (xy 340.912307 -398.305124) (xy 340.9478 -398.339216)
			(xy 340.977365 -398.37856) (xy 341.000236 -398.422137) (xy 341.01582 -398.468818) (xy 341.023715 -398.517395)
			(xy 341.02421 -398.542002) (xy 341.612994 -398.542002) (xy 341.616954 -398.492948) (xy 341.628731 -398.445164)
			(xy 341.648022 -398.399888) (xy 341.674325 -398.358292) (xy 341.70696 -398.321455) (xy 341.745081 -398.29033)
			(xy 341.787702 -398.265723) (xy 341.833718 -398.248271) (xy 341.881937 -398.238427) (xy 341.931112 -398.236446)
			(xy 341.979967 -398.242378) (xy 342.027238 -398.25607) (xy 342.0717 -398.277168) (xy 342.112203 -398.305124)
			(xy 342.147696 -398.339216) (xy 342.177261 -398.37856) (xy 342.200132 -398.422137) (xy 342.215716 -398.468818)
			(xy 342.223611 -398.517395) (xy 342.224106 -398.542002) (xy 342.81289 -398.542002) (xy 342.81685 -398.492948)
			(xy 342.828627 -398.445164) (xy 342.847918 -398.399888) (xy 342.874221 -398.358292) (xy 342.906856 -398.321455)
			(xy 342.944977 -398.29033) (xy 342.987598 -398.265723) (xy 343.033614 -398.248271) (xy 343.081833 -398.238427)
			(xy 343.131008 -398.236446) (xy 343.179863 -398.242378) (xy 343.227134 -398.25607) (xy 343.271596 -398.277168)
			(xy 343.312099 -398.305124) (xy 343.347592 -398.339216) (xy 343.377157 -398.37856) (xy 343.400028 -398.422137)
			(xy 343.415612 -398.468818) (xy 343.423507 -398.517395) (xy 343.424002 -398.542002) (xy 344.01304 -398.542002)
			(xy 344.017 -398.492948) (xy 344.028777 -398.445164) (xy 344.048068 -398.399888) (xy 344.074371 -398.358292)
			(xy 344.107006 -398.321455) (xy 344.145127 -398.29033) (xy 344.187748 -398.265723) (xy 344.233764 -398.248271)
			(xy 344.281983 -398.238427) (xy 344.331158 -398.236446) (xy 344.380013 -398.242378) (xy 344.427284 -398.25607)
			(xy 344.471746 -398.277168) (xy 344.512249 -398.305124) (xy 344.547742 -398.339216) (xy 344.577307 -398.37856)
			(xy 344.600178 -398.422137) (xy 344.615762 -398.468818) (xy 344.623657 -398.517395) (xy 344.624152 -398.542002)
			(xy 345.212936 -398.542002) (xy 345.216896 -398.492948) (xy 345.228673 -398.445164) (xy 345.247964 -398.399888)
			(xy 345.274267 -398.358292) (xy 345.306902 -398.321455) (xy 345.345023 -398.29033) (xy 345.387644 -398.265723)
			(xy 345.43366 -398.248271) (xy 345.481879 -398.238427) (xy 345.531054 -398.236446) (xy 345.579909 -398.242378)
			(xy 345.62718 -398.25607) (xy 345.671642 -398.277168) (xy 345.712145 -398.305124) (xy 345.747638 -398.339216)
			(xy 345.777203 -398.37856) (xy 345.800074 -398.422137) (xy 345.815658 -398.468818) (xy 345.823553 -398.517395)
			(xy 345.824048 -398.542002) (xy 346.413086 -398.542002) (xy 346.417046 -398.492948) (xy 346.428823 -398.445164)
			(xy 346.448114 -398.399888) (xy 346.474417 -398.358292) (xy 346.507052 -398.321455) (xy 346.545173 -398.29033)
			(xy 346.587794 -398.265723) (xy 346.63381 -398.248271) (xy 346.682029 -398.238427) (xy 346.731204 -398.236446)
			(xy 346.780059 -398.242378) (xy 346.82733 -398.25607) (xy 346.871792 -398.277168) (xy 346.912295 -398.305124)
			(xy 346.947788 -398.339216) (xy 346.977353 -398.37856) (xy 347.000224 -398.422137) (xy 347.015808 -398.468818)
			(xy 347.023703 -398.517395) (xy 347.024198 -398.542002) (xy 347.612982 -398.542002) (xy 347.616942 -398.492948)
			(xy 347.628719 -398.445164) (xy 347.64801 -398.399888) (xy 347.674313 -398.358292) (xy 347.706948 -398.321455)
			(xy 347.745069 -398.29033) (xy 347.78769 -398.265723) (xy 347.833706 -398.248271) (xy 347.881925 -398.238427)
			(xy 347.9311 -398.236446) (xy 347.979955 -398.242378) (xy 348.027226 -398.25607) (xy 348.071688 -398.277168)
			(xy 348.112191 -398.305124) (xy 348.147684 -398.339216) (xy 348.177249 -398.37856) (xy 348.20012 -398.422137)
			(xy 348.215704 -398.468818) (xy 348.223599 -398.517395) (xy 348.224094 -398.542002) (xy 348.812878 -398.542002)
			(xy 348.816838 -398.492948) (xy 348.828615 -398.445164) (xy 348.847906 -398.399888) (xy 348.874209 -398.358292)
			(xy 348.906844 -398.321455) (xy 348.944965 -398.29033) (xy 348.987586 -398.265723) (xy 349.033602 -398.248271)
			(xy 349.081821 -398.238427) (xy 349.130996 -398.236446) (xy 349.179851 -398.242378) (xy 349.227122 -398.25607)
			(xy 349.271584 -398.277168) (xy 349.312087 -398.305124) (xy 349.34758 -398.339216) (xy 349.377145 -398.37856)
			(xy 349.400016 -398.422137) (xy 349.4156 -398.468818) (xy 349.423495 -398.517395) (xy 349.42399 -398.542002)
			(xy 350.013028 -398.542002) (xy 350.016988 -398.492948) (xy 350.028765 -398.445164) (xy 350.048056 -398.399888)
			(xy 350.074359 -398.358292) (xy 350.106994 -398.321455) (xy 350.145115 -398.29033) (xy 350.187736 -398.265723)
			(xy 350.233752 -398.248271) (xy 350.281971 -398.238427) (xy 350.331146 -398.236446) (xy 350.380001 -398.242378)
			(xy 350.427272 -398.25607) (xy 350.471734 -398.277168) (xy 350.512237 -398.305124) (xy 350.54773 -398.339216)
			(xy 350.577295 -398.37856) (xy 350.600166 -398.422137) (xy 350.61575 -398.468818) (xy 350.623645 -398.517395)
			(xy 350.62414 -398.542002) (xy 351.212924 -398.542002) (xy 351.216884 -398.492948) (xy 351.228661 -398.445164)
			(xy 351.247952 -398.399888) (xy 351.274255 -398.358292) (xy 351.30689 -398.321455) (xy 351.345011 -398.29033)
			(xy 351.387632 -398.265723) (xy 351.433648 -398.248271) (xy 351.481867 -398.238427) (xy 351.531042 -398.236446)
			(xy 351.579897 -398.242378) (xy 351.627168 -398.25607) (xy 351.67163 -398.277168) (xy 351.712133 -398.305124)
			(xy 351.747626 -398.339216) (xy 351.777191 -398.37856) (xy 351.800062 -398.422137) (xy 351.815646 -398.468818)
			(xy 351.823541 -398.517395) (xy 351.824036 -398.542002) (xy 352.413074 -398.542002) (xy 352.417034 -398.492948)
			(xy 352.428811 -398.445164) (xy 352.448102 -398.399888) (xy 352.474405 -398.358292) (xy 352.50704 -398.321455)
			(xy 352.545161 -398.29033) (xy 352.587782 -398.265723) (xy 352.633798 -398.248271) (xy 352.682017 -398.238427)
			(xy 352.731192 -398.236446) (xy 352.780047 -398.242378) (xy 352.827318 -398.25607) (xy 352.87178 -398.277168)
			(xy 352.912283 -398.305124) (xy 352.947776 -398.339216) (xy 352.977341 -398.37856) (xy 353.000212 -398.422137)
			(xy 353.015796 -398.468818) (xy 353.023691 -398.517395) (xy 353.024186 -398.542002) (xy 353.023691 -398.566609)
			(xy 353.015796 -398.615186) (xy 353.000212 -398.661867) (xy 352.977341 -398.705444) (xy 352.947776 -398.744788)
			(xy 352.912283 -398.77888) (xy 352.87178 -398.806836) (xy 352.827318 -398.827934) (xy 352.780047 -398.841626)
			(xy 352.731192 -398.847558) (xy 352.682017 -398.845577) (xy 352.633798 -398.835733) (xy 352.587782 -398.818281)
			(xy 352.545161 -398.793674) (xy 352.50704 -398.762549) (xy 352.474405 -398.725712) (xy 352.448102 -398.684116)
			(xy 352.428811 -398.63884) (xy 352.417034 -398.591056) (xy 352.413074 -398.542002) (xy 351.824036 -398.542002)
			(xy 351.823541 -398.566609) (xy 351.815646 -398.615186) (xy 351.800062 -398.661867) (xy 351.777191 -398.705444)
			(xy 351.747626 -398.744788) (xy 351.712133 -398.77888) (xy 351.67163 -398.806836) (xy 351.627168 -398.827934)
			(xy 351.579897 -398.841626) (xy 351.531042 -398.847558) (xy 351.481867 -398.845577) (xy 351.433648 -398.835733)
			(xy 351.387632 -398.818281) (xy 351.345011 -398.793674) (xy 351.30689 -398.762549) (xy 351.274255 -398.725712)
			(xy 351.247952 -398.684116) (xy 351.228661 -398.63884) (xy 351.216884 -398.591056) (xy 351.212924 -398.542002)
			(xy 350.62414 -398.542002) (xy 350.623645 -398.566609) (xy 350.61575 -398.615186) (xy 350.600166 -398.661867)
			(xy 350.577295 -398.705444) (xy 350.54773 -398.744788) (xy 350.512237 -398.77888) (xy 350.471734 -398.806836)
			(xy 350.427272 -398.827934) (xy 350.380001 -398.841626) (xy 350.331146 -398.847558) (xy 350.281971 -398.845577)
			(xy 350.233752 -398.835733) (xy 350.187736 -398.818281) (xy 350.145115 -398.793674) (xy 350.106994 -398.762549)
			(xy 350.074359 -398.725712) (xy 350.048056 -398.684116) (xy 350.028765 -398.63884) (xy 350.016988 -398.591056)
			(xy 350.013028 -398.542002) (xy 349.42399 -398.542002) (xy 349.423495 -398.566609) (xy 349.4156 -398.615186)
			(xy 349.400016 -398.661867) (xy 349.377145 -398.705444) (xy 349.34758 -398.744788) (xy 349.312087 -398.77888)
			(xy 349.271584 -398.806836) (xy 349.227122 -398.827934) (xy 349.179851 -398.841626) (xy 349.130996 -398.847558)
			(xy 349.081821 -398.845577) (xy 349.033602 -398.835733) (xy 348.987586 -398.818281) (xy 348.944965 -398.793674)
			(xy 348.906844 -398.762549) (xy 348.874209 -398.725712) (xy 348.847906 -398.684116) (xy 348.828615 -398.63884)
			(xy 348.816838 -398.591056) (xy 348.812878 -398.542002) (xy 348.224094 -398.542002) (xy 348.223599 -398.566609)
			(xy 348.215704 -398.615186) (xy 348.20012 -398.661867) (xy 348.177249 -398.705444) (xy 348.147684 -398.744788)
			(xy 348.112191 -398.77888) (xy 348.071688 -398.806836) (xy 348.027226 -398.827934) (xy 347.979955 -398.841626)
			(xy 347.9311 -398.847558) (xy 347.881925 -398.845577) (xy 347.833706 -398.835733) (xy 347.78769 -398.818281)
			(xy 347.745069 -398.793674) (xy 347.706948 -398.762549) (xy 347.674313 -398.725712) (xy 347.64801 -398.684116)
			(xy 347.628719 -398.63884) (xy 347.616942 -398.591056) (xy 347.612982 -398.542002) (xy 347.024198 -398.542002)
			(xy 347.023703 -398.566609) (xy 347.015808 -398.615186) (xy 347.000224 -398.661867) (xy 346.977353 -398.705444)
			(xy 346.947788 -398.744788) (xy 346.912295 -398.77888) (xy 346.871792 -398.806836) (xy 346.82733 -398.827934)
			(xy 346.780059 -398.841626) (xy 346.731204 -398.847558) (xy 346.682029 -398.845577) (xy 346.63381 -398.835733)
			(xy 346.587794 -398.818281) (xy 346.545173 -398.793674) (xy 346.507052 -398.762549) (xy 346.474417 -398.725712)
			(xy 346.448114 -398.684116) (xy 346.428823 -398.63884) (xy 346.417046 -398.591056) (xy 346.413086 -398.542002)
			(xy 345.824048 -398.542002) (xy 345.823553 -398.566609) (xy 345.815658 -398.615186) (xy 345.800074 -398.661867)
			(xy 345.777203 -398.705444) (xy 345.747638 -398.744788) (xy 345.712145 -398.77888) (xy 345.671642 -398.806836)
			(xy 345.62718 -398.827934) (xy 345.579909 -398.841626) (xy 345.531054 -398.847558) (xy 345.481879 -398.845577)
			(xy 345.43366 -398.835733) (xy 345.387644 -398.818281) (xy 345.345023 -398.793674) (xy 345.306902 -398.762549)
			(xy 345.274267 -398.725712) (xy 345.247964 -398.684116) (xy 345.228673 -398.63884) (xy 345.216896 -398.591056)
			(xy 345.212936 -398.542002) (xy 344.624152 -398.542002) (xy 344.623657 -398.566609) (xy 344.615762 -398.615186)
			(xy 344.600178 -398.661867) (xy 344.577307 -398.705444) (xy 344.547742 -398.744788) (xy 344.512249 -398.77888)
			(xy 344.471746 -398.806836) (xy 344.427284 -398.827934) (xy 344.380013 -398.841626) (xy 344.331158 -398.847558)
			(xy 344.281983 -398.845577) (xy 344.233764 -398.835733) (xy 344.187748 -398.818281) (xy 344.145127 -398.793674)
			(xy 344.107006 -398.762549) (xy 344.074371 -398.725712) (xy 344.048068 -398.684116) (xy 344.028777 -398.63884)
			(xy 344.017 -398.591056) (xy 344.01304 -398.542002) (xy 343.424002 -398.542002) (xy 343.423507 -398.566609)
			(xy 343.415612 -398.615186) (xy 343.400028 -398.661867) (xy 343.377157 -398.705444) (xy 343.347592 -398.744788)
			(xy 343.312099 -398.77888) (xy 343.271596 -398.806836) (xy 343.227134 -398.827934) (xy 343.179863 -398.841626)
			(xy 343.131008 -398.847558) (xy 343.081833 -398.845577) (xy 343.033614 -398.835733) (xy 342.987598 -398.818281)
			(xy 342.944977 -398.793674) (xy 342.906856 -398.762549) (xy 342.874221 -398.725712) (xy 342.847918 -398.684116)
			(xy 342.828627 -398.63884) (xy 342.81685 -398.591056) (xy 342.81289 -398.542002) (xy 342.224106 -398.542002)
			(xy 342.223611 -398.566609) (xy 342.215716 -398.615186) (xy 342.200132 -398.661867) (xy 342.177261 -398.705444)
			(xy 342.147696 -398.744788) (xy 342.112203 -398.77888) (xy 342.0717 -398.806836) (xy 342.027238 -398.827934)
			(xy 341.979967 -398.841626) (xy 341.931112 -398.847558) (xy 341.881937 -398.845577) (xy 341.833718 -398.835733)
			(xy 341.787702 -398.818281) (xy 341.745081 -398.793674) (xy 341.70696 -398.762549) (xy 341.674325 -398.725712)
			(xy 341.648022 -398.684116) (xy 341.628731 -398.63884) (xy 341.616954 -398.591056) (xy 341.612994 -398.542002)
			(xy 341.02421 -398.542002) (xy 341.023715 -398.566609) (xy 341.01582 -398.615186) (xy 341.000236 -398.661867)
			(xy 340.977365 -398.705444) (xy 340.9478 -398.744788) (xy 340.912307 -398.77888) (xy 340.871804 -398.806836)
			(xy 340.827342 -398.827934) (xy 340.780071 -398.841626) (xy 340.731216 -398.847558) (xy 340.682041 -398.845577)
			(xy 340.633822 -398.835733) (xy 340.587806 -398.818281) (xy 340.545185 -398.793674) (xy 340.507064 -398.762549)
			(xy 340.474429 -398.725712) (xy 340.448126 -398.684116) (xy 340.428835 -398.63884) (xy 340.417058 -398.591056)
			(xy 340.413098 -398.542002) (xy 339.82406 -398.542002) (xy 339.823565 -398.566609) (xy 339.81567 -398.615186)
			(xy 339.800086 -398.661867) (xy 339.777215 -398.705444) (xy 339.74765 -398.744788) (xy 339.712157 -398.77888)
			(xy 339.671654 -398.806836) (xy 339.627192 -398.827934) (xy 339.579921 -398.841626) (xy 339.531066 -398.847558)
			(xy 339.481891 -398.845577) (xy 339.433672 -398.835733) (xy 339.387656 -398.818281) (xy 339.345035 -398.793674)
			(xy 339.306914 -398.762549) (xy 339.274279 -398.725712) (xy 339.247976 -398.684116) (xy 339.228685 -398.63884)
			(xy 339.216908 -398.591056) (xy 339.212948 -398.542002) (xy 338.624164 -398.542002) (xy 338.623669 -398.566609)
			(xy 338.615774 -398.615186) (xy 338.60019 -398.661867) (xy 338.577319 -398.705444) (xy 338.547754 -398.744788)
			(xy 338.512261 -398.77888) (xy 338.471758 -398.806836) (xy 338.427296 -398.827934) (xy 338.380025 -398.841626)
			(xy 338.33117 -398.847558) (xy 338.281995 -398.845577) (xy 338.233776 -398.835733) (xy 338.18776 -398.818281)
			(xy 338.145139 -398.793674) (xy 338.107018 -398.762549) (xy 338.074383 -398.725712) (xy 338.04808 -398.684116)
			(xy 338.028789 -398.63884) (xy 338.017012 -398.591056) (xy 338.013052 -398.542002) (xy 337.424014 -398.542002)
			(xy 337.423519 -398.566609) (xy 337.415624 -398.615186) (xy 337.40004 -398.661867) (xy 337.377169 -398.705444)
			(xy 337.347604 -398.744788) (xy 337.312111 -398.77888) (xy 337.271608 -398.806836) (xy 337.227146 -398.827934)
			(xy 337.179875 -398.841626) (xy 337.13102 -398.847558) (xy 337.081845 -398.845577) (xy 337.033626 -398.835733)
			(xy 336.98761 -398.818281) (xy 336.944989 -398.793674) (xy 336.906868 -398.762549) (xy 336.874233 -398.725712)
			(xy 336.84793 -398.684116) (xy 336.828639 -398.63884) (xy 336.816862 -398.591056) (xy 336.812902 -398.542002)
			(xy 336.3341 -398.542002) (xy 336.3341 -399.878296) (xy 336.359754 -399.907252) (xy 336.379058 -399.909538)
			(xy 336.403545 -399.912848) (xy 336.451073 -399.926353) (xy 336.495807 -399.947336) (xy 336.536577 -399.975249)
			(xy 336.57232 -400.009363) (xy 336.602102 -400.048789) (xy 336.625147 -400.092496) (xy 336.640851 -400.139344)
			(xy 336.648806 -400.188109) (xy 336.649314 -400.212814) (xy 336.648815 -400.237184) (xy 336.641035 -400.285299)
			(xy 336.625721 -400.331571) (xy 336.603262 -400.374828) (xy 336.589116 -400.394678) (xy 336.583528 -400.402552)
			(xy 336.578448 -400.420332) (xy 336.58683 -400.506946) (xy 336.594958 -400.52371) (xy 336.60207 -400.53006)
			(xy 336.621192 -400.548203) (xy 336.654764 -400.58884) (xy 336.682423 -400.633711) (xy 336.703644 -400.681962)
			(xy 336.718023 -400.732674) (xy 336.725286 -400.784883) (xy 336.725768 -400.811238) (xy 336.725768 -401.674838)
			(xy 337.16214 -401.674838) (xy 337.16214 -400.811238) (xy 337.16262 -400.784882) (xy 337.169883 -400.732674)
			(xy 337.184262 -400.681962) (xy 337.205483 -400.633711) (xy 337.233143 -400.58884) (xy 337.266715 -400.548202)
			(xy 337.285838 -400.53006) (xy 337.29295 -400.523456) (xy 337.301332 -400.506946) (xy 337.30946 -400.420078)
			(xy 337.304634 -400.402298) (xy 337.298792 -400.394678) (xy 337.284687 -400.374809) (xy 337.262264 -400.331554)
			(xy 337.247007 -400.285284) (xy 337.239302 -400.237175) (xy 337.238848 -400.212814) (xy 337.23937 -400.187559)
			(xy 337.247683 -400.137737) (xy 337.264084 -400.089963) (xy 337.288125 -400.04554) (xy 337.319149 -400.00568)
			(xy 337.356311 -399.97147) (xy 337.398597 -399.943844) (xy 337.444853 -399.923554) (xy 337.493818 -399.911154)
			(xy 337.544156 -399.906983) (xy 337.594494 -399.911154) (xy 337.643459 -399.923554) (xy 337.689715 -399.943844)
			(xy 337.732001 -399.97147) (xy 337.769163 -400.00568) (xy 337.800187 -400.04554) (xy 337.824228 -400.089963)
			(xy 337.840629 -400.137737) (xy 337.848942 -400.187559) (xy 337.849464 -400.212814) (xy 337.848997 -400.237217)
			(xy 337.841238 -400.285401) (xy 337.825918 -400.331739) (xy 337.803427 -400.375053) (xy 337.789266 -400.394932)
			(xy 337.783678 -400.402552) (xy 337.778598 -400.420332) (xy 337.786726 -400.5072) (xy 337.795108 -400.52371)
			(xy 337.80222 -400.530314) (xy 337.821289 -400.548466) (xy 337.85478 -400.589089) (xy 337.882377 -400.633924)
			(xy 337.903558 -400.682122) (xy 337.917923 -400.732772) (xy 337.925199 -400.784915) (xy 337.925664 -400.811238)
			(xy 337.925664 -401.674838) (xy 338.362544 -401.674838) (xy 338.362544 -400.811238) (xy 338.36301 -400.784893)
			(xy 338.370257 -400.732705) (xy 338.384606 -400.682007) (xy 338.405784 -400.633761) (xy 338.433389 -400.588882)
			(xy 338.466898 -400.548221) (xy 338.485988 -400.53006) (xy 338.4931 -400.52371) (xy 338.501228 -400.506946)
			(xy 338.50961 -400.420332) (xy 338.50453 -400.402552) (xy 338.498942 -400.394678) (xy 338.484791 -400.374832)
			(xy 338.462334 -400.331573) (xy 338.447022 -400.2853) (xy 338.439242 -400.237184) (xy 338.438744 -400.212814)
			(xy 338.439266 -400.187559) (xy 338.447579 -400.137737) (xy 338.46398 -400.089963) (xy 338.488021 -400.04554)
			(xy 338.519045 -400.00568) (xy 338.556207 -399.97147) (xy 338.598493 -399.943844) (xy 338.644749 -399.923554)
			(xy 338.693714 -399.911154) (xy 338.744052 -399.906983) (xy 338.79439 -399.911154) (xy 338.843355 -399.923554)
			(xy 338.889611 -399.943844) (xy 338.931897 -399.97147) (xy 338.969059 -400.00568) (xy 339.000083 -400.04554)
			(xy 339.024124 -400.089963) (xy 339.040525 -400.137737) (xy 339.048838 -400.187559) (xy 339.04936 -400.212814)
			(xy 339.04888 -400.237186) (xy 339.041121 -400.285309) (xy 339.025804 -400.331585) (xy 339.003319 -400.374833)
			(xy 338.989162 -400.394678) (xy 338.983574 -400.402552) (xy 338.978494 -400.420332) (xy 338.986876 -400.506946)
			(xy 338.995004 -400.52371) (xy 339.002116 -400.53006) (xy 339.021212 -400.548217) (xy 339.054735 -400.588871)
			(xy 339.08235 -400.633748) (xy 339.103533 -400.681996) (xy 339.11788 -400.732698) (xy 339.12512 -400.784891)
			(xy 339.12556 -400.811238) (xy 339.12556 -401.674838) (xy 339.56244 -401.674838) (xy 339.56244 -400.811238)
			(xy 339.562907 -400.784893) (xy 339.570154 -400.732705) (xy 339.584503 -400.682007) (xy 339.60568 -400.633761)
			(xy 339.633285 -400.588882) (xy 339.666794 -400.548221) (xy 339.685884 -400.53006) (xy 339.692996 -400.52371)
			(xy 339.701124 -400.506946) (xy 339.709506 -400.420332) (xy 339.704426 -400.402552) (xy 339.698838 -400.394678)
			(xy 339.684686 -400.374832) (xy 339.66223 -400.331573) (xy 339.646918 -400.2853) (xy 339.639138 -400.237184)
			(xy 339.63864 -400.212814) (xy 339.639162 -400.187559) (xy 339.647475 -400.137737) (xy 339.663876 -400.089963)
			(xy 339.687917 -400.04554) (xy 339.718941 -400.00568) (xy 339.756103 -399.97147) (xy 339.798389 -399.943844)
			(xy 339.844645 -399.923554) (xy 339.89361 -399.911154) (xy 339.943948 -399.906983) (xy 339.994286 -399.911154)
			(xy 340.043251 -399.923554) (xy 340.089507 -399.943844) (xy 340.131793 -399.97147) (xy 340.168955 -400.00568)
			(xy 340.199979 -400.04554) (xy 340.22402 -400.089963) (xy 340.240421 -400.137737) (xy 340.248734 -400.187559)
			(xy 340.249256 -400.212814) (xy 340.248777 -400.237186) (xy 340.241018 -400.285309) (xy 340.225701 -400.331585)
			(xy 340.203215 -400.374833) (xy 340.189058 -400.394678) (xy 340.18347 -400.402552) (xy 340.17839 -400.420332)
			(xy 340.186772 -400.506946) (xy 340.1949 -400.52371) (xy 340.202012 -400.53006) (xy 340.221107 -400.548218)
			(xy 340.254631 -400.588871) (xy 340.282246 -400.633748) (xy 340.303428 -400.681996) (xy 340.317776 -400.732698)
			(xy 340.325016 -400.784891) (xy 340.325456 -400.811238) (xy 340.325456 -401.674838) (xy 340.762336 -401.674838)
			(xy 340.762336 -400.811238) (xy 340.762817 -400.784882) (xy 340.77008 -400.732674) (xy 340.784459 -400.681962)
			(xy 340.80568 -400.633711) (xy 340.83334 -400.58884) (xy 340.866912 -400.548202) (xy 340.886034 -400.53006)
			(xy 340.893146 -400.52371) (xy 340.901274 -400.506946) (xy 340.909656 -400.420332) (xy 340.904576 -400.402552)
			(xy 340.898988 -400.394678) (xy 340.884842 -400.374828) (xy 340.862383 -400.331571) (xy 340.847069 -400.285299)
			(xy 340.839289 -400.237184) (xy 340.83879 -400.212814) (xy 340.839312 -400.187559) (xy 340.847625 -400.137737)
			(xy 340.864026 -400.089963) (xy 340.888067 -400.04554) (xy 340.919091 -400.00568) (xy 340.956253 -399.97147)
			(xy 340.998539 -399.943844) (xy 341.044795 -399.923554) (xy 341.09376 -399.911154) (xy 341.144098 -399.906983)
			(xy 341.194436 -399.911154) (xy 341.243401 -399.923554) (xy 341.289657 -399.943844) (xy 341.331943 -399.97147)
			(xy 341.369105 -400.00568) (xy 341.400129 -400.04554) (xy 341.42417 -400.089963) (xy 341.440571 -400.137737)
			(xy 341.448884 -400.187559) (xy 341.449406 -400.212814) (xy 341.448936 -400.237187) (xy 341.441176 -400.285311)
			(xy 341.425856 -400.331586) (xy 341.403367 -400.374834) (xy 341.389208 -400.394678) (xy 341.38362 -400.402552)
			(xy 341.37854 -400.420332) (xy 341.386922 -400.506946) (xy 341.39505 -400.52371) (xy 341.402162 -400.53006)
			(xy 341.421298 -400.548192) (xy 341.454886 -400.588823) (xy 341.482556 -400.633693) (xy 341.503783 -400.681947)
			(xy 341.518162 -400.732665) (xy 341.525417 -400.78488) (xy 341.52586 -400.811238) (xy 341.52586 -401.674838)
			(xy 341.962232 -401.674838) (xy 341.962232 -400.811238) (xy 341.962714 -400.784883) (xy 341.969977 -400.732674)
			(xy 341.984356 -400.681962) (xy 342.005577 -400.633711) (xy 342.033236 -400.58884) (xy 342.066808 -400.548203)
			(xy 342.08593 -400.53006) (xy 342.093042 -400.52371) (xy 342.10117 -400.506946) (xy 342.109552 -400.420332)
			(xy 342.104472 -400.402552) (xy 342.098884 -400.394678) (xy 342.084738 -400.374828) (xy 342.062279 -400.331571)
			(xy 342.046965 -400.285299) (xy 342.039185 -400.237184) (xy 342.038686 -400.212814) (xy 342.039208 -400.187559)
			(xy 342.047521 -400.137737) (xy 342.063922 -400.089963) (xy 342.087963 -400.04554) (xy 342.118987 -400.00568)
			(xy 342.156149 -399.97147) (xy 342.198435 -399.943844) (xy 342.244691 -399.923554) (xy 342.293656 -399.911154)
			(xy 342.343994 -399.906983) (xy 342.394332 -399.911154) (xy 342.443297 -399.923554) (xy 342.489553 -399.943844)
			(xy 342.531839 -399.97147) (xy 342.569001 -400.00568) (xy 342.600025 -400.04554) (xy 342.624066 -400.089963)
			(xy 342.640467 -400.137737) (xy 342.64878 -400.187559) (xy 342.649302 -400.212814) (xy 342.648833 -400.237187)
			(xy 342.641073 -400.285311) (xy 342.625753 -400.331586) (xy 342.603263 -400.374834) (xy 342.589104 -400.394678)
			(xy 342.583516 -400.402552) (xy 342.578436 -400.420332) (xy 342.586818 -400.506946) (xy 342.594946 -400.52371)
			(xy 342.602058 -400.53006) (xy 342.621193 -400.548192) (xy 342.654781 -400.588824) (xy 342.682452 -400.633694)
			(xy 342.703679 -400.681947) (xy 342.718058 -400.732665) (xy 342.725313 -400.78488) (xy 342.725756 -400.811238)
			(xy 342.725756 -401.674838) (xy 343.162636 -401.674838) (xy 343.162636 -400.811238) (xy 343.163105 -400.784893)
			(xy 343.170352 -400.732705) (xy 343.1847 -400.682007) (xy 343.205877 -400.633761) (xy 343.233482 -400.588882)
			(xy 343.26699 -400.548221) (xy 343.28608 -400.53006) (xy 343.293192 -400.52371) (xy 343.30132 -400.506946)
			(xy 343.309702 -400.420332) (xy 343.304622 -400.402552) (xy 343.299034 -400.394678) (xy 343.284882 -400.374833)
			(xy 343.262425 -400.331573) (xy 343.247114 -400.2853) (xy 343.239334 -400.237184) (xy 343.238836 -400.212814)
			(xy 343.239358 -400.187559) (xy 343.247671 -400.137737) (xy 343.264072 -400.089963) (xy 343.288113 -400.04554)
			(xy 343.319137 -400.00568) (xy 343.356299 -399.97147) (xy 343.398585 -399.943844) (xy 343.444841 -399.923554)
			(xy 343.493806 -399.911154) (xy 343.544144 -399.906983) (xy 343.594482 -399.911154) (xy 343.643447 -399.923554)
			(xy 343.689703 -399.943844) (xy 343.731989 -399.97147) (xy 343.769151 -400.00568) (xy 343.800175 -400.04554)
			(xy 343.824216 -400.089963) (xy 343.840617 -400.137737) (xy 343.84893 -400.187559) (xy 343.849452 -400.212814)
			(xy 343.848973 -400.237186) (xy 343.841215 -400.285309) (xy 343.825897 -400.331585) (xy 343.803411 -400.374833)
			(xy 343.789254 -400.394678) (xy 343.783666 -400.402552) (xy 343.778586 -400.420332) (xy 343.786968 -400.506946)
			(xy 343.795096 -400.52371) (xy 343.802208 -400.53006) (xy 343.821303 -400.548218) (xy 343.854826 -400.588872)
			(xy 343.882442 -400.633749) (xy 343.903624 -400.681996) (xy 343.917972 -400.732698) (xy 343.925212 -400.784892)
			(xy 343.925652 -400.811238) (xy 343.925652 -401.674838) (xy 344.362532 -401.674838) (xy 344.362532 -400.811238)
			(xy 344.363002 -400.784894) (xy 344.370249 -400.732705) (xy 344.384597 -400.682007) (xy 344.405774 -400.633761)
			(xy 344.433378 -400.588882) (xy 344.466887 -400.548221) (xy 344.485976 -400.53006) (xy 344.493088 -400.52371)
			(xy 344.501216 -400.506946) (xy 344.509598 -400.420332) (xy 344.504518 -400.402552) (xy 344.49893 -400.394678)
			(xy 344.484777 -400.374833) (xy 344.462321 -400.331573) (xy 344.44701 -400.2853) (xy 344.43923 -400.237184)
			(xy 344.438732 -400.212814) (xy 344.439254 -400.187559) (xy 344.447567 -400.137737) (xy 344.463968 -400.089963)
			(xy 344.488009 -400.04554) (xy 344.519033 -400.00568) (xy 344.556195 -399.97147) (xy 344.598481 -399.943844)
			(xy 344.644737 -399.923554) (xy 344.693702 -399.911154) (xy 344.74404 -399.906983) (xy 344.794378 -399.911154)
			(xy 344.843343 -399.923554) (xy 344.889599 -399.943844) (xy 344.931885 -399.97147) (xy 344.969047 -400.00568)
			(xy 345.000071 -400.04554) (xy 345.024112 -400.089963) (xy 345.040513 -400.137737) (xy 345.048826 -400.187559)
			(xy 345.049348 -400.212814) (xy 345.04887 -400.237186) (xy 345.041111 -400.28531) (xy 345.025793 -400.331585)
			(xy 345.003307 -400.374833) (xy 344.98915 -400.394678) (xy 344.983562 -400.402552) (xy 344.978482 -400.420332)
			(xy 344.986864 -400.506946) (xy 344.994992 -400.52371) (xy 345.002104 -400.53006) (xy 345.021198 -400.548219)
			(xy 345.054722 -400.588873) (xy 345.082337 -400.633749) (xy 345.10352 -400.681997) (xy 345.117868 -400.732698)
			(xy 345.125108 -400.784892) (xy 345.125548 -400.811238) (xy 345.125548 -401.674838) (xy 345.562428 -401.674838)
			(xy 345.562428 -400.811238) (xy 345.562861 -400.784911) (xy 345.570111 -400.732757) (xy 345.584465 -400.682096)
			(xy 345.60565 -400.633891) (xy 345.633263 -400.589057) (xy 345.66678 -400.548447) (xy 345.685872 -400.530314)
			(xy 345.692984 -400.52371) (xy 345.701366 -400.5072) (xy 345.709494 -400.420332) (xy 345.704414 -400.402552)
			(xy 345.698826 -400.394932) (xy 345.684674 -400.375048) (xy 345.662185 -400.331735) (xy 345.646866 -400.285398)
			(xy 345.639106 -400.237216) (xy 345.638628 -400.212814) (xy 345.63915 -400.187559) (xy 345.647463 -400.137737)
			(xy 345.663864 -400.089963) (xy 345.687905 -400.04554) (xy 345.718929 -400.00568) (xy 345.756091 -399.97147)
			(xy 345.798377 -399.943844) (xy 345.844633 -399.923554) (xy 345.893598 -399.911154) (xy 345.943936 -399.906983)
			(xy 345.994274 -399.911154) (xy 346.043239 -399.923554) (xy 346.089495 -399.943844) (xy 346.131781 -399.97147)
			(xy 346.168943 -400.00568) (xy 346.199967 -400.04554) (xy 346.224008 -400.089963) (xy 346.240409 -400.137737)
			(xy 346.248722 -400.187559) (xy 346.249244 -400.212814) (xy 346.248748 -400.237172) (xy 346.241035 -400.285275)
			(xy 346.225792 -400.331545) (xy 346.203403 -400.374812) (xy 346.1893 -400.394678) (xy 346.183458 -400.402298)
			(xy 346.178632 -400.420078) (xy 346.18676 -400.506946) (xy 346.195142 -400.523456) (xy 346.202254 -400.53006)
			(xy 346.221389 -400.548193) (xy 346.254976 -400.588824) (xy 346.282648 -400.633694) (xy 346.303875 -400.681948)
			(xy 346.318253 -400.732665) (xy 346.325509 -400.78488) (xy 346.325952 -400.811238) (xy 346.325952 -401.674838)
			(xy 346.762324 -401.674838) (xy 346.762324 -400.811238) (xy 346.762809 -400.784883) (xy 346.770072 -400.732674)
			(xy 346.78445 -400.681963) (xy 346.80567 -400.633712) (xy 346.833329 -400.588841) (xy 346.8669 -400.548203)
			(xy 346.886022 -400.53006) (xy 346.893134 -400.52371) (xy 346.901262 -400.506946) (xy 346.909644 -400.420332)
			(xy 346.904564 -400.402552) (xy 346.898976 -400.394678) (xy 346.884829 -400.374829) (xy 346.86237 -400.331571)
			(xy 346.847057 -400.285299) (xy 346.839276 -400.237184) (xy 346.838778 -400.212814) (xy 346.8393 -400.187559)
			(xy 346.847613 -400.137737) (xy 346.864014 -400.089963) (xy 346.888055 -400.04554) (xy 346.919079 -400.00568)
			(xy 346.956241 -399.97147) (xy 346.998527 -399.943844) (xy 347.044783 -399.923554) (xy 347.093748 -399.911154)
			(xy 347.144086 -399.906983) (xy 347.194424 -399.911154) (xy 347.243389 -399.923554) (xy 347.289645 -399.943844)
			(xy 347.331931 -399.97147) (xy 347.369093 -400.00568) (xy 347.400117 -400.04554) (xy 347.424158 -400.089963)
			(xy 347.440559 -400.137737) (xy 347.448872 -400.187559) (xy 347.449394 -400.212814) (xy 347.448927 -400.237187)
			(xy 347.441166 -400.285311) (xy 347.425846 -400.331587) (xy 347.403355 -400.374834) (xy 347.389196 -400.394678)
			(xy 347.383608 -400.402552) (xy 347.378528 -400.420332) (xy 347.38691 -400.506946) (xy 347.395038 -400.52371)
			(xy 347.40215 -400.53006) (xy 347.421284 -400.548194) (xy 347.454872 -400.588825) (xy 347.482543 -400.633694)
			(xy 347.503771 -400.681948) (xy 347.518149 -400.732665) (xy 347.525405 -400.78488) (xy 347.525848 -400.811238)
			(xy 347.525848 -401.674838) (xy 347.962728 -401.674838) (xy 347.962728 -400.811238) (xy 347.963151 -400.784921)
			(xy 347.970376 -400.732785) (xy 347.984694 -400.682136) (xy 348.005834 -400.633934) (xy 348.033395 -400.589093)
			(xy 348.066855 -400.548463) (xy 348.085918 -400.530314) (xy 348.09303 -400.52371) (xy 348.101412 -400.5072)
			(xy 348.10954 -400.420332) (xy 348.10446 -400.402552) (xy 348.098872 -400.394932) (xy 348.084713 -400.375052)
			(xy 348.062227 -400.331737) (xy 348.04691 -400.285399) (xy 348.039152 -400.237216) (xy 348.038674 -400.212814)
			(xy 348.039196 -400.187559) (xy 348.047509 -400.137737) (xy 348.06391 -400.089963) (xy 348.087951 -400.04554)
			(xy 348.118975 -400.00568) (xy 348.156137 -399.97147) (xy 348.198423 -399.943844) (xy 348.244679 -399.923554)
			(xy 348.293644 -399.911154) (xy 348.343982 -399.906983) (xy 348.39432 -399.911154) (xy 348.443285 -399.923554)
			(xy 348.489541 -399.943844) (xy 348.531827 -399.97147) (xy 348.568989 -400.00568) (xy 348.600013 -400.04554)
			(xy 348.624054 -400.089963) (xy 348.640455 -400.137737) (xy 348.648768 -400.187559) (xy 348.64929 -400.212814)
			(xy 348.648804 -400.237173) (xy 348.64109 -400.285276) (xy 348.625844 -400.331546) (xy 348.603451 -400.374813)
			(xy 348.589346 -400.394678) (xy 348.583504 -400.402298) (xy 348.578678 -400.420078) (xy 348.586806 -400.506946)
			(xy 348.595188 -400.523456) (xy 348.6023 -400.53006) (xy 348.621413 -400.5482) (xy 348.654931 -400.58886)
			(xy 348.682542 -400.633741) (xy 348.703721 -400.681992) (xy 348.718066 -400.732696) (xy 348.725304 -400.784891)
			(xy 348.725744 -400.811238) (xy 348.725744 -401.674838) (xy 349.162624 -401.674838) (xy 349.162624 -400.811238)
			(xy 349.163064 -400.784892) (xy 349.170313 -400.732701) (xy 349.184665 -400.682002) (xy 349.205847 -400.633755)
			(xy 349.233459 -400.588877) (xy 349.266975 -400.548219) (xy 349.286068 -400.53006) (xy 349.29318 -400.52371)
			(xy 349.301308 -400.506946) (xy 349.30969 -400.420332) (xy 349.30461 -400.402552) (xy 349.299022 -400.394678)
			(xy 349.284868 -400.374834) (xy 349.262412 -400.331574) (xy 349.247101 -400.2853) (xy 349.239322 -400.237184)
			(xy 349.238824 -400.212814) (xy 349.239346 -400.187559) (xy 349.247659 -400.137737) (xy 349.26406 -400.089963)
			(xy 349.288101 -400.04554) (xy 349.319125 -400.00568) (xy 349.356287 -399.97147) (xy 349.398573 -399.943844)
			(xy 349.444829 -399.923554) (xy 349.493794 -399.911154) (xy 349.544132 -399.906983) (xy 349.59447 -399.911154)
			(xy 349.643435 -399.923554) (xy 349.689691 -399.943844) (xy 349.731977 -399.97147) (xy 349.769139 -400.00568)
			(xy 349.800163 -400.04554) (xy 349.824204 -400.089963) (xy 349.840605 -400.137737) (xy 349.848918 -400.187559)
			(xy 349.84944 -400.212814) (xy 349.848964 -400.237186) (xy 349.841205 -400.28531) (xy 349.825886 -400.331585)
			(xy 349.803399 -400.374833) (xy 349.789242 -400.394678) (xy 349.783654 -400.402552) (xy 349.778574 -400.420332)
			(xy 349.786956 -400.506946) (xy 349.795084 -400.52371) (xy 349.802196 -400.53006) (xy 349.821308 -400.548201)
			(xy 349.854827 -400.58886) (xy 349.882438 -400.633741) (xy 349.903617 -400.681992) (xy 349.917962 -400.732696)
			(xy 349.9252 -400.784891) (xy 349.92564 -400.811238) (xy 349.92564 -401.674838) (xy 350.36252 -401.674838)
			(xy 350.36252 -400.811238) (xy 350.362962 -400.784892) (xy 350.37021 -400.732702) (xy 350.384562 -400.682002)
			(xy 350.405744 -400.633756) (xy 350.433355 -400.588877) (xy 350.466871 -400.548219) (xy 350.485964 -400.53006)
			(xy 350.493076 -400.52371) (xy 350.501204 -400.506946) (xy 350.509586 -400.420332) (xy 350.504506 -400.402552)
			(xy 350.498918 -400.394678) (xy 350.484764 -400.374834) (xy 350.462308 -400.331574) (xy 350.446997 -400.2853)
			(xy 350.439218 -400.237184) (xy 350.43872 -400.212814) (xy 350.439242 -400.187559) (xy 350.447555 -400.137737)
			(xy 350.463956 -400.089963) (xy 350.487997 -400.04554) (xy 350.519021 -400.00568) (xy 350.556183 -399.97147)
			(xy 350.598469 -399.943844) (xy 350.644725 -399.923554) (xy 350.69369 -399.911154) (xy 350.744028 -399.906983)
			(xy 350.794366 -399.911154) (xy 350.843331 -399.923554) (xy 350.889587 -399.943844) (xy 350.931873 -399.97147)
			(xy 350.969035 -400.00568) (xy 351.000059 -400.04554) (xy 351.0241 -400.089963) (xy 351.040501 -400.137737)
			(xy 351.048814 -400.187559) (xy 351.049336 -400.212814) (xy 351.04886 -400.237186) (xy 351.041101 -400.28531)
			(xy 351.025783 -400.331585) (xy 351.003296 -400.374833) (xy 350.989138 -400.394678) (xy 350.98355 -400.402552)
			(xy 350.97847 -400.420332) (xy 350.986852 -400.506946) (xy 350.99498 -400.52371) (xy 351.002092 -400.53006)
			(xy 351.021203 -400.548201) (xy 351.054722 -400.588861) (xy 351.082333 -400.633742) (xy 351.103513 -400.681992)
			(xy 351.117858 -400.732696) (xy 351.125096 -400.784891) (xy 351.125536 -400.811238) (xy 351.125536 -401.674838)
			(xy 351.562416 -401.674838) (xy 351.562416 -400.811238) (xy 351.562859 -400.784892) (xy 351.570108 -400.732702)
			(xy 351.584459 -400.682002) (xy 351.605641 -400.633756) (xy 351.633252 -400.588878) (xy 351.666767 -400.548219)
			(xy 351.68586 -400.53006) (xy 351.692972 -400.52371) (xy 351.7011 -400.506946) (xy 351.709482 -400.420332)
			(xy 351.704402 -400.402552) (xy 351.698814 -400.394678) (xy 351.684659 -400.374834) (xy 351.662204 -400.331574)
			(xy 351.646893 -400.2853) (xy 351.639114 -400.237184) (xy 351.638616 -400.212814) (xy 351.639138 -400.187559)
			(xy 351.647451 -400.137737) (xy 351.663852 -400.089963) (xy 351.687893 -400.04554) (xy 351.718917 -400.00568)
			(xy 351.756079 -399.97147) (xy 351.798365 -399.943844) (xy 351.844621 -399.923554) (xy 351.893586 -399.911154)
			(xy 351.943924 -399.906983) (xy 351.994262 -399.911154) (xy 352.043227 -399.923554) (xy 352.089483 -399.943844)
			(xy 352.131769 -399.97147) (xy 352.168931 -400.00568) (xy 352.199955 -400.04554) (xy 352.223996 -400.089963)
			(xy 352.240397 -400.137737) (xy 352.24871 -400.187559) (xy 352.249232 -400.212814) (xy 352.248757 -400.237186)
			(xy 352.240998 -400.28531) (xy 352.225679 -400.331585) (xy 352.203192 -400.374833) (xy 352.189034 -400.394678)
			(xy 352.183446 -400.402552) (xy 352.178366 -400.420332) (xy 352.186748 -400.506946) (xy 352.194876 -400.52371)
			(xy 352.201988 -400.53006) (xy 352.221098 -400.548202) (xy 352.254617 -400.588861) (xy 352.282229 -400.633742)
			(xy 352.303408 -400.681992) (xy 352.317754 -400.732696) (xy 352.324992 -400.784891) (xy 352.325432 -400.811238)
			(xy 352.325432 -401.674838) (xy 352.762312 -401.674838) (xy 352.762312 -400.811238) (xy 352.762801 -400.784883)
			(xy 352.770063 -400.732675) (xy 352.784441 -400.681963) (xy 352.805661 -400.633713) (xy 352.833319 -400.588841)
			(xy 352.866889 -400.548203) (xy 352.88601 -400.53006) (xy 352.893122 -400.52371) (xy 352.90125 -400.506946)
			(xy 352.909632 -400.420332) (xy 352.904552 -400.402552) (xy 352.898964 -400.394678) (xy 352.884815 -400.37483)
			(xy 352.862357 -400.331572) (xy 352.847044 -400.285299) (xy 352.839264 -400.237184) (xy 352.838766 -400.212814)
			(xy 352.839288 -400.187559) (xy 352.847601 -400.137737) (xy 352.864002 -400.089963) (xy 352.888043 -400.04554)
			(xy 352.919067 -400.00568) (xy 352.956229 -399.97147) (xy 352.998515 -399.943844) (xy 353.044771 -399.923554)
			(xy 353.093736 -399.911154) (xy 353.144074 -399.906983) (xy 353.194412 -399.911154) (xy 353.243377 -399.923554)
			(xy 353.289633 -399.943844) (xy 353.331919 -399.97147) (xy 353.369081 -400.00568) (xy 353.400105 -400.04554)
			(xy 353.424146 -400.089963) (xy 353.440547 -400.137737) (xy 353.44886 -400.187559) (xy 353.449382 -400.212814)
			(xy 353.448917 -400.237187) (xy 353.441156 -400.285311) (xy 353.425835 -400.331587) (xy 353.403344 -400.374834)
			(xy 353.389184 -400.394678) (xy 353.383596 -400.402552) (xy 353.378516 -400.420332) (xy 353.386898 -400.506946)
			(xy 353.395026 -400.52371) (xy 353.402138 -400.53006) (xy 353.42127 -400.548196) (xy 353.454858 -400.588826)
			(xy 353.48253 -400.633695) (xy 353.503758 -400.681948) (xy 353.518137 -400.732666) (xy 353.525393 -400.78488)
			(xy 353.525836 -400.811238) (xy 353.525836 -401.674838) (xy 353.525409 -401.701012) (xy 353.518213 -401.752864)
			(xy 353.504 -401.803247) (xy 353.483039 -401.851216) (xy 353.455722 -401.895872) (xy 353.422561 -401.936378)
			(xy 353.403662 -401.954492) (xy 353.396296 -401.96135) (xy 353.388168 -401.978876) (xy 353.382834 -402.069046)
			(xy 353.38893 -402.087334) (xy 353.395534 -402.094954) (xy 353.410439 -402.112994) (xy 353.435502 -402.152513)
			(xy 353.454748 -402.195169) (xy 353.467794 -402.240109) (xy 353.47438 -402.28644) (xy 353.474782 -402.309838)
			(xy 353.474272 -402.335825) (xy 353.466142 -402.38716) (xy 353.450081 -402.43659) (xy 353.426485 -402.4829)
			(xy 353.395935 -402.524948) (xy 353.359184 -402.561699) (xy 353.317136 -402.592249) (xy 353.270826 -402.615845)
			(xy 353.221396 -402.631906) (xy 353.170061 -402.640036) (xy 353.118087 -402.640036) (xy 353.066752 -402.631906)
			(xy 353.017322 -402.615845) (xy 352.971012 -402.592249) (xy 352.928964 -402.561699) (xy 352.892213 -402.524948)
			(xy 352.861663 -402.4829) (xy 352.838067 -402.43659) (xy 352.822006 -402.38716) (xy 352.813876 -402.335825)
			(xy 352.813366 -402.309838) (xy 352.813787 -402.286441) (xy 352.820374 -402.240114) (xy 352.833421 -402.195177)
			(xy 352.852668 -402.152526) (xy 352.877732 -402.113011) (xy 352.892614 -402.094954) (xy 352.899218 -402.087334)
			(xy 352.905314 -402.069046) (xy 352.89998 -401.978876) (xy 352.891852 -401.96135) (xy 352.884486 -401.954492)
			(xy 352.865587 -401.936378) (xy 352.832424 -401.895874) (xy 352.805108 -401.851218) (xy 352.784151 -401.803248)
			(xy 352.769946 -401.752864) (xy 352.76276 -401.701012) (xy 352.762312 -401.674838) (xy 352.325432 -401.674838)
			(xy 352.324981 -401.701002) (xy 352.31783 -401.752838) (xy 352.303667 -401.803213) (xy 352.282757 -401.851181)
			(xy 352.255493 -401.895844) (xy 352.222385 -401.936366) (xy 352.203512 -401.954492) (xy 352.196146 -401.96135)
			(xy 352.188018 -401.978876) (xy 352.182684 -402.069046) (xy 352.18878 -402.087334) (xy 352.195384 -402.094954)
			(xy 352.210282 -402.113) (xy 352.235347 -402.152517) (xy 352.254595 -402.195171) (xy 352.267643 -402.24011)
			(xy 352.27423 -402.28644) (xy 352.274632 -402.309838) (xy 352.274122 -402.335825) (xy 352.265992 -402.38716)
			(xy 352.249931 -402.43659) (xy 352.226335 -402.4829) (xy 352.195785 -402.524948) (xy 352.159034 -402.561699)
			(xy 352.116986 -402.592249) (xy 352.070676 -402.615845) (xy 352.021246 -402.631906) (xy 351.969911 -402.640036)
			(xy 351.917937 -402.640036) (xy 351.866602 -402.631906) (xy 351.817172 -402.615845) (xy 351.770862 -402.592249)
			(xy 351.728814 -402.561699) (xy 351.692063 -402.524948) (xy 351.661513 -402.4829) (xy 351.637917 -402.43659)
			(xy 351.621856 -402.38716) (xy 351.613726 -402.335825) (xy 351.613216 -402.309838) (xy 351.613649 -402.286442)
			(xy 351.620234 -402.240116) (xy 351.633279 -402.195179) (xy 351.652524 -402.152528) (xy 351.677584 -402.113012)
			(xy 351.692464 -402.094954) (xy 351.699068 -402.087334) (xy 351.705164 -402.069046) (xy 351.69983 -401.978876)
			(xy 351.691702 -401.96135) (xy 351.684336 -401.954492) (xy 351.665448 -401.936379) (xy 351.632329 -401.895861)
			(xy 351.605058 -401.851197) (xy 351.584146 -401.803225) (xy 351.569986 -401.752846) (xy 351.562843 -401.701004)
			(xy 351.562416 -401.674838) (xy 351.125536 -401.674838) (xy 351.125002 -401.703743) (xy 351.116297 -401.760893)
			(xy 351.099076 -401.816077) (xy 351.073733 -401.868035) (xy 351.040848 -401.915579) (xy 351.021396 -401.936966)
			(xy 351.0153 -401.94357) (xy 351.008188 -401.959572) (xy 351.0026 -402.041868) (xy 351.007426 -402.058886)
			(xy 351.012506 -402.065998) (xy 351.027149 -402.087223) (xy 351.050399 -402.133246) (xy 351.066223 -402.182321)
			(xy 351.074237 -402.233257) (xy 351.074736 -402.259038) (xy 351.074226 -402.285025) (xy 351.066096 -402.33636)
			(xy 351.050035 -402.38579) (xy 351.026439 -402.4321) (xy 350.995889 -402.474148) (xy 350.959138 -402.510899)
			(xy 350.91709 -402.541449) (xy 350.87078 -402.565045) (xy 350.82135 -402.581106) (xy 350.770015 -402.589236)
			(xy 350.718041 -402.589236) (xy 350.666706 -402.581106) (xy 350.617276 -402.565045) (xy 350.570966 -402.541449)
			(xy 350.528918 -402.510899) (xy 350.492167 -402.474148) (xy 350.461617 -402.4321) (xy 350.438021 -402.38579)
			(xy 350.42196 -402.33636) (xy 350.41383 -402.285025) (xy 350.41332 -402.259038) (xy 350.413789 -402.233254)
			(xy 350.421797 -402.182313) (xy 350.437624 -402.133234) (xy 350.460887 -402.087212) (xy 350.47555 -402.065998)
			(xy 350.48063 -402.058886) (xy 350.485456 -402.041868) (xy 350.479868 -401.959572) (xy 350.472756 -401.94357)
			(xy 350.46666 -401.936966) (xy 350.44717 -401.915609) (xy 350.414265 -401.868069) (xy 350.388916 -401.816106)
			(xy 350.371705 -401.760909) (xy 350.363028 -401.703747) (xy 350.36252 -401.674838) (xy 349.92564 -401.674838)
			(xy 349.925186 -401.701002) (xy 349.918035 -401.752838) (xy 349.903873 -401.803212) (xy 349.882964 -401.85118)
			(xy 349.8557 -401.895844) (xy 349.822593 -401.936366) (xy 349.80372 -401.954492) (xy 349.796354 -401.96135)
			(xy 349.788226 -401.978876) (xy 349.782892 -402.069046) (xy 349.788988 -402.087334) (xy 349.795592 -402.094954)
			(xy 349.810491 -402.112999) (xy 349.835556 -402.152516) (xy 349.854804 -402.19517) (xy 349.867851 -402.24011)
			(xy 349.874438 -402.28644) (xy 349.87484 -402.309838) (xy 349.87433 -402.335825) (xy 349.8662 -402.38716)
			(xy 349.850139 -402.43659) (xy 349.826543 -402.4829) (xy 349.795993 -402.524948) (xy 349.759242 -402.561699)
			(xy 349.717194 -402.592249) (xy 349.670884 -402.615845) (xy 349.621454 -402.631906) (xy 349.570119 -402.640036)
			(xy 349.518145 -402.640036) (xy 349.46681 -402.631906) (xy 349.41738 -402.615845) (xy 349.37107 -402.592249)
			(xy 349.329022 -402.561699) (xy 349.292271 -402.524948) (xy 349.261721 -402.4829) (xy 349.238125 -402.43659)
			(xy 349.222064 -402.38716) (xy 349.213934 -402.335825) (xy 349.213424 -402.309838) (xy 349.213855 -402.286442)
			(xy 349.220441 -402.240116) (xy 349.233486 -402.195179) (xy 349.252731 -402.152528) (xy 349.277791 -402.113012)
			(xy 349.292672 -402.094954) (xy 349.299276 -402.087334) (xy 349.305372 -402.069046) (xy 349.300038 -401.978876)
			(xy 349.29191 -401.96135) (xy 349.284544 -401.954492) (xy 349.265658 -401.936377) (xy 349.232538 -401.89586)
			(xy 349.205267 -401.851196) (xy 349.184354 -401.803225) (xy 349.170194 -401.752845) (xy 349.163051 -401.701004)
			(xy 349.162624 -401.674838) (xy 348.725744 -401.674838) (xy 348.725289 -401.701002) (xy 348.718138 -401.752838)
			(xy 348.703976 -401.803212) (xy 348.683067 -401.85118) (xy 348.655804 -401.895844) (xy 348.622696 -401.936366)
			(xy 348.603824 -401.954492) (xy 348.596458 -401.96135) (xy 348.58833 -401.978876) (xy 348.582996 -402.069046)
			(xy 348.589092 -402.087334) (xy 348.595696 -402.094954) (xy 348.610595 -402.112999) (xy 348.63566 -402.152516)
			(xy 348.654908 -402.19517) (xy 348.667955 -402.24011) (xy 348.674542 -402.28644) (xy 348.674944 -402.309838)
			(xy 348.674434 -402.335825) (xy 348.666304 -402.38716) (xy 348.650243 -402.43659) (xy 348.626647 -402.4829)
			(xy 348.596097 -402.524948) (xy 348.559346 -402.561699) (xy 348.517298 -402.592249) (xy 348.470988 -402.615845)
			(xy 348.421558 -402.631906) (xy 348.370223 -402.640036) (xy 348.318249 -402.640036) (xy 348.266914 -402.631906)
			(xy 348.217484 -402.615845) (xy 348.171174 -402.592249) (xy 348.129126 -402.561699) (xy 348.092375 -402.524948)
			(xy 348.061825 -402.4829) (xy 348.038229 -402.43659) (xy 348.022168 -402.38716) (xy 348.014038 -402.335825)
			(xy 348.013528 -402.309838) (xy 348.013958 -402.286442) (xy 348.020544 -402.240116) (xy 348.033589 -402.195179)
			(xy 348.052834 -402.152527) (xy 348.077895 -402.113012) (xy 348.092776 -402.094954) (xy 348.09938 -402.087334)
			(xy 348.105476 -402.069046) (xy 348.100142 -401.978876) (xy 348.092014 -401.96135) (xy 348.084648 -401.954492)
			(xy 348.065763 -401.936377) (xy 348.032643 -401.895859) (xy 348.005371 -401.851196) (xy 347.984459 -401.803224)
			(xy 347.970298 -401.752845) (xy 347.963155 -401.701004) (xy 347.962728 -401.674838) (xy 347.525848 -401.674838)
			(xy 347.525418 -401.701012) (xy 347.518221 -401.752863) (xy 347.504009 -401.803246) (xy 347.483049 -401.851215)
			(xy 347.455732 -401.895871) (xy 347.422572 -401.936377) (xy 347.403674 -401.954492) (xy 347.396308 -401.96135)
			(xy 347.38818 -401.978876) (xy 347.382846 -402.069046) (xy 347.388942 -402.087334) (xy 347.395546 -402.094954)
			(xy 347.410453 -402.112993) (xy 347.435515 -402.152512) (xy 347.45476 -402.195168) (xy 347.467806 -402.240109)
			(xy 347.474392 -402.28644) (xy 347.474794 -402.309838) (xy 347.474284 -402.335825) (xy 347.466154 -402.38716)
			(xy 347.450093 -402.43659) (xy 347.426497 -402.4829) (xy 347.395947 -402.524948) (xy 347.359196 -402.561699)
			(xy 347.317148 -402.592249) (xy 347.270838 -402.615845) (xy 347.221408 -402.631906) (xy 347.170073 -402.640036)
			(xy 347.118099 -402.640036) (xy 347.066764 -402.631906) (xy 347.017334 -402.615845) (xy 346.971024 -402.592249)
			(xy 346.928976 -402.561699) (xy 346.892225 -402.524948) (xy 346.861675 -402.4829) (xy 346.838079 -402.43659)
			(xy 346.822018 -402.38716) (xy 346.813888 -402.335825) (xy 346.813378 -402.309838) (xy 346.813796 -402.286441)
			(xy 346.820383 -402.240114) (xy 346.83343 -402.195177) (xy 346.852678 -402.152525) (xy 346.877743 -402.113011)
			(xy 346.892626 -402.094954) (xy 346.89923 -402.087334) (xy 346.905326 -402.069046) (xy 346.899992 -401.978876)
			(xy 346.891864 -401.96135) (xy 346.884498 -401.954492) (xy 346.865601 -401.936376) (xy 346.832438 -401.895873)
			(xy 346.805121 -401.851218) (xy 346.784164 -401.803248) (xy 346.769958 -401.752864) (xy 346.762772 -401.701012)
			(xy 346.762324 -401.674838) (xy 346.325952 -401.674838) (xy 346.32552 -401.701012) (xy 346.318324 -401.752863)
			(xy 346.304112 -401.803246) (xy 346.283152 -401.851215) (xy 346.255836 -401.895871) (xy 346.222676 -401.936377)
			(xy 346.203778 -401.954492) (xy 346.196412 -401.96135) (xy 346.188284 -401.978876) (xy 346.18295 -402.069046)
			(xy 346.189046 -402.087334) (xy 346.19565 -402.094954) (xy 346.210558 -402.112992) (xy 346.235619 -402.152512)
			(xy 346.254865 -402.195168) (xy 346.26791 -402.240109) (xy 346.274496 -402.28644) (xy 346.274898 -402.309838)
			(xy 346.274388 -402.335825) (xy 346.266258 -402.38716) (xy 346.250197 -402.43659) (xy 346.226601 -402.4829)
			(xy 346.196051 -402.524948) (xy 346.1593 -402.561699) (xy 346.117252 -402.592249) (xy 346.070942 -402.615845)
			(xy 346.021512 -402.631906) (xy 345.970177 -402.640036) (xy 345.918203 -402.640036) (xy 345.866868 -402.631906)
			(xy 345.817438 -402.615845) (xy 345.771128 -402.592249) (xy 345.72908 -402.561699) (xy 345.692329 -402.524948)
			(xy 345.661779 -402.4829) (xy 345.638183 -402.43659) (xy 345.622122 -402.38716) (xy 345.613992 -402.335825)
			(xy 345.613482 -402.309838) (xy 345.613923 -402.286442) (xy 345.620508 -402.240117) (xy 345.633551 -402.195181)
			(xy 345.652793 -402.152529) (xy 345.677851 -402.113013) (xy 345.69273 -402.094954) (xy 345.699334 -402.087334)
			(xy 345.70543 -402.069046) (xy 345.700096 -401.978876) (xy 345.691968 -401.96135) (xy 345.684602 -401.954492)
			(xy 345.665706 -401.936375) (xy 345.632543 -401.895872) (xy 345.605226 -401.851217) (xy 345.584268 -401.803248)
			(xy 345.570062 -401.752864) (xy 345.562876 -401.701012) (xy 345.562428 -401.674838) (xy 345.125548 -401.674838)
			(xy 345.124991 -401.704987) (xy 345.115535 -401.764538) (xy 345.096832 -401.821862) (xy 345.069348 -401.875532)
			(xy 345.033767 -401.924212) (xy 345.012772 -401.945856) (xy 345.006168 -401.95246) (xy 344.998548 -401.969224)
			(xy 344.993214 -402.05533) (xy 344.998548 -402.07311) (xy 345.00439 -402.080476) (xy 345.020901 -402.102461)
			(xy 345.047174 -402.150756) (xy 345.065104 -402.202728) (xy 345.0742 -402.256949) (xy 345.074748 -402.284438)
			(xy 345.074238 -402.310425) (xy 345.066108 -402.36176) (xy 345.050047 -402.41119) (xy 345.026451 -402.4575)
			(xy 344.995901 -402.499548) (xy 344.95915 -402.536299) (xy 344.917102 -402.566849) (xy 344.870792 -402.590445)
			(xy 344.821362 -402.606506) (xy 344.770027 -402.614636) (xy 344.718053 -402.614636) (xy 344.666718 -402.606506)
			(xy 344.617288 -402.590445) (xy 344.570978 -402.566849) (xy 344.52893 -402.536299) (xy 344.492179 -402.499548)
			(xy 344.461629 -402.4575) (xy 344.438033 -402.41119) (xy 344.421972 -402.36176) (xy 344.413842 -402.310425)
			(xy 344.413332 -402.284438) (xy 344.413878 -402.256947) (xy 344.422955 -402.20272) (xy 344.440882 -402.150744)
			(xy 344.467164 -402.102451) (xy 344.48369 -402.080476) (xy 344.489532 -402.07311) (xy 344.494866 -402.05533)
			(xy 344.489532 -401.969224) (xy 344.481912 -401.95246) (xy 344.475308 -401.945856) (xy 344.454314 -401.924209)
			(xy 344.418722 -401.875535) (xy 344.391232 -401.821867) (xy 344.37253 -401.764542) (xy 344.363082 -401.704988)
			(xy 344.362532 -401.674838) (xy 343.925652 -401.674838) (xy 343.925114 -401.703742) (xy 343.916409 -401.760892)
			(xy 343.899189 -401.816076) (xy 343.873847 -401.868034) (xy 343.840963 -401.915579) (xy 343.821512 -401.936966)
			(xy 343.815416 -401.94357) (xy 343.808304 -401.959572) (xy 343.802716 -402.041868) (xy 343.807542 -402.058886)
			(xy 343.812622 -402.065998) (xy 343.827255 -402.08723) (xy 343.85051 -402.13325) (xy 343.866337 -402.182322)
			(xy 343.874353 -402.233257) (xy 343.874852 -402.259038) (xy 343.874342 -402.285025) (xy 343.866212 -402.33636)
			(xy 343.850151 -402.38579) (xy 343.826555 -402.4321) (xy 343.796005 -402.474148) (xy 343.759254 -402.510899)
			(xy 343.717206 -402.541449) (xy 343.670896 -402.565045) (xy 343.621466 -402.581106) (xy 343.570131 -402.589236)
			(xy 343.518157 -402.589236) (xy 343.466822 -402.581106) (xy 343.417392 -402.565045) (xy 343.371082 -402.541449)
			(xy 343.329034 -402.510899) (xy 343.292283 -402.474148) (xy 343.261733 -402.4321) (xy 343.238137 -402.38579)
			(xy 343.222076 -402.33636) (xy 343.213946 -402.285025) (xy 343.213436 -402.259038) (xy 343.21392 -402.233255)
			(xy 343.221926 -402.182315) (xy 343.237749 -402.133237) (xy 343.261006 -402.087213) (xy 343.275666 -402.065998)
			(xy 343.280746 -402.058886) (xy 343.285572 -402.041868) (xy 343.279984 -401.959572) (xy 343.272872 -401.94357)
			(xy 343.266776 -401.936966) (xy 343.247289 -401.915607) (xy 343.214382 -401.868068) (xy 343.189033 -401.816105)
			(xy 343.171821 -401.760909) (xy 343.163144 -401.703747) (xy 343.162636 -401.674838) (xy 342.725756 -401.674838)
			(xy 342.725324 -401.701012) (xy 342.718127 -401.752863) (xy 342.703916 -401.803246) (xy 342.682956 -401.851215)
			(xy 342.65564 -401.895871) (xy 342.62248 -401.936378) (xy 342.603582 -401.954492) (xy 342.596216 -401.96135)
			(xy 342.588088 -401.978876) (xy 342.582754 -402.069046) (xy 342.58885 -402.087334) (xy 342.595454 -402.094954)
			(xy 342.610347 -402.113004) (xy 342.635414 -402.152519) (xy 342.654664 -402.195172) (xy 342.667713 -402.240111)
			(xy 342.6743 -402.28644) (xy 342.674702 -402.309838) (xy 342.674192 -402.335825) (xy 342.666062 -402.38716)
			(xy 342.650001 -402.43659) (xy 342.626405 -402.4829) (xy 342.595855 -402.524948) (xy 342.559104 -402.561699)
			(xy 342.517056 -402.592249) (xy 342.470746 -402.615845) (xy 342.421316 -402.631906) (xy 342.369981 -402.640036)
			(xy 342.318007 -402.640036) (xy 342.266672 -402.631906) (xy 342.217242 -402.615845) (xy 342.170932 -402.592249)
			(xy 342.128884 -402.561699) (xy 342.092133 -402.524948) (xy 342.061583 -402.4829) (xy 342.037987 -402.43659)
			(xy 342.021926 -402.38716) (xy 342.013796 -402.335825) (xy 342.013286 -402.309838) (xy 342.013726 -402.286442)
			(xy 342.020311 -402.240117) (xy 342.033354 -402.19518) (xy 342.052597 -402.152529) (xy 342.077655 -402.113013)
			(xy 342.092534 -402.094954) (xy 342.099138 -402.087334) (xy 342.105234 -402.069046) (xy 342.0999 -401.978876)
			(xy 342.091772 -401.96135) (xy 342.084406 -401.954492) (xy 342.065511 -401.936375) (xy 342.032347 -401.895872)
			(xy 342.00503 -401.851217) (xy 341.984072 -401.803247) (xy 341.969866 -401.752864) (xy 341.96268 -401.701012)
			(xy 341.962232 -401.674838) (xy 341.52586 -401.674838) (xy 341.525457 -401.701013) (xy 341.518259 -401.752867)
			(xy 341.504044 -401.803251) (xy 341.483078 -401.851221) (xy 341.455756 -401.895876) (xy 341.422588 -401.93638)
			(xy 341.403686 -401.954492) (xy 341.39632 -401.96135) (xy 341.388192 -401.978876) (xy 341.382858 -402.069046)
			(xy 341.388954 -402.087334) (xy 341.395558 -402.094954) (xy 341.410452 -402.113004) (xy 341.435518 -402.152519)
			(xy 341.454768 -402.195172) (xy 341.467817 -402.240111) (xy 341.474404 -402.28644) (xy 341.474806 -402.309838)
			(xy 341.474296 -402.335825) (xy 341.466166 -402.38716) (xy 341.450105 -402.43659) (xy 341.426509 -402.4829)
			(xy 341.395959 -402.524948) (xy 341.359208 -402.561699) (xy 341.31716 -402.592249) (xy 341.27085 -402.615845)
			(xy 341.22142 -402.631906) (xy 341.170085 -402.640036) (xy 341.118111 -402.640036) (xy 341.066776 -402.631906)
			(xy 341.017346 -402.615845) (xy 340.971036 -402.592249) (xy 340.928988 -402.561699) (xy 340.892237 -402.524948)
			(xy 340.861687 -402.4829) (xy 340.838091 -402.43659) (xy 340.82203 -402.38716) (xy 340.8139 -402.335825)
			(xy 340.81339 -402.309838) (xy 340.813829 -402.286442) (xy 340.820414 -402.240117) (xy 340.833458 -402.19518)
			(xy 340.852701 -402.152529) (xy 340.877759 -402.113013) (xy 340.892638 -402.094954) (xy 340.899242 -402.087334)
			(xy 340.905338 -402.069046) (xy 340.900004 -401.978876) (xy 340.891876 -401.96135) (xy 340.88451 -401.954492)
			(xy 340.865616 -401.936374) (xy 340.832452 -401.895871) (xy 340.805134 -401.851217) (xy 340.784176 -401.803247)
			(xy 340.76997 -401.752864) (xy 340.762784 -401.701012) (xy 340.762336 -401.674838) (xy 340.325456 -401.674838)
			(xy 340.324917 -401.703742) (xy 340.316212 -401.760892) (xy 340.298992 -401.816076) (xy 340.273651 -401.868034)
			(xy 340.240767 -401.915579) (xy 340.221316 -401.936966) (xy 340.21522 -401.94357) (xy 340.208108 -401.959572)
			(xy 340.20252 -402.041868) (xy 340.207346 -402.058886) (xy 340.212426 -402.065998) (xy 340.227059 -402.08723)
			(xy 340.250314 -402.13325) (xy 340.266141 -402.182322) (xy 340.274157 -402.233257) (xy 340.274656 -402.259038)
			(xy 340.274146 -402.285025) (xy 340.266016 -402.33636) (xy 340.249955 -402.38579) (xy 340.226359 -402.4321)
			(xy 340.195809 -402.474148) (xy 340.159058 -402.510899) (xy 340.11701 -402.541449) (xy 340.0707 -402.565045)
			(xy 340.02127 -402.581106) (xy 339.969935 -402.589236) (xy 339.917961 -402.589236) (xy 339.866626 -402.581106)
			(xy 339.817196 -402.565045) (xy 339.770886 -402.541449) (xy 339.728838 -402.510899) (xy 339.692087 -402.474148)
			(xy 339.661537 -402.4321) (xy 339.637941 -402.38579) (xy 339.62188 -402.33636) (xy 339.61375 -402.285025)
			(xy 339.61324 -402.259038) (xy 339.613723 -402.233255) (xy 339.621729 -402.182314) (xy 339.637553 -402.133236)
			(xy 339.660809 -402.087213) (xy 339.67547 -402.065998) (xy 339.68055 -402.058886) (xy 339.685376 -402.041868)
			(xy 339.679788 -401.959572) (xy 339.672676 -401.94357) (xy 339.66658 -401.936966) (xy 339.647094 -401.915606)
			(xy 339.614187 -401.868068) (xy 339.588837 -401.816105) (xy 339.571625 -401.760909) (xy 339.562948 -401.703747)
			(xy 339.56244 -401.674838) (xy 339.12556 -401.674838) (xy 339.1251 -401.701001) (xy 339.11795 -401.752837)
			(xy 339.103788 -401.803211) (xy 339.08288 -401.851179) (xy 339.055618 -401.895843) (xy 339.022512 -401.936366)
			(xy 339.00364 -401.954492) (xy 338.996274 -401.96135) (xy 338.988146 -401.978876) (xy 338.982812 -402.069046)
			(xy 338.988908 -402.087334) (xy 338.995512 -402.094954) (xy 339.010414 -402.112997) (xy 339.035478 -402.152515)
			(xy 339.054725 -402.195169) (xy 339.067772 -402.24011) (xy 339.074358 -402.28644) (xy 339.07476 -402.309838)
			(xy 339.07425 -402.335825) (xy 339.06612 -402.38716) (xy 339.050059 -402.43659) (xy 339.026463 -402.4829)
			(xy 338.995913 -402.524948) (xy 338.959162 -402.561699) (xy 338.917114 -402.592249) (xy 338.870804 -402.615845)
			(xy 338.821374 -402.631906) (xy 338.770039 -402.640036) (xy 338.718065 -402.640036) (xy 338.66673 -402.631906)
			(xy 338.6173 -402.615845) (xy 338.57099 -402.592249) (xy 338.528942 -402.561699) (xy 338.492191 -402.524948)
			(xy 338.461641 -402.4829) (xy 338.438045 -402.43659) (xy 338.421984 -402.38716) (xy 338.413854 -402.335825)
			(xy 338.413344 -402.309838) (xy 338.41377 -402.286442) (xy 338.420356 -402.240115) (xy 338.433402 -402.195178)
			(xy 338.452648 -402.152527) (xy 338.47771 -402.113012) (xy 338.492592 -402.094954) (xy 338.499196 -402.087334)
			(xy 338.505292 -402.069046) (xy 338.499958 -401.978876) (xy 338.49183 -401.96135) (xy 338.484464 -401.954492)
			(xy 338.465563 -401.936393) (xy 338.432448 -401.89587) (xy 338.40518 -401.851203) (xy 338.384271 -401.803229)
			(xy 338.370113 -401.752847) (xy 338.362971 -401.701004) (xy 338.362544 -401.674838) (xy 337.925664 -401.674838)
			(xy 337.925049 -401.704996) (xy 337.915555 -401.764559) (xy 337.89681 -401.821888) (xy 337.869281 -401.875554)
			(xy 337.833653 -401.924222) (xy 337.812634 -401.945856) (xy 337.80603 -401.95246) (xy 337.79841 -401.969224)
			(xy 337.793076 -402.05533) (xy 337.79841 -402.07311) (xy 337.804252 -402.080476) (xy 337.820758 -402.102465)
			(xy 337.847033 -402.150758) (xy 337.864965 -402.202729) (xy 337.874061 -402.256949) (xy 337.87461 -402.284438)
			(xy 337.8741 -402.310425) (xy 337.86597 -402.36176) (xy 337.849909 -402.41119) (xy 337.826313 -402.4575)
			(xy 337.795763 -402.499548) (xy 337.759012 -402.536299) (xy 337.716964 -402.566849) (xy 337.670654 -402.590445)
			(xy 337.621224 -402.606506) (xy 337.569889 -402.614636) (xy 337.517915 -402.614636) (xy 337.46658 -402.606506)
			(xy 337.41715 -402.590445) (xy 337.37084 -402.566849) (xy 337.328792 -402.536299) (xy 337.292041 -402.499548)
			(xy 337.261491 -402.4575) (xy 337.237895 -402.41119) (xy 337.221834 -402.36176) (xy 337.213704 -402.310425)
			(xy 337.213194 -402.284438) (xy 337.213748 -402.256948) (xy 337.222824 -402.202722) (xy 337.240748 -402.150745)
			(xy 337.267027 -402.102452) (xy 337.283552 -402.080476) (xy 337.289394 -402.07311) (xy 337.294728 -402.05533)
			(xy 337.289394 -401.969224) (xy 337.281774 -401.95246) (xy 337.27517 -401.945856) (xy 337.254126 -401.924242)
			(xy 337.21848 -401.875577) (xy 337.190941 -401.821908) (xy 337.172194 -401.764572) (xy 337.162707 -401.705)
			(xy 337.16214 -401.674838) (xy 336.725768 -401.674838) (xy 336.725201 -401.705) (xy 336.715714 -401.764572)
			(xy 336.696967 -401.821908) (xy 336.669428 -401.875578) (xy 336.633784 -401.924244) (xy 336.612738 -401.945856)
			(xy 336.606134 -401.95246) (xy 336.598514 -401.969224) (xy 336.59318 -402.05533) (xy 336.598514 -402.07311)
			(xy 336.604356 -402.080476) (xy 336.62088 -402.102452) (xy 336.647159 -402.150746) (xy 336.665083 -402.202722)
			(xy 336.674158 -402.256948) (xy 336.674714 -402.284438) (xy 336.674204 -402.310425) (xy 336.666074 -402.36176)
			(xy 336.650013 -402.41119) (xy 336.626417 -402.4575) (xy 336.595867 -402.499548) (xy 336.559116 -402.536299)
			(xy 336.517068 -402.566849) (xy 336.470758 -402.590445) (xy 336.421328 -402.606506) (xy 336.369993 -402.614636)
			(xy 336.318019 -402.614636) (xy 336.266684 -402.606506) (xy 336.217254 -402.590445) (xy 336.170944 -402.566849)
			(xy 336.128896 -402.536299) (xy 336.092145 -402.499548) (xy 336.061595 -402.4575) (xy 336.037999 -402.41119)
			(xy 336.021938 -402.36176) (xy 336.013808 -402.310425) (xy 336.013298 -402.284438) (xy 336.013847 -402.256949)
			(xy 336.022943 -402.202729) (xy 336.040876 -402.150758) (xy 336.067152 -402.102466) (xy 336.083656 -402.080476)
			(xy 336.089498 -402.07311) (xy 336.094832 -402.05533) (xy 336.089498 -401.969224) (xy 336.081878 -401.95246)
			(xy 336.075274 -401.945856) (xy 336.054255 -401.924222) (xy 336.018626 -401.875554) (xy 335.991096 -401.821888)
			(xy 335.972351 -401.764559) (xy 335.962857 -401.704996) (xy 335.962244 -401.674838) (xy 335.962244 -401.5486)
			(xy 335.961757 -401.538589) (xy 335.954099 -401.52009) (xy 335.939947 -401.505926) (xy 335.921454 -401.498252)
			(xy 335.911444 -401.4978) (xy 334.125062 -401.4978) (xy 334.114995 -401.49737) (xy 334.096401 -401.489646)
			(xy 334.088994 -401.482814) (xy 333.941674 -401.335494) (xy 333.932314 -401.327297) (xy 333.908562 -401.320021)
			(xy 333.896208 -401.321524) (xy 333.801212 -401.340066) (xy 333.781654 -401.355814) (xy 333.776574 -401.367498)
			(xy 333.765165 -401.392885) (xy 333.736072 -401.440332) (xy 333.700392 -401.483047) (xy 333.658882 -401.520123)
			(xy 333.612424 -401.550771) (xy 333.562005 -401.574342) (xy 333.508696 -401.590335) (xy 333.453628 -401.59841)
			(xy 333.4258 -401.598892) (xy 333.398548 -401.598429) (xy 333.344597 -401.590672) (xy 333.292301 -401.575315)
			(xy 333.242721 -401.552673) (xy 333.196869 -401.523204) (xy 333.155678 -401.487511) (xy 333.119986 -401.446318)
			(xy 333.09052 -401.400464) (xy 333.067879 -401.350884) (xy 333.052525 -401.298587) (xy 333.04477 -401.244636)
			(xy 333.044292 -401.217384) (xy 333.044548 -401.197357) (xy 333.04875 -401.157523) (xy 333.052674 -401.137882)
			(xy 333.05496 -401.126706) (xy 333.050134 -401.105116) (xy 332.988412 -401.025614) (xy 332.9686 -401.015708)
			(xy 332.95717 -401.0152) (xy 332.930635 -401.013701) (xy 332.878333 -401.00427) (xy 332.827845 -400.98767)
			(xy 332.780151 -400.964224) (xy 332.736172 -400.934384) (xy 332.696762 -400.898728) (xy 332.662682 -400.857947)
			(xy 332.634592 -400.812831) (xy 332.613037 -400.764252) (xy 332.598433 -400.713152) (xy 332.591063 -400.660519)
			(xy 332.590648 -400.633946) (xy 332.591108 -400.60669) (xy 332.598859 -400.552732) (xy 332.614211 -400.500426)
			(xy 332.63685 -400.450837) (xy 332.666316 -400.404975) (xy 332.702009 -400.363773) (xy 332.743203 -400.32807)
			(xy 332.789058 -400.298593) (xy 332.838641 -400.275942) (xy 332.890943 -400.260578) (xy 332.9449 -400.252814)
			(xy 332.972156 -400.252438) (xy 333.009494 -400.254216) (xy 333.020162 -400.255232) (xy 333.040482 -400.248628)
			(xy 333.104236 -400.190716) (xy 333.11175 -400.183174) (xy 333.12042 -400.163754) (xy 333.121 -400.153124)
			(xy 333.121 -397.879062) (xy 333.12057 -397.868995) (xy 333.112846 -397.850401) (xy 333.106014 -397.842994)
			(xy 332.711806 -397.448786) (xy 332.704412 -397.441929) (xy 332.685813 -397.434179) (xy 332.675738 -397.4338)
			(xy 331.391006 -397.4338) (xy 331.379028 -397.434447) (xy 331.357689 -397.445327) (xy 331.350112 -397.454628)
			(xy 331.329509 -397.481732) (xy 331.282222 -397.530714) (xy 331.22882 -397.572947) (xy 331.17026 -397.607675)
			(xy 331.107588 -397.634276) (xy 331.041927 -397.652275) (xy 330.974452 -397.66135) (xy 330.94041 -397.661892)
			(xy 330.909321 -397.661425) (xy 330.847607 -397.65384) (xy 330.78728 -397.638782) (xy 330.729241 -397.616477)
			(xy 330.674357 -397.587257) (xy 330.623448 -397.551559) (xy 330.60005 -397.531082) (xy 330.590144 -397.522192)
			(xy 330.564236 -397.51635) (xy 330.455524 -397.548862) (xy 330.436982 -397.568166) (xy 330.43368 -397.58112)
			(xy 330.426187 -397.608022) (xy 330.404414 -397.659446) (xy 330.375375 -397.707145) (xy 330.339691 -397.750101)
			(xy 330.298126 -397.787395) (xy 330.251567 -397.81823) (xy 330.20101 -397.841946) (xy 330.147536 -397.858038)
			(xy 330.092286 -397.86616) (xy 330.064364 -397.866616) (xy 330.03709 -397.866149) (xy 329.983097 -397.858374)
			(xy 329.930763 -397.84299) (xy 329.881153 -397.820308) (xy 329.835279 -397.790792) (xy 329.794077 -397.755043)
			(xy 329.758386 -397.713791) (xy 329.728935 -397.667876) (xy 329.706323 -397.618234) (xy 329.691012 -397.565878)
			(xy 329.683313 -397.511875) (xy 329.682856 -397.4846) (xy 329.682436 -397.474582) (xy 329.674764 -397.456073)
			(xy 329.66059 -397.441911) (xy 329.642074 -397.434256) (xy 329.632056 -397.4338) (xy 329.034648 -397.4338)
			(xy 329.025728 -397.434194) (xy 329.008963 -397.440299) (xy 329.001882 -397.445738) (xy 328.981184 -397.462443)
			(xy 328.936038 -397.490566) (xy 328.887428 -397.512153) (xy 328.836292 -397.526787) (xy 328.78362 -397.534184)
			(xy 328.757026 -397.534638) (xy 328.729093 -397.534153) (xy 328.673823 -397.526012) (xy 328.620331 -397.5099)
			(xy 328.569759 -397.486162) (xy 328.546206 -397.471138) (xy 328.53122 -397.461232) (xy 328.495152 -397.464788)
			(xy 328.035666 -397.924274) (xy 328.028824 -397.931673) (xy 328.021106 -397.950272) (xy 328.02068 -397.960342)
			(xy 328.02068 -398.597374) (xy 328.02118 -398.607556) (xy 328.029165 -398.626295) (xy 328.036174 -398.633696)
			(xy 328.095864 -398.691862) (xy 328.11466 -398.699228) (xy 328.125074 -398.698974) (xy 328.139298 -398.69872)
			(xy 328.169993 -398.699199) (xy 328.230934 -398.706619) (xy 328.29054 -398.721315) (xy 328.347945 -398.743075)
			(xy 328.402316 -398.771582) (xy 328.427842 -398.788636) (xy 328.436594 -398.794107) (xy 328.456798 -398.798235)
			(xy 328.477002 -398.794107) (xy 328.485754 -398.788636) (xy 328.511282 -398.771583) (xy 328.565645 -398.74306)
			(xy 328.623049 -398.721295) (xy 328.682658 -398.706606) (xy 328.743602 -398.699208) (xy 328.774298 -398.69872)
			(xy 328.80503 -398.699166) (xy 328.866045 -398.706574) (xy 328.925722 -398.721284) (xy 328.98319 -398.743079)
			(xy 329.037613 -398.771643) (xy 329.088196 -398.806559) (xy 329.1342 -398.847318) (xy 329.174957 -398.893325)
			(xy 329.20987 -398.943909) (xy 329.238431 -398.998333) (xy 329.260224 -399.055803) (xy 329.274931 -399.115481)
			(xy 329.282336 -399.176496) (xy 329.282806 -399.207228) (xy 329.282232 -399.242073) (xy 329.272714 -399.311112)
			(xy 329.253862 -399.378204) (xy 329.226027 -399.442095) (xy 329.208384 -399.47215) (xy 329.203304 -399.480278)
			(xy 329.200002 -399.498058) (xy 329.21448 -399.582386) (xy 329.223624 -399.59788) (xy 329.230736 -399.603976)
			(xy 329.255394 -399.624709) (xy 329.299797 -399.671388) (xy 329.337944 -399.723304) (xy 329.369225 -399.779624)
			(xy 329.393137 -399.839447) (xy 329.409298 -399.901811) (xy 329.417449 -399.965718) (xy 329.417934 -399.99793)
			(xy 329.417453 -400.028624) (xy 329.410029 -400.089563) (xy 329.395328 -400.149167) (xy 329.373564 -400.206569)
			(xy 329.345053 -400.260936) (xy 329.328018 -400.286474) (xy 329.32255 -400.295225) (xy 329.318431 -400.315425)
			(xy 329.32257 -400.335621) (xy 329.328018 -400.344386) (xy 329.345072 -400.369913) (xy 329.3736 -400.424276)
			(xy 329.395371 -400.48168) (xy 329.410066 -400.541288) (xy 329.417471 -400.602233) (xy 329.417934 -400.63293)
			(xy 329.417468 -400.66366) (xy 329.410057 -400.724673) (xy 329.395346 -400.784347) (xy 329.37355 -400.841813)
			(xy 329.344986 -400.896233) (xy 329.310071 -400.946814) (xy 329.269315 -400.992818) (xy 329.223311 -401.033574)
			(xy 329.17273 -401.068488) (xy 329.118309 -401.097051) (xy 329.060843 -401.118847) (xy 329.001169 -401.133558)
			(xy 328.940156 -401.140968) (xy 328.909426 -401.141438) (xy 328.888344 -401.14093) (xy 328.877422 -401.140422)
			(xy 328.857864 -401.148042) (xy 328.789538 -401.216368) (xy 328.781918 -401.235926) (xy 328.782426 -401.246848)
			(xy 328.782934 -401.26793) (xy 328.782453 -401.298624) (xy 328.775029 -401.359563) (xy 328.760328 -401.419167)
			(xy 328.738564 -401.476569) (xy 328.710053 -401.530936) (xy 328.693018 -401.556474) (xy 328.68755 -401.565225)
			(xy 328.683431 -401.585425) (xy 328.68757 -401.605621) (xy 328.693018 -401.614386) (xy 328.710072 -401.639913)
			(xy 328.7386 -401.694276) (xy 328.760371 -401.75168) (xy 328.775066 -401.811288) (xy 328.782471 -401.872233)
			(xy 328.782934 -401.90293) (xy 329.637898 -401.90293) (xy 329.638382 -401.87556) (xy 329.646196 -401.821382)
			(xy 329.661681 -401.768879) (xy 329.684518 -401.719132) (xy 329.714239 -401.673164) (xy 329.731878 -401.652232)
			(xy 329.737974 -401.64512) (xy 329.744324 -401.628102) (xy 329.744324 -401.542758) (xy 329.737974 -401.52574)
			(xy 329.731878 -401.518628) (xy 329.714269 -401.49767) (xy 329.684546 -401.451706) (xy 329.661702 -401.401963)
			(xy 329.646206 -401.349465) (xy 329.638376 -401.295291) (xy 329.638372 -401.240554) (xy 329.646196 -401.186379)
			(xy 329.661686 -401.133879) (xy 329.684525 -401.084134) (xy 329.714241 -401.038166) (xy 329.731878 -401.017232)
			(xy 329.737974 -401.01012) (xy 329.744324 -400.993102) (xy 329.744324 -400.907758) (xy 329.737974 -400.89074)
			(xy 329.731878 -400.883628) (xy 329.714269 -400.86267) (xy 329.684546 -400.816706) (xy 329.661702 -400.766963)
			(xy 329.646206 -400.714465) (xy 329.638376 -400.660291) (xy 329.638372 -400.605554) (xy 329.646196 -400.551379)
			(xy 329.661686 -400.498879) (xy 329.684525 -400.449134) (xy 329.714241 -400.403166) (xy 329.731878 -400.382232)
			(xy 329.737974 -400.37512) (xy 329.744324 -400.358102) (xy 329.744324 -400.272758) (xy 329.737974 -400.25574)
			(xy 329.731878 -400.248628) (xy 329.714235 -400.227699) (xy 329.684525 -400.181725) (xy 329.66169 -400.131977)
			(xy 329.6462 -400.079475) (xy 329.638372 -400.025299) (xy 329.637898 -399.99793) (xy 329.638403 -399.970461)
			(xy 329.646285 -399.916091) (xy 329.661878 -399.863412) (xy 329.684858 -399.813511) (xy 329.714752 -399.767419)
			(xy 329.750942 -399.726085) (xy 329.771502 -399.707862) (xy 329.779122 -399.701258) (xy 329.788266 -399.683478)
			(xy 329.795378 -399.591276) (xy 329.789028 -399.571972) (xy 329.78217 -399.564352) (xy 329.764777 -399.543446)
			(xy 329.735469 -399.497637) (xy 329.71295 -399.448137) (xy 329.697673 -399.395945) (xy 329.689948 -399.342115)
			(xy 329.68946 -399.314924) (xy 329.689926 -399.287554) (xy 329.697741 -399.233374) (xy 329.71323 -399.18087)
			(xy 329.736072 -399.131123) (xy 329.765798 -399.085157) (xy 329.78344 -399.064226) (xy 329.789536 -399.057114)
			(xy 329.795886 -399.040096) (xy 329.795886 -398.954752) (xy 329.789536 -398.937734) (xy 329.78344 -398.930622)
			(xy 329.765804 -398.909687) (xy 329.73609 -398.863716) (xy 329.713253 -398.813969) (xy 329.697761 -398.761469)
			(xy 329.689934 -398.707293) (xy 329.68946 -398.679924) (xy 329.689946 -398.652673) (xy 329.697702 -398.598725)
			(xy 329.713057 -398.54643) (xy 329.735699 -398.496853) (xy 329.765165 -398.451003) (xy 329.800856 -398.409812)
			(xy 329.842047 -398.374121) (xy 329.887897 -398.344655) (xy 329.937474 -398.322013) (xy 329.989769 -398.306658)
			(xy 330.043717 -398.298902) (xy 330.098219 -398.298902) (xy 330.152167 -398.306658) (xy 330.204462 -398.322013)
			(xy 330.254039 -398.344655) (xy 330.299889 -398.374121) (xy 330.34108 -398.409812) (xy 330.376771 -398.451003)
			(xy 330.406237 -398.496853) (xy 330.428879 -398.54643) (xy 330.444234 -398.598725) (xy 330.45199 -398.652673)
			(xy 330.452476 -398.679924) (xy 330.45203 -398.707295) (xy 330.444208 -398.761475) (xy 330.428715 -398.813979)
			(xy 330.405868 -398.863725) (xy 330.376139 -398.909691) (xy 330.358496 -398.930622) (xy 330.3524 -398.937734)
			(xy 330.34605 -398.954752) (xy 330.34605 -399.040096) (xy 330.3524 -399.057114) (xy 330.358496 -399.064226)
			(xy 330.376113 -399.085176) (xy 330.405829 -399.131144) (xy 330.428669 -399.180887) (xy 330.444165 -399.233383)
			(xy 330.451999 -399.287556) (xy 330.452476 -399.314924) (xy 330.451874 -399.344533) (xy 330.442715 -399.403039)
			(xy 330.424635 -399.459431) (xy 330.398069 -399.512356) (xy 330.363652 -399.560547) (xy 330.32221 -399.602848)
			(xy 330.298806 -399.620994) (xy 330.290368 -399.627915) (xy 330.279827 -399.646995) (xy 330.278486 -399.657824)
			(xy 330.274422 -399.713958) (xy 330.285598 -399.724626) (xy 330.292936 -399.731156) (xy 330.311094 -399.738603)
			(xy 330.320904 -399.739104) (xy 330.352908 -399.739104) (xy 330.362722 -399.738612) (xy 330.380886 -399.731171)
			(xy 330.388214 -399.724626) (xy 330.409704 -399.704442) (xy 330.457766 -399.670299) (xy 330.510508 -399.643955)
			(xy 330.566675 -399.626037) (xy 330.624928 -399.61697) (xy 330.654406 -399.616422) (xy 330.681777 -399.616879)
			(xy 330.735956 -399.624698) (xy 330.78846 -399.640189) (xy 330.838206 -399.663033) (xy 330.884173 -399.69276)
			(xy 330.905104 -399.710402) (xy 330.912216 -399.716498) (xy 330.929234 -399.722848) (xy 331.014578 -399.722848)
			(xy 331.031596 -399.716498) (xy 331.038708 -399.710402) (xy 331.059641 -399.692761) (xy 331.105609 -399.663037)
			(xy 331.155355 -399.640191) (xy 331.207857 -399.624695) (xy 331.262035 -399.616866) (xy 331.316777 -399.616866)
			(xy 331.370955 -399.624695) (xy 331.423457 -399.640191) (xy 331.473203 -399.663037) (xy 331.519171 -399.692761)
			(xy 331.540104 -399.710402) (xy 331.547216 -399.716498) (xy 331.564234 -399.722848) (xy 331.649578 -399.722848)
			(xy 331.666596 -399.716498) (xy 331.673708 -399.710402) (xy 331.694626 -399.692746) (xy 331.740603 -399.663037)
			(xy 331.790354 -399.640204) (xy 331.842858 -399.624717) (xy 331.897036 -399.616893) (xy 331.924406 -399.616422)
			(xy 331.95166 -399.61685) (xy 332.005614 -399.624608) (xy 332.057914 -399.639967) (xy 332.107497 -399.662612)
			(xy 332.153351 -399.692084) (xy 332.194545 -399.727781) (xy 332.230238 -399.768978) (xy 332.259705 -399.814835)
			(xy 332.282346 -399.864419) (xy 332.297699 -399.916721) (xy 332.305453 -399.970676) (xy 332.305914 -399.99793)
			(xy 332.305462 -400.025301) (xy 332.29764 -400.07948) (xy 332.282148 -400.131983) (xy 332.259303 -400.18173)
			(xy 332.229576 -400.227696) (xy 332.211934 -400.248628) (xy 332.205838 -400.25574) (xy 332.199488 -400.272758)
			(xy 332.199488 -400.358102) (xy 332.205838 -400.37512) (xy 332.211934 -400.382232) (xy 332.229606 -400.40314)
			(xy 332.259332 -400.449111) (xy 332.282178 -400.498861) (xy 332.297674 -400.551367) (xy 332.305501 -400.60555)
			(xy 332.305497 -400.660295) (xy 332.297664 -400.714477) (xy 332.282162 -400.766981) (xy 332.25931 -400.816728)
			(xy 332.229578 -400.862696) (xy 332.211934 -400.883628) (xy 332.205838 -400.89074) (xy 332.199488 -400.907758)
			(xy 332.199488 -400.993102) (xy 332.205838 -401.01012) (xy 332.211934 -401.017232) (xy 332.229606 -401.03814)
			(xy 332.259332 -401.084111) (xy 332.282178 -401.133861) (xy 332.297674 -401.186367) (xy 332.305501 -401.24055)
			(xy 332.305497 -401.295295) (xy 332.297664 -401.349477) (xy 332.282162 -401.401981) (xy 332.25931 -401.451728)
			(xy 332.229578 -401.497696) (xy 332.211934 -401.518628) (xy 332.205838 -401.52574) (xy 332.199488 -401.542758)
			(xy 332.199488 -401.628102) (xy 332.205838 -401.64512) (xy 332.211934 -401.652232) (xy 332.22956 -401.673175)
			(xy 332.259273 -401.719145) (xy 332.282111 -401.76889) (xy 332.297605 -401.821388) (xy 332.305437 -401.875562)
			(xy 332.305914 -401.90293) (xy 332.30545 -401.930182) (xy 332.29769 -401.98413) (xy 332.282331 -402.036425)
			(xy 332.259687 -402.086002) (xy 332.230218 -402.131852) (xy 332.194524 -402.173041) (xy 332.153332 -402.208732)
			(xy 332.107481 -402.238198) (xy 332.057902 -402.260839) (xy 332.005606 -402.276195) (xy 331.951658 -402.283952)
			(xy 331.924406 -402.284438) (xy 331.897035 -402.283984) (xy 331.842855 -402.276165) (xy 331.790351 -402.260674)
			(xy 331.740604 -402.23783) (xy 331.694639 -402.208101) (xy 331.673708 -402.190458) (xy 331.666596 -402.184362)
			(xy 331.649578 -402.178012) (xy 331.564234 -402.178012) (xy 331.547216 -402.184362) (xy 331.540104 -402.190458)
			(xy 331.519171 -402.208099) (xy 331.473203 -402.237823) (xy 331.423457 -402.260669) (xy 331.370955 -402.276165)
			(xy 331.316777 -402.283994) (xy 331.262035 -402.283994) (xy 331.207857 -402.276165) (xy 331.155355 -402.260669)
			(xy 331.105609 -402.237823) (xy 331.059641 -402.208099) (xy 331.038708 -402.190458) (xy 331.031596 -402.184362)
			(xy 331.014578 -402.178012) (xy 330.929234 -402.178012) (xy 330.912216 -402.184362) (xy 330.905104 -402.190458)
			(xy 330.884171 -402.208099) (xy 330.838203 -402.237823) (xy 330.788457 -402.260669) (xy 330.735955 -402.276165)
			(xy 330.681777 -402.283994) (xy 330.627035 -402.283994) (xy 330.572857 -402.276165) (xy 330.520355 -402.260669)
			(xy 330.470609 -402.237823) (xy 330.424641 -402.208099) (xy 330.403708 -402.190458) (xy 330.396596 -402.184362)
			(xy 330.379578 -402.178012) (xy 330.294234 -402.178012) (xy 330.277216 -402.184362) (xy 330.270104 -402.190458)
			(xy 330.249176 -402.208102) (xy 330.203203 -402.237815) (xy 330.153454 -402.26065) (xy 330.100952 -402.27614)
			(xy 330.046776 -402.283966) (xy 330.019406 -402.284438) (xy 329.992156 -402.283917) (xy 329.938211 -402.276162)
			(xy 329.885919 -402.260809) (xy 329.836344 -402.238171) (xy 329.790495 -402.208708) (xy 329.749305 -402.17302)
			(xy 329.713614 -402.131834) (xy 329.684147 -402.085988) (xy 329.661504 -402.036415) (xy 329.646146 -401.984124)
			(xy 329.638386 -401.93018) (xy 329.637898 -401.90293) (xy 328.782934 -401.90293) (xy 328.782468 -401.93366)
			(xy 328.775057 -401.994673) (xy 328.760346 -402.054347) (xy 328.73855 -402.111813) (xy 328.709986 -402.166233)
			(xy 328.675071 -402.216814) (xy 328.634315 -402.262818) (xy 328.588311 -402.303574) (xy 328.53773 -402.338488)
			(xy 328.483309 -402.367051) (xy 328.425843 -402.388847) (xy 328.366169 -402.403558) (xy 328.305156 -402.410968)
			(xy 328.274426 -402.411438) (xy 328.242391 -402.41097) (xy 328.178826 -402.402944) (xy 328.14768 -402.395436)
			(xy 328.135996 -402.392388) (xy 328.113136 -402.397214) (xy 328.040238 -402.453602) (xy 328.031421 -402.461198)
			(xy 328.02126 -402.482107) (xy 328.02068 -402.493734) (xy 328.02068 -402.59127) (xy 328.021245 -402.602352)
			(xy 328.030577 -402.622459) (xy 328.047487 -402.636791) (xy 328.058018 -402.640292) (xy 328.39667 -402.734018)
			(xy 334.732628 -402.734018) (xy 334.736699 -402.678396) (xy 334.748825 -402.623959) (xy 334.768748 -402.571868)
			(xy 334.796044 -402.523233) (xy 334.83013 -402.47909) (xy 334.870279 -402.440381) (xy 334.915637 -402.40793)
			(xy 334.965237 -402.382429) (xy 335.018021 -402.364422) (xy 335.072864 -402.354292) (xy 335.128598 -402.352255)
			(xy 335.184035 -402.358355) (xy 335.237992 -402.372461) (xy 335.289321 -402.394273) (xy 335.336927 -402.423327)
			(xy 335.379795 -402.459002) (xy 335.417012 -402.500539) (xy 335.447785 -402.547052) (xy 335.471457 -402.597549)
			(xy 335.487525 -402.650956) (xy 335.495645 -402.706132) (xy 335.496154 -402.734018) (xy 335.495645 -402.761904)
			(xy 335.487525 -402.81708) (xy 335.471457 -402.870487) (xy 335.447785 -402.920984) (xy 335.417012 -402.967497)
			(xy 335.379795 -403.009034) (xy 335.336927 -403.044709) (xy 335.289321 -403.073763) (xy 335.237992 -403.095575)
			(xy 335.184035 -403.109681) (xy 335.128598 -403.115781) (xy 335.072864 -403.113744) (xy 335.018021 -403.103614)
			(xy 334.965237 -403.085607) (xy 334.915637 -403.060106) (xy 334.870279 -403.027655) (xy 334.83013 -402.988946)
			(xy 334.796044 -402.944803) (xy 334.768748 -402.896168) (xy 334.748825 -402.844077) (xy 334.736699 -402.78964)
			(xy 334.732628 -402.734018) (xy 328.39667 -402.734018) (xy 331.823568 -403.682454) (xy 331.840332 -403.681438)
			(xy 331.84846 -403.677882) (xy 331.884498 -403.663202) (xy 331.959519 -403.642527) (xy 332.036628 -403.632058)
			(xy 332.075536 -403.6314) (xy 332.114699 -403.632067) (xy 332.192307 -403.642651) (xy 332.230222 -403.652482)
			(xy 332.641702 -403.766528) (xy 332.672884 -403.775635) (xy 332.733158 -403.799868) (xy 332.790343 -403.830692)
			(xy 332.843719 -403.867721) (xy 332.892618 -403.910489) (xy 332.936425 -403.95846) (xy 332.9559 -403.98446)
			(xy 332.96098 -403.991572) (xy 332.97495 -404.001224) (xy 334.376268 -404.389082) (xy 334.38973 -404.39086)
		)
		(stroke
			(width 0)
			(type solid)
		)
		(fill yes)
		(layer "In4.Cu")
		(net "P0V9_CPU0_RT1_2A_2D")
	)
	(gr_poly
		(pts
			(xy 373.3165 -263.08431) (xy 373.322872 -263.084078) (xy 373.335207 -263.080864) (xy 373.340884 -263.07796)
			(xy 373.347385 -263.074061) (xy 373.357959 -263.063211) (xy 373.361712 -263.056624) (xy 373.408448 -262.96493)
			(xy 373.406162 -262.936736) (xy 373.397526 -262.925052) (xy 373.383891 -262.905386) (xy 373.362256 -262.862705)
			(xy 373.347533 -262.817175) (xy 373.340082 -262.769908) (xy 373.339614 -262.745982) (xy 373.340136 -262.720727)
			(xy 373.348449 -262.670905) (xy 373.36485 -262.623131) (xy 373.388891 -262.578708) (xy 373.419915 -262.538848)
			(xy 373.457077 -262.504638) (xy 373.499363 -262.477012) (xy 373.545619 -262.456722) (xy 373.594584 -262.444322)
			(xy 373.644922 -262.440151) (xy 373.69526 -262.444322) (xy 373.744225 -262.456722) (xy 373.790481 -262.477012)
			(xy 373.832767 -262.504638) (xy 373.869929 -262.538848) (xy 373.900953 -262.578708) (xy 373.924994 -262.623131)
			(xy 373.941395 -262.670905) (xy 373.949708 -262.720727) (xy 373.95023 -262.745982) (xy 373.949787 -262.76991)
			(xy 373.942355 -262.817185) (xy 373.927625 -262.862717) (xy 373.905959 -262.905387) (xy 373.892318 -262.925052)
			(xy 373.883682 -262.936736) (xy 373.881396 -262.96493) (xy 373.928132 -263.056624) (xy 373.931809 -263.063265)
			(xy 373.942414 -263.074115) (xy 373.94896 -263.07796) (xy 373.96039 -263.08431) (xy 375.196354 -263.08431)
			(xy 375.202728 -263.084084) (xy 375.215068 -263.080879) (xy 375.220738 -263.07796) (xy 375.227243 -263.074065)
			(xy 375.237826 -263.063219) (xy 375.241566 -263.056624) (xy 375.288302 -262.96493) (xy 375.286016 -262.936736)
			(xy 375.27738 -262.925052) (xy 375.263747 -262.905385) (xy 375.242115 -262.862704) (xy 375.227394 -262.817174)
			(xy 375.219945 -262.769907) (xy 375.219468 -262.745982) (xy 375.21999 -262.720727) (xy 375.228303 -262.670905)
			(xy 375.244704 -262.623131) (xy 375.268745 -262.578708) (xy 375.299769 -262.538848) (xy 375.336931 -262.504638)
			(xy 375.379217 -262.477012) (xy 375.425473 -262.456722) (xy 375.474438 -262.444322) (xy 375.524776 -262.440151)
			(xy 375.575114 -262.444322) (xy 375.624079 -262.456722) (xy 375.670335 -262.477012) (xy 375.712621 -262.504638)
			(xy 375.749783 -262.538848) (xy 375.780807 -262.578708) (xy 375.804848 -262.623131) (xy 375.821249 -262.670905)
			(xy 375.829562 -262.720727) (xy 375.830084 -262.745982) (xy 375.829641 -262.769911) (xy 375.822211 -262.817186)
			(xy 375.807483 -262.86272) (xy 375.78582 -262.905392) (xy 375.772172 -262.925052) (xy 375.763536 -262.936736)
			(xy 375.76125 -262.96493) (xy 375.807986 -263.056624) (xy 375.81166 -263.063268) (xy 375.822261 -263.074126)
			(xy 375.828814 -263.07796) (xy 375.840244 -263.08431) (xy 376.136408 -263.08431) (xy 376.143075 -263.084114)
			(xy 376.155948 -263.080638) (xy 376.161808 -263.077452) (xy 376.16799 -263.073567) (xy 376.178041 -263.062988)
			(xy 376.18162 -263.056624) (xy 376.223022 -262.975344) (xy 376.220736 -262.946388) (xy 376.211846 -262.934704)
			(xy 376.197102 -262.914132) (xy 376.173676 -262.869272) (xy 376.157717 -262.821246) (xy 376.149635 -262.771286)
			(xy 376.149108 -262.745982) (xy 376.149595 -262.721172) (xy 376.157357 -262.672164) (xy 376.17269 -262.624974)
			(xy 376.195217 -262.580763) (xy 376.224382 -262.54062) (xy 376.259468 -262.505534) (xy 376.299611 -262.476369)
			(xy 376.343822 -262.453842) (xy 376.391012 -262.438509) (xy 376.44002 -262.430747) (xy 376.48964 -262.430747)
			(xy 376.538648 -262.438509) (xy 376.585838 -262.453842) (xy 376.630049 -262.476369) (xy 376.670192 -262.505534)
			(xy 376.705278 -262.54062) (xy 376.734443 -262.580763) (xy 376.75697 -262.624974) (xy 376.772303 -262.672164)
			(xy 376.780065 -262.721172) (xy 376.780552 -262.745982) (xy 376.780024 -262.771283) (xy 376.771905 -262.821231)
			(xy 376.755937 -262.86925) (xy 376.732525 -262.914112) (xy 376.717814 -262.934704) (xy 376.708924 -262.946388)
			(xy 376.706638 -262.975344) (xy 376.74804 -263.056624) (xy 376.751574 -263.06302) (xy 376.76164 -263.073604)
			(xy 376.767852 -263.077452) (xy 376.77979 -263.08431) (xy 377.076462 -263.08431) (xy 377.083131 -263.08412)
			(xy 377.09601 -263.080654) (xy 377.101862 -263.077452) (xy 377.108048 -263.073571) (xy 377.118107 -263.062996)
			(xy 377.121674 -263.056624) (xy 377.163076 -262.975344) (xy 377.16079 -262.946388) (xy 377.1519 -262.934704)
			(xy 377.137189 -262.914121) (xy 377.113823 -262.86925) (xy 377.097918 -262.821225) (xy 377.08988 -262.771277)
			(xy 377.089416 -262.745982) (xy 377.089902 -262.721192) (xy 377.097658 -262.672224) (xy 377.112979 -262.625071)
			(xy 377.135488 -262.580896) (xy 377.16463 -262.540785) (xy 377.199687 -262.505728) (xy 377.239798 -262.476586)
			(xy 377.283973 -262.454077) (xy 377.331126 -262.438756) (xy 377.380094 -262.431) (xy 377.429674 -262.431)
			(xy 377.478642 -262.438756) (xy 377.525795 -262.454077) (xy 377.56997 -262.476586) (xy 377.610081 -262.505728)
			(xy 377.645138 -262.540785) (xy 377.67428 -262.580896) (xy 377.696789 -262.625071) (xy 377.71211 -262.672224)
			(xy 377.719866 -262.721192) (xy 377.720352 -262.745982) (xy 377.719868 -262.771276) (xy 377.71183 -262.821219)
			(xy 377.695924 -262.86924) (xy 377.672558 -262.914107) (xy 377.657868 -262.934704) (xy 377.648978 -262.946388)
			(xy 377.646692 -262.975344) (xy 377.688094 -263.056624) (xy 377.691626 -263.063022) (xy 377.701687 -263.073614)
			(xy 377.707906 -263.077452) (xy 377.719844 -263.08431) (xy 377.997466 -263.08431) (xy 378.007304 -263.083775)
			(xy 378.025467 -263.07619) (xy 378.032772 -263.069578) (xy 378.10059 -263.00176) (xy 378.106894 -262.994961)
			(xy 378.114556 -262.978095) (xy 378.115683 -262.959604) (xy 378.110126 -262.941932) (xy 378.104654 -262.93445)
			(xy 378.089382 -262.914144) (xy 378.065095 -262.869521) (xy 378.048529 -262.821492) (xy 378.040139 -262.771385)
			(xy 378.03963 -262.745982) (xy 378.040078 -262.721991) (xy 378.047587 -262.6746) (xy 378.062417 -262.628967)
			(xy 378.084204 -262.586216) (xy 378.112411 -262.5474) (xy 378.146343 -262.513474) (xy 378.185164 -262.485275)
			(xy 378.227919 -262.463496) (xy 378.273554 -262.448674) (xy 378.320947 -262.441173) (xy 378.344938 -262.440674)
			(xy 378.37034 -262.44118) (xy 378.420443 -262.449584) (xy 378.468468 -262.466155) (xy 378.513094 -262.490436)
			(xy 378.533406 -262.505698) (xy 378.540936 -262.511076) (xy 378.55859 -262.51657) (xy 378.577046 -262.515467)
			(xy 378.593921 -262.507911) (xy 378.600716 -262.501634) (xy 378.756926 -262.345424) (xy 378.763643 -262.338187)
			(xy 378.771248 -262.319983) (xy 378.771658 -262.310118) (xy 378.771658 -262.279384) (xy 378.771101 -262.268298)
			(xy 378.761775 -262.248183) (xy 378.744858 -262.233851) (xy 378.73432 -262.230362) (xy 378.710434 -262.223337)
			(xy 378.665167 -262.202614) (xy 378.623865 -262.174817) (xy 378.587624 -262.140683) (xy 378.557405 -262.101118)
			(xy 378.53401 -262.057172) (xy 378.518061 -262.010011) (xy 378.509979 -261.960886) (xy 378.50998 -261.911101)
			(xy 378.518064 -261.861977) (xy 378.534015 -261.814816) (xy 378.557412 -261.770871) (xy 378.587632 -261.731308)
			(xy 378.623875 -261.697175) (xy 378.665178 -261.66938) (xy 378.710446 -261.648658) (xy 378.73432 -261.64159)
			(xy 378.744873 -261.638121) (xy 378.761813 -261.623793) (xy 378.771144 -261.603662) (xy 378.771658 -261.592568)
			(xy 378.771658 -256.87274) (xy 378.758958 -256.839974) (xy 378.753116 -256.83337) (xy 378.736094 -256.812687)
			(xy 378.708833 -256.766581) (xy 378.690041 -256.716423) (xy 378.680295 -256.663755) (xy 378.679895 -256.610194)
			(xy 378.683774 -256.583688) (xy 378.68352 -256.583688) (xy 378.688709 -256.556503) (xy 378.707585 -256.504484)
			(xy 378.735524 -256.456717) (xy 378.753116 -256.435352) (xy 378.758958 -256.428494) (xy 378.771658 -256.395728)
			(xy 378.771658 -256.19837) (xy 378.77115 -256.191766) (xy 378.769476 -256.182259) (xy 378.760071 -256.16542)
			(xy 378.752862 -256.159) (xy 378.749052 -256.156206) (xy 378.680218 -256.110486) (xy 378.669575 -256.104137)
			(xy 378.644948 -256.101624) (xy 378.633228 -256.10566) (xy 378.632466 -256.105914) (xy 378.632212 -256.106168)
			(xy 378.604949 -256.116771) (xy 378.547655 -256.128538) (xy 378.51842 -256.129536) (xy 378.513594 -256.129536)
			(xy 378.489669 -256.128968) (xy 378.442433 -256.121301) (xy 378.396972 -256.106358) (xy 378.354398 -256.084506)
			(xy 378.315755 -256.056281) (xy 378.281988 -256.022372) (xy 378.253924 -255.983611) (xy 378.232251 -255.940946)
			(xy 378.217499 -255.895422) (xy 378.210029 -255.848155) (xy 378.209556 -255.824228) (xy 378.209302 -255.824228)
			(xy 378.20977 -255.799916) (xy 378.21747 -255.751907) (xy 378.23268 -255.705724) (xy 378.255016 -255.662534)
			(xy 378.283913 -255.623429) (xy 378.318641 -255.589397) (xy 378.358322 -255.561297) (xy 378.401955 -255.53984)
			(xy 378.448437 -255.525568) (xy 378.472446 -255.521714) (xy 378.4727 -255.521714) (xy 378.484972 -255.519327)
			(xy 378.5052 -255.504683) (xy 378.511308 -255.493774) (xy 378.54763 -255.420114) (xy 378.552563 -255.408504)
			(xy 378.551618 -255.383329) (xy 378.545852 -255.372108) (xy 378.501148 -255.295146) (xy 378.490678 -255.276666)
			(xy 378.472245 -255.238397) (xy 378.464318 -255.218692) (xy 378.459238 -255.205738) (xy 378.437648 -255.18872)
			(xy 378.337826 -255.175512) (xy 378.328789 -255.174695) (xy 378.311117 -255.178753) (xy 378.295977 -255.188731)
			(xy 378.290328 -255.195832) (xy 378.275812 -255.214681) (xy 378.241925 -255.248069) (xy 378.203271 -255.275799)
			(xy 378.160785 -255.297202) (xy 378.115495 -255.31176) (xy 378.068496 -255.319121) (xy 378.04471 -255.31953)
			(xy 378.01945 -255.319038) (xy 377.969619 -255.310724) (xy 377.921835 -255.294322) (xy 377.877404 -255.270278)
			(xy 377.837536 -255.239248) (xy 377.803319 -255.20208) (xy 377.775686 -255.159787) (xy 377.755392 -255.113522)
			(xy 377.74299 -255.064548) (xy 377.738818 -255.0142) (xy 377.74299 -254.963852) (xy 377.755392 -254.914878)
			(xy 377.775686 -254.868613) (xy 377.803319 -254.82632) (xy 377.837536 -254.789152) (xy 377.877404 -254.758122)
			(xy 377.921835 -254.734078) (xy 377.969619 -254.717676) (xy 378.01945 -254.709362) (xy 378.04471 -254.708914)
			(xy 378.068497 -254.709347) (xy 378.115499 -254.716686) (xy 378.160793 -254.731232) (xy 378.20328 -254.752633)
			(xy 378.24193 -254.780368) (xy 378.275807 -254.813767) (xy 378.290328 -254.832612) (xy 378.295983 -254.839708)
			(xy 378.311123 -254.849687) (xy 378.328792 -254.853767) (xy 378.337826 -254.852932) (xy 378.437394 -254.839724)
			(xy 378.459238 -254.822706) (xy 378.464318 -254.809752) (xy 378.477111 -254.778456) (xy 378.509197 -254.718942)
			(xy 378.548231 -254.663735) (xy 378.593642 -254.613642) (xy 378.644766 -254.569395) (xy 378.700857 -254.531642)
			(xy 378.730764 -254.515874) (xy 378.73671 -254.512591) (xy 378.746751 -254.503452) (xy 378.750576 -254.49784)
			(xy 378.763784 -254.477266) (xy 378.767419 -254.471067) (xy 378.771419 -254.45727) (xy 378.771658 -254.450088)
			(xy 378.771658 -254.112268) (xy 378.769372 -254.104902) (xy 378.764038 -254.086106) (xy 378.76226 -254.079502)
			(xy 378.748798 -254.056388) (xy 378.743718 -254.051308) (xy 378.743464 -254.051054) (xy 378.716612 -254.024035)
			(xy 378.669712 -253.964011) (xy 378.649992 -253.93142) (xy 378.501148 -253.675134) (xy 378.490679 -253.656654)
			(xy 378.472246 -253.618384) (xy 378.464318 -253.59868) (xy 378.459238 -253.585726) (xy 378.437648 -253.568708)
			(xy 378.337826 -253.5555) (xy 378.328789 -253.554683) (xy 378.311116 -253.558741) (xy 378.295975 -253.568717)
			(xy 378.290328 -253.57582) (xy 378.275809 -253.594664) (xy 378.241918 -253.628043) (xy 378.203263 -253.655765)
			(xy 378.160778 -253.677162) (xy 378.11549 -253.691715) (xy 378.068494 -253.699074) (xy 378.04471 -253.699518)
			(xy 378.019451 -253.699026) (xy 377.969622 -253.690713) (xy 377.92184 -253.674311) (xy 377.87741 -253.650268)
			(xy 377.837544 -253.619239) (xy 377.803328 -253.582073) (xy 377.775697 -253.539781) (xy 377.755404 -253.493518)
			(xy 377.743002 -253.444546) (xy 377.73883 -253.3942) (xy 377.743002 -253.343854) (xy 377.755404 -253.294882)
			(xy 377.775697 -253.248619) (xy 377.803328 -253.206327) (xy 377.837544 -253.169161) (xy 377.87741 -253.138132)
			(xy 377.92184 -253.114089) (xy 377.969622 -253.097687) (xy 378.019451 -253.089374) (xy 378.04471 -253.088902)
			(xy 378.068497 -253.089335) (xy 378.1155 -253.096674) (xy 378.160794 -253.11122) (xy 378.203281 -253.132619)
			(xy 378.241933 -253.160354) (xy 378.275811 -253.193752) (xy 378.290328 -253.2126) (xy 378.295982 -253.219698)
			(xy 378.311122 -253.229679) (xy 378.328792 -253.23376) (xy 378.337826 -253.23292) (xy 378.437648 -253.219712)
			(xy 378.459238 -253.202694) (xy 378.464318 -253.18974) (xy 378.479867 -253.152068) (xy 378.520288 -253.081302)
			(xy 378.544836 -253.04877) (xy 378.553472 -253.038102) (xy 378.557282 -253.01067) (xy 378.513594 -252.905514)
			(xy 378.492004 -252.889004) (xy 378.478034 -252.887226) (xy 378.453672 -252.883765) (xy 378.406412 -252.870069)
			(xy 378.36196 -252.848972) (xy 378.321466 -252.82102) (xy 378.285978 -252.786937) (xy 378.256415 -252.747604)
			(xy 378.233542 -252.704039) (xy 378.21795 -252.657371) (xy 378.210043 -252.608806) (xy 378.209556 -252.584204)
			(xy 378.209302 -252.584204) (xy 378.209765 -252.559889) (xy 378.217455 -252.51187) (xy 378.232658 -252.465677)
			(xy 378.254989 -252.422477) (xy 378.283884 -252.383362) (xy 378.318613 -252.34932) (xy 378.358298 -252.321212)
			(xy 378.401935 -252.299748) (xy 378.448423 -252.285471) (xy 378.472446 -252.28169) (xy 378.4727 -252.28169)
			(xy 378.48497 -252.279302) (xy 378.505193 -252.264654) (xy 378.511308 -252.25375) (xy 378.54763 -252.18009)
			(xy 378.552582 -252.168479) (xy 378.551669 -252.143284) (xy 378.545852 -252.132084) (xy 378.501148 -252.055122)
			(xy 378.483229 -252.023051) (xy 378.455024 -251.955215) (xy 378.435941 -251.884271) (xy 378.42631 -251.811439)
			(xy 378.42571 -251.774706) (xy 378.42571 -251.77369) (xy 378.426321 -251.736992) (xy 378.436004 -251.664236)
			(xy 378.445014 -251.628656) (xy 378.44857 -251.615194) (xy 378.441712 -251.589286) (xy 377.978162 -251.125736)
			(xy 377.970034 -251.117608) (xy 377.948952 -251.109988) (xy 377.863608 -251.117608) (xy 377.84405 -251.129292)
			(xy 377.837446 -251.138944) (xy 377.822679 -251.160199) (xy 377.787366 -251.198028) (xy 377.746351 -251.229587)
			(xy 377.700735 -251.254028) (xy 377.651742 -251.270696) (xy 377.600685 -251.279144) (xy 377.57481 -251.27966)
			(xy 377.550012 -251.279175) (xy 377.501024 -251.271422) (xy 377.453852 -251.256106) (xy 377.409654 -251.233603)
			(xy 377.369518 -251.204466) (xy 377.334431 -251.169412) (xy 377.305255 -251.129304) (xy 377.28271 -251.085128)
			(xy 377.267348 -251.03797) (xy 377.259549 -250.98899) (xy 377.259088 -250.964192) (xy 377.259513 -250.941331)
			(xy 377.266141 -250.89609) (xy 377.279213 -250.852275) (xy 377.298458 -250.810799) (xy 377.323474 -250.772525)
			(xy 377.338336 -250.75515) (xy 377.348496 -250.74372) (xy 377.352814 -250.714256) (xy 377.313952 -250.628658)
			(xy 377.309535 -250.61999) (xy 377.295482 -250.606561) (xy 377.277443 -250.599322) (xy 377.267724 -250.59894)
			(xy 376.941842 -250.59894) (xy 376.932133 -250.599379) (xy 376.914111 -250.60661) (xy 376.900061 -250.620015)
			(xy 376.895614 -250.628658) (xy 376.851926 -250.724162) (xy 376.85599 -250.753372) (xy 376.865896 -250.764802)
			(xy 376.88321 -250.785763) (xy 376.910886 -250.832553) (xy 376.929833 -250.883506) (xy 376.93945 -250.937011)
			(xy 376.940064 -250.964192) (xy 376.939542 -250.989447) (xy 376.931229 -251.039269) (xy 376.914828 -251.087043)
			(xy 376.890787 -251.131466) (xy 376.859763 -251.171326) (xy 376.822601 -251.205536) (xy 376.780315 -251.233162)
			(xy 376.734059 -251.253452) (xy 376.685094 -251.265852) (xy 376.634756 -251.270023) (xy 376.584418 -251.265852)
			(xy 376.535453 -251.253452) (xy 376.489197 -251.233162) (xy 376.446911 -251.205536) (xy 376.409749 -251.171326)
			(xy 376.378725 -251.131466) (xy 376.354684 -251.087043) (xy 376.338283 -251.039269) (xy 376.32997 -250.989447)
			(xy 376.329448 -250.964192) (xy 376.330043 -250.93701) (xy 376.339671 -250.883506) (xy 376.358623 -250.832553)
			(xy 376.386298 -250.785761) (xy 376.403616 -250.764802) (xy 376.413522 -250.753372) (xy 376.417586 -250.724162)
			(xy 376.373898 -250.628658) (xy 376.369479 -250.619996) (xy 376.355423 -250.606581) (xy 376.337385 -250.599361)
			(xy 376.32767 -250.59894) (xy 376.001788 -250.59894) (xy 375.992074 -250.599371) (xy 375.974038 -250.606592)
			(xy 375.959975 -250.619996) (xy 375.95556 -250.628658) (xy 375.916444 -250.714002) (xy 375.921016 -250.74372)
			(xy 375.930922 -250.754896) (xy 375.945811 -250.772295) (xy 375.970928 -250.810586) (xy 375.990243 -250.852106)
			(xy 376.003351 -250.895984) (xy 376.009975 -250.941295) (xy 376.010424 -250.964192) (xy 376.009937 -250.989002)
			(xy 376.002175 -251.03801) (xy 375.986842 -251.0852) (xy 375.964315 -251.129411) (xy 375.93515 -251.169554)
			(xy 375.900064 -251.20464) (xy 375.859921 -251.233805) (xy 375.81571 -251.256332) (xy 375.76852 -251.271665)
			(xy 375.719512 -251.279427) (xy 375.669892 -251.279427) (xy 375.620884 -251.271665) (xy 375.573694 -251.256332)
			(xy 375.529483 -251.233805) (xy 375.48934 -251.20464) (xy 375.454254 -251.169554) (xy 375.425089 -251.129411)
			(xy 375.402562 -251.0852) (xy 375.387229 -251.03801) (xy 375.379467 -250.989002) (xy 375.37898 -250.964192)
			(xy 375.379404 -250.941319) (xy 375.386051 -250.896059) (xy 375.399174 -250.852236) (xy 375.418497 -250.810771)
			(xy 375.443615 -250.772538) (xy 375.458482 -250.75515) (xy 375.468388 -250.74372) (xy 375.47296 -250.714256)
			(xy 375.433844 -250.628658) (xy 375.429426 -250.619991) (xy 375.415373 -250.606564) (xy 375.397334 -250.599328)
			(xy 375.387616 -250.59894) (xy 375.061988 -250.59894) (xy 375.052274 -250.599371) (xy 375.034238 -250.606592)
			(xy 375.020175 -250.619996) (xy 375.01576 -250.628658) (xy 374.972072 -250.724162) (xy 374.976136 -250.753372)
			(xy 374.986042 -250.764802) (xy 375.003354 -250.785764) (xy 375.031026 -250.832555) (xy 375.049969 -250.883508)
			(xy 375.059585 -250.937011) (xy 375.06021 -250.964192) (xy 375.059688 -250.989447) (xy 375.051375 -251.039269)
			(xy 375.034974 -251.087043) (xy 375.010933 -251.131466) (xy 374.979909 -251.171326) (xy 374.942747 -251.205536)
			(xy 374.900461 -251.233162) (xy 374.854205 -251.253452) (xy 374.80524 -251.265852) (xy 374.754902 -251.270023)
			(xy 374.704564 -251.265852) (xy 374.655599 -251.253452) (xy 374.609343 -251.233162) (xy 374.567057 -251.205536)
			(xy 374.529895 -251.171326) (xy 374.498871 -251.131466) (xy 374.47483 -251.087043) (xy 374.458429 -251.039269)
			(xy 374.450116 -250.989447) (xy 374.449594 -250.964192) (xy 374.450189 -250.937011) (xy 374.459819 -250.883507)
			(xy 374.478772 -250.832556) (xy 374.506451 -250.785766) (xy 374.523762 -250.764802) (xy 374.533668 -250.753372)
			(xy 374.537732 -250.724162) (xy 374.494044 -250.628658) (xy 374.489626 -250.619991) (xy 374.475573 -250.606564)
			(xy 374.457534 -250.599328) (xy 374.447816 -250.59894) (xy 373.252746 -250.59894) (xy 373.242906 -250.599471)
			(xy 373.224735 -250.607048) (xy 373.21744 -250.613672) (xy 373.13362 -250.697492) (xy 373.127382 -250.704356)
			(xy 373.119836 -250.721285) (xy 373.118888 -250.730512) (xy 373.117618 -250.752356) (xy 373.116856 -250.762008)
			(xy 373.126 -250.790456) (xy 373.12981 -250.796298) (xy 373.141762 -250.815161) (xy 373.160617 -250.855638)
			(xy 373.173372 -250.898431) (xy 373.179756 -250.942626) (xy 373.180102 -250.964954) (xy 373.180102 -250.97105)
			(xy 373.179131 -250.994648) (xy 373.170812 -251.041138) (xy 373.155433 -251.085792) (xy 373.133361 -251.127545)
			(xy 373.105121 -251.165401) (xy 373.071388 -251.198456) (xy 373.032968 -251.225922) (xy 372.990775 -251.247143)
			(xy 372.945818 -251.261612) (xy 372.899169 -251.268986) (xy 372.875556 -251.2695) (xy 372.87454 -251.2695)
			(xy 372.849448 -251.26897) (xy 372.799947 -251.260715) (xy 372.752464 -251.24447) (xy 372.70828 -251.220674)
			(xy 372.688104 -251.205746) (xy 372.68785 -251.205746) (xy 372.680353 -251.200448) (xy 372.662811 -251.195086)
			(xy 372.644507 -251.19627) (xy 372.627802 -251.203846) (xy 372.621048 -251.210064) (xy 372.498366 -251.332746)
			(xy 372.490183 -251.342044) (xy 372.48287 -251.365668) (xy 372.484396 -251.377958) (xy 372.501922 -251.470414)
			(xy 372.517162 -251.489972) (xy 372.528846 -251.495052) (xy 372.551626 -251.505748) (xy 372.59363 -251.533459)
			(xy 372.630528 -251.567677) (xy 372.661323 -251.607476) (xy 372.685182 -251.651782) (xy 372.701461 -251.699398)
			(xy 372.709721 -251.749037) (xy 372.710202 -251.774198) (xy 373.978944 -251.774198) (xy 373.982904 -251.725144)
			(xy 373.994681 -251.67736) (xy 374.013972 -251.632084) (xy 374.040275 -251.590488) (xy 374.07291 -251.553651)
			(xy 374.111031 -251.522526) (xy 374.153652 -251.497919) (xy 374.199668 -251.480467) (xy 374.247887 -251.470623)
			(xy 374.297062 -251.468642) (xy 374.345917 -251.474574) (xy 374.393188 -251.488266) (xy 374.43765 -251.509364)
			(xy 374.478153 -251.53732) (xy 374.513646 -251.571412) (xy 374.543211 -251.610756) (xy 374.566082 -251.654333)
			(xy 374.581666 -251.701014) (xy 374.589561 -251.749591) (xy 374.590056 -251.774198) (xy 375.848621 -251.774198)
			(xy 375.852716 -251.72347) (xy 375.864895 -251.674056) (xy 375.884843 -251.627236) (xy 375.912044 -251.584222)
			(xy 375.945792 -251.546128) (xy 375.985214 -251.513941) (xy 376.029288 -251.488495) (xy 376.076874 -251.470448)
			(xy 376.126738 -251.460268) (xy 376.17759 -251.458219) (xy 376.228111 -251.464353) (xy 376.276995 -251.478513)
			(xy 376.322974 -251.50033) (xy 376.364858 -251.52924) (xy 376.401562 -251.564495) (xy 376.432135 -251.605181)
			(xy 376.455786 -251.650244) (xy 376.471902 -251.698518) (xy 376.480066 -251.748752) (xy 376.480578 -251.774198)
			(xy 376.799106 -251.774198) (xy 376.803066 -251.725144) (xy 376.814843 -251.67736) (xy 376.834134 -251.632084)
			(xy 376.860437 -251.590488) (xy 376.893072 -251.553651) (xy 376.931193 -251.522526) (xy 376.973814 -251.497919)
			(xy 377.01983 -251.480467) (xy 377.068049 -251.470623) (xy 377.117224 -251.468642) (xy 377.166079 -251.474574)
			(xy 377.21335 -251.488266) (xy 377.257812 -251.509364) (xy 377.298315 -251.53732) (xy 377.333808 -251.571412)
			(xy 377.363373 -251.610756) (xy 377.386244 -251.654333) (xy 377.401828 -251.701014) (xy 377.409723 -251.749591)
			(xy 377.410218 -251.774198) (xy 377.409723 -251.798805) (xy 377.401828 -251.847382) (xy 377.386244 -251.894063)
			(xy 377.363373 -251.93764) (xy 377.333808 -251.976984) (xy 377.298315 -252.011076) (xy 377.257812 -252.039032)
			(xy 377.21335 -252.06013) (xy 377.166079 -252.073822) (xy 377.117224 -252.079754) (xy 377.068049 -252.077773)
			(xy 377.01983 -252.067929) (xy 376.973814 -252.050477) (xy 376.931193 -252.02587) (xy 376.893072 -251.994745)
			(xy 376.860437 -251.957908) (xy 376.834134 -251.916312) (xy 376.814843 -251.871036) (xy 376.803066 -251.823252)
			(xy 376.799106 -251.774198) (xy 376.480578 -251.774198) (xy 376.480066 -251.799644) (xy 376.471902 -251.849878)
			(xy 376.455786 -251.898152) (xy 376.432135 -251.943215) (xy 376.401562 -251.983901) (xy 376.364858 -252.019156)
			(xy 376.322974 -252.048066) (xy 376.276995 -252.069883) (xy 376.228111 -252.084043) (xy 376.17759 -252.090177)
			(xy 376.126738 -252.088128) (xy 376.076874 -252.077948) (xy 376.029288 -252.059901) (xy 375.985214 -252.034455)
			(xy 375.945792 -252.002268) (xy 375.912044 -251.964174) (xy 375.884843 -251.92116) (xy 375.864895 -251.87434)
			(xy 375.852716 -251.824926) (xy 375.848621 -251.774198) (xy 374.590056 -251.774198) (xy 374.589561 -251.798805)
			(xy 374.581666 -251.847382) (xy 374.566082 -251.894063) (xy 374.543211 -251.93764) (xy 374.513646 -251.976984)
			(xy 374.478153 -252.011076) (xy 374.43765 -252.039032) (xy 374.393188 -252.06013) (xy 374.345917 -252.073822)
			(xy 374.297062 -252.079754) (xy 374.247887 -252.077773) (xy 374.199668 -252.067929) (xy 374.153652 -252.050477)
			(xy 374.111031 -252.02587) (xy 374.07291 -251.994745) (xy 374.040275 -251.957908) (xy 374.013972 -251.916312)
			(xy 373.994681 -251.871036) (xy 373.982904 -251.823252) (xy 373.978944 -251.774198) (xy 372.710202 -251.774198)
			(xy 372.70968 -251.799453) (xy 372.701367 -251.849275) (xy 372.684966 -251.897049) (xy 372.660925 -251.941472)
			(xy 372.629901 -251.981332) (xy 372.592739 -252.015542) (xy 372.550453 -252.043168) (xy 372.504197 -252.063458)
			(xy 372.455232 -252.075858) (xy 372.404894 -252.080029) (xy 372.354556 -252.075858) (xy 372.305591 -252.063458)
			(xy 372.259335 -252.043168) (xy 372.217049 -252.015542) (xy 372.179887 -251.981332) (xy 372.148863 -251.941472)
			(xy 372.124822 -251.897049) (xy 372.108421 -251.849275) (xy 372.100108 -251.799453) (xy 372.099586 -251.774198)
			(xy 372.100239 -251.745499) (xy 372.110982 -251.689115) (xy 372.120922 -251.662184) (xy 372.123208 -251.656342)
			(xy 372.124732 -251.64415) (xy 372.124224 -251.6378) (xy 372.123298 -251.631691) (xy 372.118936 -251.620134)
			(xy 372.115588 -251.61494) (xy 372.069614 -251.547122) (xy 372.062086 -251.5371) (xy 372.039969 -251.525369)
			(xy 372.02745 -251.52477) (xy 371.359176 -251.52477) (xy 371.349335 -251.524242) (xy 371.331165 -251.516663)
			(xy 371.32387 -251.510038) (xy 371.084094 -251.270262) (xy 371.060472 -251.262642) (xy 371.04828 -251.264928)
			(xy 371.034989 -251.267102) (xy 371.008153 -251.269393) (xy 370.994686 -251.2695) (xy 370.970696 -251.269028)
			(xy 370.923306 -251.26152) (xy 370.877675 -251.246692) (xy 370.834924 -251.224907) (xy 370.796108 -251.196704)
			(xy 370.762182 -251.162775) (xy 370.733981 -251.123957) (xy 370.7122 -251.081205) (xy 370.697374 -251.035572)
			(xy 370.68987 -250.988182) (xy 370.689378 -250.964192) (xy 370.689475 -250.950724) (xy 370.691765 -250.923887)
			(xy 370.69395 -250.910598) (xy 370.696236 -250.898406) (xy 370.688616 -250.874784) (xy 370.427758 -250.613926)
			(xy 370.420646 -250.60656) (xy 370.40185 -250.59894) (xy 369.485926 -250.59894) (xy 369.476088 -250.599475)
			(xy 369.457922 -250.607056) (xy 369.45062 -250.613672) (xy 369.34394 -250.720352) (xy 369.341654 -250.75896)
			(xy 369.353846 -250.7742) (xy 369.369396 -250.794604) (xy 369.394157 -250.839531) (xy 369.411057 -250.887965)
			(xy 369.41962 -250.938543) (xy 369.42014 -250.964192) (xy 369.41967 -250.988185) (xy 369.412165 -251.035579)
			(xy 369.397339 -251.081216) (xy 369.375556 -251.123972) (xy 369.347353 -251.162795) (xy 369.313425 -251.196727)
			(xy 369.274606 -251.224935) (xy 369.231853 -251.246723) (xy 369.186218 -251.261556) (xy 369.138824 -251.269067)
			(xy 369.114832 -251.2695) (xy 369.102069 -251.26936) (xy 369.076636 -251.267195) (xy 369.064032 -251.265182)
			(xy 369.064032 -251.265436) (xy 369.041599 -251.2612) (xy 368.998225 -251.246961) (xy 368.957445 -251.226442)
			(xy 368.938556 -251.21362) (xy 368.931367 -251.208923) (xy 368.914886 -251.204135) (xy 368.906298 -251.204222)
			(xy 368.87658 -251.206) (xy 368.867345 -251.206913) (xy 368.850416 -251.214477) (xy 368.84356 -251.220732)
			(xy 368.733832 -251.33046) (xy 368.725476 -251.339729) (xy 368.718162 -251.363561) (xy 368.719862 -251.375926)
			(xy 368.737896 -251.469144) (xy 368.753644 -251.488702) (xy 368.765328 -251.493782) (xy 368.788468 -251.50429)
			(xy 368.831177 -251.531829) (xy 368.868739 -251.566058) (xy 368.900117 -251.606031) (xy 368.924445 -251.650647)
			(xy 368.941052 -251.698675) (xy 368.949481 -251.748789) (xy 368.949986 -251.774198) (xy 370.218982 -251.774198)
			(xy 370.222942 -251.725144) (xy 370.234719 -251.67736) (xy 370.25401 -251.632084) (xy 370.280313 -251.590488)
			(xy 370.312948 -251.553651) (xy 370.351069 -251.522526) (xy 370.39369 -251.497919) (xy 370.439706 -251.480467)
			(xy 370.487925 -251.470623) (xy 370.5371 -251.468642) (xy 370.585955 -251.474574) (xy 370.633226 -251.488266)
			(xy 370.677688 -251.509364) (xy 370.718191 -251.53732) (xy 370.753684 -251.571412) (xy 370.783249 -251.610756)
			(xy 370.80612 -251.654333) (xy 370.821704 -251.701014) (xy 370.829599 -251.749591) (xy 370.830094 -251.774198)
			(xy 370.829599 -251.798805) (xy 370.821704 -251.847382) (xy 370.80612 -251.894063) (xy 370.783249 -251.93764)
			(xy 370.753684 -251.976984) (xy 370.718191 -252.011076) (xy 370.677688 -252.039032) (xy 370.633226 -252.06013)
			(xy 370.585955 -252.073822) (xy 370.5371 -252.079754) (xy 370.487925 -252.077773) (xy 370.439706 -252.067929)
			(xy 370.39369 -252.050477) (xy 370.351069 -252.02587) (xy 370.312948 -251.994745) (xy 370.280313 -251.957908)
			(xy 370.25401 -251.916312) (xy 370.234719 -251.871036) (xy 370.222942 -251.823252) (xy 370.218982 -251.774198)
			(xy 368.949986 -251.774198) (xy 368.949464 -251.799453) (xy 368.941151 -251.849275) (xy 368.92475 -251.897049)
			(xy 368.900709 -251.941472) (xy 368.869685 -251.981332) (xy 368.832523 -252.015542) (xy 368.790237 -252.043168)
			(xy 368.743981 -252.063458) (xy 368.695016 -252.075858) (xy 368.644678 -252.080029) (xy 368.59434 -252.075858)
			(xy 368.545375 -252.063458) (xy 368.499119 -252.043168) (xy 368.456833 -252.015542) (xy 368.419671 -251.981332)
			(xy 368.388647 -251.941472) (xy 368.364606 -251.897049) (xy 368.348205 -251.849275) (xy 368.339892 -251.799453)
			(xy 368.33937 -251.774198) (xy 368.339914 -251.747974) (xy 368.348876 -251.696297) (xy 368.366536 -251.646912)
			(xy 368.378994 -251.62383) (xy 368.382296 -251.617988) (xy 368.385598 -251.605542) (xy 368.385598 -251.598684)
			(xy 368.385434 -251.59195) (xy 368.381971 -251.578939) (xy 368.37874 -251.57303) (xy 368.33556 -251.499116)
			(xy 368.333274 -251.49556) (xy 368.326197 -251.486566) (xy 368.306281 -251.475353) (xy 368.29492 -251.47397)
			(xy 367.650776 -251.47397) (xy 367.640935 -251.473442) (xy 367.622765 -251.465863) (xy 367.61547 -251.459238)
			(xy 367.400586 -251.244354) (xy 367.369852 -251.238512) (xy 367.355628 -251.244608) (xy 367.336453 -251.252477)
			(xy 367.296515 -251.263559) (xy 367.255448 -251.269154) (xy 367.234724 -251.2695) (xy 367.230152 -251.2695)
			(xy 367.206623 -251.268714) (xy 367.160217 -251.260797) (xy 367.115576 -251.24585) (xy 367.073758 -251.224229)
			(xy 367.035754 -251.196445) (xy 367.002465 -251.163158) (xy 366.97468 -251.125156) (xy 366.953056 -251.083339)
			(xy 366.938107 -251.038699) (xy 366.930187 -250.992293) (xy 366.929416 -250.968764) (xy 366.929416 -250.964192)
			(xy 366.929739 -250.943466) (xy 366.935312 -250.902391) (xy 366.946407 -250.862452) (xy 366.954308 -250.843288)
			(xy 366.960404 -250.829064) (xy 366.954562 -250.79833) (xy 366.770158 -250.613926) (xy 366.763046 -250.60656)
			(xy 366.74425 -250.59894) (xy 365.880396 -250.59894) (xy 365.870552 -250.599462) (xy 365.852368 -250.607026)
			(xy 365.84509 -250.613672) (xy 365.642652 -250.81611) (xy 365.636302 -250.844812) (xy 365.641382 -250.859036)
			(xy 365.650124 -250.884443) (xy 365.659573 -250.93733) (xy 365.660178 -250.964192) (xy 365.660178 -250.968256)
			(xy 365.659407 -250.992038) (xy 365.651402 -251.03894) (xy 365.636218 -251.084032) (xy 365.614223 -251.126222)
			(xy 365.585948 -251.16449) (xy 365.55208 -251.197908) (xy 365.513437 -251.225668) (xy 365.470956 -251.247097)
			(xy 365.425665 -251.261676) (xy 365.37866 -251.269052) (xy 365.35487 -251.2695) (xy 365.352076 -251.2695)
			(xy 365.325918 -251.268704) (xy 365.274448 -251.259255) (xy 365.249714 -251.250704) (xy 365.23549 -251.245624)
			(xy 365.206788 -251.251974) (xy 365.117634 -251.341128) (xy 365.110398 -251.347847) (xy 365.092193 -251.355455)
			(xy 365.082328 -251.35586) (xy 365.035846 -251.35586) (xy 365.026095 -251.356374) (xy 365.008064 -251.36382)
			(xy 365.000794 -251.370338) (xy 364.968536 -251.402596) (xy 364.961699 -251.409959) (xy 364.953963 -251.428487)
			(xy 364.953973 -251.448565) (xy 364.961728 -251.467084) (xy 364.968536 -251.474478) (xy 364.976664 -251.482606)
			(xy 364.987332 -251.486416) (xy 365.009282 -251.494709) (xy 365.050539 -251.517061) (xy 365.087892 -251.545458)
			(xy 365.120464 -251.579233) (xy 365.147488 -251.617592) (xy 365.168329 -251.659632) (xy 365.182496 -251.704364)
			(xy 365.189656 -251.750737) (xy 365.190024 -251.774198) (xy 366.45902 -251.774198) (xy 366.46298 -251.725144)
			(xy 366.474757 -251.67736) (xy 366.494048 -251.632084) (xy 366.520351 -251.590488) (xy 366.552986 -251.553651)
			(xy 366.591107 -251.522526) (xy 366.633728 -251.497919) (xy 366.679744 -251.480467) (xy 366.727963 -251.470623)
			(xy 366.777138 -251.468642) (xy 366.825993 -251.474574) (xy 366.873264 -251.488266) (xy 366.917726 -251.509364)
			(xy 366.958229 -251.53732) (xy 366.993722 -251.571412) (xy 367.023287 -251.610756) (xy 367.046158 -251.654333)
			(xy 367.061742 -251.701014) (xy 367.069637 -251.749591) (xy 367.070132 -251.774198) (xy 367.069637 -251.798805)
			(xy 367.061742 -251.847382) (xy 367.046158 -251.894063) (xy 367.023287 -251.93764) (xy 366.993722 -251.976984)
			(xy 366.958229 -252.011076) (xy 366.917726 -252.039032) (xy 366.873264 -252.06013) (xy 366.825993 -252.073822)
			(xy 366.777138 -252.079754) (xy 366.727963 -252.077773) (xy 366.679744 -252.067929) (xy 366.633728 -252.050477)
			(xy 366.591107 -252.02587) (xy 366.552986 -251.994745) (xy 366.520351 -251.957908) (xy 366.494048 -251.916312)
			(xy 366.474757 -251.871036) (xy 366.46298 -251.823252) (xy 366.45902 -251.774198) (xy 365.190024 -251.774198)
			(xy 365.189502 -251.799453) (xy 365.181189 -251.849275) (xy 365.164788 -251.897049) (xy 365.140747 -251.941472)
			(xy 365.109723 -251.981332) (xy 365.072561 -252.015542) (xy 365.030275 -252.043168) (xy 364.984019 -252.063458)
			(xy 364.935054 -252.075858) (xy 364.884716 -252.080029) (xy 364.834378 -252.075858) (xy 364.785413 -252.063458)
			(xy 364.739157 -252.043168) (xy 364.696871 -252.015542) (xy 364.659709 -251.981332) (xy 364.628685 -251.941472)
			(xy 364.604644 -251.897049) (xy 364.588243 -251.849275) (xy 364.57993 -251.799453) (xy 364.579408 -251.774198)
			(xy 364.579952 -251.747974) (xy 364.588915 -251.696298) (xy 364.606577 -251.646914) (xy 364.619032 -251.62383)
			(xy 364.622334 -251.617988) (xy 364.625636 -251.605542) (xy 364.625636 -251.598684) (xy 364.625471 -251.591951)
			(xy 364.622005 -251.578941) (xy 364.618778 -251.57303) (xy 364.575598 -251.499116) (xy 364.573312 -251.49556)
			(xy 364.56623 -251.486576) (xy 364.546312 -251.475387) (xy 364.534958 -251.47397) (xy 364.163356 -251.47397)
			(xy 364.153517 -251.473438) (xy 364.135352 -251.465854) (xy 364.12805 -251.459238) (xy 363.840776 -251.171964)
			(xy 363.83341 -251.164598) (xy 363.81436 -251.156724) (xy 363.722158 -251.158248) (xy 363.70387 -251.166376)
			(xy 363.696504 -251.173996) (xy 363.67909 -251.191713) (xy 363.63957 -251.221811) (xy 363.595694 -251.245104)
			(xy 363.548622 -251.260976) (xy 363.4996 -251.269007) (xy 363.474762 -251.2695) (xy 363.450773 -251.269027)
			(xy 363.403386 -251.261516) (xy 363.357758 -251.246685) (xy 363.315011 -251.224899) (xy 363.276198 -251.196695)
			(xy 363.242275 -251.162767) (xy 363.214077 -251.12395) (xy 363.192298 -251.0812) (xy 363.177474 -251.035569)
			(xy 363.16997 -250.988181) (xy 363.169454 -250.964192) (xy 363.170047 -250.937009) (xy 363.179667 -250.8835)
			(xy 363.198603 -250.832538) (xy 363.226257 -250.78573) (xy 363.261756 -250.744553) (xy 363.282484 -250.726956)
			(xy 363.29013 -250.720144) (xy 363.2997 -250.702058) (xy 363.301026 -250.691904) (xy 363.30382 -250.660662)
			(xy 363.304198 -250.649507) (xy 363.296568 -250.628559) (xy 363.289088 -250.620276) (xy 363.282738 -250.613926)
			(xy 363.275337 -250.607087) (xy 363.256739 -250.599371) (xy 363.24667 -250.59894) (xy 361.901994 -250.59894)
			(xy 361.89228 -250.59937) (xy 361.874242 -250.60659) (xy 361.860177 -250.619993) (xy 361.855766 -250.628658)
			(xy 361.812078 -250.724162) (xy 361.816142 -250.753372) (xy 361.826048 -250.764802) (xy 361.84336 -250.785764)
			(xy 361.871031 -250.832555) (xy 361.889974 -250.883508) (xy 361.89959 -250.937012) (xy 361.900216 -250.964192)
			(xy 361.899694 -250.989447) (xy 361.891381 -251.039269) (xy 361.87498 -251.087043) (xy 361.850939 -251.131466)
			(xy 361.819915 -251.171326) (xy 361.782753 -251.205536) (xy 361.740467 -251.233162) (xy 361.694211 -251.253452)
			(xy 361.645246 -251.265852) (xy 361.594908 -251.270023) (xy 361.54457 -251.265852) (xy 361.495605 -251.253452)
			(xy 361.449349 -251.233162) (xy 361.407063 -251.205536) (xy 361.369901 -251.171326) (xy 361.338877 -251.131466)
			(xy 361.314836 -251.087043) (xy 361.298435 -251.039269) (xy 361.290122 -250.989447) (xy 361.2896 -250.964192)
			(xy 361.290195 -250.937011) (xy 361.299825 -250.883508) (xy 361.318779 -250.832556) (xy 361.346458 -250.785767)
			(xy 361.363768 -250.764802) (xy 361.373674 -250.753372) (xy 361.377738 -250.724162) (xy 361.33405 -250.628658)
			(xy 361.329633 -250.61999) (xy 361.31558 -250.606562) (xy 361.29754 -250.599324) (xy 361.287822 -250.59894)
			(xy 359.858818 -250.59894) (xy 359.850944 -250.601734) (xy 359.824109 -250.610191) (xy 359.768585 -250.619262)
			(xy 359.740454 -250.619768) (xy 359.712322 -250.619269) (xy 359.656795 -250.610206) (xy 359.629964 -250.601734)
			(xy 359.62209 -250.59894) (xy 357.404416 -250.59894) (xy 357.394578 -250.599477) (xy 357.376415 -250.607061)
			(xy 357.36911 -250.613672) (xy 357.182166 -250.800616) (xy 357.176324 -250.830842) (xy 357.18242 -250.84532)
			(xy 357.193628 -250.873753) (xy 357.205774 -250.933639) (xy 357.20655 -250.964192) (xy 357.20608 -250.988185)
			(xy 357.198575 -251.03558) (xy 357.183749 -251.081218) (xy 357.161967 -251.123975) (xy 357.133764 -251.162798)
			(xy 357.099836 -251.196732) (xy 357.061017 -251.22494) (xy 357.018264 -251.24673) (xy 356.972629 -251.261563)
			(xy 356.925235 -251.269076) (xy 356.901242 -251.2695) (xy 356.870687 -251.268756) (xy 356.810801 -251.256589)
			(xy 356.78237 -251.24537) (xy 356.767892 -251.239274) (xy 356.737666 -251.245116) (xy 356.627176 -251.355606)
			(xy 356.619938 -251.362318) (xy 356.601732 -251.369909) (xy 356.59187 -251.370338) (xy 355.759766 -251.370338)
			(xy 355.749459 -251.370809) (xy 355.73051 -251.378924) (xy 355.716307 -251.393863) (xy 355.713565 -251.40031)
			(xy 359.872791 -251.40031) (xy 359.876821 -251.347812) (xy 359.888818 -251.296544) (xy 359.908501 -251.247709)
			(xy 359.935407 -251.20245) (xy 359.968907 -251.161829) (xy 360.008215 -251.126798) (xy 360.05241 -251.098178)
			(xy 360.100455 -251.076639) (xy 360.151226 -251.062687) (xy 360.203531 -251.056649) (xy 360.256145 -251.058666)
			(xy 360.307835 -251.06869) (xy 360.357388 -251.086488) (xy 360.403644 -251.111641) (xy 360.445518 -251.14356)
			(xy 360.48203 -251.181498) (xy 360.512322 -251.224564) (xy 360.535685 -251.271749) (xy 360.551571 -251.321948)
			(xy 360.559608 -251.373984) (xy 360.560112 -251.40031) (xy 360.559608 -251.426636) (xy 360.551571 -251.478672)
			(xy 360.535685 -251.528871) (xy 360.512322 -251.576056) (xy 360.48203 -251.619122) (xy 360.445518 -251.65706)
			(xy 360.403644 -251.688979) (xy 360.357388 -251.714132) (xy 360.307835 -251.73193) (xy 360.256145 -251.741954)
			(xy 360.203531 -251.743971) (xy 360.151226 -251.737933) (xy 360.100455 -251.723981) (xy 360.05241 -251.702442)
			(xy 360.008215 -251.673822) (xy 359.968907 -251.638791) (xy 359.935407 -251.59817) (xy 359.908501 -251.552911)
			(xy 359.888818 -251.504076) (xy 359.876821 -251.452808) (xy 359.872791 -251.40031) (xy 355.713565 -251.40031)
			(xy 355.712268 -251.403358) (xy 355.679756 -251.489718) (xy 355.676554 -251.499456) (xy 355.677367 -251.51992)
			(xy 355.686148 -251.538422) (xy 355.693472 -251.545598) (xy 355.712467 -251.563138) (xy 355.74485 -251.603438)
			(xy 355.76998 -251.648618) (xy 355.787138 -251.697386) (xy 355.795832 -251.748349) (xy 355.796342 -251.774198)
			(xy 357.065338 -251.774198) (xy 357.069298 -251.725144) (xy 357.081075 -251.67736) (xy 357.100366 -251.632084)
			(xy 357.126669 -251.590488) (xy 357.159304 -251.553651) (xy 357.197425 -251.522526) (xy 357.240046 -251.497919)
			(xy 357.286062 -251.480467) (xy 357.334281 -251.470623) (xy 357.383456 -251.468642) (xy 357.432311 -251.474574)
			(xy 357.479582 -251.488266) (xy 357.524044 -251.509364) (xy 357.564547 -251.53732) (xy 357.60004 -251.571412)
			(xy 357.629605 -251.610756) (xy 357.652476 -251.654333) (xy 357.66806 -251.701014) (xy 357.675955 -251.749591)
			(xy 357.67645 -251.774198) (xy 360.81895 -251.774198) (xy 360.82291 -251.725144) (xy 360.834687 -251.67736)
			(xy 360.853978 -251.632084) (xy 360.880281 -251.590488) (xy 360.912916 -251.553651) (xy 360.951037 -251.522526)
			(xy 360.993658 -251.497919) (xy 361.039674 -251.480467) (xy 361.087893 -251.470623) (xy 361.137068 -251.468642)
			(xy 361.185923 -251.474574) (xy 361.233194 -251.488266) (xy 361.277656 -251.509364) (xy 361.318159 -251.53732)
			(xy 361.353652 -251.571412) (xy 361.383217 -251.610756) (xy 361.406088 -251.654333) (xy 361.421672 -251.701014)
			(xy 361.429567 -251.749591) (xy 361.430062 -251.774198) (xy 362.699058 -251.774198) (xy 362.703018 -251.725144)
			(xy 362.714795 -251.67736) (xy 362.734086 -251.632084) (xy 362.760389 -251.590488) (xy 362.793024 -251.553651)
			(xy 362.831145 -251.522526) (xy 362.873766 -251.497919) (xy 362.919782 -251.480467) (xy 362.968001 -251.470623)
			(xy 363.017176 -251.468642) (xy 363.066031 -251.474574) (xy 363.113302 -251.488266) (xy 363.157764 -251.509364)
			(xy 363.198267 -251.53732) (xy 363.23376 -251.571412) (xy 363.263325 -251.610756) (xy 363.286196 -251.654333)
			(xy 363.30178 -251.701014) (xy 363.309675 -251.749591) (xy 363.31017 -251.774198) (xy 363.309675 -251.798805)
			(xy 363.30178 -251.847382) (xy 363.286196 -251.894063) (xy 363.263325 -251.93764) (xy 363.23376 -251.976984)
			(xy 363.198267 -252.011076) (xy 363.157764 -252.039032) (xy 363.113302 -252.06013) (xy 363.066031 -252.073822)
			(xy 363.017176 -252.079754) (xy 362.968001 -252.077773) (xy 362.919782 -252.067929) (xy 362.873766 -252.050477)
			(xy 362.831145 -252.02587) (xy 362.793024 -251.994745) (xy 362.760389 -251.957908) (xy 362.734086 -251.916312)
			(xy 362.714795 -251.871036) (xy 362.703018 -251.823252) (xy 362.699058 -251.774198) (xy 361.430062 -251.774198)
			(xy 361.429567 -251.798805) (xy 361.421672 -251.847382) (xy 361.406088 -251.894063) (xy 361.383217 -251.93764)
			(xy 361.353652 -251.976984) (xy 361.318159 -252.011076) (xy 361.277656 -252.039032) (xy 361.233194 -252.06013)
			(xy 361.185923 -252.073822) (xy 361.137068 -252.079754) (xy 361.087893 -252.077773) (xy 361.039674 -252.067929)
			(xy 360.993658 -252.050477) (xy 360.951037 -252.02587) (xy 360.912916 -251.994745) (xy 360.880281 -251.957908)
			(xy 360.853978 -251.916312) (xy 360.834687 -251.871036) (xy 360.82291 -251.823252) (xy 360.81895 -251.774198)
			(xy 357.67645 -251.774198) (xy 357.675955 -251.798805) (xy 357.66806 -251.847382) (xy 357.652476 -251.894063)
			(xy 357.629605 -251.93764) (xy 357.60004 -251.976984) (xy 357.564547 -252.011076) (xy 357.524044 -252.039032)
			(xy 357.479582 -252.06013) (xy 357.432311 -252.073822) (xy 357.383456 -252.079754) (xy 357.334281 -252.077773)
			(xy 357.286062 -252.067929) (xy 357.240046 -252.050477) (xy 357.197425 -252.02587) (xy 357.159304 -251.994745)
			(xy 357.126669 -251.957908) (xy 357.100366 -251.916312) (xy 357.081075 -251.871036) (xy 357.069298 -251.823252)
			(xy 357.065338 -251.774198) (xy 355.796342 -251.774198) (xy 355.79582 -251.799453) (xy 355.787507 -251.849275)
			(xy 355.771106 -251.897049) (xy 355.747065 -251.941472) (xy 355.716041 -251.981332) (xy 355.678879 -252.015542)
			(xy 355.636593 -252.043168) (xy 355.590337 -252.063458) (xy 355.541372 -252.075858) (xy 355.491034 -252.080029)
			(xy 355.440696 -252.075858) (xy 355.391731 -252.063458) (xy 355.345475 -252.043168) (xy 355.303189 -252.015542)
			(xy 355.266027 -251.981332) (xy 355.235003 -251.941472) (xy 355.210962 -251.897049) (xy 355.194561 -251.849275)
			(xy 355.186248 -251.799453) (xy 355.185726 -251.774198) (xy 355.185863 -251.761435) (xy 355.188022 -251.736)
			(xy 355.190044 -251.723398) (xy 355.18979 -251.723398) (xy 355.194669 -251.69792) (xy 355.211855 -251.648981)
			(xy 355.23706 -251.603646) (xy 355.269557 -251.563219) (xy 355.288596 -251.545598) (xy 355.295921 -251.53843)
			(xy 355.304663 -251.519914) (xy 355.305508 -251.499454) (xy 355.302312 -251.489718) (xy 355.2698 -251.403358)
			(xy 355.265735 -251.393885) (xy 355.251515 -251.378988) (xy 355.232597 -251.370848) (xy 355.222302 -251.370338)
			(xy 353.879912 -251.370338) (xy 353.869599 -251.370801) (xy 353.850636 -251.378907) (xy 353.836418 -251.393845)
			(xy 353.832414 -251.403358) (xy 353.799902 -251.489718) (xy 353.796702 -251.499457) (xy 353.797515 -251.519922)
			(xy 353.806289 -251.538428) (xy 353.813618 -251.545598) (xy 353.832616 -251.563137) (xy 353.865005 -251.603434)
			(xy 353.890139 -251.648614) (xy 353.9073 -251.697384) (xy 353.915996 -251.748348) (xy 353.916488 -251.774198)
			(xy 353.915966 -251.799453) (xy 353.907653 -251.849275) (xy 353.891252 -251.897049) (xy 353.867211 -251.941472)
			(xy 353.836187 -251.981332) (xy 353.799025 -252.015542) (xy 353.756739 -252.043168) (xy 353.710483 -252.063458)
			(xy 353.661518 -252.075858) (xy 353.61118 -252.080029) (xy 353.560842 -252.075858) (xy 353.511877 -252.063458)
			(xy 353.465621 -252.043168) (xy 353.423335 -252.015542) (xy 353.386173 -251.981332) (xy 353.355149 -251.941472)
			(xy 353.331108 -251.897049) (xy 353.314707 -251.849275) (xy 353.306394 -251.799453) (xy 353.305872 -251.774198)
			(xy 353.305991 -251.762594) (xy 353.307772 -251.739456) (xy 353.309428 -251.72797) (xy 353.309936 -251.72416)
			(xy 353.309936 -251.723398) (xy 353.314814 -251.697919) (xy 353.331998 -251.648978) (xy 353.357199 -251.60364)
			(xy 353.389693 -251.563208) (xy 353.408742 -251.545598) (xy 353.420426 -251.53493) (xy 353.428046 -251.50445)
			(xy 353.389946 -251.403358) (xy 353.385878 -251.393892) (xy 353.371656 -251.379009) (xy 353.352739 -251.370889)
			(xy 353.342448 -251.370338) (xy 351.999804 -251.370338) (xy 351.989492 -251.370802) (xy 351.970532 -251.37891)
			(xy 351.956316 -251.393848) (xy 351.952306 -251.403358) (xy 351.919794 -251.489718) (xy 351.916594 -251.499457)
			(xy 351.917407 -251.519922) (xy 351.92618 -251.538429) (xy 351.93351 -251.545598) (xy 351.952509 -251.563136)
			(xy 351.984898 -251.603434) (xy 352.010033 -251.648614) (xy 352.027194 -251.697383) (xy 352.035891 -251.748347)
			(xy 352.03638 -251.774198) (xy 352.035858 -251.799453) (xy 352.027545 -251.849275) (xy 352.011144 -251.897049)
			(xy 351.987103 -251.941472) (xy 351.956079 -251.981332) (xy 351.918917 -252.015542) (xy 351.876631 -252.043168)
			(xy 351.830375 -252.063458) (xy 351.78141 -252.075858) (xy 351.731072 -252.080029) (xy 351.680734 -252.075858)
			(xy 351.631769 -252.063458) (xy 351.585513 -252.043168) (xy 351.543227 -252.015542) (xy 351.506065 -251.981332)
			(xy 351.475041 -251.941472) (xy 351.451 -251.897049) (xy 351.434599 -251.849275) (xy 351.426286 -251.799453)
			(xy 351.425764 -251.774198) (xy 351.425901 -251.761435) (xy 351.42806 -251.736001) (xy 351.430082 -251.723398)
			(xy 351.429828 -251.723398) (xy 351.434706 -251.697919) (xy 351.45189 -251.648977) (xy 351.47709 -251.603639)
			(xy 351.509584 -251.563207) (xy 351.528634 -251.545598) (xy 351.535967 -251.538434) (xy 351.54472 -251.519916)
			(xy 351.545565 -251.49945) (xy 351.54235 -251.489718) (xy 351.509838 -251.403358) (xy 351.505775 -251.393881)
			(xy 351.491557 -251.378973) (xy 351.472638 -251.37082) (xy 351.46234 -251.370338) (xy 350.263206 -251.370338)
			(xy 350.253369 -251.370876) (xy 350.235208 -251.378463) (xy 350.2279 -251.38507) (xy 350.108266 -251.504704)
			(xy 350.102025 -251.511567) (xy 350.094476 -251.528495) (xy 350.093534 -251.537724) (xy 350.092264 -251.560076)
			(xy 350.092076 -251.564712) (xy 350.093219 -251.573919) (xy 350.09455 -251.578364) (xy 350.1009 -251.59843)
			(xy 350.104964 -251.604526) (xy 350.117134 -251.623456) (xy 350.136386 -251.664131) (xy 350.149471 -251.707188)
			(xy 350.156108 -251.751698) (xy 350.156526 -251.774198) (xy 350.156099 -251.79772) (xy 350.148894 -251.844209)
			(xy 350.13464 -251.88904) (xy 350.113673 -251.931153) (xy 350.086491 -251.969549) (xy 350.053738 -252.003318)
			(xy 350.01619 -252.03166) (xy 349.974738 -252.053903) (xy 349.930362 -252.069521) (xy 349.884115 -252.078142)
			(xy 349.860616 -252.079252) (xy 349.852234 -252.079506) (xy 349.829542 -252.079179) (xy 349.784634 -252.072647)
			(xy 349.741182 -252.05956) (xy 349.700137 -252.040202) (xy 349.681038 -252.027944) (xy 349.675196 -252.02388)
			(xy 349.655384 -252.01753) (xy 349.650929 -252.016249) (xy 349.64173 -252.015104) (xy 349.637096 -252.015244)
			(xy 349.614744 -252.016514) (xy 349.60551 -252.01743) (xy 349.588581 -252.024993) (xy 349.581724 -252.031246)
			(xy 349.471742 -252.141228) (xy 349.463539 -252.150586) (xy 349.456257 -252.17434) (xy 349.457772 -252.186694)
			(xy 349.475552 -252.279404) (xy 349.4913 -252.298962) (xy 349.50273 -252.304042) (xy 349.52577 -252.314609)
			(xy 349.568276 -252.342221) (xy 349.605644 -252.376466) (xy 349.636774 -252.41631) (xy 359.853741 -252.41631)
			(xy 359.857771 -252.363812) (xy 359.869768 -252.312544) (xy 359.889451 -252.263709) (xy 359.916357 -252.21845)
			(xy 359.949857 -252.177829) (xy 359.989165 -252.142798) (xy 360.03336 -252.114178) (xy 360.081405 -252.092639)
			(xy 360.132176 -252.078687) (xy 360.184481 -252.072649) (xy 360.237095 -252.074666) (xy 360.288785 -252.08469)
			(xy 360.338338 -252.102488) (xy 360.384594 -252.127641) (xy 360.426468 -252.15956) (xy 360.46298 -252.197498)
			(xy 360.493272 -252.240564) (xy 360.516635 -252.287749) (xy 360.532521 -252.337948) (xy 360.540558 -252.389984)
			(xy 360.541062 -252.41631) (xy 360.540558 -252.442636) (xy 360.532521 -252.494672) (xy 360.516635 -252.544871)
			(xy 360.49716 -252.584204) (xy 368.809028 -252.584204) (xy 368.812988 -252.53515) (xy 368.824765 -252.487366)
			(xy 368.844056 -252.44209) (xy 368.870359 -252.400494) (xy 368.902994 -252.363657) (xy 368.941115 -252.332532)
			(xy 368.983736 -252.307925) (xy 369.029752 -252.290473) (xy 369.077971 -252.280629) (xy 369.127146 -252.278648)
			(xy 369.176001 -252.28458) (xy 369.223272 -252.298272) (xy 369.267734 -252.31937) (xy 369.308237 -252.347326)
			(xy 369.34373 -252.381418) (xy 369.373295 -252.420762) (xy 369.396166 -252.464339) (xy 369.41175 -252.51102)
			(xy 369.419645 -252.559597) (xy 369.42014 -252.584204) (xy 370.688882 -252.584204) (xy 370.692842 -252.53515)
			(xy 370.704619 -252.487366) (xy 370.72391 -252.44209) (xy 370.750213 -252.400494) (xy 370.782848 -252.363657)
			(xy 370.820969 -252.332532) (xy 370.86359 -252.307925) (xy 370.909606 -252.290473) (xy 370.957825 -252.280629)
			(xy 371.007 -252.278648) (xy 371.055855 -252.28458) (xy 371.103126 -252.298272) (xy 371.147588 -252.31937)
			(xy 371.188091 -252.347326) (xy 371.223584 -252.381418) (xy 371.253149 -252.420762) (xy 371.27602 -252.464339)
			(xy 371.291604 -252.51102) (xy 371.299499 -252.559597) (xy 371.299994 -252.584204) (xy 372.56899 -252.584204)
			(xy 372.57295 -252.53515) (xy 372.584727 -252.487366) (xy 372.604018 -252.44209) (xy 372.630321 -252.400494)
			(xy 372.662956 -252.363657) (xy 372.701077 -252.332532) (xy 372.743698 -252.307925) (xy 372.789714 -252.290473)
			(xy 372.837933 -252.280629) (xy 372.887108 -252.278648) (xy 372.935963 -252.28458) (xy 372.983234 -252.298272)
			(xy 373.027696 -252.31937) (xy 373.068199 -252.347326) (xy 373.103692 -252.381418) (xy 373.133257 -252.420762)
			(xy 373.156128 -252.464339) (xy 373.171712 -252.51102) (xy 373.179607 -252.559597) (xy 373.180102 -252.584204)
			(xy 374.449098 -252.584204) (xy 374.453058 -252.53515) (xy 374.464835 -252.487366) (xy 374.484126 -252.44209)
			(xy 374.510429 -252.400494) (xy 374.543064 -252.363657) (xy 374.581185 -252.332532) (xy 374.623806 -252.307925)
			(xy 374.669822 -252.290473) (xy 374.718041 -252.280629) (xy 374.767216 -252.278648) (xy 374.816071 -252.28458)
			(xy 374.863342 -252.298272) (xy 374.907804 -252.31937) (xy 374.948307 -252.347326) (xy 374.9838 -252.381418)
			(xy 375.013365 -252.420762) (xy 375.036236 -252.464339) (xy 375.05182 -252.51102) (xy 375.059715 -252.559597)
			(xy 375.06021 -252.584204) (xy 375.388898 -252.584204) (xy 375.392858 -252.53515) (xy 375.404635 -252.487366)
			(xy 375.423926 -252.44209) (xy 375.450229 -252.400494) (xy 375.482864 -252.363657) (xy 375.520985 -252.332532)
			(xy 375.563606 -252.307925) (xy 375.609622 -252.290473) (xy 375.657841 -252.280629) (xy 375.707016 -252.278648)
			(xy 375.755871 -252.28458) (xy 375.803142 -252.298272) (xy 375.847604 -252.31937) (xy 375.888107 -252.347326)
			(xy 375.9236 -252.381418) (xy 375.953165 -252.420762) (xy 375.976036 -252.464339) (xy 375.99162 -252.51102)
			(xy 375.999515 -252.559597) (xy 376.00001 -252.584204) (xy 376.328952 -252.584204) (xy 376.332912 -252.53515)
			(xy 376.344689 -252.487366) (xy 376.36398 -252.44209) (xy 376.390283 -252.400494) (xy 376.422918 -252.363657)
			(xy 376.461039 -252.332532) (xy 376.50366 -252.307925) (xy 376.549676 -252.290473) (xy 376.597895 -252.280629)
			(xy 376.64707 -252.278648) (xy 376.695925 -252.28458) (xy 376.743196 -252.298272) (xy 376.787658 -252.31937)
			(xy 376.828161 -252.347326) (xy 376.863654 -252.381418) (xy 376.893219 -252.420762) (xy 376.91609 -252.464339)
			(xy 376.931674 -252.51102) (xy 376.939569 -252.559597) (xy 376.940064 -252.584204) (xy 377.258575 -252.584204)
			(xy 377.26267 -252.533476) (xy 377.274849 -252.484062) (xy 377.294797 -252.437242) (xy 377.321998 -252.394228)
			(xy 377.355746 -252.356134) (xy 377.395168 -252.323947) (xy 377.439242 -252.298501) (xy 377.486828 -252.280454)
			(xy 377.536692 -252.270274) (xy 377.587544 -252.268225) (xy 377.638065 -252.274359) (xy 377.686949 -252.288519)
			(xy 377.732928 -252.310336) (xy 377.774812 -252.339246) (xy 377.811516 -252.374501) (xy 377.842089 -252.415187)
			(xy 377.86574 -252.46025) (xy 377.881856 -252.508524) (xy 377.89002 -252.558758) (xy 377.890532 -252.584204)
			(xy 377.89002 -252.60965) (xy 377.881856 -252.659884) (xy 377.86574 -252.708158) (xy 377.842089 -252.753221)
			(xy 377.811516 -252.793907) (xy 377.774812 -252.829162) (xy 377.732928 -252.858072) (xy 377.686949 -252.879889)
			(xy 377.638065 -252.894049) (xy 377.587544 -252.900183) (xy 377.536692 -252.898134) (xy 377.486828 -252.887954)
			(xy 377.439242 -252.869907) (xy 377.395168 -252.844461) (xy 377.355746 -252.812274) (xy 377.321998 -252.77418)
			(xy 377.294797 -252.731166) (xy 377.274849 -252.684346) (xy 377.26267 -252.634932) (xy 377.258575 -252.584204)
			(xy 376.940064 -252.584204) (xy 376.939569 -252.608811) (xy 376.931674 -252.657388) (xy 376.91609 -252.704069)
			(xy 376.893219 -252.747646) (xy 376.863654 -252.78699) (xy 376.828161 -252.821082) (xy 376.787658 -252.849038)
			(xy 376.743196 -252.870136) (xy 376.695925 -252.883828) (xy 376.64707 -252.88976) (xy 376.597895 -252.887779)
			(xy 376.549676 -252.877935) (xy 376.50366 -252.860483) (xy 376.461039 -252.835876) (xy 376.422918 -252.804751)
			(xy 376.390283 -252.767914) (xy 376.36398 -252.726318) (xy 376.344689 -252.681042) (xy 376.332912 -252.633258)
			(xy 376.328952 -252.584204) (xy 376.00001 -252.584204) (xy 375.999515 -252.608811) (xy 375.99162 -252.657388)
			(xy 375.976036 -252.704069) (xy 375.953165 -252.747646) (xy 375.9236 -252.78699) (xy 375.888107 -252.821082)
			(xy 375.847604 -252.849038) (xy 375.803142 -252.870136) (xy 375.755871 -252.883828) (xy 375.707016 -252.88976)
			(xy 375.657841 -252.887779) (xy 375.609622 -252.877935) (xy 375.563606 -252.860483) (xy 375.520985 -252.835876)
			(xy 375.482864 -252.804751) (xy 375.450229 -252.767914) (xy 375.423926 -252.726318) (xy 375.404635 -252.681042)
			(xy 375.392858 -252.633258) (xy 375.388898 -252.584204) (xy 375.06021 -252.584204) (xy 375.059715 -252.608811)
			(xy 375.05182 -252.657388) (xy 375.036236 -252.704069) (xy 375.013365 -252.747646) (xy 374.9838 -252.78699)
			(xy 374.948307 -252.821082) (xy 374.907804 -252.849038) (xy 374.863342 -252.870136) (xy 374.816071 -252.883828)
			(xy 374.767216 -252.88976) (xy 374.718041 -252.887779) (xy 374.669822 -252.877935) (xy 374.623806 -252.860483)
			(xy 374.581185 -252.835876) (xy 374.543064 -252.804751) (xy 374.510429 -252.767914) (xy 374.484126 -252.726318)
			(xy 374.464835 -252.681042) (xy 374.453058 -252.633258) (xy 374.449098 -252.584204) (xy 373.180102 -252.584204)
			(xy 373.179607 -252.608811) (xy 373.171712 -252.657388) (xy 373.156128 -252.704069) (xy 373.133257 -252.747646)
			(xy 373.103692 -252.78699) (xy 373.068199 -252.821082) (xy 373.027696 -252.849038) (xy 372.983234 -252.870136)
			(xy 372.935963 -252.883828) (xy 372.887108 -252.88976) (xy 372.837933 -252.887779) (xy 372.789714 -252.877935)
			(xy 372.743698 -252.860483) (xy 372.701077 -252.835876) (xy 372.662956 -252.804751) (xy 372.630321 -252.767914)
			(xy 372.604018 -252.726318) (xy 372.584727 -252.681042) (xy 372.57295 -252.633258) (xy 372.56899 -252.584204)
			(xy 371.299994 -252.584204) (xy 371.299499 -252.608811) (xy 371.291604 -252.657388) (xy 371.27602 -252.704069)
			(xy 371.253149 -252.747646) (xy 371.223584 -252.78699) (xy 371.188091 -252.821082) (xy 371.147588 -252.849038)
			(xy 371.103126 -252.870136) (xy 371.055855 -252.883828) (xy 371.007 -252.88976) (xy 370.957825 -252.887779)
			(xy 370.909606 -252.877935) (xy 370.86359 -252.860483) (xy 370.820969 -252.835876) (xy 370.782848 -252.804751)
			(xy 370.750213 -252.767914) (xy 370.72391 -252.726318) (xy 370.704619 -252.681042) (xy 370.692842 -252.633258)
			(xy 370.688882 -252.584204) (xy 369.42014 -252.584204) (xy 369.419645 -252.608811) (xy 369.41175 -252.657388)
			(xy 369.396166 -252.704069) (xy 369.373295 -252.747646) (xy 369.34373 -252.78699) (xy 369.308237 -252.821082)
			(xy 369.267734 -252.849038) (xy 369.223272 -252.870136) (xy 369.176001 -252.883828) (xy 369.127146 -252.88976)
			(xy 369.077971 -252.887779) (xy 369.029752 -252.877935) (xy 368.983736 -252.860483) (xy 368.941115 -252.835876)
			(xy 368.902994 -252.804751) (xy 368.870359 -252.767914) (xy 368.844056 -252.726318) (xy 368.824765 -252.681042)
			(xy 368.812988 -252.633258) (xy 368.809028 -252.584204) (xy 360.49716 -252.584204) (xy 360.493272 -252.592056)
			(xy 360.46298 -252.635122) (xy 360.426468 -252.67306) (xy 360.384594 -252.704979) (xy 360.338338 -252.730132)
			(xy 360.288785 -252.74793) (xy 360.237095 -252.757954) (xy 360.184481 -252.759971) (xy 360.132176 -252.753933)
			(xy 360.081405 -252.739981) (xy 360.03336 -252.718442) (xy 359.989165 -252.689822) (xy 359.949857 -252.654791)
			(xy 359.916357 -252.61417) (xy 359.889451 -252.568911) (xy 359.869768 -252.520076) (xy 359.857771 -252.468808)
			(xy 359.853741 -252.41631) (xy 349.636774 -252.41631) (xy 349.63685 -252.416407) (xy 349.661039 -252.460949)
			(xy 349.677549 -252.508872) (xy 349.685927 -252.558861) (xy 349.686372 -252.584204) (xy 349.685925 -252.608196)
			(xy 349.678418 -252.655589) (xy 349.663589 -252.701224) (xy 349.641803 -252.743977) (xy 349.613596 -252.782795)
			(xy 349.579664 -252.816722) (xy 349.540842 -252.844923) (xy 349.498087 -252.866704) (xy 349.45245 -252.881527)
			(xy 349.405056 -252.889029) (xy 349.381064 -252.889512) (xy 349.368301 -252.889374) (xy 349.342867 -252.887211)
			(xy 349.330264 -252.885194) (xy 349.330264 -252.885448) (xy 349.305377 -252.880749) (xy 349.257512 -252.864207)
			(xy 349.213032 -252.839994) (xy 349.173158 -252.808773) (xy 349.138982 -252.771399) (xy 349.111442 -252.728899)
			(xy 349.100902 -252.70587) (xy 349.095822 -252.69444) (xy 349.076264 -252.678692) (xy 348.983554 -252.660912)
			(xy 348.971188 -252.659161) (xy 348.947345 -252.666496) (xy 348.938088 -252.674882) (xy 348.706186 -252.906784)
			(xy 348.699469 -252.914021) (xy 348.691865 -252.932226) (xy 348.691454 -252.94209) (xy 348.691454 -253.39421)
			(xy 349.545414 -253.39421) (xy 349.549374 -253.345156) (xy 349.561151 -253.297372) (xy 349.580442 -253.252096)
			(xy 349.606745 -253.2105) (xy 349.63938 -253.173663) (xy 349.677501 -253.142538) (xy 349.720122 -253.117931)
			(xy 349.766138 -253.100479) (xy 349.814357 -253.090635) (xy 349.863532 -253.088654) (xy 349.912387 -253.094586)
			(xy 349.959658 -253.108278) (xy 350.00412 -253.129376) (xy 350.044623 -253.157332) (xy 350.080116 -253.191424)
			(xy 350.109681 -253.230768) (xy 350.132552 -253.274345) (xy 350.148136 -253.321026) (xy 350.156031 -253.369603)
			(xy 350.156485 -253.392178) (xy 351.42222 -253.392178) (xy 351.42618 -253.343124) (xy 351.437957 -253.29534)
			(xy 351.457248 -253.250064) (xy 351.483551 -253.208468) (xy 351.516186 -253.171631) (xy 351.554307 -253.140506)
			(xy 351.596928 -253.115899) (xy 351.642944 -253.098447) (xy 351.691163 -253.088603) (xy 351.740338 -253.086622)
			(xy 351.789193 -253.092554) (xy 351.836464 -253.106246) (xy 351.880926 -253.127344) (xy 351.921429 -253.1553)
			(xy 351.956922 -253.189392) (xy 351.986487 -253.228736) (xy 352.009358 -253.272313) (xy 352.024942 -253.318994)
			(xy 352.032837 -253.367571) (xy 352.033332 -253.392178) (xy 353.302074 -253.392178) (xy 353.306034 -253.343124)
			(xy 353.317811 -253.29534) (xy 353.337102 -253.250064) (xy 353.363405 -253.208468) (xy 353.39604 -253.171631)
			(xy 353.434161 -253.140506) (xy 353.476782 -253.115899) (xy 353.522798 -253.098447) (xy 353.571017 -253.088603)
			(xy 353.620192 -253.086622) (xy 353.669047 -253.092554) (xy 353.716318 -253.106246) (xy 353.76078 -253.127344)
			(xy 353.801283 -253.1553) (xy 353.836776 -253.189392) (xy 353.866341 -253.228736) (xy 353.889212 -253.272313)
			(xy 353.904796 -253.318994) (xy 353.912691 -253.367571) (xy 353.913186 -253.392178) (xy 355.182182 -253.392178)
			(xy 355.186142 -253.343124) (xy 355.197919 -253.29534) (xy 355.21721 -253.250064) (xy 355.243513 -253.208468)
			(xy 355.276148 -253.171631) (xy 355.314269 -253.140506) (xy 355.35689 -253.115899) (xy 355.402906 -253.098447)
			(xy 355.451125 -253.088603) (xy 355.5003 -253.086622) (xy 355.549155 -253.092554) (xy 355.596426 -253.106246)
			(xy 355.640888 -253.127344) (xy 355.681391 -253.1553) (xy 355.716884 -253.189392) (xy 355.746449 -253.228736)
			(xy 355.76932 -253.272313) (xy 355.784904 -253.318994) (xy 355.792799 -253.367571) (xy 355.793294 -253.392178)
			(xy 357.06229 -253.392178) (xy 357.06625 -253.343124) (xy 357.078027 -253.29534) (xy 357.097318 -253.250064)
			(xy 357.123621 -253.208468) (xy 357.156256 -253.171631) (xy 357.194377 -253.140506) (xy 357.236998 -253.115899)
			(xy 357.283014 -253.098447) (xy 357.331233 -253.088603) (xy 357.380408 -253.086622) (xy 357.429263 -253.092554)
			(xy 357.476534 -253.106246) (xy 357.520996 -253.127344) (xy 357.561499 -253.1553) (xy 357.596992 -253.189392)
			(xy 357.626557 -253.228736) (xy 357.649428 -253.272313) (xy 357.665012 -253.318994) (xy 357.672907 -253.367571)
			(xy 357.673402 -253.392178) (xy 357.672907 -253.416785) (xy 357.670384 -253.43231) (xy 359.853741 -253.43231)
			(xy 359.857771 -253.379812) (xy 359.869768 -253.328544) (xy 359.889451 -253.279709) (xy 359.916357 -253.23445)
			(xy 359.949857 -253.193829) (xy 359.989165 -253.158798) (xy 360.03336 -253.130178) (xy 360.081405 -253.108639)
			(xy 360.132176 -253.094687) (xy 360.184481 -253.088649) (xy 360.237095 -253.090666) (xy 360.288785 -253.10069)
			(xy 360.338338 -253.118488) (xy 360.384594 -253.143641) (xy 360.426468 -253.17556) (xy 360.46298 -253.213498)
			(xy 360.493272 -253.256564) (xy 360.516635 -253.303749) (xy 360.532521 -253.353948) (xy 360.538426 -253.392178)
			(xy 360.822252 -253.392178) (xy 360.826212 -253.343124) (xy 360.837989 -253.29534) (xy 360.85728 -253.250064)
			(xy 360.883583 -253.208468) (xy 360.916218 -253.171631) (xy 360.954339 -253.140506) (xy 360.99696 -253.115899)
			(xy 361.042976 -253.098447) (xy 361.091195 -253.088603) (xy 361.14037 -253.086622) (xy 361.189225 -253.092554)
			(xy 361.236496 -253.106246) (xy 361.280958 -253.127344) (xy 361.321461 -253.1553) (xy 361.356954 -253.189392)
			(xy 361.386519 -253.228736) (xy 361.40939 -253.272313) (xy 361.424974 -253.318994) (xy 361.432869 -253.367571)
			(xy 361.433364 -253.392178) (xy 362.702106 -253.392178) (xy 362.706066 -253.343124) (xy 362.717843 -253.29534)
			(xy 362.737134 -253.250064) (xy 362.763437 -253.208468) (xy 362.796072 -253.171631) (xy 362.834193 -253.140506)
			(xy 362.876814 -253.115899) (xy 362.92283 -253.098447) (xy 362.971049 -253.088603) (xy 363.020224 -253.086622)
			(xy 363.069079 -253.092554) (xy 363.11635 -253.106246) (xy 363.160812 -253.127344) (xy 363.201315 -253.1553)
			(xy 363.236808 -253.189392) (xy 363.266373 -253.228736) (xy 363.289244 -253.272313) (xy 363.304828 -253.318994)
			(xy 363.312723 -253.367571) (xy 363.313218 -253.392178) (xy 364.582214 -253.392178) (xy 364.586174 -253.343124)
			(xy 364.597951 -253.29534) (xy 364.617242 -253.250064) (xy 364.643545 -253.208468) (xy 364.67618 -253.171631)
			(xy 364.714301 -253.140506) (xy 364.756922 -253.115899) (xy 364.802938 -253.098447) (xy 364.851157 -253.088603)
			(xy 364.900332 -253.086622) (xy 364.949187 -253.092554) (xy 364.996458 -253.106246) (xy 365.04092 -253.127344)
			(xy 365.081423 -253.1553) (xy 365.116916 -253.189392) (xy 365.146481 -253.228736) (xy 365.169352 -253.272313)
			(xy 365.184936 -253.318994) (xy 365.192831 -253.367571) (xy 365.193326 -253.392178) (xy 366.462068 -253.392178)
			(xy 366.466028 -253.343124) (xy 366.477805 -253.29534) (xy 366.497096 -253.250064) (xy 366.523399 -253.208468)
			(xy 366.556034 -253.171631) (xy 366.594155 -253.140506) (xy 366.636776 -253.115899) (xy 366.682792 -253.098447)
			(xy 366.731011 -253.088603) (xy 366.780186 -253.086622) (xy 366.829041 -253.092554) (xy 366.876312 -253.106246)
			(xy 366.920774 -253.127344) (xy 366.961277 -253.1553) (xy 366.99677 -253.189392) (xy 367.026335 -253.228736)
			(xy 367.049206 -253.272313) (xy 367.06479 -253.318994) (xy 367.072685 -253.367571) (xy 367.07318 -253.392178)
			(xy 367.073139 -253.39421) (xy 370.218982 -253.39421) (xy 370.222942 -253.345156) (xy 370.234719 -253.297372)
			(xy 370.25401 -253.252096) (xy 370.280313 -253.2105) (xy 370.312948 -253.173663) (xy 370.351069 -253.142538)
			(xy 370.39369 -253.117931) (xy 370.439706 -253.100479) (xy 370.487925 -253.090635) (xy 370.5371 -253.088654)
			(xy 370.585955 -253.094586) (xy 370.633226 -253.108278) (xy 370.677688 -253.129376) (xy 370.718191 -253.157332)
			(xy 370.753684 -253.191424) (xy 370.783249 -253.230768) (xy 370.80612 -253.274345) (xy 370.821704 -253.321026)
			(xy 370.829599 -253.369603) (xy 370.830094 -253.39421) (xy 372.09909 -253.39421) (xy 372.10305 -253.345156)
			(xy 372.114827 -253.297372) (xy 372.134118 -253.252096) (xy 372.160421 -253.2105) (xy 372.193056 -253.173663)
			(xy 372.231177 -253.142538) (xy 372.273798 -253.117931) (xy 372.319814 -253.100479) (xy 372.368033 -253.090635)
			(xy 372.417208 -253.088654) (xy 372.466063 -253.094586) (xy 372.513334 -253.108278) (xy 372.557796 -253.129376)
			(xy 372.598299 -253.157332) (xy 372.633792 -253.191424) (xy 372.663357 -253.230768) (xy 372.686228 -253.274345)
			(xy 372.701812 -253.321026) (xy 372.709707 -253.369603) (xy 372.710202 -253.39421) (xy 373.978944 -253.39421)
			(xy 373.982904 -253.345156) (xy 373.994681 -253.297372) (xy 374.013972 -253.252096) (xy 374.040275 -253.2105)
			(xy 374.07291 -253.173663) (xy 374.111031 -253.142538) (xy 374.153652 -253.117931) (xy 374.199668 -253.100479)
			(xy 374.247887 -253.090635) (xy 374.297062 -253.088654) (xy 374.345917 -253.094586) (xy 374.393188 -253.108278)
			(xy 374.43765 -253.129376) (xy 374.478153 -253.157332) (xy 374.513646 -253.191424) (xy 374.543211 -253.230768)
			(xy 374.566082 -253.274345) (xy 374.581666 -253.321026) (xy 374.589561 -253.369603) (xy 374.590056 -253.39421)
			(xy 375.848621 -253.39421) (xy 375.852716 -253.343482) (xy 375.864895 -253.294068) (xy 375.884843 -253.247248)
			(xy 375.912044 -253.204234) (xy 375.945792 -253.16614) (xy 375.985214 -253.133953) (xy 376.029288 -253.108507)
			(xy 376.076874 -253.09046) (xy 376.126738 -253.08028) (xy 376.17759 -253.078231) (xy 376.228111 -253.084365)
			(xy 376.276995 -253.098525) (xy 376.322974 -253.120342) (xy 376.364858 -253.149252) (xy 376.401562 -253.184507)
			(xy 376.432135 -253.225193) (xy 376.455786 -253.270256) (xy 376.471902 -253.31853) (xy 376.480066 -253.368764)
			(xy 376.480578 -253.39421) (xy 376.788675 -253.39421) (xy 376.79277 -253.343482) (xy 376.804949 -253.294068)
			(xy 376.824897 -253.247248) (xy 376.852098 -253.204234) (xy 376.885846 -253.16614) (xy 376.925268 -253.133953)
			(xy 376.969342 -253.108507) (xy 377.016928 -253.09046) (xy 377.066792 -253.08028) (xy 377.117644 -253.078231)
			(xy 377.168165 -253.084365) (xy 377.217049 -253.098525) (xy 377.263028 -253.120342) (xy 377.304912 -253.149252)
			(xy 377.341616 -253.184507) (xy 377.372189 -253.225193) (xy 377.39584 -253.270256) (xy 377.411956 -253.31853)
			(xy 377.42012 -253.368764) (xy 377.420632 -253.39421) (xy 377.42012 -253.419656) (xy 377.411956 -253.46989)
			(xy 377.39584 -253.518164) (xy 377.372189 -253.563227) (xy 377.341616 -253.603913) (xy 377.304912 -253.639168)
			(xy 377.263028 -253.668078) (xy 377.217049 -253.689895) (xy 377.168165 -253.704055) (xy 377.117644 -253.710189)
			(xy 377.066792 -253.70814) (xy 377.016928 -253.69796) (xy 376.969342 -253.679913) (xy 376.925268 -253.654467)
			(xy 376.885846 -253.62228) (xy 376.852098 -253.584186) (xy 376.824897 -253.541172) (xy 376.804949 -253.494352)
			(xy 376.79277 -253.444938) (xy 376.788675 -253.39421) (xy 376.480578 -253.39421) (xy 376.480066 -253.419656)
			(xy 376.471902 -253.46989) (xy 376.455786 -253.518164) (xy 376.432135 -253.563227) (xy 376.401562 -253.603913)
			(xy 376.364858 -253.639168) (xy 376.322974 -253.668078) (xy 376.276995 -253.689895) (xy 376.228111 -253.704055)
			(xy 376.17759 -253.710189) (xy 376.126738 -253.70814) (xy 376.076874 -253.69796) (xy 376.029288 -253.679913)
			(xy 375.985214 -253.654467) (xy 375.945792 -253.62228) (xy 375.912044 -253.584186) (xy 375.884843 -253.541172)
			(xy 375.864895 -253.494352) (xy 375.852716 -253.444938) (xy 375.848621 -253.39421) (xy 374.590056 -253.39421)
			(xy 374.589561 -253.418817) (xy 374.581666 -253.467394) (xy 374.566082 -253.514075) (xy 374.543211 -253.557652)
			(xy 374.513646 -253.596996) (xy 374.478153 -253.631088) (xy 374.43765 -253.659044) (xy 374.393188 -253.680142)
			(xy 374.345917 -253.693834) (xy 374.297062 -253.699766) (xy 374.247887 -253.697785) (xy 374.199668 -253.687941)
			(xy 374.153652 -253.670489) (xy 374.111031 -253.645882) (xy 374.07291 -253.614757) (xy 374.040275 -253.57792)
			(xy 374.013972 -253.536324) (xy 373.994681 -253.491048) (xy 373.982904 -253.443264) (xy 373.978944 -253.39421)
			(xy 372.710202 -253.39421) (xy 372.709707 -253.418817) (xy 372.701812 -253.467394) (xy 372.686228 -253.514075)
			(xy 372.663357 -253.557652) (xy 372.633792 -253.596996) (xy 372.598299 -253.631088) (xy 372.557796 -253.659044)
			(xy 372.513334 -253.680142) (xy 372.466063 -253.693834) (xy 372.417208 -253.699766) (xy 372.368033 -253.697785)
			(xy 372.319814 -253.687941) (xy 372.273798 -253.670489) (xy 372.231177 -253.645882) (xy 372.193056 -253.614757)
			(xy 372.160421 -253.57792) (xy 372.134118 -253.536324) (xy 372.114827 -253.491048) (xy 372.10305 -253.443264)
			(xy 372.09909 -253.39421) (xy 370.830094 -253.39421) (xy 370.829599 -253.418817) (xy 370.821704 -253.467394)
			(xy 370.80612 -253.514075) (xy 370.783249 -253.557652) (xy 370.753684 -253.596996) (xy 370.718191 -253.631088)
			(xy 370.677688 -253.659044) (xy 370.633226 -253.680142) (xy 370.585955 -253.693834) (xy 370.5371 -253.699766)
			(xy 370.487925 -253.697785) (xy 370.439706 -253.687941) (xy 370.39369 -253.670489) (xy 370.351069 -253.645882)
			(xy 370.312948 -253.614757) (xy 370.280313 -253.57792) (xy 370.25401 -253.536324) (xy 370.234719 -253.491048)
			(xy 370.222942 -253.443264) (xy 370.218982 -253.39421) (xy 367.073139 -253.39421) (xy 367.072685 -253.416785)
			(xy 367.06479 -253.465362) (xy 367.049206 -253.512043) (xy 367.026335 -253.55562) (xy 366.99677 -253.594964)
			(xy 366.961277 -253.629056) (xy 366.920774 -253.657012) (xy 366.876312 -253.67811) (xy 366.829041 -253.691802)
			(xy 366.780186 -253.697734) (xy 366.731011 -253.695753) (xy 366.682792 -253.685909) (xy 366.636776 -253.668457)
			(xy 366.594155 -253.64385) (xy 366.556034 -253.612725) (xy 366.523399 -253.575888) (xy 366.497096 -253.534292)
			(xy 366.477805 -253.489016) (xy 366.466028 -253.441232) (xy 366.462068 -253.392178) (xy 365.193326 -253.392178)
			(xy 365.192831 -253.416785) (xy 365.184936 -253.465362) (xy 365.169352 -253.512043) (xy 365.146481 -253.55562)
			(xy 365.116916 -253.594964) (xy 365.081423 -253.629056) (xy 365.04092 -253.657012) (xy 364.996458 -253.67811)
			(xy 364.949187 -253.691802) (xy 364.900332 -253.697734) (xy 364.851157 -253.695753) (xy 364.802938 -253.685909)
			(xy 364.756922 -253.668457) (xy 364.714301 -253.64385) (xy 364.67618 -253.612725) (xy 364.643545 -253.575888)
			(xy 364.617242 -253.534292) (xy 364.597951 -253.489016) (xy 364.586174 -253.441232) (xy 364.582214 -253.392178)
			(xy 363.313218 -253.392178) (xy 363.312723 -253.416785) (xy 363.304828 -253.465362) (xy 363.289244 -253.512043)
			(xy 363.266373 -253.55562) (xy 363.236808 -253.594964) (xy 363.201315 -253.629056) (xy 363.160812 -253.657012)
			(xy 363.11635 -253.67811) (xy 363.069079 -253.691802) (xy 363.020224 -253.697734) (xy 362.971049 -253.695753)
			(xy 362.92283 -253.685909) (xy 362.876814 -253.668457) (xy 362.834193 -253.64385) (xy 362.796072 -253.612725)
			(xy 362.763437 -253.575888) (xy 362.737134 -253.534292) (xy 362.717843 -253.489016) (xy 362.706066 -253.441232)
			(xy 362.702106 -253.392178) (xy 361.433364 -253.392178) (xy 361.432869 -253.416785) (xy 361.424974 -253.465362)
			(xy 361.40939 -253.512043) (xy 361.386519 -253.55562) (xy 361.356954 -253.594964) (xy 361.321461 -253.629056)
			(xy 361.280958 -253.657012) (xy 361.236496 -253.67811) (xy 361.189225 -253.691802) (xy 361.14037 -253.697734)
			(xy 361.091195 -253.695753) (xy 361.042976 -253.685909) (xy 360.99696 -253.668457) (xy 360.954339 -253.64385)
			(xy 360.916218 -253.612725) (xy 360.883583 -253.575888) (xy 360.85728 -253.534292) (xy 360.837989 -253.489016)
			(xy 360.826212 -253.441232) (xy 360.822252 -253.392178) (xy 360.538426 -253.392178) (xy 360.540558 -253.405984)
			(xy 360.541062 -253.43231) (xy 360.540558 -253.458636) (xy 360.532521 -253.510672) (xy 360.516635 -253.560871)
			(xy 360.493272 -253.608056) (xy 360.46298 -253.651122) (xy 360.426468 -253.68906) (xy 360.384594 -253.720979)
			(xy 360.338338 -253.746132) (xy 360.288785 -253.76393) (xy 360.237095 -253.773954) (xy 360.184481 -253.775971)
			(xy 360.132176 -253.769933) (xy 360.081405 -253.755981) (xy 360.03336 -253.734442) (xy 359.989165 -253.705822)
			(xy 359.949857 -253.670791) (xy 359.916357 -253.63017) (xy 359.889451 -253.584911) (xy 359.869768 -253.536076)
			(xy 359.857771 -253.484808) (xy 359.853741 -253.43231) (xy 357.670384 -253.43231) (xy 357.665012 -253.465362)
			(xy 357.649428 -253.512043) (xy 357.626557 -253.55562) (xy 357.596992 -253.594964) (xy 357.561499 -253.629056)
			(xy 357.520996 -253.657012) (xy 357.476534 -253.67811) (xy 357.429263 -253.691802) (xy 357.380408 -253.697734)
			(xy 357.331233 -253.695753) (xy 357.283014 -253.685909) (xy 357.236998 -253.668457) (xy 357.194377 -253.64385)
			(xy 357.156256 -253.612725) (xy 357.123621 -253.575888) (xy 357.097318 -253.534292) (xy 357.078027 -253.489016)
			(xy 357.06625 -253.441232) (xy 357.06229 -253.392178) (xy 355.793294 -253.392178) (xy 355.792799 -253.416785)
			(xy 355.784904 -253.465362) (xy 355.76932 -253.512043) (xy 355.746449 -253.55562) (xy 355.716884 -253.594964)
			(xy 355.681391 -253.629056) (xy 355.640888 -253.657012) (xy 355.596426 -253.67811) (xy 355.549155 -253.691802)
			(xy 355.5003 -253.697734) (xy 355.451125 -253.695753) (xy 355.402906 -253.685909) (xy 355.35689 -253.668457)
			(xy 355.314269 -253.64385) (xy 355.276148 -253.612725) (xy 355.243513 -253.575888) (xy 355.21721 -253.534292)
			(xy 355.197919 -253.489016) (xy 355.186142 -253.441232) (xy 355.182182 -253.392178) (xy 353.913186 -253.392178)
			(xy 353.912691 -253.416785) (xy 353.904796 -253.465362) (xy 353.889212 -253.512043) (xy 353.866341 -253.55562)
			(xy 353.836776 -253.594964) (xy 353.801283 -253.629056) (xy 353.76078 -253.657012) (xy 353.716318 -253.67811)
			(xy 353.669047 -253.691802) (xy 353.620192 -253.697734) (xy 353.571017 -253.695753) (xy 353.522798 -253.685909)
			(xy 353.476782 -253.668457) (xy 353.434161 -253.64385) (xy 353.39604 -253.612725) (xy 353.363405 -253.575888)
			(xy 353.337102 -253.534292) (xy 353.317811 -253.489016) (xy 353.306034 -253.441232) (xy 353.302074 -253.392178)
			(xy 352.033332 -253.392178) (xy 352.032837 -253.416785) (xy 352.024942 -253.465362) (xy 352.009358 -253.512043)
			(xy 351.986487 -253.55562) (xy 351.956922 -253.594964) (xy 351.921429 -253.629056) (xy 351.880926 -253.657012)
			(xy 351.836464 -253.67811) (xy 351.789193 -253.691802) (xy 351.740338 -253.697734) (xy 351.691163 -253.695753)
			(xy 351.642944 -253.685909) (xy 351.596928 -253.668457) (xy 351.554307 -253.64385) (xy 351.516186 -253.612725)
			(xy 351.483551 -253.575888) (xy 351.457248 -253.534292) (xy 351.437957 -253.489016) (xy 351.42618 -253.441232)
			(xy 351.42222 -253.392178) (xy 350.156485 -253.392178) (xy 350.156526 -253.39421) (xy 350.156031 -253.418817)
			(xy 350.148136 -253.467394) (xy 350.132552 -253.514075) (xy 350.109681 -253.557652) (xy 350.080116 -253.596996)
			(xy 350.044623 -253.631088) (xy 350.00412 -253.659044) (xy 349.959658 -253.680142) (xy 349.912387 -253.693834)
			(xy 349.863532 -253.699766) (xy 349.814357 -253.697785) (xy 349.766138 -253.687941) (xy 349.720122 -253.670489)
			(xy 349.677501 -253.645882) (xy 349.63938 -253.614757) (xy 349.606745 -253.57792) (xy 349.580442 -253.536324)
			(xy 349.561151 -253.491048) (xy 349.549374 -253.443264) (xy 349.545414 -253.39421) (xy 348.691454 -253.39421)
			(xy 348.691454 -254.007366) (xy 348.691514 -254.010972) (xy 348.692529 -254.018113) (xy 348.693486 -254.02159)
			(xy 348.699328 -254.041148) (xy 348.70263 -254.046736) (xy 348.716357 -254.070684) (xy 348.735855 -254.122318)
			(xy 348.745737 -254.176619) (xy 348.746318 -254.204216) (xy 349.07526 -254.204216) (xy 349.07922 -254.155162)
			(xy 349.090997 -254.107378) (xy 349.110288 -254.062102) (xy 349.136591 -254.020506) (xy 349.169226 -253.983669)
			(xy 349.207347 -253.952544) (xy 349.249968 -253.927937) (xy 349.295984 -253.910485) (xy 349.344203 -253.900641)
			(xy 349.393378 -253.89866) (xy 349.442233 -253.904592) (xy 349.489504 -253.918284) (xy 349.533966 -253.939382)
			(xy 349.574469 -253.967338) (xy 349.609962 -254.00143) (xy 349.639527 -254.040774) (xy 349.662398 -254.084351)
			(xy 349.677982 -254.131032) (xy 349.685877 -254.179609) (xy 349.686372 -254.204216) (xy 349.685877 -254.228823)
			(xy 349.677982 -254.2774) (xy 349.662398 -254.324081) (xy 349.639527 -254.367658) (xy 349.609962 -254.407002)
			(xy 349.574469 -254.441094) (xy 349.564014 -254.44831) (xy 359.853741 -254.44831) (xy 359.857771 -254.395812)
			(xy 359.869768 -254.344544) (xy 359.889451 -254.295709) (xy 359.916357 -254.25045) (xy 359.949857 -254.209829)
			(xy 359.989165 -254.174798) (xy 360.03336 -254.146178) (xy 360.081405 -254.124639) (xy 360.132176 -254.110687)
			(xy 360.184481 -254.104649) (xy 360.237095 -254.106666) (xy 360.288785 -254.11669) (xy 360.338338 -254.134488)
			(xy 360.384594 -254.159641) (xy 360.426468 -254.19156) (xy 360.438648 -254.204216) (xy 368.809028 -254.204216)
			(xy 368.812988 -254.155162) (xy 368.824765 -254.107378) (xy 368.844056 -254.062102) (xy 368.870359 -254.020506)
			(xy 368.902994 -253.983669) (xy 368.941115 -253.952544) (xy 368.983736 -253.927937) (xy 369.029752 -253.910485)
			(xy 369.077971 -253.900641) (xy 369.127146 -253.89866) (xy 369.176001 -253.904592) (xy 369.223272 -253.918284)
			(xy 369.267734 -253.939382) (xy 369.308237 -253.967338) (xy 369.34373 -254.00143) (xy 369.373295 -254.040774)
			(xy 369.396166 -254.084351) (xy 369.41175 -254.131032) (xy 369.419645 -254.179609) (xy 369.42014 -254.204216)
			(xy 370.688882 -254.204216) (xy 370.692842 -254.155162) (xy 370.704619 -254.107378) (xy 370.72391 -254.062102)
			(xy 370.750213 -254.020506) (xy 370.782848 -253.983669) (xy 370.820969 -253.952544) (xy 370.86359 -253.927937)
			(xy 370.909606 -253.910485) (xy 370.957825 -253.900641) (xy 371.007 -253.89866) (xy 371.055855 -253.904592)
			(xy 371.103126 -253.918284) (xy 371.147588 -253.939382) (xy 371.188091 -253.967338) (xy 371.223584 -254.00143)
			(xy 371.253149 -254.040774) (xy 371.27602 -254.084351) (xy 371.291604 -254.131032) (xy 371.299499 -254.179609)
			(xy 371.299994 -254.204216) (xy 372.56899 -254.204216) (xy 372.57295 -254.155162) (xy 372.584727 -254.107378)
			(xy 372.604018 -254.062102) (xy 372.630321 -254.020506) (xy 372.662956 -253.983669) (xy 372.701077 -253.952544)
			(xy 372.743698 -253.927937) (xy 372.789714 -253.910485) (xy 372.837933 -253.900641) (xy 372.887108 -253.89866)
			(xy 372.935963 -253.904592) (xy 372.983234 -253.918284) (xy 373.027696 -253.939382) (xy 373.068199 -253.967338)
			(xy 373.103692 -254.00143) (xy 373.133257 -254.040774) (xy 373.156128 -254.084351) (xy 373.171712 -254.131032)
			(xy 373.179607 -254.179609) (xy 373.180102 -254.204216) (xy 374.449098 -254.204216) (xy 374.453058 -254.155162)
			(xy 374.464835 -254.107378) (xy 374.484126 -254.062102) (xy 374.510429 -254.020506) (xy 374.543064 -253.983669)
			(xy 374.581185 -253.952544) (xy 374.623806 -253.927937) (xy 374.669822 -253.910485) (xy 374.718041 -253.900641)
			(xy 374.767216 -253.89866) (xy 374.816071 -253.904592) (xy 374.863342 -253.918284) (xy 374.907804 -253.939382)
			(xy 374.948307 -253.967338) (xy 374.9838 -254.00143) (xy 375.013365 -254.040774) (xy 375.036236 -254.084351)
			(xy 375.05182 -254.131032) (xy 375.059715 -254.179609) (xy 375.06021 -254.204216) (xy 375.378467 -254.204216)
			(xy 375.382562 -254.153488) (xy 375.394741 -254.104074) (xy 375.414689 -254.057254) (xy 375.44189 -254.01424)
			(xy 375.475638 -253.976146) (xy 375.51506 -253.943959) (xy 375.559134 -253.918513) (xy 375.60672 -253.900466)
			(xy 375.656584 -253.890286) (xy 375.707436 -253.888237) (xy 375.757957 -253.894371) (xy 375.806841 -253.908531)
			(xy 375.85282 -253.930348) (xy 375.894704 -253.959258) (xy 375.931408 -253.994513) (xy 375.961981 -254.035199)
			(xy 375.985632 -254.080262) (xy 376.001748 -254.128536) (xy 376.009912 -254.17877) (xy 376.010424 -254.204216)
			(xy 376.328952 -254.204216) (xy 376.332912 -254.155162) (xy 376.344689 -254.107378) (xy 376.36398 -254.062102)
			(xy 376.390283 -254.020506) (xy 376.422918 -253.983669) (xy 376.461039 -253.952544) (xy 376.50366 -253.927937)
			(xy 376.549676 -253.910485) (xy 376.597895 -253.900641) (xy 376.64707 -253.89866) (xy 376.695925 -253.904592)
			(xy 376.743196 -253.918284) (xy 376.787658 -253.939382) (xy 376.828161 -253.967338) (xy 376.863654 -254.00143)
			(xy 376.893219 -254.040774) (xy 376.91609 -254.084351) (xy 376.931674 -254.131032) (xy 376.939569 -254.179609)
			(xy 376.940064 -254.204216) (xy 377.258575 -254.204216) (xy 377.26267 -254.153488) (xy 377.274849 -254.104074)
			(xy 377.294797 -254.057254) (xy 377.321998 -254.01424) (xy 377.355746 -253.976146) (xy 377.395168 -253.943959)
			(xy 377.439242 -253.918513) (xy 377.486828 -253.900466) (xy 377.536692 -253.890286) (xy 377.587544 -253.888237)
			(xy 377.638065 -253.894371) (xy 377.686949 -253.908531) (xy 377.732928 -253.930348) (xy 377.774812 -253.959258)
			(xy 377.811516 -253.994513) (xy 377.842089 -254.035199) (xy 377.86574 -254.080262) (xy 377.881856 -254.128536)
			(xy 377.89002 -254.17877) (xy 377.890532 -254.204216) (xy 377.89002 -254.229662) (xy 377.881856 -254.279896)
			(xy 377.86574 -254.32817) (xy 377.842089 -254.373233) (xy 377.811516 -254.413919) (xy 377.774812 -254.449174)
			(xy 377.732928 -254.478084) (xy 377.686949 -254.499901) (xy 377.638065 -254.514061) (xy 377.587544 -254.520195)
			(xy 377.536692 -254.518146) (xy 377.486828 -254.507966) (xy 377.439242 -254.489919) (xy 377.395168 -254.464473)
			(xy 377.355746 -254.432286) (xy 377.321998 -254.394192) (xy 377.294797 -254.351178) (xy 377.274849 -254.304358)
			(xy 377.26267 -254.254944) (xy 377.258575 -254.204216) (xy 376.940064 -254.204216) (xy 376.939569 -254.228823)
			(xy 376.931674 -254.2774) (xy 376.91609 -254.324081) (xy 376.893219 -254.367658) (xy 376.863654 -254.407002)
			(xy 376.828161 -254.441094) (xy 376.787658 -254.46905) (xy 376.743196 -254.490148) (xy 376.695925 -254.50384)
			(xy 376.64707 -254.509772) (xy 376.597895 -254.507791) (xy 376.549676 -254.497947) (xy 376.50366 -254.480495)
			(xy 376.461039 -254.455888) (xy 376.422918 -254.424763) (xy 376.390283 -254.387926) (xy 376.36398 -254.34633)
			(xy 376.344689 -254.301054) (xy 376.332912 -254.25327) (xy 376.328952 -254.204216) (xy 376.010424 -254.204216)
			(xy 376.009912 -254.229662) (xy 376.001748 -254.279896) (xy 375.985632 -254.32817) (xy 375.961981 -254.373233)
			(xy 375.931408 -254.413919) (xy 375.894704 -254.449174) (xy 375.85282 -254.478084) (xy 375.806841 -254.499901)
			(xy 375.757957 -254.514061) (xy 375.707436 -254.520195) (xy 375.656584 -254.518146) (xy 375.60672 -254.507966)
			(xy 375.559134 -254.489919) (xy 375.51506 -254.464473) (xy 375.475638 -254.432286) (xy 375.44189 -254.394192)
			(xy 375.414689 -254.351178) (xy 375.394741 -254.304358) (xy 375.382562 -254.254944) (xy 375.378467 -254.204216)
			(xy 375.06021 -254.204216) (xy 375.059715 -254.228823) (xy 375.05182 -254.2774) (xy 375.036236 -254.324081)
			(xy 375.013365 -254.367658) (xy 374.9838 -254.407002) (xy 374.948307 -254.441094) (xy 374.907804 -254.46905)
			(xy 374.863342 -254.490148) (xy 374.816071 -254.50384) (xy 374.767216 -254.509772) (xy 374.718041 -254.507791)
			(xy 374.669822 -254.497947) (xy 374.623806 -254.480495) (xy 374.581185 -254.455888) (xy 374.543064 -254.424763)
			(xy 374.510429 -254.387926) (xy 374.484126 -254.34633) (xy 374.464835 -254.301054) (xy 374.453058 -254.25327)
			(xy 374.449098 -254.204216) (xy 373.180102 -254.204216) (xy 373.179607 -254.228823) (xy 373.171712 -254.2774)
			(xy 373.156128 -254.324081) (xy 373.133257 -254.367658) (xy 373.103692 -254.407002) (xy 373.068199 -254.441094)
			(xy 373.027696 -254.46905) (xy 372.983234 -254.490148) (xy 372.935963 -254.50384) (xy 372.887108 -254.509772)
			(xy 372.837933 -254.507791) (xy 372.789714 -254.497947) (xy 372.743698 -254.480495) (xy 372.701077 -254.455888)
			(xy 372.662956 -254.424763) (xy 372.630321 -254.387926) (xy 372.604018 -254.34633) (xy 372.584727 -254.301054)
			(xy 372.57295 -254.25327) (xy 372.56899 -254.204216) (xy 371.299994 -254.204216) (xy 371.299499 -254.228823)
			(xy 371.291604 -254.2774) (xy 371.27602 -254.324081) (xy 371.253149 -254.367658) (xy 371.223584 -254.407002)
			(xy 371.188091 -254.441094) (xy 371.147588 -254.46905) (xy 371.103126 -254.490148) (xy 371.055855 -254.50384)
			(xy 371.007 -254.509772) (xy 370.957825 -254.507791) (xy 370.909606 -254.497947) (xy 370.86359 -254.480495)
			(xy 370.820969 -254.455888) (xy 370.782848 -254.424763) (xy 370.750213 -254.387926) (xy 370.72391 -254.34633)
			(xy 370.704619 -254.301054) (xy 370.692842 -254.25327) (xy 370.688882 -254.204216) (xy 369.42014 -254.204216)
			(xy 369.419645 -254.228823) (xy 369.41175 -254.2774) (xy 369.396166 -254.324081) (xy 369.373295 -254.367658)
			(xy 369.34373 -254.407002) (xy 369.308237 -254.441094) (xy 369.267734 -254.46905) (xy 369.223272 -254.490148)
			(xy 369.176001 -254.50384) (xy 369.127146 -254.509772) (xy 369.077971 -254.507791) (xy 369.029752 -254.497947)
			(xy 368.983736 -254.480495) (xy 368.941115 -254.455888) (xy 368.902994 -254.424763) (xy 368.870359 -254.387926)
			(xy 368.844056 -254.34633) (xy 368.824765 -254.301054) (xy 368.812988 -254.25327) (xy 368.809028 -254.204216)
			(xy 360.438648 -254.204216) (xy 360.46298 -254.229498) (xy 360.493272 -254.272564) (xy 360.516635 -254.319749)
			(xy 360.532521 -254.369948) (xy 360.540558 -254.421984) (xy 360.541062 -254.44831) (xy 360.540558 -254.474636)
			(xy 360.532521 -254.526672) (xy 360.516635 -254.576871) (xy 360.493272 -254.624056) (xy 360.46298 -254.667122)
			(xy 360.426468 -254.70506) (xy 360.384594 -254.736979) (xy 360.338338 -254.762132) (xy 360.288785 -254.77993)
			(xy 360.237095 -254.789954) (xy 360.184481 -254.791971) (xy 360.132176 -254.785933) (xy 360.081405 -254.771981)
			(xy 360.03336 -254.750442) (xy 359.989165 -254.721822) (xy 359.949857 -254.686791) (xy 359.916357 -254.64617)
			(xy 359.889451 -254.600911) (xy 359.869768 -254.552076) (xy 359.857771 -254.500808) (xy 359.853741 -254.44831)
			(xy 349.564014 -254.44831) (xy 349.533966 -254.46905) (xy 349.489504 -254.490148) (xy 349.442233 -254.50384)
			(xy 349.393378 -254.509772) (xy 349.344203 -254.507791) (xy 349.295984 -254.497947) (xy 349.249968 -254.480495)
			(xy 349.207347 -254.455888) (xy 349.169226 -254.424763) (xy 349.136591 -254.387926) (xy 349.110288 -254.34633)
			(xy 349.090997 -254.301054) (xy 349.07922 -254.25327) (xy 349.07526 -254.204216) (xy 348.746318 -254.204216)
			(xy 348.745719 -254.231809) (xy 348.735808 -254.286099) (xy 348.716326 -254.337734) (xy 348.70263 -254.361696)
			(xy 348.699328 -254.367284) (xy 348.693486 -254.386842) (xy 348.692535 -254.390321) (xy 348.691512 -254.39746)
			(xy 348.691454 -254.401066) (xy 348.691454 -255.014222) (xy 349.545414 -255.014222) (xy 349.549374 -254.965168)
			(xy 349.561151 -254.917384) (xy 349.580442 -254.872108) (xy 349.606745 -254.830512) (xy 349.63938 -254.793675)
			(xy 349.677501 -254.76255) (xy 349.720122 -254.737943) (xy 349.766138 -254.720491) (xy 349.814357 -254.710647)
			(xy 349.863532 -254.708666) (xy 349.912387 -254.714598) (xy 349.959658 -254.72829) (xy 350.00412 -254.749388)
			(xy 350.044623 -254.777344) (xy 350.080116 -254.811436) (xy 350.109681 -254.85078) (xy 350.132552 -254.894357)
			(xy 350.148136 -254.941038) (xy 350.156031 -254.989615) (xy 350.156526 -255.014222) (xy 370.218982 -255.014222)
			(xy 370.222942 -254.965168) (xy 370.234719 -254.917384) (xy 370.25401 -254.872108) (xy 370.280313 -254.830512)
			(xy 370.312948 -254.793675) (xy 370.351069 -254.76255) (xy 370.39369 -254.737943) (xy 370.439706 -254.720491)
			(xy 370.487925 -254.710647) (xy 370.5371 -254.708666) (xy 370.585955 -254.714598) (xy 370.633226 -254.72829)
			(xy 370.677688 -254.749388) (xy 370.718191 -254.777344) (xy 370.753684 -254.811436) (xy 370.783249 -254.85078)
			(xy 370.80612 -254.894357) (xy 370.821704 -254.941038) (xy 370.829599 -254.989615) (xy 370.830094 -255.014222)
			(xy 372.09909 -255.014222) (xy 372.10305 -254.965168) (xy 372.114827 -254.917384) (xy 372.134118 -254.872108)
			(xy 372.160421 -254.830512) (xy 372.193056 -254.793675) (xy 372.231177 -254.76255) (xy 372.273798 -254.737943)
			(xy 372.319814 -254.720491) (xy 372.368033 -254.710647) (xy 372.417208 -254.708666) (xy 372.466063 -254.714598)
			(xy 372.513334 -254.72829) (xy 372.557796 -254.749388) (xy 372.598299 -254.777344) (xy 372.633792 -254.811436)
			(xy 372.663357 -254.85078) (xy 372.686228 -254.894357) (xy 372.701812 -254.941038) (xy 372.709707 -254.989615)
			(xy 372.710202 -255.014222) (xy 373.978944 -255.014222) (xy 373.982904 -254.965168) (xy 373.994681 -254.917384)
			(xy 374.013972 -254.872108) (xy 374.040275 -254.830512) (xy 374.07291 -254.793675) (xy 374.111031 -254.76255)
			(xy 374.153652 -254.737943) (xy 374.199668 -254.720491) (xy 374.247887 -254.710647) (xy 374.297062 -254.708666)
			(xy 374.345917 -254.714598) (xy 374.393188 -254.72829) (xy 374.43765 -254.749388) (xy 374.478153 -254.777344)
			(xy 374.513646 -254.811436) (xy 374.543211 -254.85078) (xy 374.566082 -254.894357) (xy 374.581666 -254.941038)
			(xy 374.589561 -254.989615) (xy 374.590056 -255.014222) (xy 375.848621 -255.014222) (xy 375.852716 -254.963494)
			(xy 375.864895 -254.91408) (xy 375.884843 -254.86726) (xy 375.912044 -254.824246) (xy 375.945792 -254.786152)
			(xy 375.985214 -254.753965) (xy 376.029288 -254.728519) (xy 376.076874 -254.710472) (xy 376.126738 -254.700292)
			(xy 376.17759 -254.698243) (xy 376.228111 -254.704377) (xy 376.276995 -254.718537) (xy 376.322974 -254.740354)
			(xy 376.364858 -254.769264) (xy 376.401562 -254.804519) (xy 376.432135 -254.845205) (xy 376.455786 -254.890268)
			(xy 376.471902 -254.938542) (xy 376.480066 -254.988776) (xy 376.480578 -255.014222) (xy 376.788675 -255.014222)
			(xy 376.79277 -254.963494) (xy 376.804949 -254.91408) (xy 376.824897 -254.86726) (xy 376.852098 -254.824246)
			(xy 376.885846 -254.786152) (xy 376.925268 -254.753965) (xy 376.969342 -254.728519) (xy 377.016928 -254.710472)
			(xy 377.066792 -254.700292) (xy 377.117644 -254.698243) (xy 377.168165 -254.704377) (xy 377.217049 -254.718537)
			(xy 377.263028 -254.740354) (xy 377.304912 -254.769264) (xy 377.341616 -254.804519) (xy 377.372189 -254.845205)
			(xy 377.39584 -254.890268) (xy 377.411956 -254.938542) (xy 377.42012 -254.988776) (xy 377.420632 -255.014222)
			(xy 377.42012 -255.039668) (xy 377.411956 -255.089902) (xy 377.39584 -255.138176) (xy 377.372189 -255.183239)
			(xy 377.341616 -255.223925) (xy 377.304912 -255.25918) (xy 377.263028 -255.28809) (xy 377.217049 -255.309907)
			(xy 377.168165 -255.324067) (xy 377.117644 -255.330201) (xy 377.066792 -255.328152) (xy 377.016928 -255.317972)
			(xy 376.969342 -255.299925) (xy 376.925268 -255.274479) (xy 376.885846 -255.242292) (xy 376.852098 -255.204198)
			(xy 376.824897 -255.161184) (xy 376.804949 -255.114364) (xy 376.79277 -255.06495) (xy 376.788675 -255.014222)
			(xy 376.480578 -255.014222) (xy 376.480066 -255.039668) (xy 376.471902 -255.089902) (xy 376.455786 -255.138176)
			(xy 376.432135 -255.183239) (xy 376.401562 -255.223925) (xy 376.364858 -255.25918) (xy 376.322974 -255.28809)
			(xy 376.276995 -255.309907) (xy 376.228111 -255.324067) (xy 376.17759 -255.330201) (xy 376.126738 -255.328152)
			(xy 376.076874 -255.317972) (xy 376.029288 -255.299925) (xy 375.985214 -255.274479) (xy 375.945792 -255.242292)
			(xy 375.912044 -255.204198) (xy 375.884843 -255.161184) (xy 375.864895 -255.114364) (xy 375.852716 -255.06495)
			(xy 375.848621 -255.014222) (xy 374.590056 -255.014222) (xy 374.589561 -255.038829) (xy 374.581666 -255.087406)
			(xy 374.566082 -255.134087) (xy 374.543211 -255.177664) (xy 374.513646 -255.217008) (xy 374.478153 -255.2511)
			(xy 374.43765 -255.279056) (xy 374.393188 -255.300154) (xy 374.345917 -255.313846) (xy 374.297062 -255.319778)
			(xy 374.247887 -255.317797) (xy 374.199668 -255.307953) (xy 374.153652 -255.290501) (xy 374.111031 -255.265894)
			(xy 374.07291 -255.234769) (xy 374.040275 -255.197932) (xy 374.013972 -255.156336) (xy 373.994681 -255.11106)
			(xy 373.982904 -255.063276) (xy 373.978944 -255.014222) (xy 372.710202 -255.014222) (xy 372.709707 -255.038829)
			(xy 372.701812 -255.087406) (xy 372.686228 -255.134087) (xy 372.663357 -255.177664) (xy 372.633792 -255.217008)
			(xy 372.598299 -255.2511) (xy 372.557796 -255.279056) (xy 372.513334 -255.300154) (xy 372.466063 -255.313846)
			(xy 372.417208 -255.319778) (xy 372.368033 -255.317797) (xy 372.319814 -255.307953) (xy 372.273798 -255.290501)
			(xy 372.231177 -255.265894) (xy 372.193056 -255.234769) (xy 372.160421 -255.197932) (xy 372.134118 -255.156336)
			(xy 372.114827 -255.11106) (xy 372.10305 -255.063276) (xy 372.09909 -255.014222) (xy 370.830094 -255.014222)
			(xy 370.829599 -255.038829) (xy 370.821704 -255.087406) (xy 370.80612 -255.134087) (xy 370.783249 -255.177664)
			(xy 370.753684 -255.217008) (xy 370.718191 -255.2511) (xy 370.677688 -255.279056) (xy 370.633226 -255.300154)
			(xy 370.585955 -255.313846) (xy 370.5371 -255.319778) (xy 370.487925 -255.317797) (xy 370.439706 -255.307953)
			(xy 370.39369 -255.290501) (xy 370.351069 -255.265894) (xy 370.312948 -255.234769) (xy 370.280313 -255.197932)
			(xy 370.25401 -255.156336) (xy 370.234719 -255.11106) (xy 370.222942 -255.063276) (xy 370.218982 -255.014222)
			(xy 350.156526 -255.014222) (xy 350.156031 -255.038829) (xy 350.148136 -255.087406) (xy 350.132552 -255.134087)
			(xy 350.109681 -255.177664) (xy 350.080116 -255.217008) (xy 350.044623 -255.2511) (xy 350.00412 -255.279056)
			(xy 349.959658 -255.300154) (xy 349.912387 -255.313846) (xy 349.863532 -255.319778) (xy 349.814357 -255.317797)
			(xy 349.766138 -255.307953) (xy 349.720122 -255.290501) (xy 349.677501 -255.265894) (xy 349.63938 -255.234769)
			(xy 349.606745 -255.197932) (xy 349.580442 -255.156336) (xy 349.561151 -255.11106) (xy 349.549374 -255.063276)
			(xy 349.545414 -255.014222) (xy 348.691454 -255.014222) (xy 348.691454 -255.627378) (xy 348.691515 -255.630984)
			(xy 348.692531 -255.638124) (xy 348.693486 -255.641602) (xy 348.699328 -255.66116) (xy 348.70263 -255.666748)
			(xy 348.716356 -255.690696) (xy 348.735852 -255.74233) (xy 348.745732 -255.796631) (xy 348.746318 -255.824228)
			(xy 349.07526 -255.824228) (xy 349.07922 -255.775174) (xy 349.090997 -255.72739) (xy 349.110288 -255.682114)
			(xy 349.136591 -255.640518) (xy 349.169226 -255.603681) (xy 349.207347 -255.572556) (xy 349.249968 -255.547949)
			(xy 349.295984 -255.530497) (xy 349.344203 -255.520653) (xy 349.393378 -255.518672) (xy 349.442233 -255.524604)
			(xy 349.489504 -255.538296) (xy 349.533966 -255.559394) (xy 349.574469 -255.58735) (xy 349.609962 -255.621442)
			(xy 349.639527 -255.660786) (xy 349.662398 -255.704363) (xy 349.677982 -255.751044) (xy 349.685877 -255.799621)
			(xy 349.686331 -255.822196) (xy 351.89212 -255.822196) (xy 351.89608 -255.773142) (xy 351.907857 -255.725358)
			(xy 351.927148 -255.680082) (xy 351.953451 -255.638486) (xy 351.986086 -255.601649) (xy 352.024207 -255.570524)
			(xy 352.066828 -255.545917) (xy 352.112844 -255.528465) (xy 352.161063 -255.518621) (xy 352.210238 -255.51664)
			(xy 352.259093 -255.522572) (xy 352.285069 -255.530096) (xy 353.086927 -255.530096) (xy 353.090957 -255.477598)
			(xy 353.102954 -255.42633) (xy 353.122637 -255.377495) (xy 353.149543 -255.332236) (xy 353.183043 -255.291615)
			(xy 353.222351 -255.256584) (xy 353.266546 -255.227964) (xy 353.314591 -255.206425) (xy 353.365362 -255.192473)
			(xy 353.417667 -255.186435) (xy 353.470281 -255.188452) (xy 353.521971 -255.198476) (xy 353.571524 -255.216274)
			(xy 353.61778 -255.241427) (xy 353.659654 -255.273346) (xy 353.696166 -255.311284) (xy 353.726458 -255.35435)
			(xy 353.749821 -255.401535) (xy 353.765707 -255.451734) (xy 353.773744 -255.50377) (xy 353.774248 -255.530096)
			(xy 354.001327 -255.530096) (xy 354.005357 -255.477598) (xy 354.017354 -255.42633) (xy 354.037037 -255.377495)
			(xy 354.063943 -255.332236) (xy 354.097443 -255.291615) (xy 354.136751 -255.256584) (xy 354.180946 -255.227964)
			(xy 354.228991 -255.206425) (xy 354.279762 -255.192473) (xy 354.332067 -255.186435) (xy 354.384681 -255.188452)
			(xy 354.436371 -255.198476) (xy 354.485924 -255.216274) (xy 354.53218 -255.241427) (xy 354.574054 -255.273346)
			(xy 354.610566 -255.311284) (xy 354.640858 -255.35435) (xy 354.664221 -255.401535) (xy 354.680107 -255.451734)
			(xy 354.688144 -255.50377) (xy 354.688648 -255.530096) (xy 365.036865 -255.530096) (xy 365.040895 -255.477598)
			(xy 365.052892 -255.42633) (xy 365.072575 -255.377495) (xy 365.099481 -255.332236) (xy 365.132981 -255.291615)
			(xy 365.172289 -255.256584) (xy 365.216484 -255.227964) (xy 365.264529 -255.206425) (xy 365.3153 -255.192473)
			(xy 365.367605 -255.186435) (xy 365.420219 -255.188452) (xy 365.471909 -255.198476) (xy 365.521462 -255.216274)
			(xy 365.567718 -255.241427) (xy 365.609592 -255.273346) (xy 365.646104 -255.311284) (xy 365.676396 -255.35435)
			(xy 365.699759 -255.401535) (xy 365.715645 -255.451734) (xy 365.723682 -255.50377) (xy 365.724186 -255.530096)
			(xy 365.723682 -255.556422) (xy 365.715645 -255.608458) (xy 365.699759 -255.658657) (xy 365.676396 -255.705842)
			(xy 365.646104 -255.748908) (xy 365.609592 -255.786846) (xy 365.567718 -255.818765) (xy 365.557672 -255.824228)
			(xy 368.809028 -255.824228) (xy 368.812988 -255.775174) (xy 368.824765 -255.72739) (xy 368.844056 -255.682114)
			(xy 368.870359 -255.640518) (xy 368.902994 -255.603681) (xy 368.941115 -255.572556) (xy 368.983736 -255.547949)
			(xy 369.029752 -255.530497) (xy 369.077971 -255.520653) (xy 369.127146 -255.518672) (xy 369.176001 -255.524604)
			(xy 369.223272 -255.538296) (xy 369.267734 -255.559394) (xy 369.308237 -255.58735) (xy 369.34373 -255.621442)
			(xy 369.373295 -255.660786) (xy 369.396166 -255.704363) (xy 369.41175 -255.751044) (xy 369.419645 -255.799621)
			(xy 369.42014 -255.824228) (xy 370.688882 -255.824228) (xy 370.692842 -255.775174) (xy 370.704619 -255.72739)
			(xy 370.72391 -255.682114) (xy 370.750213 -255.640518) (xy 370.782848 -255.603681) (xy 370.820969 -255.572556)
			(xy 370.86359 -255.547949) (xy 370.909606 -255.530497) (xy 370.957825 -255.520653) (xy 371.007 -255.518672)
			(xy 371.055855 -255.524604) (xy 371.103126 -255.538296) (xy 371.147588 -255.559394) (xy 371.188091 -255.58735)
			(xy 371.223584 -255.621442) (xy 371.253149 -255.660786) (xy 371.27602 -255.704363) (xy 371.291604 -255.751044)
			(xy 371.299499 -255.799621) (xy 371.299994 -255.824228) (xy 372.56899 -255.824228) (xy 372.57295 -255.775174)
			(xy 372.584727 -255.72739) (xy 372.604018 -255.682114) (xy 372.630321 -255.640518) (xy 372.662956 -255.603681)
			(xy 372.701077 -255.572556) (xy 372.743698 -255.547949) (xy 372.789714 -255.530497) (xy 372.837933 -255.520653)
			(xy 372.887108 -255.518672) (xy 372.935963 -255.524604) (xy 372.983234 -255.538296) (xy 373.027696 -255.559394)
			(xy 373.068199 -255.58735) (xy 373.103692 -255.621442) (xy 373.133257 -255.660786) (xy 373.156128 -255.704363)
			(xy 373.171712 -255.751044) (xy 373.179607 -255.799621) (xy 373.180102 -255.824228) (xy 374.449098 -255.824228)
			(xy 374.453058 -255.775174) (xy 374.464835 -255.72739) (xy 374.484126 -255.682114) (xy 374.510429 -255.640518)
			(xy 374.543064 -255.603681) (xy 374.581185 -255.572556) (xy 374.623806 -255.547949) (xy 374.669822 -255.530497)
			(xy 374.718041 -255.520653) (xy 374.767216 -255.518672) (xy 374.816071 -255.524604) (xy 374.863342 -255.538296)
			(xy 374.907804 -255.559394) (xy 374.948307 -255.58735) (xy 374.9838 -255.621442) (xy 375.013365 -255.660786)
			(xy 375.036236 -255.704363) (xy 375.05182 -255.751044) (xy 375.059715 -255.799621) (xy 375.06021 -255.824228)
			(xy 375.378467 -255.824228) (xy 375.382562 -255.7735) (xy 375.394741 -255.724086) (xy 375.414689 -255.677266)
			(xy 375.44189 -255.634252) (xy 375.475638 -255.596158) (xy 375.51506 -255.563971) (xy 375.559134 -255.538525)
			(xy 375.60672 -255.520478) (xy 375.656584 -255.510298) (xy 375.707436 -255.508249) (xy 375.757957 -255.514383)
			(xy 375.806841 -255.528543) (xy 375.85282 -255.55036) (xy 375.894704 -255.57927) (xy 375.931408 -255.614525)
			(xy 375.961981 -255.655211) (xy 375.985632 -255.700274) (xy 376.001748 -255.748548) (xy 376.009912 -255.798782)
			(xy 376.010424 -255.824228) (xy 376.328952 -255.824228) (xy 376.332912 -255.775174) (xy 376.344689 -255.72739)
			(xy 376.36398 -255.682114) (xy 376.390283 -255.640518) (xy 376.422918 -255.603681) (xy 376.461039 -255.572556)
			(xy 376.50366 -255.547949) (xy 376.549676 -255.530497) (xy 376.597895 -255.520653) (xy 376.64707 -255.518672)
			(xy 376.695925 -255.524604) (xy 376.743196 -255.538296) (xy 376.787658 -255.559394) (xy 376.828161 -255.58735)
			(xy 376.863654 -255.621442) (xy 376.893219 -255.660786) (xy 376.91609 -255.704363) (xy 376.931674 -255.751044)
			(xy 376.939569 -255.799621) (xy 376.940064 -255.824228) (xy 377.258575 -255.824228) (xy 377.26267 -255.7735)
			(xy 377.274849 -255.724086) (xy 377.294797 -255.677266) (xy 377.321998 -255.634252) (xy 377.355746 -255.596158)
			(xy 377.395168 -255.563971) (xy 377.439242 -255.538525) (xy 377.486828 -255.520478) (xy 377.536692 -255.510298)
			(xy 377.587544 -255.508249) (xy 377.638065 -255.514383) (xy 377.686949 -255.528543) (xy 377.732928 -255.55036)
			(xy 377.774812 -255.57927) (xy 377.811516 -255.614525) (xy 377.842089 -255.655211) (xy 377.86574 -255.700274)
			(xy 377.881856 -255.748548) (xy 377.89002 -255.798782) (xy 377.890532 -255.824228) (xy 377.89002 -255.849674)
			(xy 377.881856 -255.899908) (xy 377.86574 -255.948182) (xy 377.842089 -255.993245) (xy 377.811516 -256.033931)
			(xy 377.774812 -256.069186) (xy 377.732928 -256.098096) (xy 377.686949 -256.119913) (xy 377.638065 -256.134073)
			(xy 377.587544 -256.140207) (xy 377.536692 -256.138158) (xy 377.486828 -256.127978) (xy 377.439242 -256.109931)
			(xy 377.395168 -256.084485) (xy 377.355746 -256.052298) (xy 377.321998 -256.014204) (xy 377.294797 -255.97119)
			(xy 377.274849 -255.92437) (xy 377.26267 -255.874956) (xy 377.258575 -255.824228) (xy 376.940064 -255.824228)
			(xy 376.939569 -255.848835) (xy 376.931674 -255.897412) (xy 376.91609 -255.944093) (xy 376.893219 -255.98767)
			(xy 376.863654 -256.027014) (xy 376.828161 -256.061106) (xy 376.787658 -256.089062) (xy 376.743196 -256.11016)
			(xy 376.695925 -256.123852) (xy 376.64707 -256.129784) (xy 376.597895 -256.127803) (xy 376.549676 -256.117959)
			(xy 376.50366 -256.100507) (xy 376.461039 -256.0759) (xy 376.422918 -256.044775) (xy 376.390283 -256.007938)
			(xy 376.36398 -255.966342) (xy 376.344689 -255.921066) (xy 376.332912 -255.873282) (xy 376.328952 -255.824228)
			(xy 376.010424 -255.824228) (xy 376.009912 -255.849674) (xy 376.001748 -255.899908) (xy 375.985632 -255.948182)
			(xy 375.961981 -255.993245) (xy 375.931408 -256.033931) (xy 375.894704 -256.069186) (xy 375.85282 -256.098096)
			(xy 375.806841 -256.119913) (xy 375.757957 -256.134073) (xy 375.707436 -256.140207) (xy 375.656584 -256.138158)
			(xy 375.60672 -256.127978) (xy 375.559134 -256.109931) (xy 375.51506 -256.084485) (xy 375.475638 -256.052298)
			(xy 375.44189 -256.014204) (xy 375.414689 -255.97119) (xy 375.394741 -255.92437) (xy 375.382562 -255.874956)
			(xy 375.378467 -255.824228) (xy 375.06021 -255.824228) (xy 375.059715 -255.848835) (xy 375.05182 -255.897412)
			(xy 375.036236 -255.944093) (xy 375.013365 -255.98767) (xy 374.9838 -256.027014) (xy 374.948307 -256.061106)
			(xy 374.907804 -256.089062) (xy 374.863342 -256.11016) (xy 374.816071 -256.123852) (xy 374.767216 -256.129784)
			(xy 374.718041 -256.127803) (xy 374.669822 -256.117959) (xy 374.623806 -256.100507) (xy 374.581185 -256.0759)
			(xy 374.543064 -256.044775) (xy 374.510429 -256.007938) (xy 374.484126 -255.966342) (xy 374.464835 -255.921066)
			(xy 374.453058 -255.873282) (xy 374.449098 -255.824228) (xy 373.180102 -255.824228) (xy 373.179607 -255.848835)
			(xy 373.171712 -255.897412) (xy 373.156128 -255.944093) (xy 373.133257 -255.98767) (xy 373.103692 -256.027014)
			(xy 373.068199 -256.061106) (xy 373.027696 -256.089062) (xy 372.983234 -256.11016) (xy 372.935963 -256.123852)
			(xy 372.887108 -256.129784) (xy 372.837933 -256.127803) (xy 372.789714 -256.117959) (xy 372.743698 -256.100507)
			(xy 372.701077 -256.0759) (xy 372.662956 -256.044775) (xy 372.630321 -256.007938) (xy 372.604018 -255.966342)
			(xy 372.584727 -255.921066) (xy 372.57295 -255.873282) (xy 372.56899 -255.824228) (xy 371.299994 -255.824228)
			(xy 371.299499 -255.848835) (xy 371.291604 -255.897412) (xy 371.27602 -255.944093) (xy 371.253149 -255.98767)
			(xy 371.223584 -256.027014) (xy 371.188091 -256.061106) (xy 371.147588 -256.089062) (xy 371.103126 -256.11016)
			(xy 371.055855 -256.123852) (xy 371.007 -256.129784) (xy 370.957825 -256.127803) (xy 370.909606 -256.117959)
			(xy 370.86359 -256.100507) (xy 370.820969 -256.0759) (xy 370.782848 -256.044775) (xy 370.750213 -256.007938)
			(xy 370.72391 -255.966342) (xy 370.704619 -255.921066) (xy 370.692842 -255.873282) (xy 370.688882 -255.824228)
			(xy 369.42014 -255.824228) (xy 369.419645 -255.848835) (xy 369.41175 -255.897412) (xy 369.396166 -255.944093)
			(xy 369.373295 -255.98767) (xy 369.34373 -256.027014) (xy 369.308237 -256.061106) (xy 369.267734 -256.089062)
			(xy 369.223272 -256.11016) (xy 369.176001 -256.123852) (xy 369.127146 -256.129784) (xy 369.077971 -256.127803)
			(xy 369.029752 -256.117959) (xy 368.983736 -256.100507) (xy 368.941115 -256.0759) (xy 368.902994 -256.044775)
			(xy 368.870359 -256.007938) (xy 368.844056 -255.966342) (xy 368.824765 -255.921066) (xy 368.812988 -255.873282)
			(xy 368.809028 -255.824228) (xy 365.557672 -255.824228) (xy 365.521462 -255.843918) (xy 365.471909 -255.861716)
			(xy 365.420219 -255.87174) (xy 365.367605 -255.873757) (xy 365.3153 -255.867719) (xy 365.264529 -255.853767)
			(xy 365.216484 -255.832228) (xy 365.172289 -255.803608) (xy 365.132981 -255.768577) (xy 365.099481 -255.727956)
			(xy 365.072575 -255.682697) (xy 365.052892 -255.633862) (xy 365.040895 -255.582594) (xy 365.036865 -255.530096)
			(xy 354.688648 -255.530096) (xy 354.688144 -255.556422) (xy 354.680107 -255.608458) (xy 354.664221 -255.658657)
			(xy 354.640858 -255.705842) (xy 354.610566 -255.748908) (xy 354.574054 -255.786846) (xy 354.53218 -255.818765)
			(xy 354.485924 -255.843918) (xy 354.436371 -255.861716) (xy 354.384681 -255.87174) (xy 354.332067 -255.873757)
			(xy 354.279762 -255.867719) (xy 354.228991 -255.853767) (xy 354.180946 -255.832228) (xy 354.136751 -255.803608)
			(xy 354.097443 -255.768577) (xy 354.063943 -255.727956) (xy 354.037037 -255.682697) (xy 354.017354 -255.633862)
			(xy 354.005357 -255.582594) (xy 354.001327 -255.530096) (xy 353.774248 -255.530096) (xy 353.773744 -255.556422)
			(xy 353.765707 -255.608458) (xy 353.749821 -255.658657) (xy 353.726458 -255.705842) (xy 353.696166 -255.748908)
			(xy 353.659654 -255.786846) (xy 353.61778 -255.818765) (xy 353.571524 -255.843918) (xy 353.521971 -255.861716)
			(xy 353.470281 -255.87174) (xy 353.417667 -255.873757) (xy 353.365362 -255.867719) (xy 353.314591 -255.853767)
			(xy 353.266546 -255.832228) (xy 353.222351 -255.803608) (xy 353.183043 -255.768577) (xy 353.149543 -255.727956)
			(xy 353.122637 -255.682697) (xy 353.102954 -255.633862) (xy 353.090957 -255.582594) (xy 353.086927 -255.530096)
			(xy 352.285069 -255.530096) (xy 352.306364 -255.536264) (xy 352.350826 -255.557362) (xy 352.391329 -255.585318)
			(xy 352.426822 -255.61941) (xy 352.456387 -255.658754) (xy 352.479258 -255.702331) (xy 352.494842 -255.749012)
			(xy 352.502737 -255.797589) (xy 352.503232 -255.822196) (xy 352.502737 -255.846803) (xy 352.494842 -255.89538)
			(xy 352.479258 -255.942061) (xy 352.456387 -255.985638) (xy 352.426822 -256.024982) (xy 352.391329 -256.059074)
			(xy 352.350826 -256.08703) (xy 352.306364 -256.108128) (xy 352.259093 -256.12182) (xy 352.210238 -256.127752)
			(xy 352.161063 -256.125771) (xy 352.112844 -256.115927) (xy 352.066828 -256.098475) (xy 352.024207 -256.073868)
			(xy 351.986086 -256.042743) (xy 351.953451 -256.005906) (xy 351.927148 -255.96431) (xy 351.907857 -255.919034)
			(xy 351.89608 -255.87125) (xy 351.89212 -255.822196) (xy 349.686331 -255.822196) (xy 349.686372 -255.824228)
			(xy 349.685877 -255.848835) (xy 349.677982 -255.897412) (xy 349.662398 -255.944093) (xy 349.639527 -255.98767)
			(xy 349.609962 -256.027014) (xy 349.574469 -256.061106) (xy 349.533966 -256.089062) (xy 349.489504 -256.11016)
			(xy 349.442233 -256.123852) (xy 349.393378 -256.129784) (xy 349.344203 -256.127803) (xy 349.295984 -256.117959)
			(xy 349.249968 -256.100507) (xy 349.207347 -256.0759) (xy 349.169226 -256.044775) (xy 349.136591 -256.007938)
			(xy 349.110288 -255.966342) (xy 349.090997 -255.921066) (xy 349.07922 -255.873282) (xy 349.07526 -255.824228)
			(xy 348.746318 -255.824228) (xy 348.745668 -255.852868) (xy 348.734995 -255.909146) (xy 348.714027 -255.962452)
			(xy 348.699328 -255.987042) (xy 348.695264 -255.993392) (xy 348.691454 -256.006854) (xy 348.691454 -256.078228)
			(xy 348.691915 -256.088105) (xy 348.699355 -256.106405) (xy 348.705932 -256.113788) (xy 348.706186 -256.114042)
			(xy 348.913958 -256.321814) (xy 348.92996 -256.329434) (xy 348.93885 -256.330196) (xy 348.962289 -256.332768)
			(xy 349.00803 -256.344208) (xy 349.051469 -256.362546) (xy 349.091571 -256.387345) (xy 349.127384 -256.418015)
			(xy 349.158054 -256.453827) (xy 349.182853 -256.493929) (xy 349.201191 -256.537368) (xy 349.212632 -256.583109)
			(xy 349.215202 -256.606548) (xy 349.215964 -256.615438) (xy 349.223584 -256.63144) (xy 349.438468 -256.846324)
			(xy 349.438976 -256.846832) (xy 349.446357 -256.853413) (xy 349.464657 -256.860858) (xy 349.474536 -256.86131)
			(xy 350.4057 -256.86131) (xy 350.417765 -256.860631) (xy 350.439232 -256.849613) (xy 350.446848 -256.840228)
			(xy 350.50095 -256.765044) (xy 350.50476 -256.74066) (xy 350.50095 -256.72923) (xy 350.493629 -256.705773)
			(xy 350.485715 -256.657278) (xy 350.485202 -256.63271) (xy 350.485724 -256.607455) (xy 350.494037 -256.557633)
			(xy 350.510438 -256.509859) (xy 350.534479 -256.465436) (xy 350.565503 -256.425576) (xy 350.602665 -256.391366)
			(xy 350.644951 -256.36374) (xy 350.691207 -256.34345) (xy 350.740172 -256.33105) (xy 350.79051 -256.326879)
			(xy 350.840848 -256.33105) (xy 350.889813 -256.34345) (xy 350.936069 -256.36374) (xy 350.978355 -256.391366)
			(xy 351.015517 -256.425576) (xy 351.046541 -256.465436) (xy 351.070582 -256.509859) (xy 351.086983 -256.557633)
			(xy 351.095296 -256.607455) (xy 351.095818 -256.63271) (xy 351.095308 -256.657278) (xy 351.0874 -256.705775)
			(xy 351.08007 -256.72923) (xy 351.07626 -256.74066) (xy 351.08007 -256.765044) (xy 351.134172 -256.840228)
			(xy 351.141783 -256.84961) (xy 351.163259 -256.860601) (xy 351.17532 -256.86131) (xy 353.087432 -256.86131)
			(xy 353.09048 -256.86131) (xy 353.101715 -256.859979) (xy 353.12149 -256.849044) (xy 353.12858 -256.840228)
			(xy 353.133406 -256.8321) (xy 353.171506 -256.751328) (xy 353.175198 -256.742493) (xy 353.176422 -256.723399)
			(xy 353.170607 -256.705171) (xy 353.164902 -256.69748) (xy 353.164902 -256.697226) (xy 353.146752 -256.674071)
			(xy 353.117825 -256.622845) (xy 353.098053 -256.567437) (xy 353.088015 -256.509471) (xy 353.087432 -256.480056)
			(xy 353.087432 -256.472182) (xy 353.08854 -256.445601) (xy 353.097945 -256.393241) (xy 353.115309 -256.342957)
			(xy 353.140218 -256.29595) (xy 353.172076 -256.253346) (xy 353.210121 -256.216163) (xy 353.253445 -256.18529)
			(xy 353.301009 -256.161465) (xy 353.351679 -256.145258) (xy 353.404241 -256.137057) (xy 353.457439 -256.137057)
			(xy 353.510001 -256.145258) (xy 353.560671 -256.161465) (xy 353.608235 -256.18529) (xy 353.651559 -256.216163)
			(xy 353.689604 -256.253346) (xy 353.721462 -256.29595) (xy 353.746371 -256.342957) (xy 353.763735 -256.393241)
			(xy 353.77314 -256.445601) (xy 353.774248 -256.472182) (xy 353.774248 -256.478024) (xy 353.774248 -256.480056)
			(xy 353.773647 -256.509471) (xy 353.763624 -256.567441) (xy 353.743865 -256.622854) (xy 353.714948 -256.674087)
			(xy 353.696778 -256.697226) (xy 353.696778 -256.69748) (xy 353.691007 -256.70514) (xy 353.685144 -256.723383)
			(xy 353.686422 -256.742503) (xy 353.690174 -256.751328) (xy 353.728274 -256.8321) (xy 353.7331 -256.840228)
			(xy 353.740177 -256.84906) (xy 353.759958 -256.859997) (xy 353.7712 -256.86131) (xy 354.001832 -256.86131)
			(xy 354.00488 -256.86131) (xy 354.016115 -256.859979) (xy 354.03589 -256.849044) (xy 354.04298 -256.840228)
			(xy 354.047806 -256.8321) (xy 354.085906 -256.751328) (xy 354.089598 -256.742493) (xy 354.090822 -256.723399)
			(xy 354.085007 -256.705171) (xy 354.079302 -256.69748) (xy 354.079302 -256.697226) (xy 354.061152 -256.674071)
			(xy 354.032225 -256.622845) (xy 354.012453 -256.567437) (xy 354.002415 -256.509471) (xy 354.001832 -256.480056)
			(xy 354.001832 -256.472182) (xy 354.00294 -256.445601) (xy 354.012345 -256.393241) (xy 354.029709 -256.342957)
			(xy 354.054618 -256.29595) (xy 354.086476 -256.253346) (xy 354.124521 -256.216163) (xy 354.167845 -256.18529)
			(xy 354.215409 -256.161465) (xy 354.266079 -256.145258) (xy 354.318641 -256.137057) (xy 354.371839 -256.137057)
			(xy 354.424401 -256.145258) (xy 354.475071 -256.161465) (xy 354.522635 -256.18529) (xy 354.565959 -256.216163)
			(xy 354.604004 -256.253346) (xy 354.635862 -256.29595) (xy 354.660771 -256.342957) (xy 354.676099 -256.387346)
			(xy 355.244149 -256.387346) (xy 355.248179 -256.334848) (xy 355.260176 -256.28358) (xy 355.279859 -256.234745)
			(xy 355.306765 -256.189486) (xy 355.340265 -256.148865) (xy 355.379573 -256.113834) (xy 355.423768 -256.085214)
			(xy 355.471813 -256.063675) (xy 355.522584 -256.049723) (xy 355.574889 -256.043685) (xy 355.627503 -256.045702)
			(xy 355.679193 -256.055726) (xy 355.728746 -256.073524) (xy 355.775002 -256.098677) (xy 355.816876 -256.130596)
			(xy 355.853388 -256.168534) (xy 355.88368 -256.2116) (xy 355.907043 -256.258785) (xy 355.922929 -256.308984)
			(xy 355.930966 -256.36102) (xy 355.93147 -256.387346) (xy 356.194109 -256.387346) (xy 356.198139 -256.334848)
			(xy 356.210136 -256.28358) (xy 356.229819 -256.234745) (xy 356.256725 -256.189486) (xy 356.290225 -256.148865)
			(xy 356.329533 -256.113834) (xy 356.373728 -256.085214) (xy 356.421773 -256.063675) (xy 356.472544 -256.049723)
			(xy 356.524849 -256.043685) (xy 356.577463 -256.045702) (xy 356.629153 -256.055726) (xy 356.678706 -256.073524)
			(xy 356.724962 -256.098677) (xy 356.766836 -256.130596) (xy 356.803348 -256.168534) (xy 356.83364 -256.2116)
			(xy 356.857003 -256.258785) (xy 356.872889 -256.308984) (xy 356.880926 -256.36102) (xy 356.88143 -256.387346)
			(xy 357.144069 -256.387346) (xy 357.148099 -256.334848) (xy 357.160096 -256.28358) (xy 357.179779 -256.234745)
			(xy 357.206685 -256.189486) (xy 357.240185 -256.148865) (xy 357.279493 -256.113834) (xy 357.323688 -256.085214)
			(xy 357.371733 -256.063675) (xy 357.422504 -256.049723) (xy 357.474809 -256.043685) (xy 357.527423 -256.045702)
			(xy 357.579113 -256.055726) (xy 357.628666 -256.073524) (xy 357.674922 -256.098677) (xy 357.716796 -256.130596)
			(xy 357.753308 -256.168534) (xy 357.7836 -256.2116) (xy 357.806963 -256.258785) (xy 357.822849 -256.308984)
			(xy 357.830886 -256.36102) (xy 357.83139 -256.387346) (xy 358.094029 -256.387346) (xy 358.098059 -256.334848)
			(xy 358.110056 -256.28358) (xy 358.129739 -256.234745) (xy 358.156645 -256.189486) (xy 358.190145 -256.148865)
			(xy 358.229453 -256.113834) (xy 358.273648 -256.085214) (xy 358.321693 -256.063675) (xy 358.372464 -256.049723)
			(xy 358.424769 -256.043685) (xy 358.477383 -256.045702) (xy 358.529073 -256.055726) (xy 358.578626 -256.073524)
			(xy 358.624882 -256.098677) (xy 358.666756 -256.130596) (xy 358.703268 -256.168534) (xy 358.73356 -256.2116)
			(xy 358.756923 -256.258785) (xy 358.772809 -256.308984) (xy 358.780846 -256.36102) (xy 358.78135 -256.387346)
			(xy 359.043989 -256.387346) (xy 359.048019 -256.334848) (xy 359.060016 -256.28358) (xy 359.079699 -256.234745)
			(xy 359.106605 -256.189486) (xy 359.140105 -256.148865) (xy 359.179413 -256.113834) (xy 359.223608 -256.085214)
			(xy 359.271653 -256.063675) (xy 359.322424 -256.049723) (xy 359.374729 -256.043685) (xy 359.427343 -256.045702)
			(xy 359.479033 -256.055726) (xy 359.528586 -256.073524) (xy 359.574842 -256.098677) (xy 359.616716 -256.130596)
			(xy 359.653228 -256.168534) (xy 359.68352 -256.2116) (xy 359.706883 -256.258785) (xy 359.722769 -256.308984)
			(xy 359.730806 -256.36102) (xy 359.73131 -256.387346) (xy 359.993949 -256.387346) (xy 359.997979 -256.334848)
			(xy 360.009976 -256.28358) (xy 360.029659 -256.234745) (xy 360.056565 -256.189486) (xy 360.090065 -256.148865)
			(xy 360.129373 -256.113834) (xy 360.173568 -256.085214) (xy 360.221613 -256.063675) (xy 360.272384 -256.049723)
			(xy 360.324689 -256.043685) (xy 360.377303 -256.045702) (xy 360.428993 -256.055726) (xy 360.478546 -256.073524)
			(xy 360.524802 -256.098677) (xy 360.566676 -256.130596) (xy 360.603188 -256.168534) (xy 360.63348 -256.2116)
			(xy 360.656843 -256.258785) (xy 360.672729 -256.308984) (xy 360.680766 -256.36102) (xy 360.68127 -256.387346)
			(xy 360.944163 -256.387346) (xy 360.948193 -256.334848) (xy 360.96019 -256.28358) (xy 360.979873 -256.234745)
			(xy 361.006779 -256.189486) (xy 361.040279 -256.148865) (xy 361.079587 -256.113834) (xy 361.123782 -256.085214)
			(xy 361.171827 -256.063675) (xy 361.222598 -256.049723) (xy 361.274903 -256.043685) (xy 361.327517 -256.045702)
			(xy 361.379207 -256.055726) (xy 361.42876 -256.073524) (xy 361.475016 -256.098677) (xy 361.51689 -256.130596)
			(xy 361.553402 -256.168534) (xy 361.583694 -256.2116) (xy 361.607057 -256.258785) (xy 361.622943 -256.308984)
			(xy 361.63098 -256.36102) (xy 361.631484 -256.387346) (xy 361.894123 -256.387346) (xy 361.898153 -256.334848)
			(xy 361.91015 -256.28358) (xy 361.929833 -256.234745) (xy 361.956739 -256.189486) (xy 361.990239 -256.148865)
			(xy 362.029547 -256.113834) (xy 362.073742 -256.085214) (xy 362.121787 -256.063675) (xy 362.172558 -256.049723)
			(xy 362.224863 -256.043685) (xy 362.277477 -256.045702) (xy 362.329167 -256.055726) (xy 362.37872 -256.073524)
			(xy 362.424976 -256.098677) (xy 362.46685 -256.130596) (xy 362.503362 -256.168534) (xy 362.533654 -256.2116)
			(xy 362.557017 -256.258785) (xy 362.572903 -256.308984) (xy 362.58094 -256.36102) (xy 362.581444 -256.387346)
			(xy 362.844083 -256.387346) (xy 362.848113 -256.334848) (xy 362.86011 -256.28358) (xy 362.879793 -256.234745)
			(xy 362.906699 -256.189486) (xy 362.940199 -256.148865) (xy 362.979507 -256.113834) (xy 363.023702 -256.085214)
			(xy 363.071747 -256.063675) (xy 363.122518 -256.049723) (xy 363.174823 -256.043685) (xy 363.227437 -256.045702)
			(xy 363.279127 -256.055726) (xy 363.32868 -256.073524) (xy 363.374936 -256.098677) (xy 363.41681 -256.130596)
			(xy 363.453322 -256.168534) (xy 363.483614 -256.2116) (xy 363.506977 -256.258785) (xy 363.522863 -256.308984)
			(xy 363.5309 -256.36102) (xy 363.531404 -256.387346) (xy 363.794043 -256.387346) (xy 363.798073 -256.334848)
			(xy 363.81007 -256.28358) (xy 363.829753 -256.234745) (xy 363.856659 -256.189486) (xy 363.890159 -256.148865)
			(xy 363.929467 -256.113834) (xy 363.973662 -256.085214) (xy 364.021707 -256.063675) (xy 364.072478 -256.049723)
			(xy 364.124783 -256.043685) (xy 364.177397 -256.045702) (xy 364.229087 -256.055726) (xy 364.27864 -256.073524)
			(xy 364.324896 -256.098677) (xy 364.36677 -256.130596) (xy 364.403282 -256.168534) (xy 364.433574 -256.2116)
			(xy 364.456937 -256.258785) (xy 364.472823 -256.308984) (xy 364.48086 -256.36102) (xy 364.481364 -256.387346)
			(xy 364.48086 -256.413672) (xy 364.472823 -256.465708) (xy 364.468282 -256.480056) (xy 365.036865 -256.480056)
			(xy 365.040895 -256.427558) (xy 365.052892 -256.37629) (xy 365.072575 -256.327455) (xy 365.099481 -256.282196)
			(xy 365.132981 -256.241575) (xy 365.172289 -256.206544) (xy 365.216484 -256.177924) (xy 365.264529 -256.156385)
			(xy 365.3153 -256.142433) (xy 365.367605 -256.136395) (xy 365.420219 -256.138412) (xy 365.471909 -256.148436)
			(xy 365.521462 -256.166234) (xy 365.567718 -256.191387) (xy 365.609592 -256.223306) (xy 365.646104 -256.261244)
			(xy 365.676396 -256.30431) (xy 365.699759 -256.351495) (xy 365.715645 -256.401694) (xy 365.723682 -256.45373)
			(xy 365.724186 -256.480056) (xy 365.723682 -256.506382) (xy 365.715645 -256.558418) (xy 365.699759 -256.608617)
			(xy 365.687075 -256.634234) (xy 370.218982 -256.634234) (xy 370.222942 -256.58518) (xy 370.234719 -256.537396)
			(xy 370.25401 -256.49212) (xy 370.280313 -256.450524) (xy 370.312948 -256.413687) (xy 370.351069 -256.382562)
			(xy 370.39369 -256.357955) (xy 370.439706 -256.340503) (xy 370.487925 -256.330659) (xy 370.5371 -256.328678)
			(xy 370.585955 -256.33461) (xy 370.633226 -256.348302) (xy 370.677688 -256.3694) (xy 370.718191 -256.397356)
			(xy 370.753684 -256.431448) (xy 370.783249 -256.470792) (xy 370.80612 -256.514369) (xy 370.821704 -256.56105)
			(xy 370.829599 -256.609627) (xy 370.830094 -256.634234) (xy 372.09909 -256.634234) (xy 372.10305 -256.58518)
			(xy 372.114827 -256.537396) (xy 372.134118 -256.49212) (xy 372.160421 -256.450524) (xy 372.193056 -256.413687)
			(xy 372.231177 -256.382562) (xy 372.273798 -256.357955) (xy 372.319814 -256.340503) (xy 372.368033 -256.330659)
			(xy 372.417208 -256.328678) (xy 372.466063 -256.33461) (xy 372.513334 -256.348302) (xy 372.557796 -256.3694)
			(xy 372.598299 -256.397356) (xy 372.633792 -256.431448) (xy 372.663357 -256.470792) (xy 372.686228 -256.514369)
			(xy 372.701812 -256.56105) (xy 372.709707 -256.609627) (xy 372.710202 -256.634234) (xy 373.978944 -256.634234)
			(xy 373.982904 -256.58518) (xy 373.994681 -256.537396) (xy 374.013972 -256.49212) (xy 374.040275 -256.450524)
			(xy 374.07291 -256.413687) (xy 374.111031 -256.382562) (xy 374.153652 -256.357955) (xy 374.199668 -256.340503)
			(xy 374.247887 -256.330659) (xy 374.297062 -256.328678) (xy 374.345917 -256.33461) (xy 374.393188 -256.348302)
			(xy 374.43765 -256.3694) (xy 374.478153 -256.397356) (xy 374.513646 -256.431448) (xy 374.543211 -256.470792)
			(xy 374.566082 -256.514369) (xy 374.581666 -256.56105) (xy 374.589561 -256.609627) (xy 374.590056 -256.634234)
			(xy 375.859052 -256.634234) (xy 375.863012 -256.58518) (xy 375.874789 -256.537396) (xy 375.89408 -256.49212)
			(xy 375.920383 -256.450524) (xy 375.953018 -256.413687) (xy 375.991139 -256.382562) (xy 376.03376 -256.357955)
			(xy 376.079776 -256.340503) (xy 376.127995 -256.330659) (xy 376.17717 -256.328678) (xy 376.226025 -256.33461)
			(xy 376.273296 -256.348302) (xy 376.317758 -256.3694) (xy 376.358261 -256.397356) (xy 376.393754 -256.431448)
			(xy 376.423319 -256.470792) (xy 376.44619 -256.514369) (xy 376.461774 -256.56105) (xy 376.469669 -256.609627)
			(xy 376.470164 -256.634234) (xy 376.788675 -256.634234) (xy 376.79277 -256.583506) (xy 376.804949 -256.534092)
			(xy 376.824897 -256.487272) (xy 376.852098 -256.444258) (xy 376.885846 -256.406164) (xy 376.925268 -256.373977)
			(xy 376.969342 -256.348531) (xy 377.016928 -256.330484) (xy 377.066792 -256.320304) (xy 377.117644 -256.318255)
			(xy 377.168165 -256.324389) (xy 377.217049 -256.338549) (xy 377.263028 -256.360366) (xy 377.304912 -256.389276)
			(xy 377.341616 -256.424531) (xy 377.372189 -256.465217) (xy 377.39584 -256.51028) (xy 377.411956 -256.558554)
			(xy 377.42012 -256.608788) (xy 377.420632 -256.634234) (xy 377.42012 -256.65968) (xy 377.411956 -256.709914)
			(xy 377.39584 -256.758188) (xy 377.372189 -256.803251) (xy 377.341616 -256.843937) (xy 377.304912 -256.879192)
			(xy 377.263028 -256.908102) (xy 377.217049 -256.929919) (xy 377.168165 -256.944079) (xy 377.117644 -256.950213)
			(xy 377.066792 -256.948164) (xy 377.016928 -256.937984) (xy 376.969342 -256.919937) (xy 376.925268 -256.894491)
			(xy 376.885846 -256.862304) (xy 376.852098 -256.82421) (xy 376.824897 -256.781196) (xy 376.804949 -256.734376)
			(xy 376.79277 -256.684962) (xy 376.788675 -256.634234) (xy 376.470164 -256.634234) (xy 376.469669 -256.658841)
			(xy 376.461774 -256.707418) (xy 376.44619 -256.754099) (xy 376.423319 -256.797676) (xy 376.393754 -256.83702)
			(xy 376.358261 -256.871112) (xy 376.317758 -256.899068) (xy 376.273296 -256.920166) (xy 376.226025 -256.933858)
			(xy 376.17717 -256.93979) (xy 376.127995 -256.937809) (xy 376.079776 -256.927965) (xy 376.03376 -256.910513)
			(xy 375.991139 -256.885906) (xy 375.953018 -256.854781) (xy 375.920383 -256.817944) (xy 375.89408 -256.776348)
			(xy 375.874789 -256.731072) (xy 375.863012 -256.683288) (xy 375.859052 -256.634234) (xy 374.590056 -256.634234)
			(xy 374.589561 -256.658841) (xy 374.581666 -256.707418) (xy 374.566082 -256.754099) (xy 374.543211 -256.797676)
			(xy 374.513646 -256.83702) (xy 374.478153 -256.871112) (xy 374.43765 -256.899068) (xy 374.393188 -256.920166)
			(xy 374.345917 -256.933858) (xy 374.297062 -256.93979) (xy 374.247887 -256.937809) (xy 374.199668 -256.927965)
			(xy 374.153652 -256.910513) (xy 374.111031 -256.885906) (xy 374.07291 -256.854781) (xy 374.040275 -256.817944)
			(xy 374.013972 -256.776348) (xy 373.994681 -256.731072) (xy 373.982904 -256.683288) (xy 373.978944 -256.634234)
			(xy 372.710202 -256.634234) (xy 372.709707 -256.658841) (xy 372.701812 -256.707418) (xy 372.686228 -256.754099)
			(xy 372.663357 -256.797676) (xy 372.633792 -256.83702) (xy 372.598299 -256.871112) (xy 372.557796 -256.899068)
			(xy 372.513334 -256.920166) (xy 372.466063 -256.933858) (xy 372.417208 -256.93979) (xy 372.368033 -256.937809)
			(xy 372.319814 -256.927965) (xy 372.273798 -256.910513) (xy 372.231177 -256.885906) (xy 372.193056 -256.854781)
			(xy 372.160421 -256.817944) (xy 372.134118 -256.776348) (xy 372.114827 -256.731072) (xy 372.10305 -256.683288)
			(xy 372.09909 -256.634234) (xy 370.830094 -256.634234) (xy 370.829599 -256.658841) (xy 370.821704 -256.707418)
			(xy 370.80612 -256.754099) (xy 370.783249 -256.797676) (xy 370.753684 -256.83702) (xy 370.718191 -256.871112)
			(xy 370.677688 -256.899068) (xy 370.633226 -256.920166) (xy 370.585955 -256.933858) (xy 370.5371 -256.93979)
			(xy 370.487925 -256.937809) (xy 370.439706 -256.927965) (xy 370.39369 -256.910513) (xy 370.351069 -256.885906)
			(xy 370.312948 -256.854781) (xy 370.280313 -256.817944) (xy 370.25401 -256.776348) (xy 370.234719 -256.731072)
			(xy 370.222942 -256.683288) (xy 370.218982 -256.634234) (xy 365.687075 -256.634234) (xy 365.676396 -256.655802)
			(xy 365.646104 -256.698868) (xy 365.609592 -256.736806) (xy 365.567718 -256.768725) (xy 365.521462 -256.793878)
			(xy 365.471909 -256.811676) (xy 365.420219 -256.8217) (xy 365.367605 -256.823717) (xy 365.3153 -256.817679)
			(xy 365.264529 -256.803727) (xy 365.216484 -256.782188) (xy 365.172289 -256.753568) (xy 365.132981 -256.718537)
			(xy 365.099481 -256.677916) (xy 365.072575 -256.632657) (xy 365.052892 -256.583822) (xy 365.040895 -256.532554)
			(xy 365.036865 -256.480056) (xy 364.468282 -256.480056) (xy 364.456937 -256.515907) (xy 364.433574 -256.563092)
			(xy 364.403282 -256.606158) (xy 364.36677 -256.644096) (xy 364.324896 -256.676015) (xy 364.27864 -256.701168)
			(xy 364.229087 -256.718966) (xy 364.177397 -256.72899) (xy 364.124783 -256.731007) (xy 364.072478 -256.724969)
			(xy 364.021707 -256.711017) (xy 363.973662 -256.689478) (xy 363.929467 -256.660858) (xy 363.890159 -256.625827)
			(xy 363.856659 -256.585206) (xy 363.829753 -256.539947) (xy 363.81007 -256.491112) (xy 363.798073 -256.439844)
			(xy 363.794043 -256.387346) (xy 363.531404 -256.387346) (xy 363.5309 -256.413672) (xy 363.522863 -256.465708)
			(xy 363.506977 -256.515907) (xy 363.483614 -256.563092) (xy 363.453322 -256.606158) (xy 363.41681 -256.644096)
			(xy 363.374936 -256.676015) (xy 363.32868 -256.701168) (xy 363.279127 -256.718966) (xy 363.227437 -256.72899)
			(xy 363.174823 -256.731007) (xy 363.122518 -256.724969) (xy 363.071747 -256.711017) (xy 363.023702 -256.689478)
			(xy 362.979507 -256.660858) (xy 362.940199 -256.625827) (xy 362.906699 -256.585206) (xy 362.879793 -256.539947)
			(xy 362.86011 -256.491112) (xy 362.848113 -256.439844) (xy 362.844083 -256.387346) (xy 362.581444 -256.387346)
			(xy 362.58094 -256.413672) (xy 362.572903 -256.465708) (xy 362.557017 -256.515907) (xy 362.533654 -256.563092)
			(xy 362.503362 -256.606158) (xy 362.46685 -256.644096) (xy 362.424976 -256.676015) (xy 362.37872 -256.701168)
			(xy 362.329167 -256.718966) (xy 362.277477 -256.72899) (xy 362.224863 -256.731007) (xy 362.172558 -256.724969)
			(xy 362.121787 -256.711017) (xy 362.073742 -256.689478) (xy 362.029547 -256.660858) (xy 361.990239 -256.625827)
			(xy 361.956739 -256.585206) (xy 361.929833 -256.539947) (xy 361.91015 -256.491112) (xy 361.898153 -256.439844)
			(xy 361.894123 -256.387346) (xy 361.631484 -256.387346) (xy 361.63098 -256.413672) (xy 361.622943 -256.465708)
			(xy 361.607057 -256.515907) (xy 361.583694 -256.563092) (xy 361.553402 -256.606158) (xy 361.51689 -256.644096)
			(xy 361.475016 -256.676015) (xy 361.42876 -256.701168) (xy 361.379207 -256.718966) (xy 361.327517 -256.72899)
			(xy 361.274903 -256.731007) (xy 361.222598 -256.724969) (xy 361.171827 -256.711017) (xy 361.123782 -256.689478)
			(xy 361.079587 -256.660858) (xy 361.040279 -256.625827) (xy 361.006779 -256.585206) (xy 360.979873 -256.539947)
			(xy 360.96019 -256.491112) (xy 360.948193 -256.439844) (xy 360.944163 -256.387346) (xy 360.68127 -256.387346)
			(xy 360.680766 -256.413672) (xy 360.672729 -256.465708) (xy 360.656843 -256.515907) (xy 360.63348 -256.563092)
			(xy 360.603188 -256.606158) (xy 360.566676 -256.644096) (xy 360.524802 -256.676015) (xy 360.478546 -256.701168)
			(xy 360.428993 -256.718966) (xy 360.377303 -256.72899) (xy 360.324689 -256.731007) (xy 360.272384 -256.724969)
			(xy 360.221613 -256.711017) (xy 360.173568 -256.689478) (xy 360.129373 -256.660858) (xy 360.090065 -256.625827)
			(xy 360.056565 -256.585206) (xy 360.029659 -256.539947) (xy 360.009976 -256.491112) (xy 359.997979 -256.439844)
			(xy 359.993949 -256.387346) (xy 359.73131 -256.387346) (xy 359.730806 -256.413672) (xy 359.722769 -256.465708)
			(xy 359.706883 -256.515907) (xy 359.68352 -256.563092) (xy 359.653228 -256.606158) (xy 359.616716 -256.644096)
			(xy 359.574842 -256.676015) (xy 359.528586 -256.701168) (xy 359.479033 -256.718966) (xy 359.427343 -256.72899)
			(xy 359.374729 -256.731007) (xy 359.322424 -256.724969) (xy 359.271653 -256.711017) (xy 359.223608 -256.689478)
			(xy 359.179413 -256.660858) (xy 359.140105 -256.625827) (xy 359.106605 -256.585206) (xy 359.079699 -256.539947)
			(xy 359.060016 -256.491112) (xy 359.048019 -256.439844) (xy 359.043989 -256.387346) (xy 358.78135 -256.387346)
			(xy 358.780846 -256.413672) (xy 358.772809 -256.465708) (xy 358.756923 -256.515907) (xy 358.73356 -256.563092)
			(xy 358.703268 -256.606158) (xy 358.666756 -256.644096) (xy 358.624882 -256.676015) (xy 358.578626 -256.701168)
			(xy 358.529073 -256.718966) (xy 358.477383 -256.72899) (xy 358.424769 -256.731007) (xy 358.372464 -256.724969)
			(xy 358.321693 -256.711017) (xy 358.273648 -256.689478) (xy 358.229453 -256.660858) (xy 358.190145 -256.625827)
			(xy 358.156645 -256.585206) (xy 358.129739 -256.539947) (xy 358.110056 -256.491112) (xy 358.098059 -256.439844)
			(xy 358.094029 -256.387346) (xy 357.83139 -256.387346) (xy 357.830886 -256.413672) (xy 357.822849 -256.465708)
			(xy 357.806963 -256.515907) (xy 357.7836 -256.563092) (xy 357.753308 -256.606158) (xy 357.716796 -256.644096)
			(xy 357.674922 -256.676015) (xy 357.628666 -256.701168) (xy 357.579113 -256.718966) (xy 357.527423 -256.72899)
			(xy 357.474809 -256.731007) (xy 357.422504 -256.724969) (xy 357.371733 -256.711017) (xy 357.323688 -256.689478)
			(xy 357.279493 -256.660858) (xy 357.240185 -256.625827) (xy 357.206685 -256.585206) (xy 357.179779 -256.539947)
			(xy 357.160096 -256.491112) (xy 357.148099 -256.439844) (xy 357.144069 -256.387346) (xy 356.88143 -256.387346)
			(xy 356.880926 -256.413672) (xy 356.872889 -256.465708) (xy 356.857003 -256.515907) (xy 356.83364 -256.563092)
			(xy 356.803348 -256.606158) (xy 356.766836 -256.644096) (xy 356.724962 -256.676015) (xy 356.678706 -256.701168)
			(xy 356.629153 -256.718966) (xy 356.577463 -256.72899) (xy 356.524849 -256.731007) (xy 356.472544 -256.724969)
			(xy 356.421773 -256.711017) (xy 356.373728 -256.689478) (xy 356.329533 -256.660858) (xy 356.290225 -256.625827)
			(xy 356.256725 -256.585206) (xy 356.229819 -256.539947) (xy 356.210136 -256.491112) (xy 356.198139 -256.439844)
			(xy 356.194109 -256.387346) (xy 355.93147 -256.387346) (xy 355.930966 -256.413672) (xy 355.922929 -256.465708)
			(xy 355.907043 -256.515907) (xy 355.88368 -256.563092) (xy 355.853388 -256.606158) (xy 355.816876 -256.644096)
			(xy 355.775002 -256.676015) (xy 355.728746 -256.701168) (xy 355.679193 -256.718966) (xy 355.627503 -256.72899)
			(xy 355.574889 -256.731007) (xy 355.522584 -256.724969) (xy 355.471813 -256.711017) (xy 355.423768 -256.689478)
			(xy 355.379573 -256.660858) (xy 355.340265 -256.625827) (xy 355.306765 -256.585206) (xy 355.279859 -256.539947)
			(xy 355.260176 -256.491112) (xy 355.248179 -256.439844) (xy 355.244149 -256.387346) (xy 354.676099 -256.387346)
			(xy 354.678135 -256.393241) (xy 354.68754 -256.445601) (xy 354.688648 -256.472182) (xy 354.688648 -256.478024)
			(xy 354.688648 -256.480056) (xy 354.688047 -256.509471) (xy 354.678024 -256.567441) (xy 354.658265 -256.622854)
			(xy 354.629348 -256.674087) (xy 354.611178 -256.697226) (xy 354.611178 -256.69748) (xy 354.605407 -256.70514)
			(xy 354.599544 -256.723383) (xy 354.600822 -256.742503) (xy 354.604574 -256.751328) (xy 354.642674 -256.8321)
			(xy 354.6475 -256.840228) (xy 354.654577 -256.84906) (xy 354.674358 -256.859997) (xy 354.6856 -256.86131)
			(xy 355.19868 -256.86131) (xy 355.208516 -256.861848) (xy 355.226674 -256.869439) (xy 355.233986 -256.876042)
			(xy 355.305868 -256.947924) (xy 355.306376 -256.948432) (xy 355.313757 -256.955013) (xy 355.332057 -256.962458)
			(xy 355.341936 -256.96291) (xy 356.90048 -256.96291) (xy 356.910316 -256.963448) (xy 356.928474 -256.971039)
			(xy 356.935786 -256.977642) (xy 357.70312 -257.744976) (xy 358.928419 -257.744976) (xy 358.932449 -257.692478)
			(xy 358.944446 -257.64121) (xy 358.964129 -257.592375) (xy 358.991035 -257.547116) (xy 359.024535 -257.506495)
			(xy 359.063843 -257.471464) (xy 359.108038 -257.442844) (xy 359.156083 -257.421305) (xy 359.206854 -257.407353)
			(xy 359.259159 -257.401315) (xy 359.311773 -257.403332) (xy 359.363463 -257.413356) (xy 359.413016 -257.431154)
			(xy 359.459272 -257.456307) (xy 359.501146 -257.488226) (xy 359.537658 -257.526164) (xy 359.56795 -257.56923)
			(xy 359.591313 -257.616415) (xy 359.607199 -257.666614) (xy 359.615236 -257.71865) (xy 359.61574 -257.744976)
			(xy 361.178351 -257.744976) (xy 361.182381 -257.692478) (xy 361.194378 -257.64121) (xy 361.214061 -257.592375)
			(xy 361.240967 -257.547116) (xy 361.274467 -257.506495) (xy 361.313775 -257.471464) (xy 361.35797 -257.442844)
			(xy 361.406015 -257.421305) (xy 361.456786 -257.407353) (xy 361.509091 -257.401315) (xy 361.561705 -257.403332)
			(xy 361.613395 -257.413356) (xy 361.662948 -257.431154) (xy 361.709204 -257.456307) (xy 361.751078 -257.488226)
			(xy 361.78759 -257.526164) (xy 361.817882 -257.56923) (xy 361.841245 -257.616415) (xy 361.857131 -257.666614)
			(xy 361.865168 -257.71865) (xy 361.865672 -257.744976) (xy 363.778295 -257.744976) (xy 363.782325 -257.692478)
			(xy 363.794322 -257.64121) (xy 363.814005 -257.592375) (xy 363.840911 -257.547116) (xy 363.874411 -257.506495)
			(xy 363.913719 -257.471464) (xy 363.957914 -257.442844) (xy 364.005959 -257.421305) (xy 364.05673 -257.407353)
			(xy 364.109035 -257.401315) (xy 364.161649 -257.403332) (xy 364.213339 -257.413356) (xy 364.259724 -257.430016)
			(xy 365.036865 -257.430016) (xy 365.040895 -257.377518) (xy 365.052892 -257.32625) (xy 365.072575 -257.277415)
			(xy 365.099481 -257.232156) (xy 365.132981 -257.191535) (xy 365.172289 -257.156504) (xy 365.216484 -257.127884)
			(xy 365.264529 -257.106345) (xy 365.3153 -257.092393) (xy 365.367605 -257.086355) (xy 365.420219 -257.088372)
			(xy 365.471909 -257.098396) (xy 365.521462 -257.116194) (xy 365.567718 -257.141347) (xy 365.609592 -257.173266)
			(xy 365.646104 -257.211204) (xy 365.676396 -257.25427) (xy 365.699759 -257.301455) (xy 365.715645 -257.351654)
			(xy 365.723682 -257.40369) (xy 365.724186 -257.430016) (xy 365.723682 -257.456342) (xy 365.715645 -257.508378)
			(xy 365.699759 -257.558577) (xy 365.676396 -257.605762) (xy 365.646104 -257.648828) (xy 365.609592 -257.686766)
			(xy 365.567718 -257.718685) (xy 365.521462 -257.743838) (xy 365.471909 -257.761636) (xy 365.420219 -257.77166)
			(xy 365.367605 -257.773677) (xy 365.3153 -257.767639) (xy 365.264529 -257.753687) (xy 365.216484 -257.732148)
			(xy 365.172289 -257.703528) (xy 365.132981 -257.668497) (xy 365.099481 -257.627876) (xy 365.072575 -257.582617)
			(xy 365.052892 -257.533782) (xy 365.040895 -257.482514) (xy 365.036865 -257.430016) (xy 364.259724 -257.430016)
			(xy 364.262892 -257.431154) (xy 364.309148 -257.456307) (xy 364.351022 -257.488226) (xy 364.387534 -257.526164)
			(xy 364.417826 -257.56923) (xy 364.441189 -257.616415) (xy 364.457075 -257.666614) (xy 364.465112 -257.71865)
			(xy 364.465616 -257.744976) (xy 364.465112 -257.771302) (xy 364.457075 -257.823338) (xy 364.441189 -257.873537)
			(xy 364.417826 -257.920722) (xy 364.4112 -257.930142) (xy 368.805717 -257.930142) (xy 368.809747 -257.877644)
			(xy 368.821744 -257.826376) (xy 368.841427 -257.777541) (xy 368.868333 -257.732282) (xy 368.901833 -257.691661)
			(xy 368.941141 -257.65663) (xy 368.985336 -257.62801) (xy 369.033381 -257.606471) (xy 369.084152 -257.592519)
			(xy 369.136457 -257.586481) (xy 369.189071 -257.588498) (xy 369.240761 -257.598522) (xy 369.290314 -257.61632)
			(xy 369.33657 -257.641473) (xy 369.378444 -257.673392) (xy 369.414956 -257.71133) (xy 369.445248 -257.754396)
			(xy 369.468611 -257.801581) (xy 369.484497 -257.85178) (xy 369.492534 -257.903816) (xy 369.493038 -257.930142)
			(xy 370.731291 -257.930142) (xy 370.735321 -257.877644) (xy 370.747318 -257.826376) (xy 370.767001 -257.777541)
			(xy 370.793907 -257.732282) (xy 370.827407 -257.691661) (xy 370.866715 -257.65663) (xy 370.91091 -257.62801)
			(xy 370.958955 -257.606471) (xy 371.009726 -257.592519) (xy 371.062031 -257.586481) (xy 371.114645 -257.588498)
			(xy 371.166335 -257.598522) (xy 371.215888 -257.61632) (xy 371.262144 -257.641473) (xy 371.304018 -257.673392)
			(xy 371.34053 -257.71133) (xy 371.370822 -257.754396) (xy 371.394185 -257.801581) (xy 371.410071 -257.85178)
			(xy 371.418108 -257.903816) (xy 371.418612 -257.930142) (xy 372.509291 -257.930142) (xy 372.513321 -257.877644)
			(xy 372.525318 -257.826376) (xy 372.545001 -257.777541) (xy 372.571907 -257.732282) (xy 372.605407 -257.691661)
			(xy 372.644715 -257.65663) (xy 372.68891 -257.62801) (xy 372.736955 -257.606471) (xy 372.787726 -257.592519)
			(xy 372.840031 -257.586481) (xy 372.892645 -257.588498) (xy 372.944335 -257.598522) (xy 372.993888 -257.61632)
			(xy 373.040144 -257.641473) (xy 373.082018 -257.673392) (xy 373.11853 -257.71133) (xy 373.148822 -257.754396)
			(xy 373.172185 -257.801581) (xy 373.188071 -257.85178) (xy 373.196108 -257.903816) (xy 373.196612 -257.930142)
			(xy 373.196108 -257.956468) (xy 373.188071 -258.008504) (xy 373.172185 -258.058703) (xy 373.148822 -258.105888)
			(xy 373.11853 -258.148954) (xy 373.082018 -258.186892) (xy 373.040144 -258.218811) (xy 372.993888 -258.243964)
			(xy 372.944335 -258.261762) (xy 372.892645 -258.271786) (xy 372.840031 -258.273803) (xy 372.787726 -258.267765)
			(xy 372.736955 -258.253813) (xy 372.68891 -258.232274) (xy 372.644715 -258.203654) (xy 372.605407 -258.168623)
			(xy 372.571907 -258.128002) (xy 372.545001 -258.082743) (xy 372.525318 -258.033908) (xy 372.513321 -257.98264)
			(xy 372.509291 -257.930142) (xy 371.418612 -257.930142) (xy 371.418108 -257.956468) (xy 371.410071 -258.008504)
			(xy 371.394185 -258.058703) (xy 371.370822 -258.105888) (xy 371.34053 -258.148954) (xy 371.304018 -258.186892)
			(xy 371.262144 -258.218811) (xy 371.215888 -258.243964) (xy 371.166335 -258.261762) (xy 371.114645 -258.271786)
			(xy 371.062031 -258.273803) (xy 371.009726 -258.267765) (xy 370.958955 -258.253813) (xy 370.91091 -258.232274)
			(xy 370.866715 -258.203654) (xy 370.827407 -258.168623) (xy 370.793907 -258.128002) (xy 370.767001 -258.082743)
			(xy 370.747318 -258.033908) (xy 370.735321 -257.98264) (xy 370.731291 -257.930142) (xy 369.493038 -257.930142)
			(xy 369.492534 -257.956468) (xy 369.484497 -258.008504) (xy 369.468611 -258.058703) (xy 369.445248 -258.105888)
			(xy 369.414956 -258.148954) (xy 369.378444 -258.186892) (xy 369.33657 -258.218811) (xy 369.290314 -258.243964)
			(xy 369.240761 -258.261762) (xy 369.189071 -258.271786) (xy 369.136457 -258.273803) (xy 369.084152 -258.267765)
			(xy 369.033381 -258.253813) (xy 368.985336 -258.232274) (xy 368.941141 -258.203654) (xy 368.901833 -258.168623)
			(xy 368.868333 -258.128002) (xy 368.841427 -258.082743) (xy 368.821744 -258.033908) (xy 368.809747 -257.98264)
			(xy 368.805717 -257.930142) (xy 364.4112 -257.930142) (xy 364.387534 -257.963788) (xy 364.351022 -258.001726)
			(xy 364.309148 -258.033645) (xy 364.262892 -258.058798) (xy 364.213339 -258.076596) (xy 364.161649 -258.08662)
			(xy 364.109035 -258.088637) (xy 364.05673 -258.082599) (xy 364.005959 -258.068647) (xy 363.957914 -258.047108)
			(xy 363.913719 -258.018488) (xy 363.874411 -257.983457) (xy 363.840911 -257.942836) (xy 363.814005 -257.897577)
			(xy 363.794322 -257.848742) (xy 363.782325 -257.797474) (xy 363.778295 -257.744976) (xy 361.865672 -257.744976)
			(xy 361.865168 -257.771302) (xy 361.857131 -257.823338) (xy 361.841245 -257.873537) (xy 361.817882 -257.920722)
			(xy 361.78759 -257.963788) (xy 361.751078 -258.001726) (xy 361.709204 -258.033645) (xy 361.662948 -258.058798)
			(xy 361.613395 -258.076596) (xy 361.561705 -258.08662) (xy 361.509091 -258.088637) (xy 361.456786 -258.082599)
			(xy 361.406015 -258.068647) (xy 361.35797 -258.047108) (xy 361.313775 -258.018488) (xy 361.274467 -257.983457)
			(xy 361.240967 -257.942836) (xy 361.214061 -257.897577) (xy 361.194378 -257.848742) (xy 361.182381 -257.797474)
			(xy 361.178351 -257.744976) (xy 359.61574 -257.744976) (xy 359.615236 -257.771302) (xy 359.607199 -257.823338)
			(xy 359.591313 -257.873537) (xy 359.56795 -257.920722) (xy 359.537658 -257.963788) (xy 359.501146 -258.001726)
			(xy 359.459272 -258.033645) (xy 359.413016 -258.058798) (xy 359.363463 -258.076596) (xy 359.311773 -258.08662)
			(xy 359.259159 -258.088637) (xy 359.206854 -258.082599) (xy 359.156083 -258.068647) (xy 359.108038 -258.047108)
			(xy 359.063843 -258.018488) (xy 359.024535 -257.983457) (xy 358.991035 -257.942836) (xy 358.964129 -257.897577)
			(xy 358.944446 -257.848742) (xy 358.932449 -257.797474) (xy 358.928419 -257.744976) (xy 357.70312 -257.744976)
			(xy 358.201468 -258.243324) (xy 358.201976 -258.243832) (xy 358.209357 -258.250413) (xy 358.227657 -258.257858)
			(xy 358.237536 -258.25831) (xy 359.44048 -258.25831) (xy 359.450316 -258.258848) (xy 359.468474 -258.266439)
			(xy 359.475786 -258.273042) (xy 359.58272 -258.379976) (xy 365.036865 -258.379976) (xy 365.040895 -258.327478)
			(xy 365.052892 -258.27621) (xy 365.072575 -258.227375) (xy 365.099481 -258.182116) (xy 365.132981 -258.141495)
			(xy 365.172289 -258.106464) (xy 365.216484 -258.077844) (xy 365.264529 -258.056305) (xy 365.3153 -258.042353)
			(xy 365.367605 -258.036315) (xy 365.420219 -258.038332) (xy 365.471909 -258.048356) (xy 365.521462 -258.066154)
			(xy 365.567718 -258.091307) (xy 365.609592 -258.123226) (xy 365.646104 -258.161164) (xy 365.676396 -258.20423)
			(xy 365.699759 -258.251415) (xy 365.715645 -258.301614) (xy 365.723682 -258.35365) (xy 365.724186 -258.379976)
			(xy 365.723682 -258.406302) (xy 365.715645 -258.458338) (xy 365.699759 -258.508537) (xy 365.676396 -258.555722)
			(xy 365.646104 -258.598788) (xy 365.609592 -258.636726) (xy 365.567718 -258.668645) (xy 365.521462 -258.693798)
			(xy 365.471909 -258.711596) (xy 365.420219 -258.72162) (xy 365.367605 -258.723637) (xy 365.3153 -258.717599)
			(xy 365.264529 -258.703647) (xy 365.216484 -258.682108) (xy 365.172289 -258.653488) (xy 365.132981 -258.618457)
			(xy 365.099481 -258.577836) (xy 365.072575 -258.532577) (xy 365.052892 -258.483742) (xy 365.040895 -258.432474)
			(xy 365.036865 -258.379976) (xy 359.58272 -258.379976) (xy 360.335068 -259.132324) (xy 360.335576 -259.132832)
			(xy 360.342957 -259.139413) (xy 360.361257 -259.146858) (xy 360.371136 -259.14731) (xy 361.156758 -259.14731)
			(xy 361.165962 -259.146916) (xy 361.183195 -259.140441) (xy 361.197062 -259.128334) (xy 361.201716 -259.120386)
			(xy 361.24261 -259.042662) (xy 361.2466 -259.034298) (xy 361.248894 -259.015924) (xy 361.244475 -258.997943)
			(xy 361.239562 -258.990084) (xy 361.225211 -258.968464) (xy 361.202495 -258.921809) (xy 361.187072 -258.872263)
			(xy 361.179293 -258.820958) (xy 361.178856 -258.795012) (xy 361.178856 -258.7879) (xy 361.179909 -258.761284)
			(xy 361.189221 -258.708841) (xy 361.206521 -258.658466) (xy 361.231393 -258.611366) (xy 361.263241 -258.568673)
			(xy 361.301301 -258.531411) (xy 361.344658 -258.500473) (xy 361.392273 -258.476603) (xy 361.443004 -258.460373)
			(xy 361.495632 -258.452172) (xy 361.522264 -258.451604) (xy 361.548906 -258.452111) (xy 361.60155 -258.460349)
			(xy 361.65229 -258.476617) (xy 361.699909 -258.500526) (xy 361.743265 -258.5315) (xy 361.781318 -258.568799)
			(xy 361.813155 -258.611526) (xy 361.838013 -258.658657) (xy 361.855294 -258.70906) (xy 361.864585 -258.761528)
			(xy 361.865672 -258.788154) (xy 361.865672 -258.792726) (xy 361.865672 -258.795012) (xy 361.865192 -258.820953)
			(xy 361.857386 -258.872246) (xy 361.841967 -258.921784) (xy 361.819284 -258.968447) (xy 361.804966 -258.990084)
			(xy 361.800078 -258.997946) (xy 361.795715 -259.015924) (xy 361.797977 -259.034284) (xy 361.801918 -259.042662)
			(xy 361.842812 -259.120386) (xy 361.847468 -259.128346) (xy 361.8613 -259.140518) (xy 361.878556 -259.146977)
			(xy 361.88777 -259.14731) (xy 363.756702 -259.14731) (xy 363.765902 -259.146909) (xy 363.783123 -259.140424)
			(xy 363.796977 -259.128314) (xy 363.80166 -259.120386) (xy 363.842554 -259.042662) (xy 363.846548 -259.034299)
			(xy 363.848845 -259.015924) (xy 363.844421 -258.997943) (xy 363.839506 -258.990084) (xy 363.825157 -258.968463)
			(xy 363.802445 -258.921807) (xy 363.787024 -258.872261) (xy 363.779247 -258.820957) (xy 363.7788 -258.795012)
			(xy 363.7788 -258.7879) (xy 363.779852 -258.761283) (xy 363.789164 -258.708836) (xy 363.806464 -258.658457)
			(xy 363.831335 -258.611353) (xy 363.863182 -258.568656) (xy 363.901241 -258.531388) (xy 363.944598 -258.500444)
			(xy 363.992213 -258.476567) (xy 364.042944 -258.460329) (xy 364.095575 -258.45212) (xy 364.122208 -258.451604)
			(xy 364.149195 -258.452106) (xy 364.202503 -258.460551) (xy 364.253834 -258.477231) (xy 364.301924 -258.501735)
			(xy 364.345588 -258.533461) (xy 364.383752 -258.571627) (xy 364.415475 -258.615293) (xy 364.439977 -258.663384)
			(xy 364.456654 -258.714717) (xy 364.465095 -258.768025) (xy 364.465616 -258.795012) (xy 364.465108 -258.82171)
			(xy 364.463799 -258.830064) (xy 368.805717 -258.830064) (xy 368.809747 -258.777566) (xy 368.821744 -258.726298)
			(xy 368.841427 -258.677463) (xy 368.868333 -258.632204) (xy 368.901833 -258.591583) (xy 368.941141 -258.556552)
			(xy 368.985336 -258.527932) (xy 369.033381 -258.506393) (xy 369.084152 -258.492441) (xy 369.136457 -258.486403)
			(xy 369.189071 -258.48842) (xy 369.240761 -258.498444) (xy 369.290314 -258.516242) (xy 369.33657 -258.541395)
			(xy 369.378444 -258.573314) (xy 369.414956 -258.611252) (xy 369.445248 -258.654318) (xy 369.468611 -258.701503)
			(xy 369.484497 -258.751702) (xy 369.492534 -258.803738) (xy 369.493038 -258.830064) (xy 370.731291 -258.830064)
			(xy 370.735321 -258.777566) (xy 370.747318 -258.726298) (xy 370.767001 -258.677463) (xy 370.793907 -258.632204)
			(xy 370.827407 -258.591583) (xy 370.866715 -258.556552) (xy 370.91091 -258.527932) (xy 370.958955 -258.506393)
			(xy 371.009726 -258.492441) (xy 371.062031 -258.486403) (xy 371.114645 -258.48842) (xy 371.166335 -258.498444)
			(xy 371.215888 -258.516242) (xy 371.262144 -258.541395) (xy 371.304018 -258.573314) (xy 371.34053 -258.611252)
			(xy 371.370822 -258.654318) (xy 371.394185 -258.701503) (xy 371.410071 -258.751702) (xy 371.418108 -258.803738)
			(xy 371.418612 -258.830064) (xy 372.509291 -258.830064) (xy 372.513321 -258.777566) (xy 372.525318 -258.726298)
			(xy 372.545001 -258.677463) (xy 372.571907 -258.632204) (xy 372.605407 -258.591583) (xy 372.644715 -258.556552)
			(xy 372.68891 -258.527932) (xy 372.736955 -258.506393) (xy 372.787726 -258.492441) (xy 372.840031 -258.486403)
			(xy 372.892645 -258.48842) (xy 372.944335 -258.498444) (xy 372.993888 -258.516242) (xy 373.040144 -258.541395)
			(xy 373.082018 -258.573314) (xy 373.11853 -258.611252) (xy 373.148822 -258.654318) (xy 373.172185 -258.701503)
			(xy 373.188071 -258.751702) (xy 373.196108 -258.803738) (xy 373.196612 -258.830064) (xy 373.196108 -258.85639)
			(xy 373.188071 -258.908426) (xy 373.172185 -258.958625) (xy 373.148822 -259.00581) (xy 373.11853 -259.048876)
			(xy 373.082018 -259.086814) (xy 373.040144 -259.118733) (xy 372.993888 -259.143886) (xy 372.944335 -259.161684)
			(xy 372.892645 -259.171708) (xy 372.840031 -259.173725) (xy 372.787726 -259.167687) (xy 372.736955 -259.153735)
			(xy 372.68891 -259.132196) (xy 372.644715 -259.103576) (xy 372.605407 -259.068545) (xy 372.571907 -259.027924)
			(xy 372.545001 -258.982665) (xy 372.525318 -258.93383) (xy 372.513321 -258.882562) (xy 372.509291 -258.830064)
			(xy 371.418612 -258.830064) (xy 371.418108 -258.85639) (xy 371.410071 -258.908426) (xy 371.394185 -258.958625)
			(xy 371.370822 -259.00581) (xy 371.34053 -259.048876) (xy 371.304018 -259.086814) (xy 371.262144 -259.118733)
			(xy 371.215888 -259.143886) (xy 371.166335 -259.161684) (xy 371.114645 -259.171708) (xy 371.062031 -259.173725)
			(xy 371.009726 -259.167687) (xy 370.958955 -259.153735) (xy 370.91091 -259.132196) (xy 370.866715 -259.103576)
			(xy 370.827407 -259.068545) (xy 370.793907 -259.027924) (xy 370.767001 -258.982665) (xy 370.747318 -258.93383)
			(xy 370.735321 -258.882562) (xy 370.731291 -258.830064) (xy 369.493038 -258.830064) (xy 369.492534 -258.85639)
			(xy 369.484497 -258.908426) (xy 369.468611 -258.958625) (xy 369.445248 -259.00581) (xy 369.414956 -259.048876)
			(xy 369.378444 -259.086814) (xy 369.33657 -259.118733) (xy 369.290314 -259.143886) (xy 369.240761 -259.161684)
			(xy 369.189071 -259.171708) (xy 369.136457 -259.173725) (xy 369.084152 -259.167687) (xy 369.033381 -259.153735)
			(xy 368.985336 -259.132196) (xy 368.941141 -259.103576) (xy 368.901833 -259.068545) (xy 368.868333 -259.027924)
			(xy 368.841427 -258.982665) (xy 368.821744 -258.93383) (xy 368.809747 -258.882562) (xy 368.805717 -258.830064)
			(xy 364.463799 -258.830064) (xy 364.456842 -258.874462) (xy 364.440511 -258.925299) (xy 364.416508 -258.972996)
			(xy 364.385412 -259.016403) (xy 364.367064 -259.035804) (xy 364.359952 -259.042916) (xy 364.352586 -259.061204)
			(xy 364.35284 -259.141468) (xy 364.353337 -259.151279) (xy 364.360782 -259.16944) (xy 364.367318 -259.176774)
			(xy 364.367572 -259.177028) (xy 364.520734 -259.33019) (xy 365.036865 -259.33019) (xy 365.040895 -259.277692)
			(xy 365.052892 -259.226424) (xy 365.072575 -259.177589) (xy 365.099481 -259.13233) (xy 365.132981 -259.091709)
			(xy 365.172289 -259.056678) (xy 365.216484 -259.028058) (xy 365.264529 -259.006519) (xy 365.3153 -258.992567)
			(xy 365.367605 -258.986529) (xy 365.420219 -258.988546) (xy 365.471909 -258.99857) (xy 365.521462 -259.016368)
			(xy 365.567718 -259.041521) (xy 365.609592 -259.07344) (xy 365.646104 -259.111378) (xy 365.676396 -259.154444)
			(xy 365.699759 -259.201629) (xy 365.715645 -259.251828) (xy 365.723682 -259.303864) (xy 365.724186 -259.33019)
			(xy 365.723682 -259.356516) (xy 365.715645 -259.408552) (xy 365.699759 -259.458751) (xy 365.676396 -259.505936)
			(xy 365.646104 -259.549002) (xy 365.609592 -259.58694) (xy 365.567718 -259.618859) (xy 365.521462 -259.644012)
			(xy 365.471909 -259.66181) (xy 365.420219 -259.671834) (xy 365.367605 -259.673851) (xy 365.3153 -259.667813)
			(xy 365.264529 -259.653861) (xy 365.216484 -259.632322) (xy 365.172289 -259.603702) (xy 365.132981 -259.568671)
			(xy 365.099481 -259.52805) (xy 365.072575 -259.482791) (xy 365.052892 -259.433956) (xy 365.040895 -259.382688)
			(xy 365.036865 -259.33019) (xy 364.520734 -259.33019) (xy 364.627922 -259.437378) (xy 364.634639 -259.444615)
			(xy 364.642244 -259.462819) (xy 364.642654 -259.472684) (xy 364.642654 -259.729986) (xy 368.805717 -259.729986)
			(xy 368.809747 -259.677488) (xy 368.821744 -259.62622) (xy 368.841427 -259.577385) (xy 368.868333 -259.532126)
			(xy 368.901833 -259.491505) (xy 368.941141 -259.456474) (xy 368.985336 -259.427854) (xy 369.033381 -259.406315)
			(xy 369.084152 -259.392363) (xy 369.136457 -259.386325) (xy 369.189071 -259.388342) (xy 369.240761 -259.398366)
			(xy 369.290314 -259.416164) (xy 369.33657 -259.441317) (xy 369.378444 -259.473236) (xy 369.414956 -259.511174)
			(xy 369.445248 -259.55424) (xy 369.468611 -259.601425) (xy 369.484497 -259.651624) (xy 369.492534 -259.70366)
			(xy 369.493038 -259.729986) (xy 370.731291 -259.729986) (xy 370.735321 -259.677488) (xy 370.747318 -259.62622)
			(xy 370.767001 -259.577385) (xy 370.793907 -259.532126) (xy 370.827407 -259.491505) (xy 370.866715 -259.456474)
			(xy 370.91091 -259.427854) (xy 370.958955 -259.406315) (xy 371.009726 -259.392363) (xy 371.062031 -259.386325)
			(xy 371.114645 -259.388342) (xy 371.166335 -259.398366) (xy 371.215888 -259.416164) (xy 371.262144 -259.441317)
			(xy 371.304018 -259.473236) (xy 371.34053 -259.511174) (xy 371.370822 -259.55424) (xy 371.394185 -259.601425)
			(xy 371.410071 -259.651624) (xy 371.418108 -259.70366) (xy 371.418612 -259.729986) (xy 372.509291 -259.729986)
			(xy 372.513321 -259.677488) (xy 372.525318 -259.62622) (xy 372.545001 -259.577385) (xy 372.571907 -259.532126)
			(xy 372.605407 -259.491505) (xy 372.644715 -259.456474) (xy 372.68891 -259.427854) (xy 372.736955 -259.406315)
			(xy 372.787726 -259.392363) (xy 372.840031 -259.386325) (xy 372.892645 -259.388342) (xy 372.944335 -259.398366)
			(xy 372.993888 -259.416164) (xy 373.040144 -259.441317) (xy 373.082018 -259.473236) (xy 373.11853 -259.511174)
			(xy 373.148822 -259.55424) (xy 373.172185 -259.601425) (xy 373.188071 -259.651624) (xy 373.196108 -259.70366)
			(xy 373.196612 -259.729986) (xy 373.196108 -259.756312) (xy 373.188071 -259.808348) (xy 373.172185 -259.858547)
			(xy 373.148822 -259.905732) (xy 373.11853 -259.948798) (xy 373.082018 -259.986736) (xy 373.040144 -260.018655)
			(xy 372.993888 -260.043808) (xy 372.944335 -260.061606) (xy 372.892645 -260.07163) (xy 372.840031 -260.073647)
			(xy 372.787726 -260.067609) (xy 372.736955 -260.053657) (xy 372.68891 -260.032118) (xy 372.644715 -260.003498)
			(xy 372.605407 -259.968467) (xy 372.571907 -259.927846) (xy 372.545001 -259.882587) (xy 372.525318 -259.833752)
			(xy 372.513321 -259.782484) (xy 372.509291 -259.729986) (xy 371.418612 -259.729986) (xy 371.418108 -259.756312)
			(xy 371.410071 -259.808348) (xy 371.394185 -259.858547) (xy 371.370822 -259.905732) (xy 371.34053 -259.948798)
			(xy 371.304018 -259.986736) (xy 371.262144 -260.018655) (xy 371.215888 -260.043808) (xy 371.166335 -260.061606)
			(xy 371.114645 -260.07163) (xy 371.062031 -260.073647) (xy 371.009726 -260.067609) (xy 370.958955 -260.053657)
			(xy 370.91091 -260.032118) (xy 370.866715 -260.003498) (xy 370.827407 -259.968467) (xy 370.793907 -259.927846)
			(xy 370.767001 -259.882587) (xy 370.747318 -259.833752) (xy 370.735321 -259.782484) (xy 370.731291 -259.729986)
			(xy 369.493038 -259.729986) (xy 369.492534 -259.756312) (xy 369.484497 -259.808348) (xy 369.468611 -259.858547)
			(xy 369.445248 -259.905732) (xy 369.414956 -259.948798) (xy 369.378444 -259.986736) (xy 369.33657 -260.018655)
			(xy 369.290314 -260.043808) (xy 369.240761 -260.061606) (xy 369.189071 -260.07163) (xy 369.136457 -260.073647)
			(xy 369.084152 -260.067609) (xy 369.033381 -260.053657) (xy 368.985336 -260.032118) (xy 368.941141 -260.003498)
			(xy 368.901833 -259.968467) (xy 368.868333 -259.927846) (xy 368.841427 -259.882587) (xy 368.821744 -259.833752)
			(xy 368.809747 -259.782484) (xy 368.805717 -259.729986) (xy 364.642654 -259.729986) (xy 364.642654 -260.28015)
			(xy 365.036865 -260.28015) (xy 365.040895 -260.227652) (xy 365.052892 -260.176384) (xy 365.072575 -260.127549)
			(xy 365.099481 -260.08229) (xy 365.132981 -260.041669) (xy 365.172289 -260.006638) (xy 365.216484 -259.978018)
			(xy 365.264529 -259.956479) (xy 365.3153 -259.942527) (xy 365.367605 -259.936489) (xy 365.420219 -259.938506)
			(xy 365.471909 -259.94853) (xy 365.521462 -259.966328) (xy 365.567718 -259.991481) (xy 365.609592 -260.0234)
			(xy 365.646104 -260.061338) (xy 365.676396 -260.104404) (xy 365.699759 -260.151589) (xy 365.715645 -260.201788)
			(xy 365.723682 -260.253824) (xy 365.724186 -260.28015) (xy 365.723682 -260.306476) (xy 365.715645 -260.358512)
			(xy 365.699759 -260.408711) (xy 365.676396 -260.455896) (xy 365.646104 -260.498962) (xy 365.609592 -260.5369)
			(xy 365.567718 -260.568819) (xy 365.521462 -260.593972) (xy 365.471909 -260.61177) (xy 365.420219 -260.621794)
			(xy 365.367605 -260.623811) (xy 365.3153 -260.617773) (xy 365.264529 -260.603821) (xy 365.216484 -260.582282)
			(xy 365.172289 -260.553662) (xy 365.132981 -260.518631) (xy 365.099481 -260.47801) (xy 365.072575 -260.432751)
			(xy 365.052892 -260.383916) (xy 365.040895 -260.332648) (xy 365.036865 -260.28015) (xy 364.642654 -260.28015)
			(xy 364.642654 -261.140448) (xy 364.643118 -261.150324) (xy 364.650564 -261.168619) (xy 364.657132 -261.176008)
			(xy 364.657386 -261.176262) (xy 365.008668 -261.527544) (xy 365.009176 -261.528052) (xy 365.016558 -261.534631)
			(xy 365.034857 -261.542073) (xy 365.044736 -261.54253) (xy 365.053118 -261.54253) (xy 365.062866 -261.542101)
			(xy 365.080951 -261.534819) (xy 365.094984 -261.521286) (xy 365.099346 -261.512558) (xy 365.11103 -261.48665)
			(xy 365.114396 -261.478246) (xy 365.115616 -261.460196) (xy 365.110521 -261.442837) (xy 365.105442 -261.435342)
			(xy 365.089436 -261.412959) (xy 365.064008 -261.364165) (xy 365.046686 -261.31194) (xy 365.037911 -261.257621)
			(xy 365.03737 -261.23011) (xy 365.037898 -261.203124) (xy 365.04634 -261.149815) (xy 365.063016 -261.098484)
			(xy 365.087518 -261.050393) (xy 365.11924 -261.006727) (xy 365.157403 -260.968561) (xy 365.201066 -260.936834)
			(xy 365.249154 -260.912329) (xy 365.300484 -260.895647) (xy 365.353792 -260.887201) (xy 365.380778 -260.886702)
			(xy 365.40747 -260.887214) (xy 365.46021 -260.895485) (xy 365.511035 -260.911815) (xy 365.558722 -260.935812)
			(xy 365.602122 -260.966898) (xy 365.640191 -261.004323) (xy 365.672011 -261.047187) (xy 365.696817 -261.094458)
			(xy 365.707538 -261.12597) (xy 369.578902 -261.12597) (xy 369.582862 -261.076916) (xy 369.594639 -261.029132)
			(xy 369.61393 -260.983856) (xy 369.640233 -260.94226) (xy 369.672868 -260.905423) (xy 369.710989 -260.874298)
			(xy 369.75361 -260.849691) (xy 369.799626 -260.832239) (xy 369.847845 -260.822395) (xy 369.89702 -260.820414)
			(xy 369.945875 -260.826346) (xy 369.993146 -260.840038) (xy 370.037608 -260.861136) (xy 370.078111 -260.889092)
			(xy 370.113604 -260.923184) (xy 370.143169 -260.962528) (xy 370.16604 -261.006105) (xy 370.181624 -261.052786)
			(xy 370.189519 -261.101363) (xy 370.190014 -261.12597) (xy 371.45901 -261.12597) (xy 371.46297 -261.076916)
			(xy 371.474747 -261.029132) (xy 371.494038 -260.983856) (xy 371.520341 -260.94226) (xy 371.552976 -260.905423)
			(xy 371.591097 -260.874298) (xy 371.633718 -260.849691) (xy 371.679734 -260.832239) (xy 371.727953 -260.822395)
			(xy 371.777128 -260.820414) (xy 371.825983 -260.826346) (xy 371.873254 -260.840038) (xy 371.917716 -260.861136)
			(xy 371.958219 -260.889092) (xy 371.993712 -260.923184) (xy 372.023277 -260.962528) (xy 372.046148 -261.006105)
			(xy 372.061732 -261.052786) (xy 372.069627 -261.101363) (xy 372.070122 -261.12597) (xy 373.339118 -261.12597)
			(xy 373.343078 -261.076916) (xy 373.354855 -261.029132) (xy 373.374146 -260.983856) (xy 373.400449 -260.94226)
			(xy 373.433084 -260.905423) (xy 373.471205 -260.874298) (xy 373.513826 -260.849691) (xy 373.559842 -260.832239)
			(xy 373.608061 -260.822395) (xy 373.657236 -260.820414) (xy 373.706091 -260.826346) (xy 373.753362 -260.840038)
			(xy 373.797824 -260.861136) (xy 373.838327 -260.889092) (xy 373.87382 -260.923184) (xy 373.903385 -260.962528)
			(xy 373.926256 -261.006105) (xy 373.94184 -261.052786) (xy 373.949735 -261.101363) (xy 373.95023 -261.12597)
			(xy 375.218972 -261.12597) (xy 375.222932 -261.076916) (xy 375.234709 -261.029132) (xy 375.254 -260.983856)
			(xy 375.280303 -260.94226) (xy 375.312938 -260.905423) (xy 375.351059 -260.874298) (xy 375.39368 -260.849691)
			(xy 375.439696 -260.832239) (xy 375.487915 -260.822395) (xy 375.53709 -260.820414) (xy 375.585945 -260.826346)
			(xy 375.633216 -260.840038) (xy 375.677678 -260.861136) (xy 375.718181 -260.889092) (xy 375.753674 -260.923184)
			(xy 375.783239 -260.962528) (xy 375.80611 -261.006105) (xy 375.821694 -261.052786) (xy 375.829589 -261.101363)
			(xy 375.830084 -261.12597) (xy 376.159026 -261.12597) (xy 376.162986 -261.076916) (xy 376.174763 -261.029132)
			(xy 376.194054 -260.983856) (xy 376.220357 -260.94226) (xy 376.252992 -260.905423) (xy 376.291113 -260.874298)
			(xy 376.333734 -260.849691) (xy 376.37975 -260.832239) (xy 376.427969 -260.822395) (xy 376.477144 -260.820414)
			(xy 376.525999 -260.826346) (xy 376.57327 -260.840038) (xy 376.617732 -260.861136) (xy 376.658235 -260.889092)
			(xy 376.693728 -260.923184) (xy 376.723293 -260.962528) (xy 376.746164 -261.006105) (xy 376.761748 -261.052786)
			(xy 376.769643 -261.101363) (xy 376.770138 -261.12597) (xy 377.09908 -261.12597) (xy 377.10304 -261.076916)
			(xy 377.114817 -261.029132) (xy 377.134108 -260.983856) (xy 377.160411 -260.94226) (xy 377.193046 -260.905423)
			(xy 377.231167 -260.874298) (xy 377.273788 -260.849691) (xy 377.319804 -260.832239) (xy 377.368023 -260.822395)
			(xy 377.417198 -260.820414) (xy 377.466053 -260.826346) (xy 377.513324 -260.840038) (xy 377.557786 -260.861136)
			(xy 377.598289 -260.889092) (xy 377.633782 -260.923184) (xy 377.663347 -260.962528) (xy 377.686218 -261.006105)
			(xy 377.701802 -261.052786) (xy 377.709697 -261.101363) (xy 377.710192 -261.12597) (xy 378.039134 -261.12597)
			(xy 378.043094 -261.076916) (xy 378.054871 -261.029132) (xy 378.074162 -260.983856) (xy 378.100465 -260.94226)
			(xy 378.1331 -260.905423) (xy 378.171221 -260.874298) (xy 378.213842 -260.849691) (xy 378.259858 -260.832239)
			(xy 378.308077 -260.822395) (xy 378.357252 -260.820414) (xy 378.406107 -260.826346) (xy 378.453378 -260.840038)
			(xy 378.49784 -260.861136) (xy 378.538343 -260.889092) (xy 378.573836 -260.923184) (xy 378.603401 -260.962528)
			(xy 378.626272 -261.006105) (xy 378.641856 -261.052786) (xy 378.649751 -261.101363) (xy 378.650246 -261.12597)
			(xy 378.649751 -261.150577) (xy 378.641856 -261.199154) (xy 378.626272 -261.245835) (xy 378.603401 -261.289412)
			(xy 378.573836 -261.328756) (xy 378.538343 -261.362848) (xy 378.49784 -261.390804) (xy 378.453378 -261.411902)
			(xy 378.406107 -261.425594) (xy 378.357252 -261.431526) (xy 378.308077 -261.429545) (xy 378.259858 -261.419701)
			(xy 378.213842 -261.402249) (xy 378.171221 -261.377642) (xy 378.1331 -261.346517) (xy 378.100465 -261.30968)
			(xy 378.074162 -261.268084) (xy 378.054871 -261.222808) (xy 378.043094 -261.175024) (xy 378.039134 -261.12597)
			(xy 377.710192 -261.12597) (xy 377.709697 -261.150577) (xy 377.701802 -261.199154) (xy 377.686218 -261.245835)
			(xy 377.663347 -261.289412) (xy 377.633782 -261.328756) (xy 377.598289 -261.362848) (xy 377.557786 -261.390804)
			(xy 377.513324 -261.411902) (xy 377.466053 -261.425594) (xy 377.417198 -261.431526) (xy 377.368023 -261.429545)
			(xy 377.319804 -261.419701) (xy 377.273788 -261.402249) (xy 377.231167 -261.377642) (xy 377.193046 -261.346517)
			(xy 377.160411 -261.30968) (xy 377.134108 -261.268084) (xy 377.114817 -261.222808) (xy 377.10304 -261.175024)
			(xy 377.09908 -261.12597) (xy 376.770138 -261.12597) (xy 376.769643 -261.150577) (xy 376.761748 -261.199154)
			(xy 376.746164 -261.245835) (xy 376.723293 -261.289412) (xy 376.693728 -261.328756) (xy 376.658235 -261.362848)
			(xy 376.617732 -261.390804) (xy 376.57327 -261.411902) (xy 376.525999 -261.425594) (xy 376.477144 -261.431526)
			(xy 376.427969 -261.429545) (xy 376.37975 -261.419701) (xy 376.333734 -261.402249) (xy 376.291113 -261.377642)
			(xy 376.252992 -261.346517) (xy 376.220357 -261.30968) (xy 376.194054 -261.268084) (xy 376.174763 -261.222808)
			(xy 376.162986 -261.175024) (xy 376.159026 -261.12597) (xy 375.830084 -261.12597) (xy 375.829589 -261.150577)
			(xy 375.821694 -261.199154) (xy 375.80611 -261.245835) (xy 375.783239 -261.289412) (xy 375.753674 -261.328756)
			(xy 375.718181 -261.362848) (xy 375.677678 -261.390804) (xy 375.633216 -261.411902) (xy 375.585945 -261.425594)
			(xy 375.53709 -261.431526) (xy 375.487915 -261.429545) (xy 375.439696 -261.419701) (xy 375.39368 -261.402249)
			(xy 375.351059 -261.377642) (xy 375.312938 -261.346517) (xy 375.280303 -261.30968) (xy 375.254 -261.268084)
			(xy 375.234709 -261.222808) (xy 375.222932 -261.175024) (xy 375.218972 -261.12597) (xy 373.95023 -261.12597)
			(xy 373.949735 -261.150577) (xy 373.94184 -261.199154) (xy 373.926256 -261.245835) (xy 373.903385 -261.289412)
			(xy 373.87382 -261.328756) (xy 373.838327 -261.362848) (xy 373.797824 -261.390804) (xy 373.753362 -261.411902)
			(xy 373.706091 -261.425594) (xy 373.657236 -261.431526) (xy 373.608061 -261.429545) (xy 373.559842 -261.419701)
			(xy 373.513826 -261.402249) (xy 373.471205 -261.377642) (xy 373.433084 -261.346517) (xy 373.400449 -261.30968)
			(xy 373.374146 -261.268084) (xy 373.354855 -261.222808) (xy 373.343078 -261.175024) (xy 373.339118 -261.12597)
			(xy 372.070122 -261.12597) (xy 372.069627 -261.150577) (xy 372.061732 -261.199154) (xy 372.046148 -261.245835)
			(xy 372.023277 -261.289412) (xy 371.993712 -261.328756) (xy 371.958219 -261.362848) (xy 371.917716 -261.390804)
			(xy 371.873254 -261.411902) (xy 371.825983 -261.425594) (xy 371.777128 -261.431526) (xy 371.727953 -261.429545)
			(xy 371.679734 -261.419701) (xy 371.633718 -261.402249) (xy 371.591097 -261.377642) (xy 371.552976 -261.346517)
			(xy 371.520341 -261.30968) (xy 371.494038 -261.268084) (xy 371.474747 -261.222808) (xy 371.46297 -261.175024)
			(xy 371.45901 -261.12597) (xy 370.190014 -261.12597) (xy 370.189519 -261.150577) (xy 370.181624 -261.199154)
			(xy 370.16604 -261.245835) (xy 370.143169 -261.289412) (xy 370.113604 -261.328756) (xy 370.078111 -261.362848)
			(xy 370.037608 -261.390804) (xy 369.993146 -261.411902) (xy 369.945875 -261.425594) (xy 369.89702 -261.431526)
			(xy 369.847845 -261.429545) (xy 369.799626 -261.419701) (xy 369.75361 -261.402249) (xy 369.710989 -261.377642)
			(xy 369.672868 -261.346517) (xy 369.640233 -261.30968) (xy 369.61393 -261.268084) (xy 369.594639 -261.222808)
			(xy 369.582862 -261.175024) (xy 369.578902 -261.12597) (xy 365.707538 -261.12597) (xy 365.714012 -261.144998)
			(xy 365.72318 -261.197589) (xy 365.724186 -261.224268) (xy 365.724186 -261.229348) (xy 365.723682 -261.257962)
			(xy 365.714314 -261.314416) (xy 365.695695 -261.368529) (xy 365.68253 -261.39394) (xy 365.67618 -261.405878)
			(xy 365.676434 -261.432802) (xy 365.726726 -261.517638) (xy 365.731529 -261.525006) (xy 365.745086 -261.53619)
			(xy 365.761626 -261.54213) (xy 365.770414 -261.54253) (xy 366.023398 -261.54253) (xy 366.030831 -261.542833)
			(xy 366.045041 -261.547209) (xy 366.051338 -261.551166) (xy 366.051592 -261.55142) (xy 366.058196 -261.555738)
			(xy 366.0648 -261.55777) (xy 366.068573 -261.558915) (xy 366.076353 -261.560189) (xy 366.080294 -261.56031)
			(xy 367.057178 -261.56031) (xy 367.067015 -261.560848) (xy 367.085173 -261.568438) (xy 367.092484 -261.575042)
			(xy 367.697766 -262.180324) (xy 367.698274 -262.180832) (xy 367.705655 -262.187413) (xy 367.723955 -262.194859)
			(xy 367.733834 -262.19531) (xy 369.981734 -262.19531) (xy 369.994374 -262.194629) (xy 370.016625 -262.182628)
			(xy 370.024152 -262.17245) (xy 370.07673 -262.09244) (xy 370.079016 -262.067548) (xy 370.073936 -262.05561)
			(xy 370.062586 -262.027012) (xy 370.050303 -261.966735) (xy 370.049552 -261.935976) (xy 370.049552 -261.931404)
			(xy 370.050428 -261.906396) (xy 370.059325 -261.857158) (xy 370.076129 -261.810028) (xy 370.100393 -261.766269)
			(xy 370.131467 -261.727052) (xy 370.168519 -261.693426) (xy 370.210558 -261.66629) (xy 370.256458 -261.646372)
			(xy 370.304992 -261.634203) (xy 370.35486 -261.630111) (xy 370.404728 -261.634203) (xy 370.453262 -261.646372)
			(xy 370.499162 -261.66629) (xy 370.541201 -261.693426) (xy 370.578253 -261.727052) (xy 370.609327 -261.766269)
			(xy 370.633591 -261.810028) (xy 370.650395 -261.857158) (xy 370.659292 -261.906396) (xy 370.660168 -261.931404)
			(xy 370.660168 -261.934452) (xy 370.660168 -261.935976) (xy 371.92891 -261.935976) (xy 371.93287 -261.886922)
			(xy 371.944647 -261.839138) (xy 371.963938 -261.793862) (xy 371.990241 -261.752266) (xy 372.022876 -261.715429)
			(xy 372.060997 -261.684304) (xy 372.103618 -261.659697) (xy 372.149634 -261.642245) (xy 372.197853 -261.632401)
			(xy 372.247028 -261.63042) (xy 372.295883 -261.636352) (xy 372.343154 -261.650044) (xy 372.387616 -261.671142)
			(xy 372.428119 -261.699098) (xy 372.463612 -261.73319) (xy 372.493177 -261.772534) (xy 372.516048 -261.816111)
			(xy 372.531632 -261.862792) (xy 372.539527 -261.911369) (xy 372.540022 -261.935976) (xy 373.809018 -261.935976)
			(xy 373.812978 -261.886922) (xy 373.824755 -261.839138) (xy 373.844046 -261.793862) (xy 373.870349 -261.752266)
			(xy 373.902984 -261.715429) (xy 373.941105 -261.684304) (xy 373.983726 -261.659697) (xy 374.029742 -261.642245)
			(xy 374.077961 -261.632401) (xy 374.127136 -261.63042) (xy 374.175991 -261.636352) (xy 374.223262 -261.650044)
			(xy 374.267724 -261.671142) (xy 374.308227 -261.699098) (xy 374.34372 -261.73319) (xy 374.373285 -261.772534)
			(xy 374.396156 -261.816111) (xy 374.41174 -261.862792) (xy 374.419635 -261.911369) (xy 374.42013 -261.935976)
			(xy 375.678695 -261.935976) (xy 375.68279 -261.885248) (xy 375.694969 -261.835834) (xy 375.714917 -261.789014)
			(xy 375.742118 -261.746) (xy 375.775866 -261.707906) (xy 375.815288 -261.675719) (xy 375.859362 -261.650273)
			(xy 375.906948 -261.632226) (xy 375.956812 -261.622046) (xy 376.007664 -261.619997) (xy 376.058185 -261.626131)
			(xy 376.107069 -261.640291) (xy 376.153048 -261.662108) (xy 376.194932 -261.691018) (xy 376.231636 -261.726273)
			(xy 376.262209 -261.766959) (xy 376.28586 -261.812022) (xy 376.301976 -261.860296) (xy 376.31014 -261.91053)
			(xy 376.310652 -261.935976) (xy 376.628926 -261.935976) (xy 376.632886 -261.886922) (xy 376.644663 -261.839138)
			(xy 376.663954 -261.793862) (xy 376.690257 -261.752266) (xy 376.722892 -261.715429) (xy 376.761013 -261.684304)
			(xy 376.803634 -261.659697) (xy 376.84965 -261.642245) (xy 376.897869 -261.632401) (xy 376.947044 -261.63042)
			(xy 376.995899 -261.636352) (xy 377.04317 -261.650044) (xy 377.087632 -261.671142) (xy 377.128135 -261.699098)
			(xy 377.163628 -261.73319) (xy 377.193193 -261.772534) (xy 377.216064 -261.816111) (xy 377.231648 -261.862792)
			(xy 377.239543 -261.911369) (xy 377.240038 -261.935976) (xy 377.56898 -261.935976) (xy 377.57294 -261.886922)
			(xy 377.584717 -261.839138) (xy 377.604008 -261.793862) (xy 377.630311 -261.752266) (xy 377.662946 -261.715429)
			(xy 377.701067 -261.684304) (xy 377.743688 -261.659697) (xy 377.789704 -261.642245) (xy 377.837923 -261.632401)
			(xy 377.887098 -261.63042) (xy 377.935953 -261.636352) (xy 377.983224 -261.650044) (xy 378.027686 -261.671142)
			(xy 378.068189 -261.699098) (xy 378.103682 -261.73319) (xy 378.133247 -261.772534) (xy 378.156118 -261.816111)
			(xy 378.171702 -261.862792) (xy 378.179597 -261.911369) (xy 378.180092 -261.935976) (xy 378.179597 -261.960583)
			(xy 378.171702 -262.00916) (xy 378.156118 -262.055841) (xy 378.133247 -262.099418) (xy 378.103682 -262.138762)
			(xy 378.068189 -262.172854) (xy 378.027686 -262.20081) (xy 377.983224 -262.221908) (xy 377.935953 -262.2356)
			(xy 377.887098 -262.241532) (xy 377.837923 -262.239551) (xy 377.789704 -262.229707) (xy 377.743688 -262.212255)
			(xy 377.701067 -262.187648) (xy 377.662946 -262.156523) (xy 377.630311 -262.119686) (xy 377.604008 -262.07809)
			(xy 377.584717 -262.032814) (xy 377.57294 -261.98503) (xy 377.56898 -261.935976) (xy 377.240038 -261.935976)
			(xy 377.239543 -261.960583) (xy 377.231648 -262.00916) (xy 377.216064 -262.055841) (xy 377.193193 -262.099418)
			(xy 377.163628 -262.138762) (xy 377.128135 -262.172854) (xy 377.087632 -262.20081) (xy 377.04317 -262.221908)
			(xy 376.995899 -262.2356) (xy 376.947044 -262.241532) (xy 376.897869 -262.239551) (xy 376.84965 -262.229707)
			(xy 376.803634 -262.212255) (xy 376.761013 -262.187648) (xy 376.722892 -262.156523) (xy 376.690257 -262.119686)
			(xy 376.663954 -262.07809) (xy 376.644663 -262.032814) (xy 376.632886 -261.98503) (xy 376.628926 -261.935976)
			(xy 376.310652 -261.935976) (xy 376.31014 -261.961422) (xy 376.301976 -262.011656) (xy 376.28586 -262.05993)
			(xy 376.262209 -262.104993) (xy 376.231636 -262.145679) (xy 376.194932 -262.180934) (xy 376.153048 -262.209844)
			(xy 376.107069 -262.231661) (xy 376.058185 -262.245821) (xy 376.007664 -262.251955) (xy 375.956812 -262.249906)
			(xy 375.906948 -262.239726) (xy 375.859362 -262.221679) (xy 375.815288 -262.196233) (xy 375.775866 -262.164046)
			(xy 375.742118 -262.125952) (xy 375.714917 -262.082938) (xy 375.694969 -262.036118) (xy 375.68279 -261.986704)
			(xy 375.678695 -261.935976) (xy 374.42013 -261.935976) (xy 374.419635 -261.960583) (xy 374.41174 -262.00916)
			(xy 374.396156 -262.055841) (xy 374.373285 -262.099418) (xy 374.34372 -262.138762) (xy 374.308227 -262.172854)
			(xy 374.267724 -262.20081) (xy 374.223262 -262.221908) (xy 374.175991 -262.2356) (xy 374.127136 -262.241532)
			(xy 374.077961 -262.239551) (xy 374.029742 -262.229707) (xy 373.983726 -262.212255) (xy 373.941105 -262.187648)
			(xy 373.902984 -262.156523) (xy 373.870349 -262.119686) (xy 373.844046 -262.07809) (xy 373.824755 -262.032814)
			(xy 373.812978 -261.98503) (xy 373.809018 -261.935976) (xy 372.540022 -261.935976) (xy 372.539527 -261.960583)
			(xy 372.531632 -262.00916) (xy 372.516048 -262.055841) (xy 372.493177 -262.099418) (xy 372.463612 -262.138762)
			(xy 372.428119 -262.172854) (xy 372.387616 -262.20081) (xy 372.343154 -262.221908) (xy 372.295883 -262.2356)
			(xy 372.247028 -262.241532) (xy 372.197853 -262.239551) (xy 372.149634 -262.229707) (xy 372.103618 -262.212255)
			(xy 372.060997 -262.187648) (xy 372.022876 -262.156523) (xy 371.990241 -262.119686) (xy 371.963938 -262.07809)
			(xy 371.944647 -262.032814) (xy 371.93287 -261.98503) (xy 371.92891 -261.935976) (xy 370.660168 -261.935976)
			(xy 370.659404 -261.966733) (xy 370.64712 -262.027008) (xy 370.635784 -262.05561) (xy 370.630704 -262.067548)
			(xy 370.63299 -262.09244) (xy 370.685568 -262.17245) (xy 370.693085 -262.182638) (xy 370.715344 -262.194633)
			(xy 370.727986 -262.19531) (xy 371.375178 -262.19531) (xy 371.385015 -262.195848) (xy 371.403173 -262.203438)
			(xy 371.410484 -262.210042) (xy 371.64772 -262.447278) (xy 371.673628 -262.45439) (xy 371.686836 -262.450834)
			(xy 371.705982 -262.446097) (xy 371.745093 -262.441) (xy 371.764814 -262.440674) (xy 371.767862 -262.440674)
			(xy 371.791544 -262.441358) (xy 371.838276 -262.449145) (xy 371.883244 -262.464055) (xy 371.92537 -262.485732)
			(xy 371.963642 -262.513656) (xy 371.997142 -262.547155) (xy 372.025065 -262.585427) (xy 372.046743 -262.627552)
			(xy 372.061654 -262.67252) (xy 372.069441 -262.719252) (xy 372.070122 -262.742934) (xy 372.070122 -262.744458)
			(xy 372.070122 -262.745982) (xy 372.069814 -262.765704) (xy 372.064718 -262.804817) (xy 372.059962 -262.82396)
			(xy 372.056406 -262.837168) (xy 372.063518 -262.863076) (xy 372.269766 -263.069324) (xy 372.270274 -263.069832)
			(xy 372.277655 -263.076413) (xy 372.295955 -263.083859) (xy 372.305834 -263.08431)
		)
		(stroke
			(width 0)
			(type solid)
		)
		(fill yes)
		(layer "In4.Cu")
		(net "PVDDCR_SOC_P0")
	)
	(gr_poly
		(pts
			(xy 388.677658 -404.3172) (xy 388.687723 -404.316766) (xy 388.706313 -404.309037) (xy 388.713726 -404.302214)
			(xy 390.172194 -402.843746) (xy 390.179033 -402.836345) (xy 390.186748 -402.817747) (xy 390.18718 -402.807678)
			(xy 390.18718 -398.901412) (xy 390.186781 -398.892212) (xy 390.180297 -398.87499) (xy 390.168184 -398.861137)
			(xy 390.160256 -398.856454) (xy 390.068816 -398.807686) (xy 390.040876 -398.808956) (xy 390.029192 -398.81683)
			(xy 390.008685 -398.830038) (xy 389.964606 -398.850925) (xy 389.917934 -398.865101) (xy 389.869685 -398.87226)
			(xy 389.845296 -398.87271) (xy 389.819309 -398.8722) (xy 389.767975 -398.864069) (xy 389.718544 -398.848008)
			(xy 389.672235 -398.824411) (xy 389.630187 -398.793861) (xy 389.593436 -398.75711) (xy 389.562887 -398.715062)
			(xy 389.539291 -398.668752) (xy 389.52323 -398.619322) (xy 389.5151 -398.567987) (xy 389.5151 -398.516013)
			(xy 389.52323 -398.464678) (xy 389.539291 -398.415248) (xy 389.562887 -398.368938) (xy 389.593436 -398.32689)
			(xy 389.630187 -398.290139) (xy 389.672235 -398.259589) (xy 389.718544 -398.235992) (xy 389.767975 -398.219931)
			(xy 389.819309 -398.2118) (xy 389.845296 -398.211294) (xy 389.869685 -398.21173) (xy 389.917935 -398.218897)
			(xy 389.964607 -398.233075) (xy 390.00869 -398.253958) (xy 390.029192 -398.267174) (xy 390.040876 -398.275048)
			(xy 390.068816 -398.276318) (xy 390.160256 -398.22755) (xy 390.168203 -398.222886) (xy 390.180348 -398.209049)
			(xy 390.186784 -398.1918) (xy 390.18718 -398.182592) (xy 390.18718 -397.434562) (xy 390.186749 -397.424495)
			(xy 390.179023 -397.405903) (xy 390.172194 -397.398494) (xy 389.03656 -396.26286) (xy 389.028436 -396.255492)
			(xy 389.0079 -396.247853) (xy 388.996936 -396.248128) (xy 388.909052 -396.254224) (xy 388.890002 -396.264638)
			(xy 388.883398 -396.273782) (xy 388.871182 -396.289616) (xy 388.843551 -396.318527) (xy 388.82828 -396.33144)
			(xy 388.81939 -396.338552) (xy 388.809992 -396.35811) (xy 388.807198 -396.457424) (xy 388.815834 -396.47749)
			(xy 388.824216 -396.48511) (xy 388.842637 -396.502598) (xy 388.873977 -396.542567) (xy 388.898273 -396.587169)
			(xy 388.914854 -396.635177) (xy 388.923263 -396.685267) (xy 388.923784 -396.710662) (xy 388.923693 -396.721944)
			(xy 388.92204 -396.744446) (xy 388.920482 -396.75562) (xy 388.919212 -396.76451) (xy 388.922768 -396.782036)
			(xy 388.966202 -396.852902) (xy 388.979918 -396.864078) (xy 388.988554 -396.866872) (xy 389.010798 -396.874809)
			(xy 389.05272 -396.89656) (xy 389.090793 -396.924504) (xy 389.124111 -396.957976) (xy 389.15188 -396.996177)
			(xy 389.163052 -397.016986) (xy 389.16356 -397.018002) (xy 389.55599 -397.696944) (xy 389.568775 -397.720294)
			(xy 389.586969 -397.770317) (xy 389.596254 -397.82273) (xy 389.596884 -397.849344) (xy 389.596434 -397.873347)
			(xy 389.588913 -397.92076) (xy 389.574065 -397.966412) (xy 389.552255 -398.009177) (xy 389.52402 -398.048002)
			(xy 389.490057 -398.08193) (xy 389.451202 -398.110123) (xy 389.408414 -398.131888) (xy 389.362746 -398.146688)
			(xy 389.315325 -398.154159) (xy 389.291322 -398.154652) (xy 389.267793 -398.154211) (xy 389.221295 -398.146978)
			(xy 389.176458 -398.132694) (xy 389.134344 -398.111699) (xy 389.095951 -398.084489) (xy 389.062188 -398.051709)
			(xy 389.033856 -398.014137) (xy 389.022336 -397.993616) (xy 389.022082 -397.993108) (xy 389.021574 -397.992346)
			(xy 388.62381 -397.304006) (xy 388.61191 -397.281338) (xy 388.595032 -397.233008) (xy 388.586469 -397.182536)
			(xy 388.585964 -397.15694) (xy 388.585964 -397.156432) (xy 388.586048 -397.145087) (xy 388.587704 -397.122457)
			(xy 388.589266 -397.11122) (xy 388.590536 -397.10233) (xy 388.58698 -397.085058) (xy 388.543546 -397.013938)
			(xy 388.529576 -397.003016) (xy 388.521194 -396.999968) (xy 388.498791 -396.99195) (xy 388.456593 -396.969965)
			(xy 388.418315 -396.941701) (xy 388.384883 -396.907844) (xy 388.357107 -396.869212) (xy 388.335657 -396.826739)
			(xy 388.321054 -396.781454) (xy 388.31365 -396.734452) (xy 388.313168 -396.710662) (xy 388.313667 -396.685264)
			(xy 388.322066 -396.635166) (xy 388.338643 -396.587151) (xy 388.362939 -396.542542) (xy 388.394285 -396.50257)
			(xy 388.412736 -396.48511) (xy 388.421118 -396.47749) (xy 388.429754 -396.457424) (xy 388.42696 -396.35811)
			(xy 388.417562 -396.338552) (xy 388.408672 -396.33144) (xy 388.390112 -396.315637) (xy 388.357388 -396.279509)
			(xy 388.330318 -396.238972) (xy 388.309487 -396.194902) (xy 388.295346 -396.148253) (xy 388.288201 -396.100035)
			(xy 388.287768 -396.075662) (xy 388.288207 -396.051546) (xy 388.295212 -396.003825) (xy 388.309068 -395.957626)
			(xy 388.329482 -395.913927) (xy 388.342378 -395.893544) (xy 388.34822 -395.884654) (xy 388.351776 -395.864588)
			(xy 388.330694 -395.772386) (xy 388.318502 -395.755622) (xy 388.309612 -395.750288) (xy 388.288807 -395.737435)
			(xy 388.250883 -395.70656) (xy 388.217927 -395.670431) (xy 388.190658 -395.629837) (xy 388.169672 -395.585667)
			(xy 388.155428 -395.538884) (xy 388.148238 -395.490513) (xy 388.147814 -395.466062) (xy 388.147957 -395.451831)
			(xy 388.150372 -395.42347) (xy 388.15264 -395.40942) (xy 388.154926 -395.396974) (xy 388.14756 -395.37386)
			(xy 387.702806 -394.929106) (xy 387.695408 -394.922258) (xy 387.67681 -394.91452) (xy 387.666738 -394.91412)
			(xy 387.620002 -394.91412) (xy 387.59384 -394.932154) (xy 387.588252 -394.94714) (xy 387.578776 -394.971021)
			(xy 387.553525 -395.015762) (xy 387.521679 -395.056075) (xy 387.503162 -395.073886) (xy 387.495722 -395.081382)
			(xy 387.487195 -395.100676) (xy 387.486652 -395.111224) (xy 387.486652 -395.1859) (xy 387.487244 -395.196432)
			(xy 387.495784 -395.215696) (xy 387.503162 -395.223238) (xy 387.522815 -395.242171) (xy 387.556255 -395.285293)
			(xy 387.582159 -395.33332) (xy 387.599827 -395.384949) (xy 387.608776 -395.438778) (xy 387.609334 -395.466062)
			(xy 387.608901 -395.49018) (xy 387.601906 -395.537905) (xy 387.588058 -395.58411) (xy 387.567652 -395.627816)
			(xy 387.554724 -395.64818) (xy 387.548882 -395.65707) (xy 387.545326 -395.677136) (xy 387.566408 -395.769338)
			(xy 387.5786 -395.786102) (xy 387.58749 -395.791436) (xy 387.608294 -395.80429) (xy 387.646215 -395.835165)
			(xy 387.679169 -395.871295) (xy 387.706435 -395.911889) (xy 387.727417 -395.95606) (xy 387.741658 -396.002841)
			(xy 387.748844 -396.051211) (xy 387.749288 -396.075662) (xy 387.748851 -396.100033) (xy 387.741695 -396.148247)
			(xy 387.727548 -396.194891) (xy 387.706716 -396.238957) (xy 387.679647 -396.279492) (xy 387.646929 -396.315621)
			(xy 387.628384 -396.33144) (xy 387.619494 -396.338552) (xy 387.610096 -396.35811) (xy 387.607302 -396.457424)
			(xy 387.615938 -396.47749) (xy 387.62432 -396.48511) (xy 387.642741 -396.502598) (xy 387.674081 -396.542567)
			(xy 387.698376 -396.58717) (xy 387.714957 -396.635177) (xy 387.723366 -396.685267) (xy 387.723888 -396.710662)
			(xy 387.723797 -396.721944) (xy 387.722144 -396.744446) (xy 387.720586 -396.75562) (xy 387.719316 -396.764764)
			(xy 387.722618 -396.782036) (xy 387.766306 -396.853156) (xy 387.780022 -396.864078) (xy 387.788658 -396.866872)
			(xy 387.816789 -396.877143) (xy 387.868722 -396.906947) (xy 387.891782 -396.926054) (xy 387.91323 -396.945669)
			(xy 387.949034 -396.991443) (xy 387.962902 -397.016986) (xy 387.963664 -397.018256) (xy 388.35584 -397.696944)
			(xy 388.368647 -397.720277) (xy 388.386794 -397.770309) (xy 388.395977 -397.822733) (xy 388.39648 -397.849344)
			(xy 388.396006 -397.873332) (xy 388.388494 -397.920717) (xy 388.373663 -397.966343) (xy 388.351876 -398.009088)
			(xy 388.323672 -398.047898) (xy 388.289743 -398.081819) (xy 388.250926 -398.110014) (xy 388.208177 -398.13179)
			(xy 388.162547 -398.146611) (xy 388.11516 -398.154112) (xy 388.091172 -398.154652) (xy 388.067641 -398.154215)
			(xy 388.021138 -398.146988) (xy 387.976296 -398.132709) (xy 387.934175 -398.111717) (xy 387.895776 -398.08451)
			(xy 387.862007 -398.051731) (xy 387.83367 -398.014158) (xy 387.822186 -397.993616) (xy 387.821932 -397.993108)
			(xy 387.821424 -397.992346) (xy 387.420866 -397.298926) (xy 387.409754 -397.276835) (xy 387.394031 -397.229955)
			(xy 387.386063 -397.181155) (xy 387.38556 -397.156432) (xy 387.385711 -397.145083) (xy 387.387492 -397.122453)
			(xy 387.389116 -397.11122) (xy 387.390386 -397.10233) (xy 387.38683 -397.085058) (xy 387.343396 -397.013938)
			(xy 387.32968 -397.002762) (xy 387.321044 -396.999968) (xy 387.298657 -396.991939) (xy 387.256494 -396.969936)
			(xy 387.218253 -396.941661) (xy 387.18486 -396.907797) (xy 387.157123 -396.869165) (xy 387.135712 -396.826699)
			(xy 387.121145 -396.781426) (xy 387.113776 -396.734441) (xy 387.113272 -396.710662) (xy 387.113771 -396.685264)
			(xy 387.12217 -396.635166) (xy 387.138747 -396.587151) (xy 387.163044 -396.542542) (xy 387.19439 -396.502571)
			(xy 387.21284 -396.48511) (xy 387.221222 -396.47749) (xy 387.229858 -396.457424) (xy 387.227064 -396.35811)
			(xy 387.217666 -396.338552) (xy 387.208776 -396.33144) (xy 387.190216 -396.315637) (xy 387.157492 -396.279509)
			(xy 387.130421 -396.238972) (xy 387.109589 -396.194902) (xy 387.095448 -396.148253) (xy 387.088303 -396.100035)
			(xy 387.087872 -396.075662) (xy 387.088311 -396.051546) (xy 387.095316 -396.003825) (xy 387.109172 -395.957626)
			(xy 387.129586 -395.913928) (xy 387.142482 -395.893544) (xy 387.148324 -395.884654) (xy 387.15188 -395.864588)
			(xy 387.130798 -395.772386) (xy 387.118606 -395.755622) (xy 387.109716 -395.750288) (xy 387.088911 -395.737435)
			(xy 387.050987 -395.70656) (xy 387.01803 -395.670431) (xy 386.99076 -395.629838) (xy 386.969774 -395.585667)
			(xy 386.95553 -395.538885) (xy 386.94834 -395.490514) (xy 386.947918 -395.466062) (xy 386.948479 -395.43878)
			(xy 386.95744 -395.384956) (xy 386.975113 -395.333332) (xy 387.001019 -395.285309) (xy 387.034455 -395.242188)
			(xy 387.05409 -395.223238) (xy 387.06154 -395.215747) (xy 387.070085 -395.196451) (xy 387.0706 -395.1859)
			(xy 387.0706 -395.111224) (xy 387.070014 -395.100689) (xy 387.061486 -395.081412) (xy 387.05409 -395.073886)
			(xy 387.03462 -395.055153) (xy 387.00143 -395.012523) (xy 386.98805 -394.98905) (xy 386.982949 -394.98068)
			(xy 386.96778 -394.968291) (xy 386.949075 -394.962487) (xy 386.939282 -394.962888) (xy 386.891276 -394.96492)
			(xy 386.852274 -394.964252) (xy 386.774982 -394.953731) (xy 386.699797 -394.932949) (xy 386.663692 -394.918184)
			(xy 386.65404 -394.91412) (xy 386.419852 -394.91412) (xy 386.39369 -394.932154) (xy 386.388102 -394.94714)
			(xy 386.378627 -394.971022) (xy 386.353379 -395.015766) (xy 386.321536 -395.056083) (xy 386.303012 -395.073886)
			(xy 386.295566 -395.081379) (xy 386.28703 -395.100674) (xy 386.286502 -395.111224) (xy 386.286502 -395.1859)
			(xy 386.287093 -395.196433) (xy 386.295627 -395.215703) (xy 386.303012 -395.223238) (xy 386.322668 -395.24217)
			(xy 386.356112 -395.28529) (xy 386.382021 -395.333317) (xy 386.399691 -395.384947) (xy 386.408642 -395.438777)
			(xy 386.409184 -395.466062) (xy 386.408751 -395.490179) (xy 386.401755 -395.537904) (xy 386.387906 -395.584108)
			(xy 386.367497 -395.627813) (xy 386.354574 -395.64818) (xy 386.348732 -395.65707) (xy 386.345176 -395.677136)
			(xy 386.366258 -395.769338) (xy 386.37845 -395.786102) (xy 386.38734 -395.791436) (xy 386.408141 -395.804292)
			(xy 386.446057 -395.83517) (xy 386.479006 -395.871301) (xy 386.506268 -395.911895) (xy 386.527247 -395.956065)
			(xy 386.541485 -396.002845) (xy 386.54867 -396.051212) (xy 386.549138 -396.075662) (xy 386.5487 -396.100033)
			(xy 386.541544 -396.148246) (xy 386.527396 -396.194888) (xy 386.506561 -396.238952) (xy 386.47949 -396.279484)
			(xy 386.446768 -396.315609) (xy 386.428234 -396.33144) (xy 386.419344 -396.338552) (xy 386.409946 -396.35811)
			(xy 386.407152 -396.457424) (xy 386.415788 -396.47749) (xy 386.42417 -396.48511) (xy 386.442593 -396.502597)
			(xy 386.473938 -396.542564) (xy 386.498237 -396.587166) (xy 386.514821 -396.635175) (xy 386.523232 -396.685266)
			(xy 386.523738 -396.710662) (xy 386.523647 -396.721944) (xy 386.521993 -396.744446) (xy 386.520436 -396.75562)
			(xy 386.519166 -396.76451) (xy 386.522722 -396.782036) (xy 386.566156 -396.852902) (xy 386.579872 -396.864078)
			(xy 386.588508 -396.866872) (xy 386.61075 -396.874812) (xy 386.652665 -396.896568) (xy 386.690733 -396.924516)
			(xy 386.724046 -396.957989) (xy 386.751809 -396.996192) (xy 386.763006 -397.016986) (xy 386.763514 -397.018002)
			(xy 387.155944 -397.696944) (xy 387.168751 -397.720277) (xy 387.186898 -397.770309) (xy 387.196081 -397.822733)
			(xy 387.196584 -397.849344) (xy 387.19611 -397.873332) (xy 387.188598 -397.920717) (xy 387.173767 -397.966344)
			(xy 387.15198 -398.009089) (xy 387.123776 -398.047899) (xy 387.089848 -398.08182) (xy 387.051031 -398.110016)
			(xy 387.008281 -398.131793) (xy 386.962651 -398.146614) (xy 386.915264 -398.154115) (xy 386.891276 -398.154652)
			(xy 386.867745 -398.154215) (xy 386.821242 -398.146989) (xy 386.776399 -398.13271) (xy 386.734278 -398.111719)
			(xy 386.695878 -398.084512) (xy 386.662109 -398.051733) (xy 386.633771 -398.01416) (xy 386.62229 -397.993616)
			(xy 386.622036 -397.993108) (xy 386.621528 -397.992346) (xy 386.223764 -397.304006) (xy 386.211831 -397.281345)
			(xy 386.194882 -397.233021) (xy 386.186241 -397.182544) (xy 386.185664 -397.15694) (xy 386.185664 -397.156432)
			(xy 386.185815 -397.145083) (xy 386.187596 -397.122453) (xy 386.18922 -397.11122) (xy 386.19049 -397.10233)
			(xy 386.186934 -397.085058) (xy 386.1435 -397.013938) (xy 386.12953 -397.003016) (xy 386.121148 -396.999968)
			(xy 386.098747 -396.991947) (xy 386.056555 -396.969958) (xy 386.018283 -396.941693) (xy 385.984856 -396.907835)
			(xy 385.957084 -396.869203) (xy 385.935639 -396.826732) (xy 385.921038 -396.78145) (xy 385.913635 -396.734451)
			(xy 385.913122 -396.710662) (xy 385.913622 -396.685264) (xy 385.922022 -396.635168) (xy 385.938601 -396.587154)
			(xy 385.9629 -396.542548) (xy 385.99425 -396.502581) (xy 386.01269 -396.48511) (xy 386.021072 -396.47749)
			(xy 386.029708 -396.457424) (xy 386.026914 -396.35811) (xy 386.017516 -396.338552) (xy 386.008626 -396.33144)
			(xy 385.990064 -396.315638) (xy 385.957334 -396.279513) (xy 385.93026 -396.238976) (xy 385.909425 -396.194906)
			(xy 385.895281 -396.148256) (xy 385.888135 -396.100036) (xy 385.887722 -396.075662) (xy 385.888161 -396.051546)
			(xy 385.895167 -396.003826) (xy 385.909025 -395.957628) (xy 385.929442 -395.913931) (xy 385.942332 -395.893544)
			(xy 385.948174 -395.884654) (xy 385.95173 -395.864588) (xy 385.930648 -395.772386) (xy 385.918456 -395.755622)
			(xy 385.909566 -395.750288) (xy 385.888763 -395.737433) (xy 385.850845 -395.706556) (xy 385.817893 -395.670425)
			(xy 385.790627 -395.629832) (xy 385.769645 -395.585662) (xy 385.755403 -395.538881) (xy 385.748214 -395.490512)
			(xy 385.747768 -395.466062) (xy 385.748329 -395.438779) (xy 385.757289 -395.384954) (xy 385.77496 -395.333329)
			(xy 385.800863 -395.285303) (xy 385.834295 -395.242179) (xy 385.85394 -395.223238) (xy 385.861384 -395.215744)
			(xy 385.869919 -395.196449) (xy 385.87045 -395.1859) (xy 385.87045 -395.111224) (xy 385.869862 -395.10069)
			(xy 385.861329 -395.081419) (xy 385.85394 -395.073886) (xy 385.834472 -395.055151) (xy 385.801287 -395.012519)
			(xy 385.7879 -394.98905) (xy 385.782796 -394.980686) (xy 385.767626 -394.968312) (xy 385.748924 -394.962526)
			(xy 385.739132 -394.962888) (xy 385.691126 -394.96492) (xy 385.652125 -394.964249) (xy 385.574835 -394.953721)
			(xy 385.499653 -394.932934) (xy 385.463542 -394.918184) (xy 385.45389 -394.91412) (xy 385.219956 -394.91412)
			(xy 385.193794 -394.932154) (xy 385.188206 -394.94714) (xy 385.178731 -394.971022) (xy 385.153484 -395.015766)
			(xy 385.12164 -395.056083) (xy 385.103116 -395.073886) (xy 385.095669 -395.081379) (xy 385.087133 -395.100674)
			(xy 385.086606 -395.111224) (xy 385.086606 -395.1859) (xy 385.087197 -395.196433) (xy 385.095731 -395.215702)
			(xy 385.103116 -395.223238) (xy 385.122772 -395.24217) (xy 385.156215 -395.28529) (xy 385.182124 -395.333317)
			(xy 385.199794 -395.384947) (xy 385.208745 -395.438777) (xy 385.209288 -395.466062) (xy 385.208855 -395.49018)
			(xy 385.201859 -395.537904) (xy 385.18801 -395.584108) (xy 385.167601 -395.627813) (xy 385.154678 -395.64818)
			(xy 385.148836 -395.65707) (xy 385.14528 -395.677136) (xy 385.166362 -395.769338) (xy 385.178554 -395.786102)
			(xy 385.187444 -395.791436) (xy 385.208245 -395.804292) (xy 385.24616 -395.835171) (xy 385.279109 -395.871302)
			(xy 385.30637 -395.911896) (xy 385.327349 -395.956065) (xy 385.341587 -396.002845) (xy 385.348772 -396.051213)
			(xy 385.349242 -396.075662) (xy 385.348804 -396.100033) (xy 385.341648 -396.148246) (xy 385.3275 -396.194888)
			(xy 385.306665 -396.238952) (xy 385.279595 -396.279485) (xy 385.246873 -396.31561) (xy 385.228338 -396.33144)
			(xy 385.219448 -396.338552) (xy 385.21005 -396.35811) (xy 385.207256 -396.457424) (xy 385.215892 -396.47749)
			(xy 385.224274 -396.48511) (xy 385.242697 -396.502597) (xy 385.274042 -396.542564) (xy 385.298341 -396.587167)
			(xy 385.314924 -396.635175) (xy 385.323335 -396.685266) (xy 385.323842 -396.710662) (xy 385.323751 -396.721944)
			(xy 385.322098 -396.744446) (xy 385.32054 -396.75562) (xy 385.31927 -396.764764) (xy 385.322572 -396.782036)
			(xy 385.36626 -396.853156) (xy 385.379976 -396.864078) (xy 385.388612 -396.866872) (xy 385.416741 -396.877147)
			(xy 385.468668 -396.906957) (xy 385.491736 -396.926054) (xy 385.513181 -396.945671) (xy 385.54898 -396.991448)
			(xy 385.562856 -397.016986) (xy 385.563618 -397.018256) (xy 385.955794 -397.696944) (xy 385.968579 -397.720294)
			(xy 385.986773 -397.770317) (xy 385.996058 -397.82273) (xy 385.996688 -397.849344) (xy 385.996238 -397.873347)
			(xy 385.988717 -397.92076) (xy 385.973869 -397.966413) (xy 385.952059 -398.009178) (xy 385.923824 -398.048003)
			(xy 385.889861 -398.081931) (xy 385.851007 -398.110125) (xy 385.808218 -398.131891) (xy 385.762551 -398.146692)
			(xy 385.71513 -398.154162) (xy 385.691126 -398.154652) (xy 385.667597 -398.154212) (xy 385.621099 -398.146979)
			(xy 385.576261 -398.132695) (xy 385.534146 -398.1117) (xy 385.495753 -398.08449) (xy 385.46199 -398.051711)
			(xy 385.433657 -398.014139) (xy 385.42214 -397.993616) (xy 385.421886 -397.993108) (xy 385.421378 -397.992346)
			(xy 385.02082 -397.298926) (xy 385.009752 -397.276825) (xy 384.994113 -397.229938) (xy 384.986221 -397.181146)
			(xy 384.985768 -397.156432) (xy 384.985852 -397.145087) (xy 384.987508 -397.122457) (xy 384.98907 -397.11122)
			(xy 384.99034 -397.10233) (xy 384.986784 -397.085058) (xy 384.94335 -397.013938) (xy 384.929634 -397.002762)
			(xy 384.920998 -396.999968) (xy 384.898608 -396.991942) (xy 384.856438 -396.969943) (xy 384.818191 -396.941671)
			(xy 384.784792 -396.907808) (xy 384.757049 -396.869175) (xy 384.735634 -396.826707) (xy 384.721064 -396.781431)
			(xy 384.713693 -396.734443) (xy 384.713226 -396.710662) (xy 384.713726 -396.685264) (xy 384.722126 -396.635168)
			(xy 384.738705 -396.587155) (xy 384.763005 -396.542549) (xy 384.794354 -396.502582) (xy 384.812794 -396.48511)
			(xy 384.821176 -396.47749) (xy 384.829812 -396.457424) (xy 384.827018 -396.35811) (xy 384.81762 -396.338552)
			(xy 384.80873 -396.33144) (xy 384.790167 -396.315638) (xy 384.757438 -396.279513) (xy 384.730363 -396.238976)
			(xy 384.709528 -396.194906) (xy 384.695384 -396.148256) (xy 384.688238 -396.100036) (xy 384.687826 -396.075662)
			(xy 384.688265 -396.051546) (xy 384.695271 -396.003826) (xy 384.709129 -395.957628) (xy 384.729546 -395.913931)
			(xy 384.742436 -395.893544) (xy 384.748278 -395.884654) (xy 384.751834 -395.864588) (xy 384.730752 -395.772386)
			(xy 384.71856 -395.755622) (xy 384.70967 -395.750288) (xy 384.688867 -395.737433) (xy 384.650948 -395.706556)
			(xy 384.617996 -395.670426) (xy 384.59073 -395.629832) (xy 384.569747 -395.585662) (xy 384.555505 -395.538882)
			(xy 384.548316 -395.490512) (xy 384.547872 -395.466062) (xy 384.548433 -395.438779) (xy 384.557393 -395.384954)
			(xy 384.575064 -395.333329) (xy 384.600967 -395.285304) (xy 384.6344 -395.24218) (xy 384.654044 -395.223238)
			(xy 384.661499 -395.215749) (xy 384.670052 -395.196453) (xy 384.670554 -395.1859) (xy 384.670554 -395.111224)
			(xy 384.669967 -395.10069) (xy 384.661433 -395.081418) (xy 384.654044 -395.073886) (xy 384.634576 -395.055151)
			(xy 384.601391 -395.012519) (xy 384.588004 -394.98905) (xy 384.5829 -394.980685) (xy 384.56773 -394.968311)
			(xy 384.549028 -394.962523) (xy 384.539236 -394.962888) (xy 384.49123 -394.96492) (xy 384.452229 -394.964249)
			(xy 384.374939 -394.953722) (xy 384.299756 -394.932935) (xy 384.263646 -394.918184) (xy 384.253994 -394.91412)
			(xy 384.019806 -394.91412) (xy 383.993644 -394.932154) (xy 383.988056 -394.94714) (xy 383.978823 -394.970448)
			(xy 383.954342 -395.014195) (xy 383.923541 -395.053747) (xy 383.887125 -395.0882) (xy 383.845928 -395.116763)
			(xy 383.800892 -395.138784) (xy 383.753049 -395.153757) (xy 383.703495 -395.161341) (xy 383.67843 -395.16177)
			(xy 383.653076 -395.16128) (xy 383.602964 -395.153533) (xy 383.554621 -395.13823) (xy 383.509179 -395.115729)
			(xy 383.467702 -395.086559) (xy 383.431161 -395.051402) (xy 383.400413 -395.01108) (xy 383.387854 -394.98905)
			(xy 383.382753 -394.980679) (xy 383.367584 -394.968289) (xy 383.348879 -394.962484) (xy 383.339086 -394.962888)
			(xy 383.291334 -394.96492) (xy 383.252333 -394.964249) (xy 383.175043 -394.953723) (xy 383.09986 -394.932937)
			(xy 383.06375 -394.918184) (xy 383.054098 -394.91412) (xy 382.81991 -394.91412) (xy 382.793748 -394.932154)
			(xy 382.78816 -394.94714) (xy 382.781328 -394.964584) (xy 382.764269 -394.997939) (xy 382.754124 -395.013688)
			(xy 382.749371 -395.021658) (xy 382.745347 -395.039757) (xy 382.74625 -395.048994) (xy 382.750568 -395.079982)
			(xy 382.752371 -395.089236) (xy 382.761624 -395.105645) (xy 382.768602 -395.111986) (xy 382.790698 -395.13066)
			(xy 382.830474 -395.172669) (xy 382.864638 -395.219357) (xy 382.892646 -395.269978) (xy 382.91405 -395.323726)
			(xy 382.928509 -395.379743) (xy 382.935793 -395.437136) (xy 382.936242 -395.466062) (xy 382.935638 -395.499382)
			(xy 382.925968 -395.565316) (xy 382.906841 -395.629152) (xy 382.893316 -395.65961) (xy 382.889057 -395.67008)
			(xy 382.889132 -395.692655) (xy 382.898879 -395.713016) (xy 382.907286 -395.72057) (xy 382.929535 -395.739243)
			(xy 382.969603 -395.781297) (xy 383.004028 -395.828082) (xy 383.032257 -395.878847) (xy 383.053837 -395.932775)
			(xy 383.068421 -395.989001) (xy 383.075775 -396.046619) (xy 383.076196 -396.075662) (xy 383.075745 -396.104666)
			(xy 383.068414 -396.162209) (xy 383.053878 -396.218366) (xy 383.032368 -396.272238) (xy 383.004229 -396.322964)
			(xy 382.969911 -396.369731) (xy 382.929963 -396.411792) (xy 382.907794 -396.4305) (xy 382.900682 -396.436088)
			(xy 382.891538 -396.451328) (xy 382.876298 -396.534132) (xy 382.879092 -396.551404) (xy 382.883664 -396.559532)
			(xy 382.896259 -396.58271) (xy 382.914148 -396.63233) (xy 382.923231 -396.684289) (xy 382.923796 -396.710662)
			(xy 383.513076 -396.710662) (xy 383.513598 -396.685407) (xy 383.521911 -396.635585) (xy 383.538312 -396.587811)
			(xy 383.562353 -396.543388) (xy 383.593377 -396.503528) (xy 383.630539 -396.469318) (xy 383.672825 -396.441692)
			(xy 383.719081 -396.421402) (xy 383.768046 -396.409002) (xy 383.818384 -396.404831) (xy 383.868722 -396.409002)
			(xy 383.917687 -396.421402) (xy 383.963943 -396.441692) (xy 384.006229 -396.469318) (xy 384.043391 -396.503528)
			(xy 384.074415 -396.543388) (xy 384.098456 -396.587811) (xy 384.114857 -396.635585) (xy 384.12317 -396.685407)
			(xy 384.123692 -396.710662) (xy 384.123588 -396.721943) (xy 384.121937 -396.744445) (xy 384.12039 -396.75562)
			(xy 384.11912 -396.76451) (xy 384.122676 -396.782036) (xy 384.16611 -396.852902) (xy 384.179826 -396.864078)
			(xy 384.188462 -396.866872) (xy 384.210708 -396.874804) (xy 384.252629 -396.896556) (xy 384.290703 -396.924501)
			(xy 384.324021 -396.957974) (xy 384.351789 -396.996176) (xy 384.36296 -397.016986) (xy 384.363468 -397.018002)
			(xy 384.755898 -397.696944) (xy 384.768701 -397.720288) (xy 384.78693 -397.770305) (xy 384.796199 -397.822727)
			(xy 384.796792 -397.849344) (xy 384.796401 -397.873352) (xy 384.78888 -397.920775) (xy 384.774029 -397.966436)
			(xy 384.752214 -398.009211) (xy 384.723974 -398.048044) (xy 384.690005 -398.081979) (xy 384.651142 -398.110179)
			(xy 384.608346 -398.131949) (xy 384.562669 -398.146753) (xy 384.515238 -398.154226) (xy 384.49123 -398.154652)
			(xy 384.467698 -398.154225) (xy 384.421189 -398.147014) (xy 384.37634 -398.132743) (xy 384.334216 -398.111751)
			(xy 384.295818 -398.084536) (xy 384.262057 -398.051746) (xy 384.233734 -398.014157) (xy 384.222244 -397.993616)
			(xy 384.22199 -397.993108) (xy 384.221482 -397.992346) (xy 383.823718 -397.304006) (xy 383.811839 -397.281331)
			(xy 383.79499 -397.232997) (xy 383.786418 -397.182533) (xy 383.785872 -397.15694) (xy 383.785872 -397.156432)
			(xy 383.785964 -397.145087) (xy 383.787618 -397.122458) (xy 383.789174 -397.11122) (xy 383.790444 -397.10233)
			(xy 383.786888 -397.085058) (xy 383.743454 -397.013938) (xy 383.729484 -397.003016) (xy 383.721102 -396.999968)
			(xy 383.698691 -396.991959) (xy 383.656474 -396.969994) (xy 383.618178 -396.941742) (xy 383.584734 -396.907886)
			(xy 383.556951 -396.869249) (xy 383.535503 -396.826767) (xy 383.520911 -396.78147) (xy 383.513529 -396.734457)
			(xy 383.513076 -396.710662) (xy 382.923796 -396.710662) (xy 382.923705 -396.721944) (xy 382.922052 -396.744446)
			(xy 382.920494 -396.75562) (xy 382.919224 -396.76451) (xy 382.92278 -396.782036) (xy 382.966214 -396.852902)
			(xy 382.97993 -396.864078) (xy 382.988566 -396.866872) (xy 383.01081 -396.87481) (xy 383.05273 -396.896561)
			(xy 383.090802 -396.924506) (xy 383.124119 -396.957979) (xy 383.151887 -396.99618) (xy 383.163064 -397.016986)
			(xy 383.163572 -397.018002) (xy 383.556002 -397.696944) (xy 383.568786 -397.720294) (xy 383.58698 -397.770317)
			(xy 383.596264 -397.822731) (xy 383.596896 -397.849344) (xy 383.596446 -397.873347) (xy 383.588925 -397.920761)
			(xy 383.574077 -397.966414) (xy 383.552267 -398.00918) (xy 383.524033 -398.048006) (xy 383.49007 -398.081934)
			(xy 383.451215 -398.110129) (xy 383.408427 -398.131896) (xy 383.362759 -398.146698) (xy 383.315338 -398.15417)
			(xy 383.291334 -398.154652) (xy 383.267805 -398.154212) (xy 383.221306 -398.14698) (xy 383.176467 -398.132698)
			(xy 383.134351 -398.111703) (xy 383.095957 -398.084494) (xy 383.062193 -398.051715) (xy 383.033859 -398.014142)
			(xy 383.022348 -397.993616) (xy 383.022094 -397.993108) (xy 383.021586 -397.992346) (xy 382.623822 -397.304006)
			(xy 382.611925 -397.281337) (xy 382.595052 -397.233006) (xy 382.586491 -397.182536) (xy 382.585976 -397.15694)
			(xy 382.585976 -397.156432) (xy 382.58606 -397.145087) (xy 382.587716 -397.122457) (xy 382.589278 -397.11122)
			(xy 382.590548 -397.10233) (xy 382.586992 -397.085058) (xy 382.543558 -397.013938) (xy 382.529588 -397.003016)
			(xy 382.521206 -396.999968) (xy 382.498802 -396.99195) (xy 382.456603 -396.969966) (xy 382.418323 -396.941704)
			(xy 382.38489 -396.907847) (xy 382.357113 -396.869214) (xy 382.335662 -396.826741) (xy 382.321058 -396.781456)
			(xy 382.313654 -396.734453) (xy 382.31318 -396.710662) (xy 382.313762 -396.684292) (xy 382.322864 -396.632341)
			(xy 382.340741 -396.582721) (xy 382.353312 -396.559532) (xy 382.357884 -396.551404) (xy 382.360678 -396.534132)
			(xy 382.345438 -396.451328) (xy 382.336294 -396.436088) (xy 382.329182 -396.4305) (xy 382.306991 -396.411816)
			(xy 382.267038 -396.369757) (xy 382.232718 -396.322988) (xy 382.204582 -396.272257) (xy 382.18308 -396.218379)
			(xy 382.168557 -396.162216) (xy 382.161245 -396.104667) (xy 382.16078 -396.075662) (xy 382.161383 -396.042342)
			(xy 382.171048 -395.976405) (xy 382.190168 -395.912566) (xy 382.203706 -395.882114) (xy 382.207976 -395.871644)
			(xy 382.20791 -395.849064) (xy 382.198155 -395.828699) (xy 382.189736 -395.821154) (xy 382.167489 -395.80248)
			(xy 382.127427 -395.760425) (xy 382.093008 -395.713639) (xy 382.064786 -395.662873) (xy 382.043213 -395.608945)
			(xy 382.028638 -395.55272) (xy 382.021293 -395.495104) (xy 382.020826 -395.466062) (xy 382.021271 -395.437137)
			(xy 382.028565 -395.379747) (xy 382.043031 -395.323734) (xy 382.064439 -395.26999) (xy 382.092448 -395.219371)
			(xy 382.126611 -395.172685) (xy 382.166384 -395.130675) (xy 382.188466 -395.111986) (xy 382.195537 -395.10572)
			(xy 382.204818 -395.089278) (xy 382.2065 -395.079982) (xy 382.210818 -395.048994) (xy 382.211766 -395.039756)
			(xy 382.207733 -395.021644) (xy 382.202944 -395.013688) (xy 382.187958 -394.98905) (xy 382.182857 -394.980679)
			(xy 382.167689 -394.968288) (xy 382.148983 -394.962481) (xy 382.13919 -394.962888) (xy 382.091184 -394.96492)
			(xy 382.052184 -394.964246) (xy 381.974896 -394.953713) (xy 381.899716 -394.932921) (xy 381.8636 -394.918184)
			(xy 381.853948 -394.91412) (xy 381.61976 -394.91412) (xy 381.593598 -394.932154) (xy 381.58801 -394.94714)
			(xy 381.578535 -394.971022) (xy 381.553288 -395.015766) (xy 381.521445 -395.056084) (xy 381.50292 -395.073886)
			(xy 381.495473 -395.081378) (xy 381.486936 -395.100674) (xy 381.48641 -395.111224) (xy 381.48641 -395.1859)
			(xy 381.487001 -395.196433) (xy 381.495536 -395.215702) (xy 381.50292 -395.223238) (xy 381.522575 -395.24217)
			(xy 381.556019 -395.285291) (xy 381.581927 -395.333317) (xy 381.599597 -395.384947) (xy 381.608548 -395.438777)
			(xy 381.609092 -395.466062) (xy 381.608659 -395.49018) (xy 381.601663 -395.537904) (xy 381.587814 -395.584109)
			(xy 381.567405 -395.627813) (xy 381.554482 -395.64818) (xy 381.54864 -395.65707) (xy 381.545084 -395.677136)
			(xy 381.566166 -395.769338) (xy 381.578358 -395.786102) (xy 381.587248 -395.791436) (xy 381.608049 -395.804292)
			(xy 381.645964 -395.835171) (xy 381.678912 -395.871302) (xy 381.706173 -395.911896) (xy 381.727151 -395.956066)
			(xy 381.741389 -396.002845) (xy 381.748574 -396.051213) (xy 381.749046 -396.075662) (xy 381.748608 -396.100033)
			(xy 381.741452 -396.148246) (xy 381.727304 -396.194889) (xy 381.70647 -396.238953) (xy 381.679399 -396.279485)
			(xy 381.646678 -396.315611) (xy 381.628142 -396.33144) (xy 381.619252 -396.338552) (xy 381.609854 -396.35811)
			(xy 381.60706 -396.457424) (xy 381.615696 -396.47749) (xy 381.624078 -396.48511) (xy 381.642501 -396.502597)
			(xy 381.673845 -396.542564) (xy 381.698144 -396.587167) (xy 381.714727 -396.635175) (xy 381.723138 -396.685266)
			(xy 381.723646 -396.710662) (xy 381.723555 -396.721944) (xy 381.721902 -396.744446) (xy 381.720344 -396.75562)
			(xy 381.719074 -396.76451) (xy 381.72263 -396.782036) (xy 381.766064 -396.852902) (xy 381.77978 -396.864078)
			(xy 381.788416 -396.866872) (xy 381.810658 -396.874813) (xy 381.852572 -396.896569) (xy 381.890639 -396.924517)
			(xy 381.923951 -396.957991) (xy 381.951713 -396.996194) (xy 381.962914 -397.016986) (xy 381.963422 -397.018002)
			(xy 382.355852 -397.696944) (xy 382.368662 -397.720276) (xy 382.386814 -397.770308) (xy 382.396 -397.822732)
			(xy 382.396492 -397.849344) (xy 382.396018 -397.873333) (xy 382.388506 -397.920718) (xy 382.373675 -397.966345)
			(xy 382.351889 -398.00909) (xy 382.323684 -398.047902) (xy 382.289756 -398.081823) (xy 382.250939 -398.11002)
			(xy 382.20819 -398.131798) (xy 382.16256 -398.14662) (xy 382.115173 -398.154123) (xy 382.091184 -398.154652)
			(xy 382.067653 -398.154216) (xy 382.021149 -398.14699) (xy 381.976305 -398.132713) (xy 381.934183 -398.111722)
			(xy 381.895782 -398.084515) (xy 381.862012 -398.051737) (xy 381.833673 -398.014163) (xy 381.822198 -397.993616)
			(xy 381.821944 -397.993108) (xy 381.821436 -397.992346) (xy 381.423672 -397.304006) (xy 381.411739 -397.281345)
			(xy 381.394789 -397.233021) (xy 381.386148 -397.182544) (xy 381.385572 -397.15694) (xy 381.385572 -397.156432)
			(xy 381.385723 -397.145083) (xy 381.387504 -397.122453) (xy 381.389128 -397.11122) (xy 381.390398 -397.10233)
			(xy 381.386842 -397.085058) (xy 381.343408 -397.013938) (xy 381.329438 -397.003016) (xy 381.321056 -396.999968)
			(xy 381.298655 -396.991948) (xy 381.256462 -396.969959) (xy 381.218188 -396.941694) (xy 381.184761 -396.907836)
			(xy 381.156988 -396.869205) (xy 381.135542 -396.826734) (xy 381.120941 -396.781451) (xy 381.113538 -396.734451)
			(xy 381.11303 -396.710662) (xy 381.11353 -396.685264) (xy 381.12193 -396.635168) (xy 381.138509 -396.587155)
			(xy 381.162809 -396.542549) (xy 381.194159 -396.502582) (xy 381.212598 -396.48511) (xy 381.22098 -396.47749)
			(xy 381.229616 -396.457424) (xy 381.226822 -396.35811) (xy 381.217424 -396.338552) (xy 381.208534 -396.33144)
			(xy 381.189971 -396.315639) (xy 381.157241 -396.279513) (xy 381.130166 -396.238977) (xy 381.109331 -396.194906)
			(xy 381.095187 -396.148256) (xy 381.08804 -396.100036) (xy 381.08763 -396.075662) (xy 381.088069 -396.051546)
			(xy 381.095075 -396.003826) (xy 381.108933 -395.957628) (xy 381.129351 -395.913931) (xy 381.14224 -395.893544)
			(xy 381.148082 -395.884654) (xy 381.151638 -395.864588) (xy 381.130556 -395.772386) (xy 381.118364 -395.755622)
			(xy 381.109474 -395.750288) (xy 381.088671 -395.737433) (xy 381.050751 -395.706556) (xy 381.017799 -395.670426)
			(xy 380.990533 -395.629833) (xy 380.969549 -395.585663) (xy 380.955308 -395.538882) (xy 380.948118 -395.490513)
			(xy 380.947676 -395.466062) (xy 380.948237 -395.438779) (xy 380.957197 -395.384954) (xy 380.974869 -395.333329)
			(xy 381.000772 -395.285304) (xy 381.034205 -395.242181) (xy 381.053848 -395.223238) (xy 381.061303 -395.215749)
			(xy 381.069855 -395.196453) (xy 381.070358 -395.1859) (xy 381.070358 -395.111224) (xy 381.069771 -395.10069)
			(xy 381.061238 -395.081418) (xy 381.053848 -395.073886) (xy 381.03438 -395.055151) (xy 381.001194 -395.012519)
			(xy 380.987808 -394.98905) (xy 380.982704 -394.980685) (xy 380.967535 -394.968309) (xy 380.948832 -394.96252)
			(xy 380.93904 -394.962888) (xy 380.891288 -394.96492) (xy 380.852287 -394.964246) (xy 380.774999 -394.953714)
			(xy 380.699819 -394.932922) (xy 380.663704 -394.918184) (xy 380.654052 -394.91412) (xy 380.419864 -394.91412)
			(xy 380.393702 -394.932154) (xy 380.388114 -394.94714) (xy 380.378639 -394.971022) (xy 380.353392 -395.015767)
			(xy 380.321549 -395.056084) (xy 380.303024 -395.073886) (xy 380.295576 -395.081378) (xy 380.287038 -395.100674)
			(xy 380.286514 -395.111224) (xy 380.286514 -395.1859) (xy 380.287105 -395.196433) (xy 380.295641 -395.215701)
			(xy 380.303024 -395.223238) (xy 380.322679 -395.24217) (xy 380.356122 -395.285291) (xy 380.38203 -395.333318)
			(xy 380.399699 -395.384947) (xy 380.408651 -395.438777) (xy 380.409196 -395.466062) (xy 380.408763 -395.49018)
			(xy 380.401767 -395.537905) (xy 380.387918 -395.584109) (xy 380.36751 -395.627813) (xy 380.354586 -395.64818)
			(xy 380.348744 -395.65707) (xy 380.345188 -395.677136) (xy 380.36627 -395.769338) (xy 380.378462 -395.786102)
			(xy 380.387352 -395.791436) (xy 380.408153 -395.804292) (xy 380.446067 -395.835171) (xy 380.479015 -395.871303)
			(xy 380.506275 -395.911897) (xy 380.527254 -395.956066) (xy 380.541491 -396.002845) (xy 380.548676 -396.051213)
			(xy 380.54915 -396.075662) (xy 380.548712 -396.100033) (xy 380.541557 -396.148246) (xy 380.527408 -396.194889)
			(xy 380.506574 -396.238953) (xy 380.479504 -396.279486) (xy 380.446783 -396.315612) (xy 380.428246 -396.33144)
			(xy 380.419356 -396.338552) (xy 380.409958 -396.35811) (xy 380.407164 -396.457424) (xy 380.4158 -396.47749)
			(xy 380.424182 -396.48511) (xy 380.442605 -396.502597) (xy 380.473948 -396.542565) (xy 380.498247 -396.587167)
			(xy 380.51483 -396.635176) (xy 380.52324 -396.685266) (xy 380.52375 -396.710662) (xy 380.523659 -396.721944)
			(xy 380.522006 -396.744446) (xy 380.520448 -396.75562) (xy 380.519178 -396.76451) (xy 380.522734 -396.782036)
			(xy 380.566168 -396.852902) (xy 380.579884 -396.864078) (xy 380.58852 -396.866872) (xy 380.610761 -396.874813)
			(xy 380.652676 -396.89657) (xy 380.690742 -396.924518) (xy 380.724053 -396.957992) (xy 380.751816 -396.996195)
			(xy 380.763018 -397.016986) (xy 380.763526 -397.018002) (xy 381.155956 -397.696944) (xy 381.168766 -397.720276)
			(xy 381.186918 -397.770308) (xy 381.196104 -397.822732) (xy 381.196596 -397.849344) (xy 381.196122 -397.873333)
			(xy 381.18861 -397.920718) (xy 381.173779 -397.966346) (xy 381.151993 -398.009091) (xy 381.123789 -398.047903)
			(xy 381.08986 -398.081825) (xy 381.051044 -398.110022) (xy 381.008294 -398.1318) (xy 380.962664 -398.146624)
			(xy 380.915277 -398.154126) (xy 380.891288 -398.154652) (xy 380.867757 -398.154216) (xy 380.821252 -398.146991)
			(xy 380.776408 -398.132714) (xy 380.734286 -398.111724) (xy 380.695884 -398.084517) (xy 380.662114 -398.051738)
			(xy 380.633774 -398.014165) (xy 380.622302 -397.993616) (xy 380.622048 -397.993108) (xy 380.62154 -397.992346)
			(xy 380.223776 -397.304006) (xy 380.211843 -397.281345) (xy 380.194893 -397.233021) (xy 380.186251 -397.182544)
			(xy 380.185676 -397.15694) (xy 380.185676 -397.156432) (xy 380.185827 -397.145083) (xy 380.187608 -397.122453)
			(xy 380.189232 -397.11122) (xy 380.190502 -397.10233) (xy 380.186946 -397.085058) (xy 380.143512 -397.013938)
			(xy 380.129542 -397.003016) (xy 380.12116 -396.999968) (xy 380.098759 -396.991948) (xy 380.056565 -396.96996)
			(xy 380.018291 -396.941695) (xy 379.984863 -396.907837) (xy 379.95709 -396.869205) (xy 379.935643 -396.826734)
			(xy 379.921042 -396.781451) (xy 379.913639 -396.734451) (xy 379.913134 -396.710662) (xy 379.913634 -396.685264)
			(xy 379.922034 -396.635169) (xy 379.938613 -396.587155) (xy 379.962914 -396.54255) (xy 379.994264 -396.502583)
			(xy 380.012702 -396.48511) (xy 380.021084 -396.47749) (xy 380.02972 -396.457424) (xy 380.026926 -396.35811)
			(xy 380.017528 -396.338552) (xy 380.008638 -396.33144) (xy 379.990075 -396.315639) (xy 379.957345 -396.279513)
			(xy 379.930269 -396.238977) (xy 379.909433 -396.194907) (xy 379.895289 -396.148256) (xy 379.888143 -396.100036)
			(xy 379.887734 -396.075662) (xy 379.888173 -396.051546) (xy 379.895179 -396.003826) (xy 379.909038 -395.957629)
			(xy 379.929455 -395.913932) (xy 379.942344 -395.893544) (xy 379.948186 -395.884654) (xy 379.951742 -395.864588)
			(xy 379.93066 -395.772386) (xy 379.918468 -395.755622) (xy 379.909578 -395.750288) (xy 379.888775 -395.737434)
			(xy 379.850855 -395.706557) (xy 379.817902 -395.670427) (xy 379.790635 -395.629833) (xy 379.769652 -395.585663)
			(xy 379.75541 -395.538882) (xy 379.74822 -395.490513) (xy 379.74778 -395.466062) (xy 379.748341 -395.438779)
			(xy 379.757301 -395.384954) (xy 379.774973 -395.33333) (xy 379.800876 -395.285305) (xy 379.83431 -395.242181)
			(xy 379.853952 -395.223238) (xy 379.861406 -395.215749) (xy 379.869958 -395.196453) (xy 379.870462 -395.1859)
			(xy 379.870462 -395.111224) (xy 379.869875 -395.10069) (xy 379.861342 -395.081417) (xy 379.853952 -395.073886)
			(xy 379.834484 -395.055151) (xy 379.801297 -395.01252) (xy 379.787912 -394.98905) (xy 379.782809 -394.980684)
			(xy 379.767639 -394.968307) (xy 379.748937 -394.962517) (xy 379.739144 -394.962888) (xy 379.691138 -394.96492)
			(xy 379.652137 -394.964249) (xy 379.574846 -394.953724) (xy 379.499663 -394.932938) (xy 379.463554 -394.918184)
			(xy 379.453902 -394.91412) (xy 379.219968 -394.91412) (xy 379.193806 -394.932154) (xy 379.188218 -394.94714)
			(xy 379.178741 -394.97102) (xy 379.153489 -395.01576) (xy 379.12164 -395.056071) (xy 379.103128 -395.073886)
			(xy 379.09568 -395.081378) (xy 379.087141 -395.100673) (xy 379.086618 -395.111224) (xy 379.086618 -395.1859)
			(xy 379.087209 -395.196433) (xy 379.095745 -395.215701) (xy 379.103128 -395.223238) (xy 379.122783 -395.24217)
			(xy 379.156226 -395.285291) (xy 379.182133 -395.333318) (xy 379.199802 -395.384947) (xy 379.208753 -395.438777)
			(xy 379.2093 -395.466062) (xy 379.208867 -395.49018) (xy 379.201871 -395.537905) (xy 379.188023 -395.584109)
			(xy 379.167614 -395.627814) (xy 379.15469 -395.64818) (xy 379.148848 -395.65707) (xy 379.145292 -395.677136)
			(xy 379.166374 -395.769338) (xy 379.178566 -395.786102) (xy 379.187456 -395.791436) (xy 379.208257 -395.804292)
			(xy 379.24617 -395.835172) (xy 379.279118 -395.871303) (xy 379.306378 -395.911897) (xy 379.327356 -395.956066)
			(xy 379.341593 -396.002846) (xy 379.348778 -396.051213) (xy 379.349254 -396.075662) (xy 379.348816 -396.100033)
			(xy 379.341661 -396.148246) (xy 379.327513 -396.194889) (xy 379.306678 -396.238953) (xy 379.279608 -396.279487)
			(xy 379.246888 -396.315613) (xy 379.22835 -396.33144) (xy 379.21946 -396.338552) (xy 379.210062 -396.35811)
			(xy 379.207268 -396.457424) (xy 379.215904 -396.47749) (xy 379.224286 -396.48511) (xy 379.242709 -396.502597)
			(xy 379.274052 -396.542565) (xy 379.29835 -396.587167) (xy 379.314933 -396.635176) (xy 379.323343 -396.685266)
			(xy 379.323854 -396.710662) (xy 379.323763 -396.721944) (xy 379.32211 -396.744446) (xy 379.320552 -396.75562)
			(xy 379.319282 -396.764764) (xy 379.322584 -396.782036) (xy 379.366272 -396.853156) (xy 379.379988 -396.864078)
			(xy 379.388624 -396.866872) (xy 379.416757 -396.87714) (xy 379.468694 -396.90694) (xy 379.491748 -396.926054)
			(xy 379.513193 -396.945672) (xy 379.54899 -396.991449) (xy 379.562868 -397.016986) (xy 379.56363 -397.018256)
			(xy 379.955806 -397.696944) (xy 379.96859 -397.720294) (xy 379.986784 -397.770317) (xy 379.996068 -397.822731)
			(xy 379.9967 -397.849344) (xy 379.99625 -397.873347) (xy 379.988729 -397.920761) (xy 379.973881 -397.966414)
			(xy 379.952071 -398.009181) (xy 379.923837 -398.048007) (xy 379.889874 -398.081936) (xy 379.85102 -398.110132)
			(xy 379.808231 -398.131899) (xy 379.762563 -398.146701) (xy 379.715142 -398.154173) (xy 379.691138 -398.154652)
			(xy 379.667609 -398.154212) (xy 379.621109 -398.146981) (xy 379.57627 -398.132699) (xy 379.534154 -398.111705)
			(xy 379.495759 -398.084496) (xy 379.461994 -398.051716) (xy 379.43366 -398.014144) (xy 379.422152 -397.993616)
			(xy 379.421898 -397.993108) (xy 379.42139 -397.992346) (xy 379.020832 -397.298926) (xy 379.009763 -397.276825)
			(xy 378.994124 -397.229938) (xy 378.986231 -397.181146) (xy 378.98578 -397.156432) (xy 378.985864 -397.145087)
			(xy 378.98752 -397.122457) (xy 378.989082 -397.11122) (xy 378.990352 -397.10233) (xy 378.986796 -397.085058)
			(xy 378.943362 -397.013938) (xy 378.929646 -397.002762) (xy 378.92101 -396.999968) (xy 378.898625 -396.991937)
			(xy 378.856466 -396.969931) (xy 378.818229 -396.941654) (xy 378.78484 -396.90779) (xy 378.757106 -396.869159)
			(xy 378.735698 -396.826693) (xy 378.721133 -396.781422) (xy 378.713765 -396.73444) (xy 378.713238 -396.710662)
			(xy 378.713738 -396.685264) (xy 378.722139 -396.635169) (xy 378.738718 -396.587155) (xy 378.763018 -396.54255)
			(xy 378.794369 -396.502584) (xy 378.812806 -396.48511) (xy 378.821188 -396.47749) (xy 378.829824 -396.457424)
			(xy 378.82703 -396.35811) (xy 378.817632 -396.338552) (xy 378.808742 -396.33144) (xy 378.790179 -396.315639)
			(xy 378.757448 -396.279514) (xy 378.730372 -396.238977) (xy 378.709536 -396.194907) (xy 378.695392 -396.148257)
			(xy 378.688245 -396.100036) (xy 378.687838 -396.075662) (xy 378.688277 -396.051546) (xy 378.695283 -396.003826)
			(xy 378.709142 -395.957629) (xy 378.72956 -395.913932) (xy 378.742448 -395.893544) (xy 378.74829 -395.884654)
			(xy 378.751846 -395.864588) (xy 378.730764 -395.772386) (xy 378.718572 -395.755622) (xy 378.709682 -395.750288)
			(xy 378.688878 -395.737434) (xy 378.650958 -395.706557) (xy 378.618005 -395.670427) (xy 378.590738 -395.629833)
			(xy 378.569754 -395.585663) (xy 378.555512 -395.538882) (xy 378.548322 -395.490513) (xy 378.547884 -395.466062)
			(xy 378.548445 -395.438779) (xy 378.557406 -395.384955) (xy 378.575077 -395.33333) (xy 378.600981 -395.285305)
			(xy 378.634414 -395.242182) (xy 378.654056 -395.223238) (xy 378.66151 -395.215748) (xy 378.67006 -395.196453)
			(xy 378.670566 -395.1859) (xy 378.670566 -395.111224) (xy 378.669979 -395.10069) (xy 378.661447 -395.081417)
			(xy 378.654056 -395.073886) (xy 378.634588 -395.055152) (xy 378.601401 -395.01252) (xy 378.588016 -394.98905)
			(xy 378.582913 -394.980684) (xy 378.567743 -394.968306) (xy 378.549041 -394.962514) (xy 378.539248 -394.962888)
			(xy 378.491242 -394.96492) (xy 378.452241 -394.96425) (xy 378.37495 -394.953725) (xy 378.299767 -394.932939)
			(xy 378.263658 -394.918184) (xy 378.254006 -394.91412) (xy 378.019818 -394.91412) (xy 377.993656 -394.932154)
			(xy 377.988068 -394.94714) (xy 377.978592 -394.971021) (xy 377.953343 -395.015763) (xy 377.921497 -395.056078)
			(xy 377.902978 -395.073886) (xy 377.895536 -395.081381) (xy 377.887006 -395.100676) (xy 377.886468 -395.111224)
			(xy 377.886468 -395.1859) (xy 377.887058 -395.196434) (xy 377.895588 -395.215707) (xy 377.902978 -395.223238)
			(xy 377.92263 -395.242172) (xy 377.956068 -395.285294) (xy 377.981972 -395.333321) (xy 377.999638 -395.38495)
			(xy 378.008587 -395.438778) (xy 378.00915 -395.466062) (xy 378.008717 -395.490179) (xy 378.00172 -395.537904)
			(xy 377.98787 -395.584107) (xy 377.967459 -395.62781) (xy 377.95454 -395.64818) (xy 377.948698 -395.65707)
			(xy 377.945142 -395.677136) (xy 377.966224 -395.769338) (xy 377.978416 -395.786102) (xy 377.987306 -395.791436)
			(xy 378.008109 -395.80429) (xy 378.046028 -395.835167) (xy 378.07898 -395.871297) (xy 378.106245 -395.911891)
			(xy 378.127227 -395.956061) (xy 378.141466 -396.002842) (xy 378.148653 -396.051212) (xy 378.149104 -396.075662)
			(xy 378.148666 -396.100032) (xy 378.14151 -396.148245) (xy 378.12736 -396.194886) (xy 378.106524 -396.238948)
			(xy 378.079451 -396.279479) (xy 378.046728 -396.315601) (xy 378.0282 -396.33144) (xy 378.01931 -396.338552)
			(xy 378.009912 -396.35811) (xy 378.007118 -396.457424) (xy 378.015754 -396.47749) (xy 378.024136 -396.48511)
			(xy 378.042556 -396.502599) (xy 378.073894 -396.542568) (xy 378.098188 -396.587171) (xy 378.114768 -396.635178)
			(xy 378.123177 -396.685267) (xy 378.123704 -396.710662) (xy 378.123613 -396.721944) (xy 378.12196 -396.744446)
			(xy 378.120402 -396.75562) (xy 378.119132 -396.76451) (xy 378.122688 -396.782036) (xy 378.166122 -396.852902)
			(xy 378.179838 -396.864078) (xy 378.188474 -396.866872) (xy 378.210718 -396.87481) (xy 378.252637 -396.896563)
			(xy 378.290708 -396.924508) (xy 378.324024 -396.957981) (xy 378.351791 -396.996183) (xy 378.362972 -397.016986)
			(xy 378.36348 -397.018002) (xy 378.75591 -397.696944) (xy 378.768694 -397.720294) (xy 378.786887 -397.770317)
			(xy 378.796171 -397.822731) (xy 378.796804 -397.849344) (xy 378.796354 -397.873347) (xy 378.788833 -397.920762)
			(xy 378.773985 -397.966415) (xy 378.752176 -398.009182) (xy 378.723941 -398.048008) (xy 378.689978 -398.081938)
			(xy 378.651124 -398.110134) (xy 378.608336 -398.131901) (xy 378.562668 -398.146704) (xy 378.515246 -398.154177)
			(xy 378.491242 -398.154652) (xy 378.467713 -398.154213) (xy 378.421212 -398.146982) (xy 378.376373 -398.1327)
			(xy 378.334256 -398.111706) (xy 378.295861 -398.084497) (xy 378.262096 -398.051718) (xy 378.233761 -398.014145)
			(xy 378.222256 -397.993616) (xy 378.222002 -397.993108) (xy 378.221494 -397.992346) (xy 377.82373 -397.304006)
			(xy 377.811833 -397.281337) (xy 377.794959 -397.233007) (xy 377.786398 -397.182536) (xy 377.785884 -397.15694)
			(xy 377.785884 -397.156432) (xy 377.785968 -397.145087) (xy 377.787624 -397.122457) (xy 377.789186 -397.11122)
			(xy 377.790456 -397.10233) (xy 377.7869 -397.085058) (xy 377.743466 -397.013938) (xy 377.729496 -397.003016)
			(xy 377.721114 -396.999968) (xy 377.69871 -396.991951) (xy 377.656509 -396.969967) (xy 377.618229 -396.941705)
			(xy 377.584795 -396.907848) (xy 377.557017 -396.869216) (xy 377.535565 -396.826742) (xy 377.520961 -396.781456)
			(xy 377.513557 -396.734453) (xy 377.513088 -396.710662) (xy 377.513588 -396.685264) (xy 377.521987 -396.635167)
			(xy 377.538564 -396.587152) (xy 377.562862 -396.542544) (xy 377.594209 -396.502574) (xy 377.612656 -396.48511)
			(xy 377.621038 -396.47749) (xy 377.629674 -396.457424) (xy 377.62688 -396.35811) (xy 377.617482 -396.338552)
			(xy 377.608592 -396.33144) (xy 377.590031 -396.315637) (xy 377.557305 -396.27951) (xy 377.530233 -396.238973)
			(xy 377.509401 -396.194903) (xy 377.495259 -396.148254) (xy 377.488113 -396.100035) (xy 377.487688 -396.075662)
			(xy 377.488127 -396.051546) (xy 377.495132 -396.003826) (xy 377.508989 -395.957627) (xy 377.529404 -395.913929)
			(xy 377.542298 -395.893544) (xy 377.54814 -395.884654) (xy 377.551696 -395.864588) (xy 377.530614 -395.772386)
			(xy 377.518422 -395.755622) (xy 377.509532 -395.750288) (xy 377.488731 -395.737432) (xy 377.450816 -395.706552)
			(xy 377.417867 -395.670421) (xy 377.390605 -395.629827) (xy 377.369625 -395.585658) (xy 377.355385 -395.538879)
			(xy 377.348197 -395.490512) (xy 377.347734 -395.466062) (xy 377.348295 -395.438779) (xy 377.357254 -395.384953)
			(xy 377.374924 -395.333327) (xy 377.400825 -395.285299) (xy 377.434255 -395.242173) (xy 377.453906 -395.223238)
			(xy 377.461354 -395.215746) (xy 377.469896 -395.196451) (xy 377.470416 -395.1859) (xy 377.470416 -395.111224)
			(xy 377.46983 -395.100688) (xy 377.461304 -395.08141) (xy 377.453906 -395.073886) (xy 377.43444 -395.05515)
			(xy 377.401258 -395.012516) (xy 377.387866 -394.98905) (xy 377.382765 -394.980678) (xy 377.367597 -394.968284)
			(xy 377.348891 -394.962475) (xy 377.339098 -394.962888) (xy 377.291346 -394.96492) (xy 377.252345 -394.96425)
			(xy 377.175054 -394.953725) (xy 377.09987 -394.93294) (xy 377.063762 -394.918184) (xy 377.05411 -394.91412)
			(xy 376.819922 -394.91412) (xy 376.79376 -394.932154) (xy 376.788172 -394.94714) (xy 376.781341 -394.964584)
			(xy 376.764282 -394.997939) (xy 376.754136 -395.013688) (xy 376.749382 -395.021657) (xy 376.745357 -395.039757)
			(xy 376.746262 -395.048994) (xy 376.75058 -395.079982) (xy 376.752383 -395.089236) (xy 376.761638 -395.105643)
			(xy 376.768614 -395.111986) (xy 376.790709 -395.13066) (xy 376.830485 -395.17267) (xy 376.864648 -395.219358)
			(xy 376.892655 -395.269979) (xy 376.914058 -395.323727) (xy 376.928517 -395.379744) (xy 376.9358 -395.437136)
			(xy 376.936254 -395.466062) (xy 376.93565 -395.499382) (xy 376.92598 -395.565316) (xy 376.906854 -395.629153)
			(xy 376.893328 -395.65961) (xy 376.889068 -395.67008) (xy 376.889143 -395.692654) (xy 376.898892 -395.713015)
			(xy 376.907298 -395.72057) (xy 376.929546 -395.739243) (xy 376.969613 -395.781298) (xy 377.004037 -395.828083)
			(xy 377.032266 -395.878848) (xy 377.053846 -395.932776) (xy 377.068429 -395.989001) (xy 377.075783 -396.046619)
			(xy 377.076208 -396.075662) (xy 377.075757 -396.104666) (xy 377.068427 -396.162209) (xy 377.05389 -396.218366)
			(xy 377.03238 -396.272239) (xy 377.004242 -396.322965) (xy 376.969925 -396.369734) (xy 376.929978 -396.411795)
			(xy 376.907806 -396.4305) (xy 376.900694 -396.436088) (xy 376.89155 -396.451328) (xy 376.87631 -396.534132)
			(xy 376.879104 -396.551404) (xy 376.883676 -396.559532) (xy 376.89627 -396.58271) (xy 376.914158 -396.632331)
			(xy 376.923241 -396.684289) (xy 376.923808 -396.710662) (xy 376.923717 -396.721944) (xy 376.922064 -396.744446)
			(xy 376.920506 -396.75562) (xy 376.919236 -396.76451) (xy 376.922792 -396.782036) (xy 376.966226 -396.852902)
			(xy 376.979942 -396.864078) (xy 376.988578 -396.866872) (xy 377.010821 -396.87481) (xy 377.05274 -396.896563)
			(xy 377.090811 -396.924509) (xy 377.124127 -396.957982) (xy 377.151893 -396.996184) (xy 377.163076 -397.016986)
			(xy 377.163584 -397.018002) (xy 377.556014 -397.696944) (xy 377.568798 -397.720294) (xy 377.586991 -397.770318)
			(xy 377.596275 -397.822731) (xy 377.596908 -397.849344) (xy 377.596458 -397.873348) (xy 377.588937 -397.920762)
			(xy 377.57409 -397.966416) (xy 377.55228 -398.009183) (xy 377.524045 -398.04801) (xy 377.490083 -398.081939)
			(xy 377.451228 -398.110136) (xy 377.40844 -398.131904) (xy 377.362772 -398.146707) (xy 377.31535 -398.154181)
			(xy 377.291346 -398.154652) (xy 377.267816 -398.154213) (xy 377.221316 -398.146983) (xy 377.176476 -398.132701)
			(xy 377.134359 -398.111708) (xy 377.095963 -398.084499) (xy 377.062197 -398.05172) (xy 377.033863 -398.014147)
			(xy 377.02236 -397.993616) (xy 377.022106 -397.993108) (xy 377.021598 -397.992346) (xy 376.623834 -397.304006)
			(xy 376.611936 -397.281337) (xy 376.595062 -397.233007) (xy 376.586502 -397.182536) (xy 376.585988 -397.15694)
			(xy 376.585988 -397.156432) (xy 376.586072 -397.145087) (xy 376.587728 -397.122458) (xy 376.58929 -397.11122)
			(xy 376.59056 -397.10233) (xy 376.587004 -397.085058) (xy 376.54357 -397.013938) (xy 376.5296 -397.003016)
			(xy 376.521218 -396.999968) (xy 376.498813 -396.991951) (xy 376.456613 -396.969968) (xy 376.418332 -396.941706)
			(xy 376.384897 -396.907849) (xy 376.357118 -396.869216) (xy 376.335667 -396.826743) (xy 376.321062 -396.781457)
			(xy 376.313658 -396.734453) (xy 376.313192 -396.710662) (xy 376.313774 -396.684292) (xy 376.322877 -396.632341)
			(xy 376.340754 -396.582721) (xy 376.353324 -396.559532) (xy 376.357896 -396.551404) (xy 376.36069 -396.534132)
			(xy 376.34545 -396.451328) (xy 376.336306 -396.436088) (xy 376.329194 -396.4305) (xy 376.307003 -396.411816)
			(xy 376.267048 -396.369758) (xy 376.232728 -396.322989) (xy 376.20459 -396.272258) (xy 376.183088 -396.21838)
			(xy 376.168564 -396.162216) (xy 376.161253 -396.104668) (xy 376.160792 -396.075662) (xy 376.161395 -396.042342)
			(xy 376.17106 -395.976405) (xy 376.190181 -395.912567) (xy 376.203718 -395.882114) (xy 376.207987 -395.871644)
			(xy 376.207921 -395.849063) (xy 376.198168 -395.828697) (xy 376.189748 -395.821154) (xy 376.167505 -395.802478)
			(xy 376.12745 -395.76042) (xy 376.093038 -395.713632) (xy 376.064821 -395.662866) (xy 376.043253 -395.608939)
			(xy 376.02868 -395.552717) (xy 376.021337 -395.495102) (xy 376.020838 -395.466062) (xy 376.021283 -395.437137)
			(xy 376.028577 -395.379748) (xy 376.043043 -395.323735) (xy 376.064452 -395.269991) (xy 376.092461 -395.219373)
			(xy 376.126625 -395.172687) (xy 376.166399 -395.130678) (xy 376.188478 -395.111986) (xy 376.195548 -395.105719)
			(xy 376.204826 -395.089277) (xy 376.206512 -395.079982) (xy 376.21083 -395.048994) (xy 376.211778 -395.039756)
			(xy 376.207746 -395.021644) (xy 376.202956 -395.013688) (xy 376.18797 -394.98905) (xy 376.182865 -394.98069)
			(xy 376.167694 -394.968325) (xy 376.148994 -394.96255) (xy 376.139202 -394.962888) (xy 376.091196 -394.96492)
			(xy 376.052195 -394.964247) (xy 375.974907 -394.953716) (xy 375.899726 -394.932925) (xy 375.863612 -394.918184)
			(xy 375.85396 -394.91412) (xy 375.619772 -394.91412) (xy 375.59361 -394.932154) (xy 375.588022 -394.94714)
			(xy 375.578788 -394.970446) (xy 375.554307 -395.01419) (xy 375.523505 -395.05374) (xy 375.487088 -395.088188)
			(xy 375.44589 -395.116748) (xy 375.400855 -395.138764) (xy 375.353013 -395.153733) (xy 375.30346 -395.161311)
			(xy 375.278396 -395.16177) (xy 375.25304 -395.161285) (xy 375.202921 -395.153546) (xy 375.154571 -395.13825)
			(xy 375.109121 -395.115754) (xy 375.067636 -395.086587) (xy 375.031087 -395.051431) (xy 375.000331 -395.011109)
			(xy 374.98782 -394.98905) (xy 374.982717 -394.980684) (xy 374.967548 -394.968304) (xy 374.948845 -394.962511)
			(xy 374.939052 -394.962888) (xy 374.8913 -394.96492) (xy 374.852299 -394.964247) (xy 374.775011 -394.953716)
			(xy 374.69983 -394.932926) (xy 374.663716 -394.918184) (xy 374.654064 -394.91412) (xy 374.419876 -394.91412)
			(xy 374.393714 -394.932154) (xy 374.388126 -394.94714) (xy 374.378649 -394.97102) (xy 374.353397 -395.01576)
			(xy 374.321549 -395.056072) (xy 374.303036 -395.073886) (xy 374.295587 -395.081377) (xy 374.287047 -395.100673)
			(xy 374.286526 -395.111224) (xy 374.286526 -395.1859) (xy 374.287117 -395.196433) (xy 374.295654 -395.215699)
			(xy 374.303036 -395.223238) (xy 374.322691 -395.242171) (xy 374.356132 -395.285292) (xy 374.382039 -395.333318)
			(xy 374.399708 -395.384948) (xy 374.408659 -395.438777) (xy 374.409208 -395.466062) (xy 374.408775 -395.49018)
			(xy 374.401779 -395.537905) (xy 374.387931 -395.584109) (xy 374.367523 -395.627814) (xy 374.354598 -395.64818)
			(xy 374.348756 -395.65707) (xy 374.3452 -395.677136) (xy 374.366282 -395.769338) (xy 374.378474 -395.786102)
			(xy 374.387364 -395.791436) (xy 374.408164 -395.804293) (xy 374.446077 -395.835172) (xy 374.479024 -395.871304)
			(xy 374.506283 -395.911898) (xy 374.527261 -395.956067) (xy 374.541498 -396.002846) (xy 374.548682 -396.051213)
			(xy 374.549162 -396.075662) (xy 374.548724 -396.100033) (xy 374.541569 -396.148246) (xy 374.527421 -396.19489)
			(xy 374.506587 -396.238954) (xy 374.479518 -396.279488) (xy 374.446797 -396.315615) (xy 374.428258 -396.33144)
			(xy 374.419368 -396.338552) (xy 374.40997 -396.35811) (xy 374.407176 -396.457424) (xy 374.415812 -396.47749)
			(xy 374.424194 -396.48511) (xy 374.442616 -396.502598) (xy 374.473959 -396.542565) (xy 374.498256 -396.587168)
			(xy 374.514838 -396.635176) (xy 374.523248 -396.685266) (xy 374.523762 -396.710662) (xy 375.113042 -396.710662)
			(xy 375.113564 -396.685407) (xy 375.121877 -396.635585) (xy 375.138278 -396.587811) (xy 375.162319 -396.543388)
			(xy 375.193343 -396.503528) (xy 375.230505 -396.469318) (xy 375.272791 -396.441692) (xy 375.319047 -396.421402)
			(xy 375.368012 -396.409002) (xy 375.41835 -396.404831) (xy 375.468688 -396.409002) (xy 375.517653 -396.421402)
			(xy 375.563909 -396.441692) (xy 375.606195 -396.469318) (xy 375.643357 -396.503528) (xy 375.674381 -396.543388)
			(xy 375.698422 -396.587811) (xy 375.714823 -396.635585) (xy 375.723136 -396.685407) (xy 375.723658 -396.710662)
			(xy 375.723555 -396.721943) (xy 375.721903 -396.744445) (xy 375.720356 -396.75562) (xy 375.719086 -396.76451)
			(xy 375.722642 -396.782036) (xy 375.766076 -396.852902) (xy 375.779792 -396.864078) (xy 375.788428 -396.866872)
			(xy 375.810668 -396.87482) (xy 375.85259 -396.896567) (xy 375.890665 -396.924509) (xy 375.923984 -396.957978)
			(xy 375.951754 -396.996178) (xy 375.962926 -397.016986) (xy 375.963434 -397.018002) (xy 376.355864 -397.696944)
			(xy 376.368602 -397.720307) (xy 376.386714 -397.770336) (xy 376.395922 -397.822741) (xy 376.396504 -397.849344)
			(xy 376.396078 -397.873337) (xy 376.388565 -397.92073) (xy 376.373731 -397.966365) (xy 376.351942 -398.009118)
			(xy 376.323733 -398.047937) (xy 376.2898 -398.081865) (xy 376.250977 -398.110067) (xy 376.208221 -398.13185)
			(xy 376.162583 -398.146676) (xy 376.115189 -398.154182) (xy 376.091196 -398.154652) (xy 376.067665 -398.154172)
			(xy 376.021159 -398.146971) (xy 375.976312 -398.132709) (xy 375.934188 -398.111726) (xy 375.895789 -398.08452)
			(xy 375.862026 -398.051736) (xy 375.833702 -398.014154) (xy 375.82221 -397.993616) (xy 375.821956 -397.993108)
			(xy 375.821448 -397.992346) (xy 375.423684 -397.304006) (xy 375.411767 -397.281338) (xy 375.394831 -397.233013)
			(xy 375.386171 -397.182542) (xy 375.385584 -397.15694) (xy 375.385584 -397.156432) (xy 375.385742 -397.145083)
			(xy 375.387518 -397.122454) (xy 375.38914 -397.11122) (xy 375.39041 -397.10233) (xy 375.386854 -397.085058)
			(xy 375.34342 -397.013938) (xy 375.32945 -397.003016) (xy 375.321068 -396.999968) (xy 375.298671 -396.991921)
			(xy 375.256452 -396.969965) (xy 375.218155 -396.94172) (xy 375.184707 -396.90787) (xy 375.156922 -396.869238)
			(xy 375.135472 -396.82676) (xy 375.120879 -396.781466) (xy 375.113495 -396.734455) (xy 375.113042 -396.710662)
			(xy 374.523762 -396.710662) (xy 374.523671 -396.721944) (xy 374.522018 -396.744446) (xy 374.52046 -396.75562)
			(xy 374.51919 -396.76451) (xy 374.522746 -396.782036) (xy 374.56618 -396.852902) (xy 374.579896 -396.864078)
			(xy 374.588532 -396.866872) (xy 374.610773 -396.874813) (xy 374.652686 -396.896571) (xy 374.690751 -396.92452)
			(xy 374.724061 -396.957995) (xy 374.751822 -396.996198) (xy 374.76303 -397.016986) (xy 374.763538 -397.018002)
			(xy 375.155968 -397.696944) (xy 375.168777 -397.720276) (xy 375.186929 -397.770308) (xy 375.196114 -397.822732)
			(xy 375.196608 -397.849344) (xy 375.196134 -397.873333) (xy 375.188623 -397.920719) (xy 375.173791 -397.966347)
			(xy 375.152005 -398.009094) (xy 375.123801 -398.047907) (xy 375.089873 -398.08183) (xy 375.051056 -398.110028)
			(xy 375.008307 -398.131808) (xy 374.962676 -398.146633) (xy 374.915289 -398.154138) (xy 374.8913 -398.154652)
			(xy 374.867772 -398.15421) (xy 374.821276 -398.146973) (xy 374.776441 -398.132687) (xy 374.73433 -398.11169)
			(xy 374.695939 -398.084479) (xy 374.66218 -398.0517) (xy 374.63385 -398.014127) (xy 374.622314 -397.993616)
			(xy 374.62206 -397.993108) (xy 374.621552 -397.992346) (xy 374.223788 -397.304006) (xy 374.211854 -397.281345)
			(xy 374.194904 -397.233021) (xy 374.186262 -397.182545) (xy 374.185688 -397.15694) (xy 374.185688 -397.156432)
			(xy 374.185839 -397.145083) (xy 374.18762 -397.122453) (xy 374.189244 -397.11122) (xy 374.190514 -397.10233)
			(xy 374.186958 -397.085058) (xy 374.143524 -397.013938) (xy 374.129554 -397.003016) (xy 374.121172 -396.999968)
			(xy 374.09877 -396.991948) (xy 374.056575 -396.969962) (xy 374.0183 -396.941697) (xy 373.98487 -396.90784)
			(xy 373.957096 -396.869208) (xy 373.935648 -396.826736) (xy 373.921046 -396.781452) (xy 373.913643 -396.734452)
			(xy 373.913146 -396.710662) (xy 373.913645 -396.685263) (xy 373.922044 -396.635166) (xy 373.938619 -396.587149)
			(xy 373.962915 -396.542539) (xy 373.994259 -396.502566) (xy 374.012714 -396.48511) (xy 374.021096 -396.47749)
			(xy 374.029732 -396.457424) (xy 374.026938 -396.35811) (xy 374.01754 -396.338552) (xy 374.00865 -396.33144)
			(xy 373.990086 -396.315639) (xy 373.957355 -396.279514) (xy 373.930278 -396.238978) (xy 373.909442 -396.194908)
			(xy 373.895297 -396.148257) (xy 373.88815 -396.100036) (xy 373.887746 -396.075662) (xy 373.888185 -396.051546)
			(xy 373.895191 -396.003826) (xy 373.90905 -395.957629) (xy 373.929468 -395.913933) (xy 373.942356 -395.893544)
			(xy 373.948198 -395.884654) (xy 373.951754 -395.864588) (xy 373.930672 -395.772386) (xy 373.91848 -395.755622)
			(xy 373.90959 -395.750288) (xy 373.888786 -395.737434) (xy 373.850865 -395.706558) (xy 373.81791 -395.670428)
			(xy 373.790643 -395.629834) (xy 373.769659 -395.585664) (xy 373.755416 -395.538883) (xy 373.748226 -395.490513)
			(xy 373.747792 -395.466062) (xy 373.748353 -395.438779) (xy 373.757314 -395.384955) (xy 373.774986 -395.33333)
			(xy 373.80089 -395.285306) (xy 373.834324 -395.242184) (xy 373.853964 -395.223238) (xy 373.861417 -395.215748)
			(xy 373.869966 -395.196452) (xy 373.870474 -395.1859) (xy 373.870474 -395.111224) (xy 373.869887 -395.100689)
			(xy 373.861356 -395.081416) (xy 373.853964 -395.073886) (xy 373.834495 -395.055152) (xy 373.801308 -395.01252)
			(xy 373.787924 -394.98905) (xy 373.782821 -394.980683) (xy 373.767652 -394.968302) (xy 373.748949 -394.962508)
			(xy 373.739156 -394.962888) (xy 373.69115 -394.96492) (xy 373.652149 -394.96425) (xy 373.574858 -394.953726)
			(xy 373.499674 -394.932941) (xy 373.463566 -394.918184) (xy 373.453914 -394.91412) (xy 373.21998 -394.91412)
			(xy 373.193818 -394.932154) (xy 373.18823 -394.94714) (xy 373.178753 -394.97102) (xy 373.153502 -395.015761)
			(xy 373.121653 -395.056072) (xy 373.10314 -395.073886) (xy 373.09569 -395.081377) (xy 373.08715 -395.100673)
			(xy 373.08663 -395.111224) (xy 373.08663 -395.1859) (xy 373.087222 -395.196432) (xy 373.095759 -395.215699)
			(xy 373.10314 -395.223238) (xy 373.122794 -395.242171) (xy 373.156236 -395.285292) (xy 373.182142 -395.333319)
			(xy 373.199811 -395.384948) (xy 373.208761 -395.438778) (xy 373.209312 -395.466062) (xy 373.208879 -395.49018)
			(xy 373.201883 -395.537905) (xy 373.188035 -395.584109) (xy 373.167628 -395.627815) (xy 373.154702 -395.64818)
			(xy 373.14886 -395.65707) (xy 373.145304 -395.677136) (xy 373.166386 -395.769338) (xy 373.178578 -395.786102)
			(xy 373.187468 -395.791436) (xy 373.208268 -395.804293) (xy 373.246181 -395.835173) (xy 373.279127 -395.871305)
			(xy 373.306386 -395.911899) (xy 373.327363 -395.956068) (xy 373.3416 -396.002847) (xy 373.348784 -396.051213)
			(xy 373.349266 -396.075662) (xy 373.348828 -396.100033) (xy 373.341673 -396.148246) (xy 373.327525 -396.19489)
			(xy 373.306692 -396.238955) (xy 373.279622 -396.279489) (xy 373.246902 -396.315616) (xy 373.228362 -396.33144)
			(xy 373.219472 -396.338552) (xy 373.210074 -396.35811) (xy 373.20728 -396.457424) (xy 373.215916 -396.47749)
			(xy 373.224298 -396.48511) (xy 373.24272 -396.502598) (xy 373.274062 -396.542566) (xy 373.298359 -396.587168)
			(xy 373.314941 -396.635176) (xy 373.323351 -396.685266) (xy 373.323866 -396.710662) (xy 373.323775 -396.721944)
			(xy 373.322122 -396.744446) (xy 373.320564 -396.75562) (xy 373.319294 -396.764764) (xy 373.322596 -396.782036)
			(xy 373.366284 -396.853156) (xy 373.38 -396.864078) (xy 373.388636 -396.866872) (xy 373.416768 -396.877141)
			(xy 373.468704 -396.906942) (xy 373.49176 -396.926054) (xy 373.513204 -396.945672) (xy 373.549 -396.99145)
			(xy 373.56288 -397.016986) (xy 373.563642 -397.018256) (xy 373.955818 -397.696944) (xy 373.968602 -397.720294)
			(xy 373.986794 -397.770318) (xy 373.996078 -397.822731) (xy 373.996712 -397.849344) (xy 373.996262 -397.873348)
			(xy 373.988741 -397.920763) (xy 373.973894 -397.966416) (xy 373.952084 -398.009184) (xy 373.92385 -398.048011)
			(xy 373.889887 -398.081941) (xy 373.851033 -398.110138) (xy 373.808244 -398.131906) (xy 373.762576 -398.14671)
			(xy 373.715154 -398.154185) (xy 373.69115 -398.154652) (xy 373.66762 -398.154213) (xy 373.621119 -398.146983)
			(xy 373.576279 -398.132703) (xy 373.534162 -398.111709) (xy 373.495765 -398.084501) (xy 373.461999 -398.051722)
			(xy 373.433664 -398.014149) (xy 373.422164 -397.993616) (xy 373.42191 -397.993108) (xy 373.421402 -397.992346)
			(xy 373.020844 -397.298926) (xy 373.009775 -397.276825) (xy 372.994135 -397.229938) (xy 372.986242 -397.181146)
			(xy 372.985792 -397.156432) (xy 372.985876 -397.145087) (xy 372.987532 -397.122458) (xy 372.989094 -397.11122)
			(xy 372.990364 -397.10233) (xy 372.986808 -397.085058) (xy 372.943374 -397.013938) (xy 372.929658 -397.002762)
			(xy 372.921022 -396.999968) (xy 372.898636 -396.991937) (xy 372.856476 -396.969933) (xy 372.818238 -396.941656)
			(xy 372.784847 -396.907793) (xy 372.757112 -396.869161) (xy 372.735703 -396.826695) (xy 372.721137 -396.781423)
			(xy 372.713769 -396.734441) (xy 372.71325 -396.710662) (xy 372.713749 -396.685263) (xy 372.722148 -396.635166)
			(xy 372.738724 -396.587149) (xy 372.763019 -396.542539) (xy 372.794364 -396.502567) (xy 372.812818 -396.48511)
			(xy 372.8212 -396.47749) (xy 372.829836 -396.457424) (xy 372.827042 -396.35811) (xy 372.817644 -396.338552)
			(xy 372.808754 -396.33144) (xy 372.79019 -396.315639) (xy 372.757458 -396.279515) (xy 372.730381 -396.238978)
			(xy 372.709545 -396.194908) (xy 372.6954 -396.148257) (xy 372.688253 -396.100036) (xy 372.68785 -396.075662)
			(xy 372.688289 -396.051546) (xy 372.695295 -396.003826) (xy 372.709155 -395.957629) (xy 372.729573 -395.913933)
			(xy 372.74246 -395.893544) (xy 372.748302 -395.884654) (xy 372.751858 -395.864588) (xy 372.730776 -395.772386)
			(xy 372.718584 -395.755622) (xy 372.709694 -395.750288) (xy 372.68889 -395.737434) (xy 372.650968 -395.706558)
			(xy 372.618013 -395.670429) (xy 372.590746 -395.629835) (xy 372.569761 -395.585665) (xy 372.555518 -395.538883)
			(xy 372.548328 -395.490513) (xy 372.547896 -395.466062) (xy 372.548457 -395.438779) (xy 372.557418 -395.384955)
			(xy 372.57509 -395.333331) (xy 372.600994 -395.285306) (xy 372.634429 -395.242184) (xy 372.654068 -395.223238)
			(xy 372.66152 -395.215748) (xy 372.670069 -395.196452) (xy 372.670578 -395.1859) (xy 372.670578 -395.111224)
			(xy 372.669991 -395.100689) (xy 372.661461 -395.081415) (xy 372.654068 -395.073886) (xy 372.634599 -395.055152)
			(xy 372.601411 -395.012521) (xy 372.588028 -394.98905) (xy 372.582925 -394.980683) (xy 372.567756 -394.968301)
			(xy 372.549053 -394.962505) (xy 372.53926 -394.962888) (xy 372.491254 -394.96492) (xy 372.452253 -394.964251)
			(xy 372.374962 -394.953727) (xy 372.299777 -394.932943) (xy 372.26367 -394.918184) (xy 372.254018 -394.91412)
			(xy 372.01983 -394.91412) (xy 371.993668 -394.932154) (xy 371.98808 -394.94714) (xy 371.978605 -394.971021)
			(xy 371.953356 -395.015764) (xy 371.921511 -395.056079) (xy 371.90299 -395.073886) (xy 371.895547 -395.08138)
			(xy 371.887015 -395.100675) (xy 371.88648 -395.111224) (xy 371.88648 -395.1859) (xy 371.88707 -395.196434)
			(xy 371.895601 -395.215706) (xy 371.90299 -395.223238) (xy 371.922642 -395.242172) (xy 371.956078 -395.285295)
			(xy 371.981981 -395.333322) (xy 371.999646 -395.38495) (xy 372.008596 -395.438778) (xy 372.009162 -395.466062)
			(xy 372.008729 -395.490179) (xy 372.001732 -395.537904) (xy 371.987882 -395.584108) (xy 371.967472 -395.627811)
			(xy 371.954552 -395.64818) (xy 371.94871 -395.65707) (xy 371.945154 -395.677136) (xy 371.966236 -395.769338)
			(xy 371.978428 -395.786102) (xy 371.987318 -395.791436) (xy 372.008121 -395.804291) (xy 372.046038 -395.835168)
			(xy 372.078989 -395.871299) (xy 372.106253 -395.911892) (xy 372.127234 -395.956062) (xy 372.141473 -396.002843)
			(xy 372.148659 -396.051212) (xy 372.149116 -396.075662) (xy 372.148678 -396.100032) (xy 372.141522 -396.148245)
			(xy 372.127373 -396.194887) (xy 372.106537 -396.23895) (xy 372.079465 -396.279481) (xy 372.046742 -396.315604)
			(xy 372.028212 -396.33144) (xy 372.019322 -396.338552) (xy 372.009924 -396.35811) (xy 372.00713 -396.457424)
			(xy 372.015766 -396.47749) (xy 372.024148 -396.48511) (xy 372.042567 -396.502599) (xy 372.073904 -396.542569)
			(xy 372.098197 -396.587172) (xy 372.114776 -396.635179) (xy 372.123185 -396.685267) (xy 372.123716 -396.710662)
			(xy 372.123625 -396.721944) (xy 372.121972 -396.744446) (xy 372.120414 -396.75562) (xy 372.119144 -396.76451)
			(xy 372.1227 -396.782036) (xy 372.166134 -396.852902) (xy 372.17985 -396.864078) (xy 372.188486 -396.866872)
			(xy 372.210729 -396.874811) (xy 372.252647 -396.896564) (xy 372.290717 -396.924511) (xy 372.324032 -396.957984)
			(xy 372.351797 -396.996186) (xy 372.362984 -397.016986) (xy 372.363492 -397.018002) (xy 372.755922 -397.696944)
			(xy 372.768706 -397.720294) (xy 372.786898 -397.770318) (xy 372.796182 -397.822731) (xy 372.796816 -397.849344)
			(xy 372.796366 -397.873348) (xy 372.788845 -397.920763) (xy 372.773998 -397.966417) (xy 372.752188 -398.009185)
			(xy 372.723954 -398.048012) (xy 372.689991 -398.081943) (xy 372.651137 -398.11014) (xy 372.608348 -398.131909)
			(xy 372.56268 -398.146713) (xy 372.515258 -398.154188) (xy 372.491254 -398.154652) (xy 372.467724 -398.154214)
			(xy 372.421223 -398.146984) (xy 372.376382 -398.132704) (xy 372.334264 -398.111711) (xy 372.295867 -398.084502)
			(xy 372.2621 -398.051723) (xy 372.233765 -398.014151) (xy 372.222268 -397.993616) (xy 372.222014 -397.993108)
			(xy 372.221506 -397.992346) (xy 371.823742 -397.304006) (xy 371.811844 -397.281337) (xy 371.79497 -397.233007)
			(xy 371.786409 -397.182536) (xy 371.785896 -397.15694) (xy 371.785896 -397.156432) (xy 371.78598 -397.145087)
			(xy 371.787636 -397.122458) (xy 371.789198 -397.11122) (xy 371.790468 -397.10233) (xy 371.786912 -397.085058)
			(xy 371.743478 -397.013938) (xy 371.729508 -397.003016) (xy 371.721126 -396.999968) (xy 371.698721 -396.991951)
			(xy 371.656519 -396.969969) (xy 371.618238 -396.941707) (xy 371.584802 -396.907851) (xy 371.557022 -396.869218)
			(xy 371.53557 -396.826744) (xy 371.520965 -396.781458) (xy 371.51356 -396.734454) (xy 371.5131 -396.710662)
			(xy 371.5136 -396.685264) (xy 371.522 -396.635167) (xy 371.538577 -396.587153) (xy 371.562875 -396.542546)
			(xy 371.594224 -396.502577) (xy 371.612668 -396.48511) (xy 371.62105 -396.47749) (xy 371.629686 -396.457424)
			(xy 371.626892 -396.35811) (xy 371.617494 -396.338552) (xy 371.608604 -396.33144) (xy 371.590043 -396.315638)
			(xy 371.557316 -396.279511) (xy 371.530242 -396.238974) (xy 371.509409 -396.194904) (xy 371.495267 -396.148255)
			(xy 371.488121 -396.100035) (xy 371.4877 -396.075662) (xy 371.488139 -396.051546) (xy 371.495144 -396.003826)
			(xy 371.509002 -395.957627) (xy 371.529417 -395.913929) (xy 371.54231 -395.893544) (xy 371.548152 -395.884654)
			(xy 371.551708 -395.864588) (xy 371.530626 -395.772386) (xy 371.518434 -395.755622) (xy 371.509544 -395.750288)
			(xy 371.488742 -395.737432) (xy 371.450826 -395.706553) (xy 371.417876 -395.670423) (xy 371.390613 -395.629829)
			(xy 371.369632 -395.58566) (xy 371.355391 -395.53888) (xy 371.348203 -395.490512) (xy 371.347746 -395.466062)
			(xy 371.348307 -395.438779) (xy 371.357267 -395.384953) (xy 371.374937 -395.333328) (xy 371.400838 -395.285301)
			(xy 371.434269 -395.242175) (xy 371.453918 -395.223238) (xy 371.461364 -395.215745) (xy 371.469904 -395.19645)
			(xy 371.470428 -395.1859) (xy 371.470428 -395.111224) (xy 371.469843 -395.100688) (xy 371.461318 -395.081408)
			(xy 371.453918 -395.073886) (xy 371.434451 -395.05515) (xy 371.401268 -395.012517) (xy 371.387878 -394.98905)
			(xy 371.382773 -394.980689) (xy 371.367602 -394.968322) (xy 371.348902 -394.962544) (xy 371.33911 -394.962888)
			(xy 371.291358 -394.96492) (xy 371.252356 -394.964251) (xy 371.175065 -394.953728) (xy 371.099881 -394.932944)
			(xy 371.063774 -394.918184) (xy 371.054122 -394.91412) (xy 370.819934 -394.91412) (xy 370.793772 -394.932154)
			(xy 370.788184 -394.94714) (xy 370.778709 -394.971021) (xy 370.75346 -395.015764) (xy 370.721615 -395.05608)
			(xy 370.703094 -395.073886) (xy 370.69565 -395.08138) (xy 370.687118 -395.100675) (xy 370.686584 -395.111224)
			(xy 370.686584 -395.1859) (xy 370.687174 -395.196434) (xy 370.695706 -395.215705) (xy 370.703094 -395.223238)
			(xy 370.722746 -395.242172) (xy 370.756182 -395.285295) (xy 370.782084 -395.333322) (xy 370.799749 -395.38495)
			(xy 370.808698 -395.438778) (xy 370.809266 -395.466062) (xy 370.808833 -395.490179) (xy 370.801836 -395.537904)
			(xy 370.787987 -395.584108) (xy 370.767577 -395.627811) (xy 370.754656 -395.64818) (xy 370.748814 -395.65707)
			(xy 370.745258 -395.677136) (xy 370.76634 -395.769338) (xy 370.778532 -395.786102) (xy 370.787422 -395.791436)
			(xy 370.808224 -395.804291) (xy 370.846142 -395.835168) (xy 370.879092 -395.871299) (xy 370.906356 -395.911893)
			(xy 370.927336 -395.956063) (xy 370.941575 -396.002843) (xy 370.948761 -396.051212) (xy 370.94922 -396.075662)
			(xy 370.948782 -396.100032) (xy 370.941626 -396.148245) (xy 370.927477 -396.194887) (xy 370.906641 -396.23895)
			(xy 370.87957 -396.279481) (xy 370.846847 -396.315605) (xy 370.828316 -396.33144) (xy 370.819426 -396.338552)
			(xy 370.810028 -396.35811) (xy 370.807234 -396.457424) (xy 370.81587 -396.47749) (xy 370.824252 -396.48511)
			(xy 370.842671 -396.502599) (xy 370.874008 -396.542569) (xy 370.8983 -396.587172) (xy 370.914879 -396.635179)
			(xy 370.923288 -396.685267) (xy 370.92382 -396.710662) (xy 370.923729 -396.721944) (xy 370.922076 -396.744446)
			(xy 370.920518 -396.75562) (xy 370.919248 -396.76451) (xy 370.922804 -396.782036) (xy 370.966238 -396.852902)
			(xy 370.979954 -396.864078) (xy 370.98859 -396.866872) (xy 371.010833 -396.874811) (xy 371.05275 -396.896565)
			(xy 371.09082 -396.924512) (xy 371.124134 -396.957985) (xy 371.151899 -396.996187) (xy 371.163088 -397.016986)
			(xy 371.163596 -397.018002) (xy 371.556026 -397.696944) (xy 371.56881 -397.720294) (xy 371.587002 -397.770318)
			(xy 371.596285 -397.822731) (xy 371.59692 -397.849344) (xy 371.59647 -397.873348) (xy 371.58895 -397.920763)
			(xy 371.574102 -397.966417) (xy 371.552292 -398.009185) (xy 371.524058 -398.048013) (xy 371.490095 -398.081944)
			(xy 371.451241 -398.110142) (xy 371.408453 -398.131911) (xy 371.362785 -398.146716) (xy 371.315362 -398.154192)
			(xy 371.291358 -398.154652) (xy 371.267828 -398.154214) (xy 371.221326 -398.146985) (xy 371.176485 -398.132705)
			(xy 371.134367 -398.111712) (xy 371.095969 -398.084504) (xy 371.062202 -398.051725) (xy 371.033866 -398.014152)
			(xy 371.022372 -397.993616) (xy 371.022118 -397.993108) (xy 371.02161 -397.992346) (xy 370.623846 -397.304006)
			(xy 370.611948 -397.281337) (xy 370.595073 -397.233007) (xy 370.586512 -397.182536) (xy 370.586 -397.15694)
			(xy 370.586 -397.156432) (xy 370.586084 -397.145087) (xy 370.58774 -397.122457) (xy 370.589302 -397.11122)
			(xy 370.590572 -397.10233) (xy 370.587016 -397.085058) (xy 370.543582 -397.013938) (xy 370.529612 -397.003016)
			(xy 370.52123 -396.999968) (xy 370.49883 -396.991946) (xy 370.45664 -396.969956) (xy 370.41837 -396.94169)
			(xy 370.384946 -396.907831) (xy 370.357175 -396.8692) (xy 370.335731 -396.82673) (xy 370.321131 -396.781448)
			(xy 370.313729 -396.73445) (xy 370.313204 -396.710662) (xy 370.313704 -396.685264) (xy 370.322104 -396.635168)
			(xy 370.338682 -396.587153) (xy 370.36298 -396.542546) (xy 370.394328 -396.502577) (xy 370.412772 -396.48511)
			(xy 370.421154 -396.47749) (xy 370.42979 -396.457424) (xy 370.426996 -396.35811) (xy 370.417598 -396.338552)
			(xy 370.408708 -396.33144) (xy 370.390146 -396.315638) (xy 370.357419 -396.279511) (xy 370.330346 -396.238975)
			(xy 370.309512 -396.194905) (xy 370.295369 -396.148255) (xy 370.288224 -396.100035) (xy 370.287804 -396.075662)
			(xy 370.288243 -396.051546) (xy 370.295248 -396.003826) (xy 370.309106 -395.957628) (xy 370.329522 -395.91393)
			(xy 370.342414 -395.893544) (xy 370.348256 -395.884654) (xy 370.351812 -395.864588) (xy 370.33073 -395.772386)
			(xy 370.318538 -395.755622) (xy 370.309648 -395.750288) (xy 370.288846 -395.737432) (xy 370.250929 -395.706554)
			(xy 370.217979 -395.670423) (xy 370.190716 -395.629829) (xy 370.169734 -395.58566) (xy 370.155494 -395.53888)
			(xy 370.148305 -395.490512) (xy 370.14785 -395.466062) (xy 370.148411 -395.438779) (xy 370.157371 -395.384954)
			(xy 370.175041 -395.333328) (xy 370.200943 -395.285301) (xy 370.234374 -395.242176) (xy 370.254022 -395.223238)
			(xy 370.261468 -395.215745) (xy 370.270007 -395.19645) (xy 370.270532 -395.1859) (xy 370.270532 -395.111224)
			(xy 370.269947 -395.100688) (xy 370.261423 -395.081408) (xy 370.254022 -395.073886) (xy 370.235486 -395.056091)
			(xy 370.203614 -395.015791) (xy 370.178379 -394.971035) (xy 370.168932 -394.94714) (xy 370.163344 -394.932154)
			(xy 370.137182 -394.91412) (xy 368.533934 -394.91412) (xy 368.506502 -394.935456) (xy 368.502184 -394.952474)
			(xy 368.496248 -394.974468) (xy 368.479151 -395.016692) (xy 368.456412 -395.056166) (xy 368.442748 -395.074394)
			(xy 368.43716 -395.08176) (xy 368.431572 -395.098524) (xy 368.435128 -395.182598) (xy 368.441986 -395.198854)
			(xy 368.448082 -395.205712) (xy 368.464456 -395.224121) (xy 368.492128 -395.264883) (xy 368.513444 -395.3093)
			(xy 368.52793 -395.356389) (xy 368.535266 -395.405107) (xy 368.535712 -395.42974) (xy 368.535202 -395.455727)
			(xy 368.527072 -395.507062) (xy 368.511011 -395.556492) (xy 368.487415 -395.602802) (xy 368.456865 -395.64485)
			(xy 368.420114 -395.681601) (xy 368.378066 -395.712151) (xy 368.331756 -395.735747) (xy 368.282326 -395.751808)
			(xy 368.230991 -395.759938) (xy 368.179017 -395.759938) (xy 368.127682 -395.751808) (xy 368.078252 -395.735747)
			(xy 368.031942 -395.712151) (xy 367.989894 -395.681601) (xy 367.953143 -395.64485) (xy 367.922593 -395.602802)
			(xy 367.898997 -395.556492) (xy 367.882936 -395.507062) (xy 367.874806 -395.455727) (xy 367.874296 -395.42974)
			(xy 367.874855 -395.402411) (xy 367.883837 -395.348495) (xy 367.901561 -395.29679) (xy 367.927547 -395.248703)
			(xy 367.943892 -395.226794) (xy 367.94948 -395.219428) (xy 367.955068 -395.202664) (xy 367.951512 -395.11859)
			(xy 367.944654 -395.102334) (xy 367.938558 -395.095476) (xy 367.920362 -395.074973) (xy 367.89034 -395.029111)
			(xy 367.868309 -394.978918) (xy 367.861088 -394.952474) (xy 367.85677 -394.935456) (xy 367.829338 -394.91412)
			(xy 365.697262 -394.91412) (xy 365.687195 -394.914551) (xy 365.668603 -394.922277) (xy 365.661194 -394.929106)
			(xy 364.779306 -395.810994) (xy 364.772494 -395.818339) (xy 364.764758 -395.836801) (xy 364.76432 -395.846808)
			(xy 364.76432 -396.171674) (xy 364.763703 -396.202804) (xy 364.753608 -396.264239) (xy 364.733698 -396.323229)
			(xy 364.719616 -396.350998) (xy 364.714536 -396.360904) (xy 364.713012 -396.382494) (xy 364.747556 -396.474442)
			(xy 364.762796 -396.489936) (xy 364.772956 -396.493746) (xy 364.799644 -396.5045) (xy 364.849702 -396.532868)
			(xy 364.894933 -396.56843) (xy 364.934312 -396.610381) (xy 364.966946 -396.657768) (xy 364.977592 -396.679674)
			(xy 366.90884 -396.679674) (xy 366.912911 -396.624052) (xy 366.925037 -396.569615) (xy 366.94496 -396.517524)
			(xy 366.972256 -396.468889) (xy 367.006342 -396.424746) (xy 367.046491 -396.386037) (xy 367.091849 -396.353586)
			(xy 367.141449 -396.328085) (xy 367.194233 -396.310078) (xy 367.249076 -396.299948) (xy 367.30481 -396.297911)
			(xy 367.360247 -396.304011) (xy 367.414204 -396.318117) (xy 367.465533 -396.339929) (xy 367.513139 -396.368983)
			(xy 367.556007 -396.404658) (xy 367.593224 -396.446195) (xy 367.623997 -396.492708) (xy 367.647669 -396.543205)
			(xy 367.663737 -396.596612) (xy 367.671857 -396.651788) (xy 367.672366 -396.679674) (xy 367.671919 -396.704137)
			(xy 367.874806 -396.704137) (xy 367.874806 -396.652163) (xy 367.882936 -396.600828) (xy 367.898997 -396.551398)
			(xy 367.922593 -396.505088) (xy 367.953143 -396.46304) (xy 367.989894 -396.426289) (xy 368.031942 -396.395739)
			(xy 368.078252 -396.372143) (xy 368.127682 -396.356082) (xy 368.179017 -396.347952) (xy 368.230991 -396.347952)
			(xy 368.282326 -396.356082) (xy 368.331756 -396.372143) (xy 368.378066 -396.395739) (xy 368.420114 -396.426289)
			(xy 368.456865 -396.46304) (xy 368.487415 -396.505088) (xy 368.511011 -396.551398) (xy 368.527072 -396.600828)
			(xy 368.535202 -396.652163) (xy 368.535712 -396.67815) (xy 368.535202 -396.704137) (xy 368.527072 -396.755472)
			(xy 368.511011 -396.804902) (xy 368.487415 -396.851212) (xy 368.456865 -396.89326) (xy 368.420114 -396.930011)
			(xy 368.378066 -396.960561) (xy 368.331756 -396.984157) (xy 368.282326 -397.000218) (xy 368.230991 -397.008348)
			(xy 368.179017 -397.008348) (xy 368.127682 -397.000218) (xy 368.078252 -396.984157) (xy 368.031942 -396.960561)
			(xy 367.989894 -396.930011) (xy 367.953143 -396.89326) (xy 367.922593 -396.851212) (xy 367.898997 -396.804902)
			(xy 367.882936 -396.755472) (xy 367.874806 -396.704137) (xy 367.671919 -396.704137) (xy 367.671857 -396.70756)
			(xy 367.663737 -396.762736) (xy 367.647669 -396.816143) (xy 367.623997 -396.86664) (xy 367.593224 -396.913153)
			(xy 367.556007 -396.95469) (xy 367.513139 -396.990365) (xy 367.465533 -397.019419) (xy 367.414204 -397.041231)
			(xy 367.360247 -397.055337) (xy 367.30481 -397.061437) (xy 367.249076 -397.0594) (xy 367.194233 -397.04927)
			(xy 367.141449 -397.031263) (xy 367.091849 -397.005762) (xy 367.046491 -396.973311) (xy 367.006342 -396.934602)
			(xy 366.972256 -396.890459) (xy 366.94496 -396.841824) (xy 366.925037 -396.789733) (xy 366.912911 -396.735296)
			(xy 366.90884 -396.679674) (xy 364.977592 -396.679674) (xy 364.992096 -396.709518) (xy 365.009191 -396.764457)
			(xy 365.017843 -396.82134) (xy 365.01832 -396.850108) (xy 365.017848 -396.877478) (xy 365.010024 -396.931656)
			(xy 364.994536 -396.98416) (xy 364.971704 -397.033911) (xy 364.941996 -397.079888) (xy 364.92434 -397.100806)
			(xy 364.918244 -397.107918) (xy 364.911894 -397.124936) (xy 364.911894 -397.21028) (xy 364.918244 -397.227298)
			(xy 364.92434 -397.23441) (xy 364.941984 -397.25534) (xy 364.971713 -397.301306) (xy 364.994559 -397.351052)
			(xy 365.01005 -397.403556) (xy 365.017869 -397.457737) (xy 365.01832 -397.485108) (xy 365.017834 -397.512359)
			(xy 365.010078 -397.566307) (xy 364.994723 -397.618602) (xy 364.972081 -397.668179) (xy 364.942615 -397.714029)
			(xy 364.906924 -397.75522) (xy 364.865733 -397.790911) (xy 364.819883 -397.820377) (xy 364.770306 -397.843019)
			(xy 364.718011 -397.858374) (xy 364.664063 -397.86613) (xy 364.609561 -397.86613) (xy 364.555613 -397.858374)
			(xy 364.503318 -397.843019) (xy 364.453741 -397.820377) (xy 364.407891 -397.790911) (xy 364.3667 -397.75522)
			(xy 364.331009 -397.714029) (xy 364.301543 -397.668179) (xy 364.278901 -397.618602) (xy 364.263546 -397.566307)
			(xy 364.25579 -397.512359) (xy 364.255304 -397.485108) (xy 364.255775 -397.457738) (xy 364.263598 -397.403559)
			(xy 364.279084 -397.351055) (xy 364.301916 -397.301303) (xy 364.331624 -397.255325) (xy 364.349284 -397.23441)
			(xy 364.35538 -397.227298) (xy 364.36173 -397.21028) (xy 364.36173 -397.124936) (xy 364.35538 -397.107918)
			(xy 364.349284 -397.100806) (xy 364.331642 -397.079874) (xy 364.301917 -397.033908) (xy 364.279074 -396.984161)
			(xy 364.263583 -396.931658) (xy 364.255764 -396.877478) (xy 364.255304 -396.850108) (xy 364.255923 -396.818979)
			(xy 364.26602 -396.757545) (xy 364.285934 -396.698557) (xy 364.300008 -396.670784) (xy 364.305088 -396.661132)
			(xy 364.306612 -396.639542) (xy 364.272322 -396.547594) (xy 364.256828 -396.5321) (xy 364.246668 -396.52829)
			(xy 364.225049 -396.519667) (xy 364.183913 -396.497886) (xy 364.164626 -396.484856) (xy 364.157109 -396.480106)
			(xy 364.139933 -396.475565) (xy 364.122238 -396.477151) (xy 364.106144 -396.484677) (xy 364.099602 -396.490698)
			(xy 363.663484 -396.926816) (xy 363.658658 -396.959582) (xy 363.666532 -396.974568) (xy 363.680526 -397.002229)
			(xy 363.700337 -397.060966) (xy 363.710373 -397.122136) (xy 363.710982 -397.15313) (xy 363.710494 -397.180379)
			(xy 363.702734 -397.234322) (xy 363.687376 -397.286612) (xy 363.664732 -397.336184) (xy 363.635265 -397.382028)
			(xy 363.599573 -397.423213) (xy 363.558383 -397.458899) (xy 363.512534 -397.488359) (xy 363.462959 -397.510995)
			(xy 363.410667 -397.526345) (xy 363.356723 -397.534098) (xy 363.329474 -397.534638) (xy 363.298482 -397.53401)
			(xy 363.237319 -397.523957) (xy 363.178579 -397.504166) (xy 363.150912 -397.490188) (xy 363.135926 -397.482314)
			(xy 363.10316 -397.48714) (xy 362.506006 -398.084294) (xy 362.499158 -398.091692) (xy 362.49142 -398.11029)
			(xy 362.49102 -398.120362) (xy 362.49102 -398.329658) (xy 362.491586 -398.340764) (xy 362.500942 -398.360912)
			(xy 362.509054 -398.36852) (xy 362.577126 -398.425924) (xy 362.598462 -398.431766) (xy 362.609638 -398.429734)
			(xy 362.630687 -398.426392) (xy 362.673162 -398.422832) (xy 362.694474 -398.422622) (xy 362.725168 -398.423105)
			(xy 362.786105 -398.430534) (xy 362.845706 -398.445238) (xy 362.903106 -398.467005) (xy 362.957471 -398.495517)
			(xy 362.983018 -398.512538) (xy 362.99177 -398.518009) (xy 363.011974 -398.522137) (xy 363.032178 -398.518009)
			(xy 363.04093 -398.512538) (xy 363.066457 -398.495484) (xy 363.12082 -398.466958) (xy 363.178224 -398.44519)
			(xy 363.237833 -398.430499) (xy 363.298778 -398.423097) (xy 363.329474 -398.422622) (xy 363.360206 -398.423066)
			(xy 363.421224 -398.430472) (xy 363.480903 -398.44518) (xy 363.538374 -398.466974) (xy 363.592799 -398.495537)
			(xy 363.643384 -398.530453) (xy 363.689391 -398.571212) (xy 363.73015 -398.617219) (xy 363.765065 -398.667804)
			(xy 363.793628 -398.72223) (xy 363.815421 -398.779701) (xy 363.830128 -398.83938) (xy 363.837534 -398.900398)
			(xy 363.837982 -398.93113) (xy 363.837427 -398.965315) (xy 363.82827 -399.033069) (xy 363.810126 -399.098988)
			(xy 363.78332 -399.161885) (xy 363.748336 -399.220627) (xy 363.705803 -399.274156) (xy 363.656487 -399.321511)
			(xy 363.629194 -399.342102) (xy 363.61751 -399.350484) (xy 363.606842 -399.376138) (xy 363.623352 -399.493232)
			(xy 363.641132 -399.514822) (xy 363.654594 -399.519648) (xy 363.683721 -399.530666) (xy 363.739272 -399.558811)
			(xy 363.79097 -399.59353) (xy 363.838042 -399.634303) (xy 363.879781 -399.680519) (xy 363.915563 -399.731487)
			(xy 363.944853 -399.786444) (xy 363.967213 -399.844566) (xy 363.982306 -399.904984) (xy 363.989908 -399.966793)
			(xy 363.990382 -399.99793) (xy 363.989902 -400.028625) (xy 363.982478 -400.089564) (xy 363.967778 -400.149168)
			(xy 363.946015 -400.206571) (xy 363.917506 -400.260939) (xy 363.900466 -400.286474) (xy 363.895003 -400.295226)
			(xy 363.890888 -400.315425) (xy 363.895022 -400.33562) (xy 363.900466 -400.344386) (xy 363.917522 -400.369913)
			(xy 363.946053 -400.424275) (xy 363.967825 -400.481678) (xy 363.982522 -400.541287) (xy 363.989928 -400.602233)
			(xy 363.990382 -400.63293) (xy 363.989916 -400.663659) (xy 363.982505 -400.724669) (xy 363.967793 -400.784341)
			(xy 363.945996 -400.841805) (xy 363.917432 -400.896222) (xy 363.882517 -400.946799) (xy 363.84176 -400.992799)
			(xy 363.795755 -401.033551) (xy 363.745174 -401.068461) (xy 363.690753 -401.097019) (xy 363.633288 -401.11881)
			(xy 363.573614 -401.133515) (xy 363.512603 -401.14092) (xy 363.481874 -401.141438) (xy 363.460792 -401.14093)
			(xy 363.44987 -401.140422) (xy 363.430312 -401.148042) (xy 363.361986 -401.216368) (xy 363.354366 -401.235926)
			(xy 363.354874 -401.246848) (xy 363.355382 -401.26793) (xy 363.354902 -401.298625) (xy 363.347478 -401.359564)
			(xy 363.332778 -401.419168) (xy 363.311015 -401.476571) (xy 363.282506 -401.530939) (xy 363.265466 -401.556474)
			(xy 363.260003 -401.565226) (xy 363.255888 -401.585425) (xy 363.260022 -401.60562) (xy 363.265466 -401.614386)
			(xy 363.282522 -401.639913) (xy 363.311053 -401.694275) (xy 363.332825 -401.751678) (xy 363.347522 -401.811287)
			(xy 363.354928 -401.872233) (xy 363.355382 -401.90293) (xy 364.210346 -401.90293) (xy 364.210818 -401.87556)
			(xy 364.218633 -401.821381) (xy 364.23412 -401.768877) (xy 364.256961 -401.71913) (xy 364.286685 -401.673163)
			(xy 364.304326 -401.652232) (xy 364.310422 -401.64512) (xy 364.316772 -401.628102) (xy 364.316772 -401.542758)
			(xy 364.310422 -401.52574) (xy 364.304326 -401.518628) (xy 364.286715 -401.497671) (xy 364.256989 -401.451708)
			(xy 364.234142 -401.401965) (xy 364.218643 -401.349467) (xy 364.210812 -401.295292) (xy 364.210809 -401.240553)
			(xy 364.218634 -401.186377) (xy 364.234126 -401.133877) (xy 364.256967 -401.084132) (xy 364.286687 -401.038165)
			(xy 364.304326 -401.017232) (xy 364.310422 -401.01012) (xy 364.316772 -400.993102) (xy 364.316772 -400.907758)
			(xy 364.310422 -400.89074) (xy 364.304326 -400.883628) (xy 364.286715 -400.862671) (xy 364.256989 -400.816708)
			(xy 364.234142 -400.766965) (xy 364.218643 -400.714467) (xy 364.210812 -400.660292) (xy 364.210809 -400.605553)
			(xy 364.218634 -400.551377) (xy 364.234126 -400.498877) (xy 364.256967 -400.449132) (xy 364.286687 -400.403165)
			(xy 364.304326 -400.382232) (xy 364.310422 -400.37512) (xy 364.316772 -400.358102) (xy 364.316772 -400.272758)
			(xy 364.310422 -400.25574) (xy 364.304326 -400.248628) (xy 364.286691 -400.227693) (xy 364.256977 -400.181721)
			(xy 364.23414 -400.131975) (xy 364.218648 -400.079474) (xy 364.21082 -400.025299) (xy 364.210346 -399.99793)
			(xy 364.210834 -399.97046) (xy 364.218718 -399.916089) (xy 364.234312 -399.863409) (xy 364.257296 -399.813508)
			(xy 364.287193 -399.767415) (xy 364.323388 -399.726084) (xy 364.34395 -399.707862) (xy 364.35157 -399.701258)
			(xy 364.360714 -399.683478) (xy 364.367826 -399.591276) (xy 364.361476 -399.571972) (xy 364.354618 -399.564352)
			(xy 364.337232 -399.54344) (xy 364.307922 -399.497634) (xy 364.2854 -399.448135) (xy 364.270122 -399.395944)
			(xy 364.262396 -399.342115) (xy 364.261908 -399.314924) (xy 364.262386 -399.287554) (xy 364.270201 -399.233376)
			(xy 364.285687 -399.180872) (xy 364.308526 -399.131125) (xy 364.338248 -399.085158) (xy 364.355888 -399.064226)
			(xy 364.361984 -399.057114) (xy 364.368334 -399.040096) (xy 364.368334 -398.954752) (xy 364.361984 -398.937734)
			(xy 364.355888 -398.930622) (xy 364.338244 -398.909694) (xy 364.308533 -398.86372) (xy 364.285698 -398.813971)
			(xy 364.270209 -398.76147) (xy 364.262381 -398.707293) (xy 364.261908 -398.679924) (xy 364.262394 -398.652673)
			(xy 364.27015 -398.598725) (xy 364.285505 -398.54643) (xy 364.308147 -398.496853) (xy 364.337613 -398.451003)
			(xy 364.373304 -398.409812) (xy 364.414495 -398.374121) (xy 364.460345 -398.344655) (xy 364.509922 -398.322013)
			(xy 364.562217 -398.306658) (xy 364.616165 -398.298902) (xy 364.670667 -398.298902) (xy 364.724615 -398.306658)
			(xy 364.77691 -398.322013) (xy 364.826487 -398.344655) (xy 364.872337 -398.374121) (xy 364.913528 -398.409812)
			(xy 364.949219 -398.451003) (xy 364.978685 -398.496853) (xy 365.001327 -398.54643) (xy 365.016682 -398.598725)
			(xy 365.024438 -398.652673) (xy 365.024924 -398.679924) (xy 365.024491 -398.707296) (xy 365.016668 -398.761477)
			(xy 365.001172 -398.813981) (xy 364.978323 -398.863727) (xy 364.94859 -398.909692) (xy 364.930944 -398.930622)
			(xy 364.924848 -398.937734) (xy 364.918498 -398.954752) (xy 364.918498 -399.040096) (xy 364.924848 -399.057114)
			(xy 364.930944 -399.064226) (xy 364.948569 -399.085169) (xy 364.978282 -399.13114) (xy 365.00112 -399.180884)
			(xy 365.016614 -399.233382) (xy 365.024447 -399.287556) (xy 365.024924 -399.314924) (xy 365.024342 -399.344534)
			(xy 365.015182 -399.403042) (xy 364.9971 -399.459435) (xy 364.97053 -399.512361) (xy 364.936108 -399.560551)
			(xy 364.894661 -399.60285) (xy 364.871254 -399.620994) (xy 364.862807 -399.627905) (xy 364.852273 -399.646993)
			(xy 364.850934 -399.657824) (xy 364.84687 -399.713958) (xy 364.858046 -399.724626) (xy 364.865368 -399.731177)
			(xy 364.883538 -399.738612) (xy 364.893352 -399.739104) (xy 364.925356 -399.739104) (xy 364.935172 -399.738636)
			(xy 364.953336 -399.731178) (xy 364.960662 -399.724626) (xy 364.982174 -399.704467) (xy 365.030231 -399.670321)
			(xy 365.082967 -399.643972) (xy 365.139128 -399.626048) (xy 365.197378 -399.616974) (xy 365.226854 -399.616422)
			(xy 365.254224 -399.61691) (xy 365.308402 -399.624721) (xy 365.360905 -399.640205) (xy 365.410652 -399.663042)
			(xy 365.45662 -399.692763) (xy 365.477552 -399.710402) (xy 365.484664 -399.716498) (xy 365.501682 -399.722848)
			(xy 365.587026 -399.722848) (xy 365.604044 -399.716498) (xy 365.611156 -399.710402) (xy 365.632089 -399.692761)
			(xy 365.678057 -399.663037) (xy 365.727803 -399.640191) (xy 365.780305 -399.624695) (xy 365.834483 -399.616866)
			(xy 365.889225 -399.616866) (xy 365.943403 -399.624695) (xy 365.995905 -399.640191) (xy 366.045651 -399.663037)
			(xy 366.091619 -399.692761) (xy 366.112552 -399.710402) (xy 366.119664 -399.716498) (xy 366.136682 -399.722848)
			(xy 366.222026 -399.722848) (xy 366.239044 -399.716498) (xy 366.246156 -399.710402) (xy 366.267094 -399.69277)
			(xy 366.313065 -399.663057) (xy 366.362811 -399.64022) (xy 366.415311 -399.624727) (xy 366.469485 -399.616897)
			(xy 366.496854 -399.616422) (xy 366.524107 -399.616898) (xy 366.578059 -399.62465) (xy 366.630359 -399.640001)
			(xy 366.679941 -399.662641) (xy 366.725795 -399.692107) (xy 366.766989 -399.727799) (xy 366.802684 -399.768992)
			(xy 366.832152 -399.814845) (xy 366.854793 -399.864426) (xy 366.870147 -399.916725) (xy 366.877901 -399.970677)
			(xy 366.878362 -399.99793) (xy 366.877923 -400.025301) (xy 366.8701 -400.079482) (xy 366.854605 -400.131986)
			(xy 366.831757 -400.181732) (xy 366.802026 -400.227697) (xy 366.784382 -400.248628) (xy 366.778286 -400.25574)
			(xy 366.771936 -400.272758) (xy 366.771936 -400.358102) (xy 366.778286 -400.37512) (xy 366.784382 -400.382232)
			(xy 366.802052 -400.403141) (xy 366.831775 -400.449113) (xy 366.854618 -400.498863) (xy 366.870111 -400.551369)
			(xy 366.877937 -400.605551) (xy 366.877934 -400.660294) (xy 366.870102 -400.714475) (xy 366.854602 -400.766979)
			(xy 366.831753 -400.816726) (xy 366.802024 -400.862695) (xy 366.784382 -400.883628) (xy 366.778286 -400.89074)
			(xy 366.771936 -400.907758) (xy 366.771936 -400.993102) (xy 366.778286 -401.01012) (xy 366.784382 -401.017232)
			(xy 366.802052 -401.038141) (xy 366.831775 -401.084113) (xy 366.854618 -401.133863) (xy 366.870111 -401.186369)
			(xy 366.877937 -401.240551) (xy 366.877934 -401.295294) (xy 366.870102 -401.349475) (xy 366.854602 -401.401979)
			(xy 366.831753 -401.451726) (xy 366.802024 -401.497695) (xy 366.784382 -401.518628) (xy 366.778286 -401.52574)
			(xy 366.771936 -401.542758) (xy 366.771936 -401.628102) (xy 366.778286 -401.64512) (xy 366.784382 -401.652232)
			(xy 366.802 -401.673181) (xy 366.831716 -401.719149) (xy 366.854556 -401.768892) (xy 366.870052 -401.821389)
			(xy 366.877885 -401.875562) (xy 366.878362 -401.90293) (xy 366.877973 -401.930186) (xy 366.870211 -401.984142)
			(xy 366.854848 -402.036444) (xy 366.832199 -402.086027) (xy 366.802724 -402.131882) (xy 366.767022 -402.173076)
			(xy 366.725822 -402.208769) (xy 366.67996 -402.238236) (xy 366.630373 -402.260875) (xy 366.578067 -402.276227)
			(xy 366.52411 -402.283978) (xy 366.496854 -402.284438) (xy 366.469484 -402.283955) (xy 366.415305 -402.276144)
			(xy 366.362802 -402.26066) (xy 366.313054 -402.237821) (xy 366.267088 -402.208099) (xy 366.246156 -402.190458)
			(xy 366.239044 -402.184362) (xy 366.222026 -402.178012) (xy 366.136682 -402.178012) (xy 366.119664 -402.184362)
			(xy 366.112552 -402.190458) (xy 366.091619 -402.208099) (xy 366.045651 -402.237823) (xy 365.995905 -402.260669)
			(xy 365.943403 -402.276165) (xy 365.889225 -402.283994) (xy 365.834483 -402.283994) (xy 365.780305 -402.276165)
			(xy 365.727803 -402.260669) (xy 365.678057 -402.237823) (xy 365.632089 -402.208099) (xy 365.611156 -402.190458)
			(xy 365.604044 -402.184362) (xy 365.587026 -402.178012) (xy 365.501682 -402.178012) (xy 365.484664 -402.184362)
			(xy 365.477552 -402.190458) (xy 365.456619 -402.208099) (xy 365.410651 -402.237823) (xy 365.360905 -402.260669)
			(xy 365.308403 -402.276165) (xy 365.254225 -402.283994) (xy 365.199483 -402.283994) (xy 365.145305 -402.276165)
			(xy 365.092803 -402.260669) (xy 365.043057 -402.237823) (xy 364.997089 -402.208099) (xy 364.976156 -402.190458)
			(xy 364.969044 -402.184362) (xy 364.952026 -402.178012) (xy 364.866682 -402.178012) (xy 364.849664 -402.184362)
			(xy 364.842552 -402.190458) (xy 364.821606 -402.20808) (xy 364.775638 -402.237796) (xy 364.725894 -402.260636)
			(xy 364.673396 -402.276131) (xy 364.619222 -402.283962) (xy 364.591854 -402.284438) (xy 364.564603 -402.283965)
			(xy 364.510656 -402.276203) (xy 364.458363 -402.260844) (xy 364.408788 -402.238199) (xy 364.362939 -402.208731)
			(xy 364.32175 -402.173038) (xy 364.286059 -402.131848) (xy 364.256593 -402.085998) (xy 364.233951 -402.036422)
			(xy 364.218594 -401.984128) (xy 364.210834 -401.930181) (xy 364.210346 -401.90293) (xy 363.355382 -401.90293)
			(xy 363.354916 -401.933659) (xy 363.347505 -401.994669) (xy 363.332793 -402.054341) (xy 363.310996 -402.111805)
			(xy 363.282432 -402.166222) (xy 363.247517 -402.216799) (xy 363.20676 -402.262799) (xy 363.160755 -402.303551)
			(xy 363.110174 -402.338461) (xy 363.055753 -402.367019) (xy 362.998288 -402.38881) (xy 362.938614 -402.403515)
			(xy 362.877603 -402.41092) (xy 362.846874 -402.411438) (xy 362.810441 -402.410811) (xy 362.73832 -402.400405)
			(xy 362.668424 -402.37981) (xy 362.635038 -402.36521) (xy 362.6231 -402.359622) (xy 362.597192 -402.361654)
			(xy 362.514388 -402.41474) (xy 362.507428 -402.419594) (xy 362.496938 -402.432919) (xy 362.491358 -402.448934)
			(xy 362.49102 -402.457412) (xy 362.49102 -402.967698) (xy 362.491443 -402.977768) (xy 362.499159 -402.996371)
			(xy 362.506006 -403.003766) (xy 362.793534 -403.291294) (xy 362.800934 -403.298136) (xy 362.819532 -403.305859)
			(xy 362.829602 -403.30628) (xy 365.956596 -403.30628) (xy 365.966666 -403.305857) (xy 365.98527 -403.298142)
			(xy 365.992664 -403.291294) (xy 367.63579 -401.648168) (xy 367.642399 -401.640995) (xy 367.650116 -401.6231)
			(xy 367.650776 -401.61337) (xy 367.6523 -401.533106) (xy 367.645696 -401.515072) (xy 367.638838 -401.507706)
			(xy 367.620118 -401.486492) (xy 367.588502 -401.439573) (xy 367.56416 -401.388501) (xy 367.547627 -401.334394)
			(xy 367.539266 -401.278438) (xy 367.538762 -401.25015) (xy 367.539254 -401.221916) (xy 367.547547 -401.16606)
			(xy 367.555272 -401.138898) (xy 367.558574 -401.12823) (xy 367.556034 -401.107148) (xy 367.504726 -401.023328)
			(xy 367.4872 -401.01139) (xy 367.476278 -401.009358) (xy 367.450243 -401.004159) (xy 367.399831 -400.987511)
			(xy 367.352216 -400.964032) (xy 367.308316 -400.934176) (xy 367.268982 -400.89852) (xy 367.234973 -400.857754)
			(xy 367.206946 -400.812664) (xy 367.185443 -400.764124) (xy 367.17088 -400.713071) (xy 367.163539 -400.660491)
			(xy 367.163096 -400.633946) (xy 367.163664 -400.603153) (xy 367.173515 -400.542362) (xy 367.192999 -400.483941)
			(xy 367.206784 -400.4564) (xy 367.214658 -400.441668) (xy 367.209832 -400.408902) (xy 367.14811 -400.34718)
			(xy 367.125942 -400.32437) (xy 367.086296 -400.274628) (xy 367.052467 -400.220761) (xy 367.024883 -400.163444)
			(xy 367.003889 -400.1034) (xy 366.98975 -400.041383) (xy 366.982643 -399.978172) (xy 366.982248 -399.946368)
			(xy 366.982248 -398.954498) (xy 366.982661 -398.922693) (xy 366.989753 -398.859479) (xy 367.003881 -398.797457)
			(xy 367.024866 -398.737408) (xy 367.052445 -398.680088) (xy 367.086272 -398.626217) (xy 367.125919 -398.576474)
			(xy 367.14811 -398.553686) (xy 367.653316 -398.04848) (xy 367.676107 -398.026282) (xy 367.725838 -397.986598)
			(xy 367.779701 -397.952733) (xy 367.837018 -397.925114) (xy 367.897067 -397.904088) (xy 367.959093 -397.889918)
			(xy 368.022316 -397.882785) (xy 368.054128 -397.882364) (xy 368.19332 -397.882364) (xy 368.227581 -397.882882)
			(xy 368.295603 -397.891144) (xy 368.362133 -397.907544) (xy 368.426202 -397.931844) (xy 368.486874 -397.963689)
			(xy 368.543266 -398.002615) (xy 368.594555 -398.048054) (xy 368.639993 -398.099343) (xy 368.678917 -398.155736)
			(xy 368.710761 -398.216409) (xy 368.735059 -398.280478) (xy 368.751458 -398.347009) (xy 368.759718 -398.415031)
			(xy 368.760248 -398.449292) (xy 368.759753 -398.482582) (xy 368.752719 -398.542002) (xy 370.1852 -398.542002)
			(xy 370.18916 -398.492948) (xy 370.200937 -398.445164) (xy 370.220228 -398.399888) (xy 370.246531 -398.358292)
			(xy 370.279166 -398.321455) (xy 370.317287 -398.29033) (xy 370.359908 -398.265723) (xy 370.405924 -398.248271)
			(xy 370.454143 -398.238427) (xy 370.503318 -398.236446) (xy 370.552173 -398.242378) (xy 370.599444 -398.25607)
			(xy 370.643906 -398.277168) (xy 370.684409 -398.305124) (xy 370.719902 -398.339216) (xy 370.749467 -398.37856)
			(xy 370.772338 -398.422137) (xy 370.787922 -398.468818) (xy 370.795817 -398.517395) (xy 370.796312 -398.542002)
			(xy 371.38535 -398.542002) (xy 371.38931 -398.492948) (xy 371.401087 -398.445164) (xy 371.420378 -398.399888)
			(xy 371.446681 -398.358292) (xy 371.479316 -398.321455) (xy 371.517437 -398.29033) (xy 371.560058 -398.265723)
			(xy 371.606074 -398.248271) (xy 371.654293 -398.238427) (xy 371.703468 -398.236446) (xy 371.752323 -398.242378)
			(xy 371.799594 -398.25607) (xy 371.844056 -398.277168) (xy 371.884559 -398.305124) (xy 371.920052 -398.339216)
			(xy 371.949617 -398.37856) (xy 371.972488 -398.422137) (xy 371.988072 -398.468818) (xy 371.995967 -398.517395)
			(xy 371.996462 -398.542002) (xy 372.5855 -398.542002) (xy 372.58946 -398.492948) (xy 372.601237 -398.445164)
			(xy 372.620528 -398.399888) (xy 372.646831 -398.358292) (xy 372.679466 -398.321455) (xy 372.717587 -398.29033)
			(xy 372.760208 -398.265723) (xy 372.806224 -398.248271) (xy 372.854443 -398.238427) (xy 372.903618 -398.236446)
			(xy 372.952473 -398.242378) (xy 372.999744 -398.25607) (xy 373.044206 -398.277168) (xy 373.084709 -398.305124)
			(xy 373.120202 -398.339216) (xy 373.149767 -398.37856) (xy 373.172638 -398.422137) (xy 373.188222 -398.468818)
			(xy 373.196117 -398.517395) (xy 373.196612 -398.542002) (xy 373.785396 -398.542002) (xy 373.789356 -398.492948)
			(xy 373.801133 -398.445164) (xy 373.820424 -398.399888) (xy 373.846727 -398.358292) (xy 373.879362 -398.321455)
			(xy 373.917483 -398.29033) (xy 373.960104 -398.265723) (xy 374.00612 -398.248271) (xy 374.054339 -398.238427)
			(xy 374.103514 -398.236446) (xy 374.152369 -398.242378) (xy 374.19964 -398.25607) (xy 374.244102 -398.277168)
			(xy 374.284605 -398.305124) (xy 374.320098 -398.339216) (xy 374.349663 -398.37856) (xy 374.372534 -398.422137)
			(xy 374.388118 -398.468818) (xy 374.396013 -398.517395) (xy 374.396508 -398.542002) (xy 374.985546 -398.542002)
			(xy 374.989506 -398.492948) (xy 375.001283 -398.445164) (xy 375.020574 -398.399888) (xy 375.046877 -398.358292)
			(xy 375.079512 -398.321455) (xy 375.117633 -398.29033) (xy 375.160254 -398.265723) (xy 375.20627 -398.248271)
			(xy 375.254489 -398.238427) (xy 375.303664 -398.236446) (xy 375.352519 -398.242378) (xy 375.39979 -398.25607)
			(xy 375.444252 -398.277168) (xy 375.484755 -398.305124) (xy 375.520248 -398.339216) (xy 375.549813 -398.37856)
			(xy 375.572684 -398.422137) (xy 375.588268 -398.468818) (xy 375.596163 -398.517395) (xy 375.596658 -398.542002)
			(xy 376.185442 -398.542002) (xy 376.189402 -398.492948) (xy 376.201179 -398.445164) (xy 376.22047 -398.399888)
			(xy 376.246773 -398.358292) (xy 376.279408 -398.321455) (xy 376.317529 -398.29033) (xy 376.36015 -398.265723)
			(xy 376.406166 -398.248271) (xy 376.454385 -398.238427) (xy 376.50356 -398.236446) (xy 376.552415 -398.242378)
			(xy 376.599686 -398.25607) (xy 376.644148 -398.277168) (xy 376.684651 -398.305124) (xy 376.720144 -398.339216)
			(xy 376.749709 -398.37856) (xy 376.77258 -398.422137) (xy 376.788164 -398.468818) (xy 376.796059 -398.517395)
			(xy 376.796554 -398.542002) (xy 377.385338 -398.542002) (xy 377.389298 -398.492948) (xy 377.401075 -398.445164)
			(xy 377.420366 -398.399888) (xy 377.446669 -398.358292) (xy 377.479304 -398.321455) (xy 377.517425 -398.29033)
			(xy 377.560046 -398.265723) (xy 377.606062 -398.248271) (xy 377.654281 -398.238427) (xy 377.703456 -398.236446)
			(xy 377.752311 -398.242378) (xy 377.799582 -398.25607) (xy 377.844044 -398.277168) (xy 377.884547 -398.305124)
			(xy 377.92004 -398.339216) (xy 377.949605 -398.37856) (xy 377.972476 -398.422137) (xy 377.98806 -398.468818)
			(xy 377.995955 -398.517395) (xy 377.99645 -398.542002) (xy 378.585488 -398.542002) (xy 378.589448 -398.492948)
			(xy 378.601225 -398.445164) (xy 378.620516 -398.399888) (xy 378.646819 -398.358292) (xy 378.679454 -398.321455)
			(xy 378.717575 -398.29033) (xy 378.760196 -398.265723) (xy 378.806212 -398.248271) (xy 378.854431 -398.238427)
			(xy 378.903606 -398.236446) (xy 378.952461 -398.242378) (xy 378.999732 -398.25607) (xy 379.044194 -398.277168)
			(xy 379.084697 -398.305124) (xy 379.12019 -398.339216) (xy 379.149755 -398.37856) (xy 379.172626 -398.422137)
			(xy 379.18821 -398.468818) (xy 379.196105 -398.517395) (xy 379.1966 -398.542002) (xy 379.785384 -398.542002)
			(xy 379.789344 -398.492948) (xy 379.801121 -398.445164) (xy 379.820412 -398.399888) (xy 379.846715 -398.358292)
			(xy 379.87935 -398.321455) (xy 379.917471 -398.29033) (xy 379.960092 -398.265723) (xy 380.006108 -398.248271)
			(xy 380.054327 -398.238427) (xy 380.103502 -398.236446) (xy 380.152357 -398.242378) (xy 380.199628 -398.25607)
			(xy 380.24409 -398.277168) (xy 380.284593 -398.305124) (xy 380.320086 -398.339216) (xy 380.349651 -398.37856)
			(xy 380.372522 -398.422137) (xy 380.388106 -398.468818) (xy 380.396001 -398.517395) (xy 380.396496 -398.542002)
			(xy 380.985534 -398.542002) (xy 380.989494 -398.492948) (xy 381.001271 -398.445164) (xy 381.020562 -398.399888)
			(xy 381.046865 -398.358292) (xy 381.0795 -398.321455) (xy 381.117621 -398.29033) (xy 381.160242 -398.265723)
			(xy 381.206258 -398.248271) (xy 381.254477 -398.238427) (xy 381.303652 -398.236446) (xy 381.352507 -398.242378)
			(xy 381.399778 -398.25607) (xy 381.44424 -398.277168) (xy 381.484743 -398.305124) (xy 381.520236 -398.339216)
			(xy 381.549801 -398.37856) (xy 381.572672 -398.422137) (xy 381.588256 -398.468818) (xy 381.596151 -398.517395)
			(xy 381.596646 -398.542002) (xy 382.18543 -398.542002) (xy 382.18939 -398.492948) (xy 382.201167 -398.445164)
			(xy 382.220458 -398.399888) (xy 382.246761 -398.358292) (xy 382.279396 -398.321455) (xy 382.317517 -398.29033)
			(xy 382.360138 -398.265723) (xy 382.406154 -398.248271) (xy 382.454373 -398.238427) (xy 382.503548 -398.236446)
			(xy 382.552403 -398.242378) (xy 382.599674 -398.25607) (xy 382.644136 -398.277168) (xy 382.684639 -398.305124)
			(xy 382.720132 -398.339216) (xy 382.749697 -398.37856) (xy 382.772568 -398.422137) (xy 382.788152 -398.468818)
			(xy 382.796047 -398.517395) (xy 382.796542 -398.542002) (xy 383.385326 -398.542002) (xy 383.389286 -398.492948)
			(xy 383.401063 -398.445164) (xy 383.420354 -398.399888) (xy 383.446657 -398.358292) (xy 383.479292 -398.321455)
			(xy 383.517413 -398.29033) (xy 383.560034 -398.265723) (xy 383.60605 -398.248271) (xy 383.654269 -398.238427)
			(xy 383.703444 -398.236446) (xy 383.752299 -398.242378) (xy 383.79957 -398.25607) (xy 383.844032 -398.277168)
			(xy 383.884535 -398.305124) (xy 383.920028 -398.339216) (xy 383.949593 -398.37856) (xy 383.972464 -398.422137)
			(xy 383.988048 -398.468818) (xy 383.995943 -398.517395) (xy 383.996438 -398.542002) (xy 384.585476 -398.542002)
			(xy 384.589436 -398.492948) (xy 384.601213 -398.445164) (xy 384.620504 -398.399888) (xy 384.646807 -398.358292)
			(xy 384.679442 -398.321455) (xy 384.717563 -398.29033) (xy 384.760184 -398.265723) (xy 384.8062 -398.248271)
			(xy 384.854419 -398.238427) (xy 384.903594 -398.236446) (xy 384.952449 -398.242378) (xy 384.99972 -398.25607)
			(xy 385.044182 -398.277168) (xy 385.084685 -398.305124) (xy 385.120178 -398.339216) (xy 385.149743 -398.37856)
			(xy 385.172614 -398.422137) (xy 385.188198 -398.468818) (xy 385.196093 -398.517395) (xy 385.196588 -398.542002)
			(xy 385.785372 -398.542002) (xy 385.789332 -398.492948) (xy 385.801109 -398.445164) (xy 385.8204 -398.399888)
			(xy 385.846703 -398.358292) (xy 385.879338 -398.321455) (xy 385.917459 -398.29033) (xy 385.96008 -398.265723)
			(xy 386.006096 -398.248271) (xy 386.054315 -398.238427) (xy 386.10349 -398.236446) (xy 386.152345 -398.242378)
			(xy 386.199616 -398.25607) (xy 386.244078 -398.277168) (xy 386.284581 -398.305124) (xy 386.320074 -398.339216)
			(xy 386.349639 -398.37856) (xy 386.37251 -398.422137) (xy 386.388094 -398.468818) (xy 386.395989 -398.517395)
			(xy 386.396484 -398.542002) (xy 386.985522 -398.542002) (xy 386.989482 -398.492948) (xy 387.001259 -398.445164)
			(xy 387.02055 -398.399888) (xy 387.046853 -398.358292) (xy 387.079488 -398.321455) (xy 387.117609 -398.29033)
			(xy 387.16023 -398.265723) (xy 387.206246 -398.248271) (xy 387.254465 -398.238427) (xy 387.30364 -398.236446)
			(xy 387.352495 -398.242378) (xy 387.399766 -398.25607) (xy 387.444228 -398.277168) (xy 387.484731 -398.305124)
			(xy 387.520224 -398.339216) (xy 387.549789 -398.37856) (xy 387.57266 -398.422137) (xy 387.588244 -398.468818)
			(xy 387.596139 -398.517395) (xy 387.596634 -398.542002) (xy 388.185418 -398.542002) (xy 388.189378 -398.492948)
			(xy 388.201155 -398.445164) (xy 388.220446 -398.399888) (xy 388.246749 -398.358292) (xy 388.279384 -398.321455)
			(xy 388.317505 -398.29033) (xy 388.360126 -398.265723) (xy 388.406142 -398.248271) (xy 388.454361 -398.238427)
			(xy 388.503536 -398.236446) (xy 388.552391 -398.242378) (xy 388.599662 -398.25607) (xy 388.644124 -398.277168)
			(xy 388.684627 -398.305124) (xy 388.72012 -398.339216) (xy 388.749685 -398.37856) (xy 388.772556 -398.422137)
			(xy 388.78814 -398.468818) (xy 388.796035 -398.517395) (xy 388.79653 -398.542002) (xy 388.796035 -398.566609)
			(xy 388.78814 -398.615186) (xy 388.772556 -398.661867) (xy 388.749685 -398.705444) (xy 388.72012 -398.744788)
			(xy 388.684627 -398.77888) (xy 388.644124 -398.806836) (xy 388.599662 -398.827934) (xy 388.552391 -398.841626)
			(xy 388.503536 -398.847558) (xy 388.454361 -398.845577) (xy 388.406142 -398.835733) (xy 388.360126 -398.818281)
			(xy 388.317505 -398.793674) (xy 388.279384 -398.762549) (xy 388.246749 -398.725712) (xy 388.220446 -398.684116)
			(xy 388.201155 -398.63884) (xy 388.189378 -398.591056) (xy 388.185418 -398.542002) (xy 387.596634 -398.542002)
			(xy 387.596139 -398.566609) (xy 387.588244 -398.615186) (xy 387.57266 -398.661867) (xy 387.549789 -398.705444)
			(xy 387.520224 -398.744788) (xy 387.484731 -398.77888) (xy 387.444228 -398.806836) (xy 387.399766 -398.827934)
			(xy 387.352495 -398.841626) (xy 387.30364 -398.847558) (xy 387.254465 -398.845577) (xy 387.206246 -398.835733)
			(xy 387.16023 -398.818281) (xy 387.117609 -398.793674) (xy 387.079488 -398.762549) (xy 387.046853 -398.725712)
			(xy 387.02055 -398.684116) (xy 387.001259 -398.63884) (xy 386.989482 -398.591056) (xy 386.985522 -398.542002)
			(xy 386.396484 -398.542002) (xy 386.395989 -398.566609) (xy 386.388094 -398.615186) (xy 386.37251 -398.661867)
			(xy 386.349639 -398.705444) (xy 386.320074 -398.744788) (xy 386.284581 -398.77888) (xy 386.244078 -398.806836)
			(xy 386.199616 -398.827934) (xy 386.152345 -398.841626) (xy 386.10349 -398.847558) (xy 386.054315 -398.845577)
			(xy 386.006096 -398.835733) (xy 385.96008 -398.818281) (xy 385.917459 -398.793674) (xy 385.879338 -398.762549)
			(xy 385.846703 -398.725712) (xy 385.8204 -398.684116) (xy 385.801109 -398.63884) (xy 385.789332 -398.591056)
			(xy 385.785372 -398.542002) (xy 385.196588 -398.542002) (xy 385.196093 -398.566609) (xy 385.188198 -398.615186)
			(xy 385.172614 -398.661867) (xy 385.149743 -398.705444) (xy 385.120178 -398.744788) (xy 385.084685 -398.77888)
			(xy 385.044182 -398.806836) (xy 384.99972 -398.827934) (xy 384.952449 -398.841626) (xy 384.903594 -398.847558)
			(xy 384.854419 -398.845577) (xy 384.8062 -398.835733) (xy 384.760184 -398.818281) (xy 384.717563 -398.793674)
			(xy 384.679442 -398.762549) (xy 384.646807 -398.725712) (xy 384.620504 -398.684116) (xy 384.601213 -398.63884)
			(xy 384.589436 -398.591056) (xy 384.585476 -398.542002) (xy 383.996438 -398.542002) (xy 383.995943 -398.566609)
			(xy 383.988048 -398.615186) (xy 383.972464 -398.661867) (xy 383.949593 -398.705444) (xy 383.920028 -398.744788)
			(xy 383.884535 -398.77888) (xy 383.844032 -398.806836) (xy 383.79957 -398.827934) (xy 383.752299 -398.841626)
			(xy 383.703444 -398.847558) (xy 383.654269 -398.845577) (xy 383.60605 -398.835733) (xy 383.560034 -398.818281)
			(xy 383.517413 -398.793674) (xy 383.479292 -398.762549) (xy 383.446657 -398.725712) (xy 383.420354 -398.684116)
			(xy 383.401063 -398.63884) (xy 383.389286 -398.591056) (xy 383.385326 -398.542002) (xy 382.796542 -398.542002)
			(xy 382.796047 -398.566609) (xy 382.788152 -398.615186) (xy 382.772568 -398.661867) (xy 382.749697 -398.705444)
			(xy 382.720132 -398.744788) (xy 382.684639 -398.77888) (xy 382.644136 -398.806836) (xy 382.599674 -398.827934)
			(xy 382.552403 -398.841626) (xy 382.503548 -398.847558) (xy 382.454373 -398.845577) (xy 382.406154 -398.835733)
			(xy 382.360138 -398.818281) (xy 382.317517 -398.793674) (xy 382.279396 -398.762549) (xy 382.246761 -398.725712)
			(xy 382.220458 -398.684116) (xy 382.201167 -398.63884) (xy 382.18939 -398.591056) (xy 382.18543 -398.542002)
			(xy 381.596646 -398.542002) (xy 381.596151 -398.566609) (xy 381.588256 -398.615186) (xy 381.572672 -398.661867)
			(xy 381.549801 -398.705444) (xy 381.520236 -398.744788) (xy 381.484743 -398.77888) (xy 381.44424 -398.806836)
			(xy 381.399778 -398.827934) (xy 381.352507 -398.841626) (xy 381.303652 -398.847558) (xy 381.254477 -398.845577)
			(xy 381.206258 -398.835733) (xy 381.160242 -398.818281) (xy 381.117621 -398.793674) (xy 381.0795 -398.762549)
			(xy 381.046865 -398.725712) (xy 381.020562 -398.684116) (xy 381.001271 -398.63884) (xy 380.989494 -398.591056)
			(xy 380.985534 -398.542002) (xy 380.396496 -398.542002) (xy 380.396001 -398.566609) (xy 380.388106 -398.615186)
			(xy 380.372522 -398.661867) (xy 380.349651 -398.705444) (xy 380.320086 -398.744788) (xy 380.284593 -398.77888)
			(xy 380.24409 -398.806836) (xy 380.199628 -398.827934) (xy 380.152357 -398.841626) (xy 380.103502 -398.847558)
			(xy 380.054327 -398.845577) (xy 380.006108 -398.835733) (xy 379.960092 -398.818281) (xy 379.917471 -398.793674)
			(xy 379.87935 -398.762549) (xy 379.846715 -398.725712) (xy 379.820412 -398.684116) (xy 379.801121 -398.63884)
			(xy 379.789344 -398.591056) (xy 379.785384 -398.542002) (xy 379.1966 -398.542002) (xy 379.196105 -398.566609)
			(xy 379.18821 -398.615186) (xy 379.172626 -398.661867) (xy 379.149755 -398.705444) (xy 379.12019 -398.744788)
			(xy 379.084697 -398.77888) (xy 379.044194 -398.806836) (xy 378.999732 -398.827934) (xy 378.952461 -398.841626)
			(xy 378.903606 -398.847558) (xy 378.854431 -398.845577) (xy 378.806212 -398.835733) (xy 378.760196 -398.818281)
			(xy 378.717575 -398.793674) (xy 378.679454 -398.762549) (xy 378.646819 -398.725712) (xy 378.620516 -398.684116)
			(xy 378.601225 -398.63884) (xy 378.589448 -398.591056) (xy 378.585488 -398.542002) (xy 377.99645 -398.542002)
			(xy 377.995955 -398.566609) (xy 377.98806 -398.615186) (xy 377.972476 -398.661867) (xy 377.949605 -398.705444)
			(xy 377.92004 -398.744788) (xy 377.884547 -398.77888) (xy 377.844044 -398.806836) (xy 377.799582 -398.827934)
			(xy 377.752311 -398.841626) (xy 377.703456 -398.847558) (xy 377.654281 -398.845577) (xy 377.606062 -398.835733)
			(xy 377.560046 -398.818281) (xy 377.517425 -398.793674) (xy 377.479304 -398.762549) (xy 377.446669 -398.725712)
			(xy 377.420366 -398.684116) (xy 377.401075 -398.63884) (xy 377.389298 -398.591056) (xy 377.385338 -398.542002)
			(xy 376.796554 -398.542002) (xy 376.796059 -398.566609) (xy 376.788164 -398.615186) (xy 376.77258 -398.661867)
			(xy 376.749709 -398.705444) (xy 376.720144 -398.744788) (xy 376.684651 -398.77888) (xy 376.644148 -398.806836)
			(xy 376.599686 -398.827934) (xy 376.552415 -398.841626) (xy 376.50356 -398.847558) (xy 376.454385 -398.845577)
			(xy 376.406166 -398.835733) (xy 376.36015 -398.818281) (xy 376.317529 -398.793674) (xy 376.279408 -398.762549)
			(xy 376.246773 -398.725712) (xy 376.22047 -398.684116) (xy 376.201179 -398.63884) (xy 376.189402 -398.591056)
			(xy 376.185442 -398.542002) (xy 375.596658 -398.542002) (xy 375.596163 -398.566609) (xy 375.588268 -398.615186)
			(xy 375.572684 -398.661867) (xy 375.549813 -398.705444) (xy 375.520248 -398.744788) (xy 375.484755 -398.77888)
			(xy 375.444252 -398.806836) (xy 375.39979 -398.827934) (xy 375.352519 -398.841626) (xy 375.303664 -398.847558)
			(xy 375.254489 -398.845577) (xy 375.20627 -398.835733) (xy 375.160254 -398.818281) (xy 375.117633 -398.793674)
			(xy 375.079512 -398.762549) (xy 375.046877 -398.725712) (xy 375.020574 -398.684116) (xy 375.001283 -398.63884)
			(xy 374.989506 -398.591056) (xy 374.985546 -398.542002) (xy 374.396508 -398.542002) (xy 374.396013 -398.566609)
			(xy 374.388118 -398.615186) (xy 374.372534 -398.661867) (xy 374.349663 -398.705444) (xy 374.320098 -398.744788)
			(xy 374.284605 -398.77888) (xy 374.244102 -398.806836) (xy 374.19964 -398.827934) (xy 374.152369 -398.841626)
			(xy 374.103514 -398.847558) (xy 374.054339 -398.845577) (xy 374.00612 -398.835733) (xy 373.960104 -398.818281)
			(xy 373.917483 -398.793674) (xy 373.879362 -398.762549) (xy 373.846727 -398.725712) (xy 373.820424 -398.684116)
			(xy 373.801133 -398.63884) (xy 373.789356 -398.591056) (xy 373.785396 -398.542002) (xy 373.196612 -398.542002)
			(xy 373.196117 -398.566609) (xy 373.188222 -398.615186) (xy 373.172638 -398.661867) (xy 373.149767 -398.705444)
			(xy 373.120202 -398.744788) (xy 373.084709 -398.77888) (xy 373.044206 -398.806836) (xy 372.999744 -398.827934)
			(xy 372.952473 -398.841626) (xy 372.903618 -398.847558) (xy 372.854443 -398.845577) (xy 372.806224 -398.835733)
			(xy 372.760208 -398.818281) (xy 372.717587 -398.793674) (xy 372.679466 -398.762549) (xy 372.646831 -398.725712)
			(xy 372.620528 -398.684116) (xy 372.601237 -398.63884) (xy 372.58946 -398.591056) (xy 372.5855 -398.542002)
			(xy 371.996462 -398.542002) (xy 371.995967 -398.566609) (xy 371.988072 -398.615186) (xy 371.972488 -398.661867)
			(xy 371.949617 -398.705444) (xy 371.920052 -398.744788) (xy 371.884559 -398.77888) (xy 371.844056 -398.806836)
			(xy 371.799594 -398.827934) (xy 371.752323 -398.841626) (xy 371.703468 -398.847558) (xy 371.654293 -398.845577)
			(xy 371.606074 -398.835733) (xy 371.560058 -398.818281) (xy 371.517437 -398.793674) (xy 371.479316 -398.762549)
			(xy 371.446681 -398.725712) (xy 371.420378 -398.684116) (xy 371.401087 -398.63884) (xy 371.38931 -398.591056)
			(xy 371.38535 -398.542002) (xy 370.796312 -398.542002) (xy 370.795817 -398.566609) (xy 370.787922 -398.615186)
			(xy 370.772338 -398.661867) (xy 370.749467 -398.705444) (xy 370.719902 -398.744788) (xy 370.684409 -398.77888)
			(xy 370.643906 -398.806836) (xy 370.599444 -398.827934) (xy 370.552173 -398.841626) (xy 370.503318 -398.847558)
			(xy 370.454143 -398.845577) (xy 370.405924 -398.835733) (xy 370.359908 -398.818281) (xy 370.317287 -398.793674)
			(xy 370.279166 -398.762549) (xy 370.246531 -398.725712) (xy 370.220228 -398.684116) (xy 370.200937 -398.63884)
			(xy 370.18916 -398.591056) (xy 370.1852 -398.542002) (xy 368.752719 -398.542002) (xy 368.751926 -398.5487)
			(xy 368.736414 -398.613448) (xy 368.713429 -398.675935) (xy 368.69878 -398.705832) (xy 368.693972 -398.716766)
			(xy 368.693968 -398.74062) (xy 368.69878 -398.751552) (xy 368.713433 -398.781448) (xy 368.736429 -398.843932)
			(xy 368.751943 -398.908681) (xy 368.75976 -398.974801) (xy 368.760248 -399.008092) (xy 368.759836 -399.039011)
			(xy 368.753106 -399.100483) (xy 368.739725 -399.160857) (xy 368.719852 -399.219415) (xy 368.707162 -399.247614)
			(xy 368.703517 -399.256233) (xy 368.702224 -399.274889) (xy 368.704622 -399.283936) (xy 368.713766 -399.3134)
			(xy 368.716765 -399.322004) (xy 368.727824 -399.336468) (xy 368.735356 -399.341594) (xy 368.755507 -399.354613)
			(xy 368.792176 -399.385546) (xy 368.82399 -399.421454) (xy 368.850281 -399.461583) (xy 368.870497 -399.505089)
			(xy 368.884214 -399.55106) (xy 368.891144 -399.598531) (xy 368.891566 -399.622518) (xy 368.891213 -399.644388)
			(xy 368.885449 -399.687746) (xy 368.874024 -399.729967) (xy 368.865912 -399.75028) (xy 368.859816 -399.764504)
			(xy 368.865912 -399.79473) (xy 369.127278 -400.056096) (xy 369.136576 -400.064277) (xy 369.160199 -400.071582)
			(xy 369.17249 -400.070066) (xy 369.267232 -400.052286) (xy 369.287044 -400.036538) (xy 369.292124 -400.025108)
			(xy 369.303582 -400.000259) (xy 369.333477 -399.954431) (xy 369.370516 -399.914157) (xy 369.413685 -399.880537)
			(xy 369.461805 -399.854492) (xy 369.51356 -399.836734) (xy 369.567533 -399.827748) (xy 369.594892 -399.827242)
			(xy 369.62088 -399.827725) (xy 369.672217 -399.835855) (xy 369.721649 -399.851917) (xy 369.76796 -399.875515)
			(xy 369.810008 -399.906068) (xy 369.846759 -399.942824) (xy 369.877307 -399.984876) (xy 369.900899 -400.03119)
			(xy 369.916955 -400.080624) (xy 369.925079 -400.131962) (xy 369.9256 -400.15795) (xy 369.925203 -400.181183)
			(xy 369.918694 -400.22719) (xy 369.905811 -400.271833) (xy 369.886807 -400.314234) (xy 369.862056 -400.353559)
			(xy 369.847368 -400.371564) (xy 369.841272 -400.378676) (xy 369.835176 -400.395186) (xy 369.835176 -400.479514)
			(xy 369.841272 -400.496024) (xy 369.847368 -400.503136) (xy 369.862076 -400.521127) (xy 369.88683 -400.560452)
			(xy 369.905835 -400.602857) (xy 369.918713 -400.647504) (xy 369.925213 -400.693516) (xy 369.9256 -400.71675)
			(xy 369.925121 -400.742742) (xy 369.916996 -400.794086) (xy 369.900938 -400.843526) (xy 369.877342 -400.889846)
			(xy 369.846791 -400.931904) (xy 369.810036 -400.968664) (xy 369.767982 -400.99922) (xy 369.721665 -401.022822)
			(xy 369.672227 -401.038886) (xy 369.620884 -401.047017) (xy 369.594892 -401.047458) (xy 369.585538 -401.047415)
			(xy 369.566858 -401.046398) (xy 369.557554 -401.045426) (xy 369.546378 -401.044156) (xy 369.526058 -401.050506)
			(xy 369.461288 -401.108418) (xy 369.45375 -401.116019) (xy 369.445104 -401.135574) (xy 369.444524 -401.146264)
			(xy 369.444524 -401.674838) (xy 370.534692 -401.674838) (xy 370.534692 -400.811238) (xy 370.535155 -400.784882)
			(xy 370.542419 -400.732672) (xy 370.5568 -400.681958) (xy 370.578025 -400.633707) (xy 370.605689 -400.588837)
			(xy 370.639265 -400.548201) (xy 370.65839 -400.53006) (xy 370.665502 -400.52371) (xy 370.67363 -400.506946)
			(xy 370.682012 -400.420332) (xy 370.676932 -400.402552) (xy 370.671344 -400.394678) (xy 370.657193 -400.374832)
			(xy 370.634736 -400.331573) (xy 370.619424 -400.2853) (xy 370.611644 -400.237184) (xy 370.611146 -400.212814)
			(xy 370.611668 -400.187559) (xy 370.619981 -400.137737) (xy 370.636382 -400.089963) (xy 370.660423 -400.04554)
			(xy 370.691447 -400.00568) (xy 370.728609 -399.97147) (xy 370.770895 -399.943844) (xy 370.817151 -399.923554)
			(xy 370.866116 -399.911154) (xy 370.916454 -399.906983) (xy 370.966792 -399.911154) (xy 371.015757 -399.923554)
			(xy 371.062013 -399.943844) (xy 371.104299 -399.97147) (xy 371.141461 -400.00568) (xy 371.172485 -400.04554)
			(xy 371.196526 -400.089963) (xy 371.212927 -400.137737) (xy 371.22124 -400.187559) (xy 371.221762 -400.212814)
			(xy 371.221281 -400.237186) (xy 371.213523 -400.285309) (xy 371.198206 -400.331585) (xy 371.175721 -400.374833)
			(xy 371.161564 -400.394678) (xy 371.155976 -400.402552) (xy 371.150896 -400.420332) (xy 371.159278 -400.506946)
			(xy 371.167406 -400.52371) (xy 371.174518 -400.53006) (xy 371.193646 -400.5482) (xy 371.227236 -400.588829)
			(xy 371.254909 -400.633697) (xy 371.276137 -400.681949) (xy 371.290517 -400.732666) (xy 371.297773 -400.78488)
			(xy 371.298216 -400.811238) (xy 371.298216 -401.674838) (xy 371.734588 -401.674838) (xy 371.734588 -400.811238)
			(xy 371.735052 -400.784882) (xy 371.742316 -400.732672) (xy 371.756697 -400.681959) (xy 371.777921 -400.633708)
			(xy 371.805585 -400.588837) (xy 371.839161 -400.548201) (xy 371.858286 -400.53006) (xy 371.865398 -400.523456)
			(xy 371.87378 -400.506946) (xy 371.881908 -400.420078) (xy 371.877082 -400.402298) (xy 371.87124 -400.394678)
			(xy 371.857129 -400.374814) (xy 371.834709 -400.331557) (xy 371.819453 -400.285285) (xy 371.81175 -400.237175)
			(xy 371.811296 -400.212814) (xy 371.811818 -400.187559) (xy 371.820131 -400.137737) (xy 371.836532 -400.089963)
			(xy 371.860573 -400.04554) (xy 371.891597 -400.00568) (xy 371.928759 -399.97147) (xy 371.971045 -399.943844)
			(xy 372.017301 -399.923554) (xy 372.066266 -399.911154) (xy 372.116604 -399.906983) (xy 372.166942 -399.911154)
			(xy 372.215907 -399.923554) (xy 372.262163 -399.943844) (xy 372.304449 -399.97147) (xy 372.341611 -400.00568)
			(xy 372.372635 -400.04554) (xy 372.396676 -400.089963) (xy 372.413077 -400.137737) (xy 372.42139 -400.187559)
			(xy 372.421912 -400.212814) (xy 372.421455 -400.237217) (xy 372.413694 -400.285402) (xy 372.398372 -400.331741)
			(xy 372.375878 -400.375054) (xy 372.361714 -400.394932) (xy 372.356126 -400.402552) (xy 372.351046 -400.420332)
			(xy 372.359174 -400.5072) (xy 372.367556 -400.52371) (xy 372.374668 -400.530314) (xy 372.393727 -400.548477)
			(xy 372.42722 -400.589096) (xy 372.45482 -400.633928) (xy 372.476004 -400.682125) (xy 372.49037 -400.732774)
			(xy 372.497647 -400.784915) (xy 372.498112 -400.811238) (xy 372.498112 -401.674838) (xy 372.934992 -401.674838)
			(xy 372.934992 -400.811238) (xy 372.935443 -400.784893) (xy 372.942691 -400.732703) (xy 372.957041 -400.682004)
			(xy 372.978222 -400.633757) (xy 373.005831 -400.588879) (xy 373.039344 -400.54822) (xy 373.058436 -400.53006)
			(xy 373.065548 -400.52371) (xy 373.073676 -400.506946) (xy 373.082058 -400.420332) (xy 373.076978 -400.402552)
			(xy 373.07139 -400.394678) (xy 373.057245 -400.374828) (xy 373.034785 -400.331571) (xy 373.019471 -400.285299)
			(xy 373.011691 -400.237184) (xy 373.011192 -400.212814) (xy 373.011714 -400.187559) (xy 373.020027 -400.137737)
			(xy 373.036428 -400.089963) (xy 373.060469 -400.04554) (xy 373.091493 -400.00568) (xy 373.128655 -399.97147)
			(xy 373.170941 -399.943844) (xy 373.217197 -399.923554) (xy 373.266162 -399.911154) (xy 373.3165 -399.906983)
			(xy 373.366838 -399.911154) (xy 373.415803 -399.923554) (xy 373.462059 -399.943844) (xy 373.504345 -399.97147)
			(xy 373.541507 -400.00568) (xy 373.572531 -400.04554) (xy 373.596572 -400.089963) (xy 373.612973 -400.137737)
			(xy 373.621286 -400.187559) (xy 373.621808 -400.212814) (xy 373.621338 -400.237187) (xy 373.613578 -400.285311)
			(xy 373.598258 -400.331586) (xy 373.575769 -400.374834) (xy 373.56161 -400.394678) (xy 373.556022 -400.402552)
			(xy 373.550942 -400.420332) (xy 373.559324 -400.506946) (xy 373.567452 -400.52371) (xy 373.574564 -400.53006)
			(xy 373.59367 -400.548207) (xy 373.62719 -400.588864) (xy 373.654803 -400.633744) (xy 373.675983 -400.681994)
			(xy 373.690329 -400.732697) (xy 373.697568 -400.784891) (xy 373.698008 -400.811238) (xy 373.698008 -401.674838)
			(xy 374.134888 -401.674838) (xy 374.134888 -400.811238) (xy 374.13534 -400.784893) (xy 374.142588 -400.732703)
			(xy 374.156938 -400.682004) (xy 374.178119 -400.633758) (xy 374.205727 -400.588879) (xy 374.23924 -400.54822)
			(xy 374.258332 -400.53006) (xy 374.265444 -400.52371) (xy 374.273572 -400.506946) (xy 374.281954 -400.420332)
			(xy 374.276874 -400.402552) (xy 374.271286 -400.394678) (xy 374.25714 -400.374828) (xy 374.234681 -400.331571)
			(xy 374.219367 -400.285299) (xy 374.211587 -400.237184) (xy 374.211088 -400.212814) (xy 374.21161 -400.187559)
			(xy 374.219923 -400.137737) (xy 374.236324 -400.089963) (xy 374.260365 -400.04554) (xy 374.291389 -400.00568)
			(xy 374.328551 -399.97147) (xy 374.370837 -399.943844) (xy 374.417093 -399.923554) (xy 374.466058 -399.911154)
			(xy 374.516396 -399.906983) (xy 374.566734 -399.911154) (xy 374.615699 -399.923554) (xy 374.661955 -399.943844)
			(xy 374.704241 -399.97147) (xy 374.741403 -400.00568) (xy 374.772427 -400.04554) (xy 374.796468 -400.089963)
			(xy 374.812869 -400.137737) (xy 374.821182 -400.187559) (xy 374.821704 -400.212814) (xy 374.821235 -400.237187)
			(xy 374.813475 -400.285311) (xy 374.798155 -400.331586) (xy 374.775665 -400.374834) (xy 374.761506 -400.394678)
			(xy 374.755918 -400.402552) (xy 374.750838 -400.420332) (xy 374.75922 -400.506946) (xy 374.767348 -400.52371)
			(xy 374.77446 -400.53006) (xy 374.793565 -400.548208) (xy 374.827086 -400.588865) (xy 374.854698 -400.633744)
			(xy 374.875879 -400.681994) (xy 374.890225 -400.732697) (xy 374.897464 -400.784891) (xy 374.897904 -400.811238)
			(xy 374.897904 -401.674838) (xy 375.334784 -401.674838) (xy 375.334784 -400.811238) (xy 375.33525 -400.784882)
			(xy 375.342513 -400.732672) (xy 375.356894 -400.681959) (xy 375.378118 -400.633708) (xy 375.405782 -400.588837)
			(xy 375.439357 -400.548201) (xy 375.458482 -400.53006) (xy 375.465594 -400.52371) (xy 375.473722 -400.506946)
			(xy 375.482104 -400.420332) (xy 375.477024 -400.402552) (xy 375.471436 -400.394678) (xy 375.457284 -400.374833)
			(xy 375.434827 -400.331573) (xy 375.419516 -400.2853) (xy 375.411736 -400.237184) (xy 375.411238 -400.212814)
			(xy 375.41176 -400.187559) (xy 375.420073 -400.137737) (xy 375.436474 -400.089963) (xy 375.460515 -400.04554)
			(xy 375.491539 -400.00568) (xy 375.528701 -399.97147) (xy 375.570987 -399.943844) (xy 375.617243 -399.923554)
			(xy 375.666208 -399.911154) (xy 375.716546 -399.906983) (xy 375.766884 -399.911154) (xy 375.815849 -399.923554)
			(xy 375.862105 -399.943844) (xy 375.904391 -399.97147) (xy 375.941553 -400.00568) (xy 375.972577 -400.04554)
			(xy 375.996618 -400.089963) (xy 376.013019 -400.137737) (xy 376.021332 -400.187559) (xy 376.021854 -400.212814)
			(xy 376.021375 -400.237186) (xy 376.013616 -400.285309) (xy 375.998299 -400.331585) (xy 375.975813 -400.374833)
			(xy 375.961656 -400.394678) (xy 375.956068 -400.402552) (xy 375.950988 -400.420332) (xy 375.95937 -400.506946)
			(xy 375.967498 -400.52371) (xy 375.97461 -400.53006) (xy 375.993736 -400.548202) (xy 376.027326 -400.58883)
			(xy 376.055 -400.633698) (xy 376.076229 -400.68195) (xy 376.090609 -400.732666) (xy 376.097865 -400.78488)
			(xy 376.098308 -400.811238) (xy 376.098308 -401.674838) (xy 376.53468 -401.674838) (xy 376.53468 -400.811238)
			(xy 376.535147 -400.784882) (xy 376.542411 -400.732672) (xy 376.556791 -400.681959) (xy 376.578015 -400.633708)
			(xy 376.605678 -400.588837) (xy 376.639254 -400.548201) (xy 376.658378 -400.53006) (xy 376.66549 -400.52371)
			(xy 376.673618 -400.506946) (xy 376.682 -400.420332) (xy 376.67692 -400.402552) (xy 376.671332 -400.394678)
			(xy 376.657179 -400.374833) (xy 376.634723 -400.331573) (xy 376.619412 -400.2853) (xy 376.611632 -400.237184)
			(xy 376.611134 -400.212814) (xy 376.611656 -400.187559) (xy 376.619969 -400.137737) (xy 376.63637 -400.089963)
			(xy 376.660411 -400.04554) (xy 376.691435 -400.00568) (xy 376.728597 -399.97147) (xy 376.770883 -399.943844)
			(xy 376.817139 -399.923554) (xy 376.866104 -399.911154) (xy 376.916442 -399.906983) (xy 376.96678 -399.911154)
			(xy 377.015745 -399.923554) (xy 377.062001 -399.943844) (xy 377.104287 -399.97147) (xy 377.141449 -400.00568)
			(xy 377.172473 -400.04554) (xy 377.196514 -400.089963) (xy 377.212915 -400.137737) (xy 377.221228 -400.187559)
			(xy 377.22175 -400.212814) (xy 377.221272 -400.237186) (xy 377.213513 -400.28531) (xy 377.198195 -400.331585)
			(xy 377.175709 -400.374833) (xy 377.161552 -400.394678) (xy 377.155964 -400.402552) (xy 377.150884 -400.420332)
			(xy 377.159266 -400.506946) (xy 377.167394 -400.52371) (xy 377.174506 -400.53006) (xy 377.193632 -400.548203)
			(xy 377.227222 -400.58883) (xy 377.254896 -400.633698) (xy 377.276125 -400.68195) (xy 377.290505 -400.732666)
			(xy 377.297761 -400.78488) (xy 377.298204 -400.811238) (xy 377.298204 -401.674838) (xy 377.735084 -401.674838)
			(xy 377.735084 -400.811238) (xy 377.735537 -400.784893) (xy 377.742785 -400.732703) (xy 377.757135 -400.682004)
			(xy 377.778316 -400.633758) (xy 377.805924 -400.588879) (xy 377.839436 -400.54822) (xy 377.858528 -400.53006)
			(xy 377.86564 -400.52371) (xy 377.873768 -400.506946) (xy 377.88215 -400.420332) (xy 377.87707 -400.402552)
			(xy 377.871482 -400.394678) (xy 377.857336 -400.374829) (xy 377.834876 -400.331571) (xy 377.819563 -400.285299)
			(xy 377.811782 -400.237184) (xy 377.811284 -400.212814) (xy 377.811806 -400.187559) (xy 377.820119 -400.137737)
			(xy 377.83652 -400.089963) (xy 377.860561 -400.04554) (xy 377.891585 -400.00568) (xy 377.928747 -399.97147)
			(xy 377.971033 -399.943844) (xy 378.017289 -399.923554) (xy 378.066254 -399.911154) (xy 378.116592 -399.906983)
			(xy 378.16693 -399.911154) (xy 378.215895 -399.923554) (xy 378.262151 -399.943844) (xy 378.304437 -399.97147)
			(xy 378.341599 -400.00568) (xy 378.372623 -400.04554) (xy 378.396664 -400.089963) (xy 378.413065 -400.137737)
			(xy 378.421378 -400.187559) (xy 378.4219 -400.212814) (xy 378.421431 -400.237187) (xy 378.413671 -400.285311)
			(xy 378.398351 -400.331586) (xy 378.375861 -400.374834) (xy 378.361702 -400.394678) (xy 378.356114 -400.402552)
			(xy 378.351034 -400.420332) (xy 378.359416 -400.506946) (xy 378.367544 -400.52371) (xy 378.374656 -400.53006)
			(xy 378.39376 -400.548209) (xy 378.427281 -400.588865) (xy 378.454894 -400.633745) (xy 378.476075 -400.681994)
			(xy 378.490421 -400.732697) (xy 378.49766 -400.784891) (xy 378.4981 -400.811238) (xy 378.4981 -401.674838)
			(xy 378.93498 -401.674838) (xy 378.93498 -400.811238) (xy 378.935434 -400.784893) (xy 378.942682 -400.732703)
			(xy 378.957032 -400.682004) (xy 378.978212 -400.633758) (xy 379.00582 -400.58888) (xy 379.039332 -400.54822)
			(xy 379.058424 -400.53006) (xy 379.065536 -400.52371) (xy 379.073664 -400.506946) (xy 379.082046 -400.420332)
			(xy 379.076966 -400.402552) (xy 379.071378 -400.394678) (xy 379.057231 -400.374829) (xy 379.034772 -400.331571)
			(xy 379.019459 -400.285299) (xy 379.011678 -400.237184) (xy 379.01118 -400.212814) (xy 379.011702 -400.187559)
			(xy 379.020015 -400.137737) (xy 379.036416 -400.089963) (xy 379.060457 -400.04554) (xy 379.091481 -400.00568)
			(xy 379.128643 -399.97147) (xy 379.170929 -399.943844) (xy 379.217185 -399.923554) (xy 379.26615 -399.911154)
			(xy 379.316488 -399.906983) (xy 379.366826 -399.911154) (xy 379.415791 -399.923554) (xy 379.462047 -399.943844)
			(xy 379.504333 -399.97147) (xy 379.541495 -400.00568) (xy 379.572519 -400.04554) (xy 379.59656 -400.089963)
			(xy 379.612961 -400.137737) (xy 379.621274 -400.187559) (xy 379.621796 -400.212814) (xy 379.621328 -400.237187)
			(xy 379.613568 -400.285311) (xy 379.598247 -400.331587) (xy 379.575757 -400.374834) (xy 379.561598 -400.394678)
			(xy 379.55601 -400.402552) (xy 379.55093 -400.420332) (xy 379.559312 -400.506946) (xy 379.56744 -400.52371)
			(xy 379.574552 -400.53006) (xy 379.593655 -400.548209) (xy 379.627177 -400.588866) (xy 379.65479 -400.633745)
			(xy 379.675971 -400.681994) (xy 379.690317 -400.732697) (xy 379.697556 -400.784891) (xy 379.697996 -400.811238)
			(xy 379.697996 -401.674838) (xy 380.134876 -401.674838) (xy 380.134876 -400.811238) (xy 380.135294 -400.78491)
			(xy 380.142545 -400.732755) (xy 380.156901 -400.682094) (xy 380.178088 -400.633888) (xy 380.205705 -400.589055)
			(xy 380.239226 -400.548446) (xy 380.25832 -400.530314) (xy 380.265432 -400.52371) (xy 380.273814 -400.5072)
			(xy 380.281942 -400.420332) (xy 380.276862 -400.402552) (xy 380.271274 -400.394932) (xy 380.257115 -400.375052)
			(xy 380.234629 -400.331737) (xy 380.219312 -400.285399) (xy 380.211554 -400.237216) (xy 380.211076 -400.212814)
			(xy 380.211598 -400.187559) (xy 380.219911 -400.137737) (xy 380.236312 -400.089963) (xy 380.260353 -400.04554)
			(xy 380.291377 -400.00568) (xy 380.328539 -399.97147) (xy 380.370825 -399.943844) (xy 380.417081 -399.923554)
			(xy 380.466046 -399.911154) (xy 380.516384 -399.906983) (xy 380.566722 -399.911154) (xy 380.615687 -399.923554)
			(xy 380.661943 -399.943844) (xy 380.704229 -399.97147) (xy 380.741391 -400.00568) (xy 380.772415 -400.04554)
			(xy 380.796456 -400.089963) (xy 380.812857 -400.137737) (xy 380.82117 -400.187559) (xy 380.821692 -400.212814)
			(xy 380.821205 -400.237173) (xy 380.813491 -400.285276) (xy 380.798245 -400.331546) (xy 380.775853 -400.374813)
			(xy 380.761748 -400.394678) (xy 380.755906 -400.402298) (xy 380.75108 -400.420078) (xy 380.759208 -400.506946)
			(xy 380.76759 -400.523456) (xy 380.774702 -400.53006) (xy 380.793827 -400.548203) (xy 380.827417 -400.588831)
			(xy 380.855091 -400.633698) (xy 380.876321 -400.68195) (xy 380.890701 -400.732667) (xy 380.897957 -400.78488)
			(xy 380.8984 -400.811238) (xy 380.8984 -401.674838) (xy 381.334772 -401.674838) (xy 381.334772 -400.811238)
			(xy 381.335242 -400.784882) (xy 381.342505 -400.732672) (xy 381.356885 -400.68196) (xy 381.378109 -400.633709)
			(xy 381.405771 -400.588838) (xy 381.439346 -400.548202) (xy 381.45847 -400.53006) (xy 381.465582 -400.52371)
			(xy 381.47371 -400.506946) (xy 381.482092 -400.420332) (xy 381.477012 -400.402552) (xy 381.471424 -400.394678)
			(xy 381.45727 -400.374834) (xy 381.434815 -400.331574) (xy 381.419503 -400.2853) (xy 381.411724 -400.237184)
			(xy 381.411226 -400.212814) (xy 381.411748 -400.187559) (xy 381.420061 -400.137737) (xy 381.436462 -400.089963)
			(xy 381.460503 -400.04554) (xy 381.491527 -400.00568) (xy 381.528689 -399.97147) (xy 381.570975 -399.943844)
			(xy 381.617231 -399.923554) (xy 381.666196 -399.911154) (xy 381.716534 -399.906983) (xy 381.766872 -399.911154)
			(xy 381.815837 -399.923554) (xy 381.862093 -399.943844) (xy 381.904379 -399.97147) (xy 381.941541 -400.00568)
			(xy 381.972565 -400.04554) (xy 381.996606 -400.089963) (xy 382.013007 -400.137737) (xy 382.02132 -400.187559)
			(xy 382.021842 -400.212814) (xy 382.021365 -400.237186) (xy 382.013606 -400.28531) (xy 381.998288 -400.331585)
			(xy 381.975801 -400.374833) (xy 381.961644 -400.394678) (xy 381.956056 -400.402552) (xy 381.950976 -400.420332)
			(xy 381.959358 -400.506946) (xy 381.967486 -400.52371) (xy 381.974598 -400.53006) (xy 381.993722 -400.548204)
			(xy 382.027313 -400.588831) (xy 382.054987 -400.633699) (xy 382.076216 -400.68195) (xy 382.090597 -400.732667)
			(xy 382.097853 -400.78488) (xy 382.098296 -400.811238) (xy 382.098296 -401.674838) (xy 382.535176 -401.674838)
			(xy 382.535176 -400.811238) (xy 382.535616 -400.784922) (xy 382.54284 -400.732787) (xy 382.557156 -400.682139)
			(xy 382.578293 -400.633937) (xy 382.60585 -400.589096) (xy 382.639305 -400.548464) (xy 382.658366 -400.530314)
			(xy 382.665478 -400.52371) (xy 382.67386 -400.5072) (xy 382.681988 -400.420332) (xy 382.676908 -400.402552)
			(xy 382.67132 -400.394932) (xy 382.657167 -400.375048) (xy 382.634678 -400.331735) (xy 382.619359 -400.285398)
			(xy 382.6116 -400.237216) (xy 382.611122 -400.212814) (xy 382.611644 -400.187559) (xy 382.619957 -400.137737)
			(xy 382.636358 -400.089963) (xy 382.660399 -400.04554) (xy 382.691423 -400.00568) (xy 382.728585 -399.97147)
			(xy 382.770871 -399.943844) (xy 382.817127 -399.923554) (xy 382.866092 -399.911154) (xy 382.91643 -399.906983)
			(xy 382.966768 -399.911154) (xy 383.015733 -399.923554) (xy 383.061989 -399.943844) (xy 383.104275 -399.97147)
			(xy 383.141437 -400.00568) (xy 383.172461 -400.04554) (xy 383.196502 -400.089963) (xy 383.212903 -400.137737)
			(xy 383.221216 -400.187559) (xy 383.221738 -400.212814) (xy 383.221243 -400.237172) (xy 383.21353 -400.285275)
			(xy 383.198287 -400.331545) (xy 383.175898 -400.374812) (xy 383.161794 -400.394678) (xy 383.155952 -400.402298)
			(xy 383.151126 -400.420078) (xy 383.159254 -400.506946) (xy 383.167636 -400.523456) (xy 383.174748 -400.53006)
			(xy 383.193851 -400.54821) (xy 383.227372 -400.588866) (xy 383.254985 -400.633745) (xy 383.276167 -400.681994)
			(xy 383.290513 -400.732697) (xy 383.297752 -400.784891) (xy 383.298192 -400.811238) (xy 383.298192 -401.674838)
			(xy 383.735072 -401.674838) (xy 383.735072 -400.811238) (xy 383.735529 -400.784893) (xy 383.742777 -400.732704)
			(xy 383.757127 -400.682005) (xy 383.778306 -400.633759) (xy 383.805913 -400.58888) (xy 383.839425 -400.54822)
			(xy 383.858516 -400.53006) (xy 383.865628 -400.52371) (xy 383.873756 -400.506946) (xy 383.882138 -400.420332)
			(xy 383.877058 -400.402552) (xy 383.87147 -400.394678) (xy 383.857322 -400.37483) (xy 383.834864 -400.331572)
			(xy 383.819551 -400.285299) (xy 383.81177 -400.237184) (xy 383.811272 -400.212814) (xy 383.811794 -400.187559)
			(xy 383.820107 -400.137737) (xy 383.836508 -400.089963) (xy 383.860549 -400.04554) (xy 383.891573 -400.00568)
			(xy 383.928735 -399.97147) (xy 383.971021 -399.943844) (xy 384.017277 -399.923554) (xy 384.066242 -399.911154)
			(xy 384.11658 -399.906983) (xy 384.166918 -399.911154) (xy 384.215883 -399.923554) (xy 384.262139 -399.943844)
			(xy 384.304425 -399.97147) (xy 384.341587 -400.00568) (xy 384.372611 -400.04554) (xy 384.396652 -400.089963)
			(xy 384.413053 -400.137737) (xy 384.421366 -400.187559) (xy 384.421888 -400.212814) (xy 384.421422 -400.237187)
			(xy 384.413661 -400.285311) (xy 384.39834 -400.331587) (xy 384.37585 -400.374834) (xy 384.36169 -400.394678)
			(xy 384.356102 -400.402552) (xy 384.351022 -400.420332) (xy 384.359404 -400.506946) (xy 384.367532 -400.52371)
			(xy 384.374644 -400.53006) (xy 384.393746 -400.548211) (xy 384.427267 -400.588867) (xy 384.454881 -400.633746)
			(xy 384.476062 -400.681995) (xy 384.490409 -400.732697) (xy 384.497648 -400.784891) (xy 384.498088 -400.811238)
			(xy 384.498088 -401.674838) (xy 384.934968 -401.674838) (xy 384.934968 -400.811238) (xy 384.935426 -400.784893)
			(xy 384.942674 -400.732704) (xy 384.957024 -400.682005) (xy 384.978203 -400.633759) (xy 385.00581 -400.58888)
			(xy 385.039321 -400.54822) (xy 385.058412 -400.53006) (xy 385.065524 -400.52371) (xy 385.073652 -400.506946)
			(xy 385.082034 -400.420332) (xy 385.076954 -400.402552) (xy 385.071366 -400.394678) (xy 385.057218 -400.37483)
			(xy 385.034759 -400.331572) (xy 385.019446 -400.285299) (xy 385.011666 -400.237184) (xy 385.011168 -400.212814)
			(xy 385.01169 -400.187559) (xy 385.020003 -400.137737) (xy 385.036404 -400.089963) (xy 385.060445 -400.04554)
			(xy 385.091469 -400.00568) (xy 385.128631 -399.97147) (xy 385.170917 -399.943844) (xy 385.217173 -399.923554)
			(xy 385.266138 -399.911154) (xy 385.316476 -399.906983) (xy 385.366814 -399.911154) (xy 385.415779 -399.923554)
			(xy 385.462035 -399.943844) (xy 385.504321 -399.97147) (xy 385.541483 -400.00568) (xy 385.572507 -400.04554)
			(xy 385.596548 -400.089963) (xy 385.612949 -400.137737) (xy 385.621262 -400.187559) (xy 385.621784 -400.212814)
			(xy 385.621319 -400.237187) (xy 385.613558 -400.285311) (xy 385.598237 -400.331587) (xy 385.575746 -400.374834)
			(xy 385.561586 -400.394678) (xy 385.555998 -400.402552) (xy 385.550918 -400.420332) (xy 385.5593 -400.506946)
			(xy 385.567428 -400.52371) (xy 385.57454 -400.53006) (xy 385.593641 -400.548212) (xy 385.627163 -400.588867)
			(xy 385.654777 -400.633746) (xy 385.675958 -400.681995) (xy 385.690305 -400.732697) (xy 385.697544 -400.784891)
			(xy 385.697984 -400.811238) (xy 385.697984 -401.674838) (xy 386.134864 -401.674838) (xy 386.134864 -400.811238)
			(xy 386.135324 -400.784893) (xy 386.142571 -400.732704) (xy 386.156921 -400.682005) (xy 386.1781 -400.633759)
			(xy 386.205706 -400.588881) (xy 386.239217 -400.54822) (xy 386.258308 -400.53006) (xy 386.26542 -400.52371)
			(xy 386.273548 -400.506946) (xy 386.28193 -400.420332) (xy 386.27685 -400.402552) (xy 386.271262 -400.394678)
			(xy 386.257113 -400.37483) (xy 386.234655 -400.331572) (xy 386.219342 -400.285299) (xy 386.211562 -400.237184)
			(xy 386.211064 -400.212814) (xy 386.211586 -400.187559) (xy 386.219899 -400.137737) (xy 386.2363 -400.089963)
			(xy 386.260341 -400.04554) (xy 386.291365 -400.00568) (xy 386.328527 -399.97147) (xy 386.370813 -399.943844)
			(xy 386.417069 -399.923554) (xy 386.466034 -399.911154) (xy 386.516372 -399.906983) (xy 386.56671 -399.911154)
			(xy 386.615675 -399.923554) (xy 386.661931 -399.943844) (xy 386.704217 -399.97147) (xy 386.741379 -400.00568)
			(xy 386.772403 -400.04554) (xy 386.796444 -400.089963) (xy 386.812845 -400.137737) (xy 386.821158 -400.187559)
			(xy 386.82168 -400.212814) (xy 386.821215 -400.237187) (xy 386.813455 -400.285311) (xy 386.798133 -400.331587)
			(xy 386.775642 -400.374834) (xy 386.761482 -400.394678) (xy 386.755894 -400.402552) (xy 386.750814 -400.420332)
			(xy 386.759196 -400.506946) (xy 386.767324 -400.52371) (xy 386.774436 -400.53006) (xy 386.793536 -400.548213)
			(xy 386.827058 -400.588868) (xy 386.854672 -400.633746) (xy 386.875854 -400.681995) (xy 386.890201 -400.732698)
			(xy 386.89744 -400.784891) (xy 386.89788 -400.811238) (xy 386.89788 -401.674838) (xy 387.33476 -401.674838)
			(xy 387.33476 -400.811238) (xy 387.335233 -400.784882) (xy 387.342497 -400.732673) (xy 387.356877 -400.68196)
			(xy 387.378099 -400.633709) (xy 387.405761 -400.588839) (xy 387.439335 -400.548202) (xy 387.458458 -400.53006)
			(xy 387.46557 -400.52371) (xy 387.473698 -400.506946) (xy 387.48208 -400.420332) (xy 387.477 -400.402552)
			(xy 387.471412 -400.394678) (xy 387.457257 -400.374835) (xy 387.434802 -400.331574) (xy 387.419491 -400.2853)
			(xy 387.411712 -400.237184) (xy 387.411214 -400.212814) (xy 387.411736 -400.187559) (xy 387.420049 -400.137737)
			(xy 387.43645 -400.089963) (xy 387.460491 -400.04554) (xy 387.491515 -400.00568) (xy 387.528677 -399.97147)
			(xy 387.570963 -399.943844) (xy 387.617219 -399.923554) (xy 387.666184 -399.911154) (xy 387.716522 -399.906983)
			(xy 387.76686 -399.911154) (xy 387.815825 -399.923554) (xy 387.862081 -399.943844) (xy 387.904367 -399.97147)
			(xy 387.941529 -400.00568) (xy 387.972553 -400.04554) (xy 387.996594 -400.089963) (xy 388.012995 -400.137737)
			(xy 388.021308 -400.187559) (xy 388.02183 -400.212814) (xy 388.021356 -400.237187) (xy 388.013596 -400.28531)
			(xy 387.998278 -400.331586) (xy 387.97579 -400.374834) (xy 387.961632 -400.394678) (xy 387.956044 -400.402552)
			(xy 387.950964 -400.420332) (xy 387.959346 -400.506946) (xy 387.967474 -400.52371) (xy 387.974586 -400.53006)
			(xy 387.993727 -400.548187) (xy 388.027313 -400.58882) (xy 388.054982 -400.633691) (xy 388.076208 -400.681946)
			(xy 388.090586 -400.732664) (xy 388.097841 -400.78488) (xy 388.098284 -400.811238) (xy 388.098284 -401.674838)
			(xy 388.534656 -401.674838) (xy 388.534656 -400.811238) (xy 388.535131 -400.784882) (xy 388.542394 -400.732673)
			(xy 388.556774 -400.681961) (xy 388.577996 -400.63371) (xy 388.605657 -400.588839) (xy 388.639231 -400.548202)
			(xy 388.658354 -400.53006) (xy 388.665466 -400.52371) (xy 388.673594 -400.506946) (xy 388.681976 -400.420332)
			(xy 388.676896 -400.402552) (xy 388.671308 -400.394678) (xy 388.657165 -400.374826) (xy 388.634704 -400.33157)
			(xy 388.619389 -400.285298) (xy 388.611609 -400.237184) (xy 388.61111 -400.212814) (xy 388.611632 -400.187559)
			(xy 388.619945 -400.137737) (xy 388.636346 -400.089963) (xy 388.660387 -400.04554) (xy 388.691411 -400.00568)
			(xy 388.728573 -399.97147) (xy 388.770859 -399.943844) (xy 388.817115 -399.923554) (xy 388.86608 -399.911154)
			(xy 388.916418 -399.906983) (xy 388.966756 -399.911154) (xy 389.015721 -399.923554) (xy 389.061977 -399.943844)
			(xy 389.104263 -399.97147) (xy 389.141425 -400.00568) (xy 389.172449 -400.04554) (xy 389.19649 -400.089963)
			(xy 389.212891 -400.137737) (xy 389.221204 -400.187559) (xy 389.221726 -400.212814) (xy 389.221252 -400.237187)
			(xy 389.213493 -400.28531) (xy 389.198174 -400.331586) (xy 389.175686 -400.374834) (xy 389.161528 -400.394678)
			(xy 389.15594 -400.402552) (xy 389.15086 -400.420332) (xy 389.159242 -400.506946) (xy 389.16737 -400.52371)
			(xy 389.174482 -400.53006) (xy 389.193622 -400.548188) (xy 389.227208 -400.58882) (xy 389.254878 -400.633692)
			(xy 389.276104 -400.681946) (xy 389.290482 -400.732664) (xy 389.297737 -400.78488) (xy 389.29818 -400.811238)
			(xy 389.29818 -401.461986) (xy 389.298587 -401.470959) (xy 389.304815 -401.487792) (xy 389.316448 -401.50146)
			(xy 389.324088 -401.506182) (xy 389.413496 -401.55622) (xy 389.441182 -401.555712) (xy 389.452866 -401.548346)
			(xy 389.475529 -401.534906) (xy 389.523781 -401.513738) (xy 389.574482 -401.499396) (xy 389.626673 -401.49215)
			(xy 389.653018 -401.491704) (xy 389.680269 -401.492167) (xy 389.734217 -401.499926) (xy 389.786511 -401.515283)
			(xy 389.836087 -401.537926) (xy 389.881937 -401.567394) (xy 389.923126 -401.603086) (xy 389.958817 -401.644277)
			(xy 389.988283 -401.690128) (xy 390.010923 -401.739706) (xy 390.026278 -401.792001) (xy 390.034034 -401.845949)
			(xy 390.034034 -401.900451) (xy 390.026278 -401.954399) (xy 390.010923 -402.006694) (xy 389.988283 -402.056272)
			(xy 389.958817 -402.102123) (xy 389.923126 -402.143314) (xy 389.881937 -402.179006) (xy 389.836087 -402.208474)
			(xy 389.786511 -402.231117) (xy 389.734217 -402.246474) (xy 389.680269 -402.254233) (xy 389.653018 -402.25472)
			(xy 389.626064 -402.254204) (xy 389.572694 -402.246605) (xy 389.520925 -402.231571) (xy 389.471787 -402.209399)
			(xy 389.426259 -402.180533) (xy 389.385248 -402.145545) (xy 389.349568 -402.105134) (xy 389.319932 -402.060104)
			(xy 389.296928 -402.01135) (xy 389.288528 -401.985734) (xy 389.285666 -401.977666) (xy 389.275516 -401.963896)
			(xy 389.261394 -401.954244) (xy 389.253222 -401.951698) (xy 389.194802 -401.93595) (xy 389.18515 -401.945856)
			(xy 389.178546 -401.95246) (xy 389.170926 -401.969224) (xy 389.165592 -402.05533) (xy 389.170926 -402.07311)
			(xy 389.176768 -402.080476) (xy 389.193276 -402.102464) (xy 389.21955 -402.150757) (xy 389.237481 -402.202729)
			(xy 389.246577 -402.256949) (xy 389.247126 -402.284438) (xy 389.246616 -402.310425) (xy 389.238486 -402.36176)
			(xy 389.222425 -402.41119) (xy 389.198829 -402.4575) (xy 389.168279 -402.499548) (xy 389.131528 -402.536299)
			(xy 389.08948 -402.566849) (xy 389.04317 -402.590445) (xy 388.99374 -402.606506) (xy 388.942405 -402.614636)
			(xy 388.890431 -402.614636) (xy 388.839096 -402.606506) (xy 388.789666 -402.590445) (xy 388.743356 -402.566849)
			(xy 388.701308 -402.536299) (xy 388.664557 -402.499548) (xy 388.634007 -402.4575) (xy 388.610411 -402.41119)
			(xy 388.59435 -402.36176) (xy 388.58622 -402.310425) (xy 388.58571 -402.284438) (xy 388.586261 -402.256947)
			(xy 388.595337 -402.202721) (xy 388.613262 -402.150745) (xy 388.639543 -402.102452) (xy 388.656068 -402.080476)
			(xy 388.66191 -402.07311) (xy 388.667244 -402.05533) (xy 388.66191 -401.969224) (xy 388.65429 -401.95246)
			(xy 388.647686 -401.945856) (xy 388.626644 -401.92424) (xy 388.590998 -401.875576) (xy 388.563458 -401.821907)
			(xy 388.54471 -401.764571) (xy 388.535223 -401.704999) (xy 388.534656 -401.674838) (xy 388.098284 -401.674838)
			(xy 388.097874 -401.701013) (xy 388.090676 -401.752866) (xy 388.076462 -401.80325) (xy 388.055498 -401.851219)
			(xy 388.028176 -401.895875) (xy 387.995011 -401.936379) (xy 387.97611 -401.954492) (xy 387.968744 -401.96135)
			(xy 387.960616 -401.978876) (xy 387.955282 -402.069046) (xy 387.961378 -402.087334) (xy 387.967982 -402.094954)
			(xy 387.982879 -402.113001) (xy 388.007945 -402.152517) (xy 388.027193 -402.195171) (xy 388.040241 -402.24011)
			(xy 388.046828 -402.28644) (xy 388.04723 -402.309838) (xy 388.04672 -402.335825) (xy 388.03859 -402.38716)
			(xy 388.022529 -402.43659) (xy 387.998933 -402.4829) (xy 387.968383 -402.524948) (xy 387.931632 -402.561699)
			(xy 387.889584 -402.592249) (xy 387.843274 -402.615845) (xy 387.793844 -402.631906) (xy 387.742509 -402.640036)
			(xy 387.690535 -402.640036) (xy 387.6392 -402.631906) (xy 387.58977 -402.615845) (xy 387.54346 -402.592249)
			(xy 387.501412 -402.561699) (xy 387.464661 -402.524948) (xy 387.434111 -402.4829) (xy 387.410515 -402.43659)
			(xy 387.394454 -402.38716) (xy 387.386324 -402.335825) (xy 387.385814 -402.309838) (xy 387.386247 -402.286442)
			(xy 387.392833 -402.240116) (xy 387.405878 -402.195179) (xy 387.425122 -402.152528) (xy 387.450182 -402.113012)
			(xy 387.465062 -402.094954) (xy 387.471666 -402.087334) (xy 387.477762 -402.069046) (xy 387.472428 -401.978876)
			(xy 387.4643 -401.96135) (xy 387.456934 -401.954492) (xy 387.438025 -401.936389) (xy 387.404865 -401.895881)
			(xy 387.377552 -401.851223) (xy 387.356597 -401.803251) (xy 387.342393 -401.752866) (xy 387.335208 -401.701012)
			(xy 387.33476 -401.674838) (xy 386.89788 -401.674838) (xy 386.897414 -401.701001) (xy 386.890264 -401.752836)
			(xy 386.876103 -401.80321) (xy 386.855196 -401.851178) (xy 386.827935 -401.895842) (xy 386.794831 -401.936365)
			(xy 386.77596 -401.954492) (xy 386.768594 -401.96135) (xy 386.760466 -401.978876) (xy 386.755132 -402.069046)
			(xy 386.761228 -402.087334) (xy 386.767832 -402.094954) (xy 386.782737 -402.112994) (xy 386.807799 -402.152513)
			(xy 386.827046 -402.195169) (xy 386.840092 -402.240109) (xy 386.846678 -402.28644) (xy 386.84708 -402.309838)
			(xy 386.84657 -402.335825) (xy 386.83844 -402.38716) (xy 386.822379 -402.43659) (xy 386.798783 -402.4829)
			(xy 386.768233 -402.524948) (xy 386.731482 -402.561699) (xy 386.689434 -402.592249) (xy 386.643124 -402.615845)
			(xy 386.593694 -402.631906) (xy 386.542359 -402.640036) (xy 386.490385 -402.640036) (xy 386.43905 -402.631906)
			(xy 386.38962 -402.615845) (xy 386.34331 -402.592249) (xy 386.301262 -402.561699) (xy 386.264511 -402.524948)
			(xy 386.233961 -402.4829) (xy 386.210365 -402.43659) (xy 386.194304 -402.38716) (xy 386.186174 -402.335825)
			(xy 386.185664 -402.309838) (xy 386.186085 -402.286441) (xy 386.192672 -402.240114) (xy 386.205719 -402.195177)
			(xy 386.224966 -402.152526) (xy 386.25003 -402.113012) (xy 386.264912 -402.094954) (xy 386.271516 -402.087334)
			(xy 386.277612 -402.069046) (xy 386.272278 -401.978876) (xy 386.26415 -401.96135) (xy 386.256784 -401.954492)
			(xy 386.237887 -401.936389) (xy 386.20477 -401.895867) (xy 386.177502 -401.851201) (xy 386.156592 -401.803228)
			(xy 386.142433 -401.752847) (xy 386.135291 -401.701004) (xy 386.134864 -401.674838) (xy 385.697984 -401.674838)
			(xy 385.697464 -401.703743) (xy 385.688758 -401.760895) (xy 385.671534 -401.81608) (xy 385.646188 -401.868038)
			(xy 385.613298 -401.91558) (xy 385.593844 -401.936966) (xy 385.587748 -401.94357) (xy 385.580636 -401.959572)
			(xy 385.575048 -402.041868) (xy 385.579874 -402.058886) (xy 385.584954 -402.065998) (xy 385.599591 -402.087228)
			(xy 385.622844 -402.133249) (xy 385.63867 -402.182322) (xy 385.646685 -402.233257) (xy 385.647184 -402.259038)
			(xy 385.646674 -402.285025) (xy 385.638544 -402.33636) (xy 385.622483 -402.38579) (xy 385.598887 -402.4321)
			(xy 385.568337 -402.474148) (xy 385.531586 -402.510899) (xy 385.489538 -402.541449) (xy 385.443228 -402.565045)
			(xy 385.393798 -402.581106) (xy 385.342463 -402.589236) (xy 385.290489 -402.589236) (xy 385.239154 -402.581106)
			(xy 385.189724 -402.565045) (xy 385.143414 -402.541449) (xy 385.101366 -402.510899) (xy 385.064615 -402.474148)
			(xy 385.034065 -402.4321) (xy 385.010469 -402.38579) (xy 384.994408 -402.33636) (xy 384.986278 -402.285025)
			(xy 384.985768 -402.259038) (xy 384.986247 -402.233255) (xy 384.994253 -402.182314) (xy 385.010078 -402.133236)
			(xy 385.033337 -402.087213) (xy 385.047998 -402.065998) (xy 385.053078 -402.058886) (xy 385.057904 -402.041868)
			(xy 385.052316 -401.959572) (xy 385.045204 -401.94357) (xy 385.039108 -401.936966) (xy 385.019626 -401.915602)
			(xy 384.986718 -401.868065) (xy 384.961366 -401.816103) (xy 384.944154 -401.760908) (xy 384.935476 -401.703747)
			(xy 384.934968 -401.674838) (xy 384.498088 -401.674838) (xy 384.497619 -401.701001) (xy 384.490469 -401.752836)
			(xy 384.476308 -401.803209) (xy 384.455402 -401.851177) (xy 384.428142 -401.895841) (xy 384.395038 -401.936365)
			(xy 384.376168 -401.954492) (xy 384.368802 -401.96135) (xy 384.360674 -401.978876) (xy 384.35534 -402.069046)
			(xy 384.361436 -402.087334) (xy 384.36804 -402.094954) (xy 384.382946 -402.112993) (xy 384.408008 -402.152513)
			(xy 384.427254 -402.195168) (xy 384.4403 -402.240109) (xy 384.446886 -402.28644) (xy 384.447288 -402.309838)
			(xy 384.446778 -402.335825) (xy 384.438648 -402.38716) (xy 384.422587 -402.43659) (xy 384.398991 -402.4829)
			(xy 384.368441 -402.524948) (xy 384.33169 -402.561699) (xy 384.289642 -402.592249) (xy 384.243332 -402.615845)
			(xy 384.193902 -402.631906) (xy 384.142567 -402.640036) (xy 384.090593 -402.640036) (xy 384.039258 -402.631906)
			(xy 383.989828 -402.615845) (xy 383.943518 -402.592249) (xy 383.90147 -402.561699) (xy 383.864719 -402.524948)
			(xy 383.834169 -402.4829) (xy 383.810573 -402.43659) (xy 383.794512 -402.38716) (xy 383.786382 -402.335825)
			(xy 383.785872 -402.309838) (xy 383.786292 -402.286441) (xy 383.792878 -402.240114) (xy 383.805925 -402.195177)
			(xy 383.825173 -402.152526) (xy 383.850237 -402.113011) (xy 383.86512 -402.094954) (xy 383.871724 -402.087334)
			(xy 383.87782 -402.069046) (xy 383.872486 -401.978876) (xy 383.864358 -401.96135) (xy 383.856992 -401.954492)
			(xy 383.838096 -401.936387) (xy 383.804979 -401.895866) (xy 383.77771 -401.8512) (xy 383.7568 -401.803227)
			(xy 383.742641 -401.752847) (xy 383.735499 -401.701004) (xy 383.735072 -401.674838) (xy 383.298192 -401.674838)
			(xy 383.297722 -401.701001) (xy 383.290572 -401.752836) (xy 383.276411 -401.803209) (xy 383.255505 -401.851177)
			(xy 383.228245 -401.895841) (xy 383.195142 -401.936365) (xy 383.176272 -401.954492) (xy 383.168906 -401.96135)
			(xy 383.160778 -401.978876) (xy 383.155444 -402.069046) (xy 383.16154 -402.087334) (xy 383.168144 -402.094954)
			(xy 383.183051 -402.112993) (xy 383.208113 -402.152513) (xy 383.227358 -402.195168) (xy 383.240404 -402.240109)
			(xy 383.24699 -402.28644) (xy 383.247392 -402.309838) (xy 383.246882 -402.335825) (xy 383.238752 -402.38716)
			(xy 383.222691 -402.43659) (xy 383.199095 -402.4829) (xy 383.168545 -402.524948) (xy 383.131794 -402.561699)
			(xy 383.089746 -402.592249) (xy 383.043436 -402.615845) (xy 382.994006 -402.631906) (xy 382.942671 -402.640036)
			(xy 382.890697 -402.640036) (xy 382.839362 -402.631906) (xy 382.789932 -402.615845) (xy 382.743622 -402.592249)
			(xy 382.701574 -402.561699) (xy 382.664823 -402.524948) (xy 382.634273 -402.4829) (xy 382.610677 -402.43659)
			(xy 382.594616 -402.38716) (xy 382.586486 -402.335825) (xy 382.585976 -402.309838) (xy 382.586395 -402.286441)
			(xy 382.592981 -402.240114) (xy 382.606029 -402.195177) (xy 382.625277 -402.152526) (xy 382.650341 -402.113011)
			(xy 382.665224 -402.094954) (xy 382.671828 -402.087334) (xy 382.677924 -402.069046) (xy 382.67259 -401.978876)
			(xy 382.664462 -401.96135) (xy 382.657096 -401.954492) (xy 382.638201 -401.936387) (xy 382.605084 -401.895866)
			(xy 382.577815 -401.8512) (xy 382.556904 -401.803227) (xy 382.542745 -401.752847) (xy 382.535603 -401.701004)
			(xy 382.535176 -401.674838) (xy 382.098296 -401.674838) (xy 382.097882 -401.701013) (xy 382.090684 -401.752866)
			(xy 382.076471 -401.803249) (xy 382.055507 -401.851218) (xy 382.028187 -401.895874) (xy 381.995022 -401.936379)
			(xy 381.976122 -401.954492) (xy 381.968756 -401.96135) (xy 381.960628 -401.978876) (xy 381.955294 -402.069046)
			(xy 381.96139 -402.087334) (xy 381.967994 -402.094954) (xy 381.982893 -402.112999) (xy 382.007958 -402.152516)
			(xy 382.027206 -402.19517) (xy 382.040253 -402.24011) (xy 382.04684 -402.28644) (xy 382.047242 -402.309838)
			(xy 382.046732 -402.335825) (xy 382.038602 -402.38716) (xy 382.022541 -402.43659) (xy 381.998945 -402.4829)
			(xy 381.968395 -402.524948) (xy 381.931644 -402.561699) (xy 381.889596 -402.592249) (xy 381.843286 -402.615845)
			(xy 381.793856 -402.631906) (xy 381.742521 -402.640036) (xy 381.690547 -402.640036) (xy 381.639212 -402.631906)
			(xy 381.589782 -402.615845) (xy 381.543472 -402.592249) (xy 381.501424 -402.561699) (xy 381.464673 -402.524948)
			(xy 381.434123 -402.4829) (xy 381.410527 -402.43659) (xy 381.394466 -402.38716) (xy 381.386336 -402.335825)
			(xy 381.385826 -402.309838) (xy 381.386256 -402.286442) (xy 381.392842 -402.240116) (xy 381.405887 -402.195179)
			(xy 381.425132 -402.152528) (xy 381.450193 -402.113012) (xy 381.465074 -402.094954) (xy 381.471678 -402.087334)
			(xy 381.477774 -402.069046) (xy 381.47244 -401.978876) (xy 381.464312 -401.96135) (xy 381.456946 -401.954492)
			(xy 381.438039 -401.936386) (xy 381.404879 -401.89588) (xy 381.377565 -401.851222) (xy 381.356609 -401.80325)
			(xy 381.342405 -401.752865) (xy 381.33522 -401.701012) (xy 381.334772 -401.674838) (xy 380.8984 -401.674838)
			(xy 380.897985 -401.701013) (xy 380.890787 -401.752865) (xy 380.876574 -401.803249) (xy 380.85561 -401.851218)
			(xy 380.82829 -401.895874) (xy 380.795126 -401.936379) (xy 380.776226 -401.954492) (xy 380.76886 -401.96135)
			(xy 380.760732 -401.978876) (xy 380.755398 -402.069046) (xy 380.761494 -402.087334) (xy 380.768098 -402.094954)
			(xy 380.782998 -402.112999) (xy 380.808062 -402.152516) (xy 380.82731 -402.19517) (xy 380.840357 -402.24011)
			(xy 380.846944 -402.28644) (xy 380.847346 -402.309838) (xy 380.846836 -402.335825) (xy 380.838706 -402.38716)
			(xy 380.822645 -402.43659) (xy 380.799049 -402.4829) (xy 380.768499 -402.524948) (xy 380.731748 -402.561699)
			(xy 380.6897 -402.592249) (xy 380.64339 -402.615845) (xy 380.59396 -402.631906) (xy 380.542625 -402.640036)
			(xy 380.490651 -402.640036) (xy 380.439316 -402.631906) (xy 380.389886 -402.615845) (xy 380.343576 -402.592249)
			(xy 380.301528 -402.561699) (xy 380.264777 -402.524948) (xy 380.234227 -402.4829) (xy 380.210631 -402.43659)
			(xy 380.19457 -402.38716) (xy 380.18644 -402.335825) (xy 380.18593 -402.309838) (xy 380.18636 -402.286442)
			(xy 380.192945 -402.240115) (xy 380.205991 -402.195179) (xy 380.225236 -402.152527) (xy 380.250297 -402.113012)
			(xy 380.265178 -402.094954) (xy 380.271782 -402.087334) (xy 380.277878 -402.069046) (xy 380.272544 -401.978876)
			(xy 380.264416 -401.96135) (xy 380.25705 -401.954492) (xy 380.238144 -401.936385) (xy 380.204984 -401.895879)
			(xy 380.177669 -401.851221) (xy 380.156713 -401.80325) (xy 380.142509 -401.752865) (xy 380.135324 -401.701012)
			(xy 380.134876 -401.674838) (xy 379.697996 -401.674838) (xy 379.697454 -401.704988) (xy 379.687996 -401.76454)
			(xy 379.669291 -401.821865) (xy 379.641803 -401.875534) (xy 379.606217 -401.924213) (xy 379.58522 -401.945856)
			(xy 379.578616 -401.95246) (xy 379.570996 -401.969224) (xy 379.565662 -402.05533) (xy 379.570996 -402.07311)
			(xy 379.576838 -402.080476) (xy 379.593342 -402.102467) (xy 379.619618 -402.150759) (xy 379.63755 -402.202729)
			(xy 379.646647 -402.256949) (xy 379.647196 -402.284438) (xy 379.646686 -402.310425) (xy 379.638556 -402.36176)
			(xy 379.622495 -402.41119) (xy 379.598899 -402.4575) (xy 379.568349 -402.499548) (xy 379.531598 -402.536299)
			(xy 379.48955 -402.566849) (xy 379.44324 -402.590445) (xy 379.39381 -402.606506) (xy 379.342475 -402.614636)
			(xy 379.290501 -402.614636) (xy 379.239166 -402.606506) (xy 379.189736 -402.590445) (xy 379.143426 -402.566849)
			(xy 379.101378 -402.536299) (xy 379.064627 -402.499548) (xy 379.034077 -402.4575) (xy 379.010481 -402.41119)
			(xy 378.99442 -402.36176) (xy 378.98629 -402.310425) (xy 378.98578 -402.284438) (xy 378.986337 -402.256948)
			(xy 378.995412 -402.202722) (xy 379.013336 -402.150746) (xy 379.039614 -402.102452) (xy 379.056138 -402.080476)
			(xy 379.06198 -402.07311) (xy 379.067314 -402.05533) (xy 379.06198 -401.969224) (xy 379.05436 -401.95246)
			(xy 379.047756 -401.945856) (xy 379.026771 -401.924201) (xy 378.991175 -401.875531) (xy 378.963683 -401.821865)
			(xy 378.944979 -401.764541) (xy 378.935531 -401.704987) (xy 378.93498 -401.674838) (xy 378.4981 -401.674838)
			(xy 378.497576 -401.703743) (xy 378.48887 -401.760894) (xy 378.471647 -401.816079) (xy 378.446302 -401.868037)
			(xy 378.413413 -401.91558) (xy 378.39396 -401.936966) (xy 378.387864 -401.94357) (xy 378.380752 -401.959572)
			(xy 378.375164 -402.041868) (xy 378.37999 -402.058886) (xy 378.38507 -402.065998) (xy 378.399709 -402.087226)
			(xy 378.422961 -402.133248) (xy 378.438786 -402.182322) (xy 378.446801 -402.233257) (xy 378.4473 -402.259038)
			(xy 378.44679 -402.285025) (xy 378.43866 -402.33636) (xy 378.422599 -402.38579) (xy 378.399003 -402.4321)
			(xy 378.368453 -402.474148) (xy 378.331702 -402.510899) (xy 378.289654 -402.541449) (xy 378.243344 -402.565045)
			(xy 378.193914 -402.581106) (xy 378.142579 -402.589236) (xy 378.090605 -402.589236) (xy 378.03927 -402.581106)
			(xy 377.98984 -402.565045) (xy 377.94353 -402.541449) (xy 377.901482 -402.510899) (xy 377.864731 -402.474148)
			(xy 377.834181 -402.4321) (xy 377.810585 -402.38579) (xy 377.794524 -402.33636) (xy 377.786394 -402.285025)
			(xy 377.785884 -402.259038) (xy 377.78636 -402.233255) (xy 377.794367 -402.182313) (xy 377.810192 -402.133235)
			(xy 377.833452 -402.087212) (xy 377.848114 -402.065998) (xy 377.853194 -402.058886) (xy 377.85802 -402.041868)
			(xy 377.852432 -401.959572) (xy 377.84532 -401.94357) (xy 377.839224 -401.936966) (xy 377.819745 -401.9156)
			(xy 377.786835 -401.868064) (xy 377.761483 -401.816102) (xy 377.74427 -401.760908) (xy 377.735592 -401.703747)
			(xy 377.735084 -401.674838) (xy 377.298204 -401.674838) (xy 377.297788 -401.701013) (xy 377.29059 -401.752865)
			(xy 377.276377 -401.803248) (xy 377.255414 -401.851218) (xy 377.228094 -401.895874) (xy 377.19493 -401.936379)
			(xy 377.17603 -401.954492) (xy 377.168664 -401.96135) (xy 377.160536 -401.978876) (xy 377.155202 -402.069046)
			(xy 377.161298 -402.087334) (xy 377.167902 -402.094954) (xy 377.182802 -402.112998) (xy 377.207867 -402.152516)
			(xy 377.227114 -402.19517) (xy 377.240161 -402.24011) (xy 377.246748 -402.28644) (xy 377.24715 -402.309838)
			(xy 377.24664 -402.335825) (xy 377.23851 -402.38716) (xy 377.222449 -402.43659) (xy 377.198853 -402.4829)
			(xy 377.168303 -402.524948) (xy 377.131552 -402.561699) (xy 377.089504 -402.592249) (xy 377.043194 -402.615845)
			(xy 376.993764 -402.631906) (xy 376.942429 -402.640036) (xy 376.890455 -402.640036) (xy 376.83912 -402.631906)
			(xy 376.78969 -402.615845) (xy 376.74338 -402.592249) (xy 376.701332 -402.561699) (xy 376.664581 -402.524948)
			(xy 376.634031 -402.4829) (xy 376.610435 -402.43659) (xy 376.594374 -402.38716) (xy 376.586244 -402.335825)
			(xy 376.585734 -402.309838) (xy 376.586163 -402.286442) (xy 376.592748 -402.240115) (xy 376.605794 -402.195178)
			(xy 376.62504 -402.152527) (xy 376.650101 -402.113012) (xy 376.664982 -402.094954) (xy 376.671586 -402.087334)
			(xy 376.677682 -402.069046) (xy 376.672348 -401.978876) (xy 376.66422 -401.96135) (xy 376.656854 -401.954492)
			(xy 376.637949 -401.936385) (xy 376.604788 -401.895879) (xy 376.577473 -401.851221) (xy 376.556518 -401.80325)
			(xy 376.542313 -401.752865) (xy 376.535128 -401.701012) (xy 376.53468 -401.674838) (xy 376.098308 -401.674838)
			(xy 376.09789 -401.701012) (xy 376.090693 -401.752865) (xy 376.07648 -401.803248) (xy 376.055517 -401.851217)
			(xy 376.028197 -401.895873) (xy 375.995034 -401.936378) (xy 375.976134 -401.954492) (xy 375.968768 -401.96135)
			(xy 375.96064 -401.978876) (xy 375.955306 -402.069046) (xy 375.961402 -402.087334) (xy 375.968006 -402.094954)
			(xy 375.982907 -402.112998) (xy 376.007971 -402.152515) (xy 376.027218 -402.19517) (xy 376.040266 -402.24011)
			(xy 376.046852 -402.28644) (xy 376.047254 -402.309838) (xy 376.046744 -402.335825) (xy 376.038614 -402.38716)
			(xy 376.022553 -402.43659) (xy 375.998957 -402.4829) (xy 375.968407 -402.524948) (xy 375.931656 -402.561699)
			(xy 375.889608 -402.592249) (xy 375.843298 -402.615845) (xy 375.793868 -402.631906) (xy 375.742533 -402.640036)
			(xy 375.690559 -402.640036) (xy 375.639224 -402.631906) (xy 375.589794 -402.615845) (xy 375.543484 -402.592249)
			(xy 375.501436 -402.561699) (xy 375.464685 -402.524948) (xy 375.434135 -402.4829) (xy 375.410539 -402.43659)
			(xy 375.394478 -402.38716) (xy 375.386348 -402.335825) (xy 375.385838 -402.309838) (xy 375.386266 -402.286442)
			(xy 375.392852 -402.240115) (xy 375.405897 -402.195178) (xy 375.425143 -402.152527) (xy 375.450205 -402.113012)
			(xy 375.465086 -402.094954) (xy 375.47169 -402.087334) (xy 375.477786 -402.069046) (xy 375.472452 -401.978876)
			(xy 375.464324 -401.96135) (xy 375.456958 -401.954492) (xy 375.438054 -401.936384) (xy 375.404893 -401.895878)
			(xy 375.377578 -401.851221) (xy 375.356622 -401.80325) (xy 375.342418 -401.752865) (xy 375.335232 -401.701012)
			(xy 375.334784 -401.674838) (xy 374.897904 -401.674838) (xy 374.897379 -401.703743) (xy 374.888673 -401.760894)
			(xy 374.87145 -401.816079) (xy 374.846105 -401.868037) (xy 374.813217 -401.91558) (xy 374.793764 -401.936966)
			(xy 374.787668 -401.94357) (xy 374.780556 -401.959572) (xy 374.774968 -402.041868) (xy 374.779794 -402.058886)
			(xy 374.784874 -402.065998) (xy 374.799513 -402.087226) (xy 374.822765 -402.133248) (xy 374.83859 -402.182321)
			(xy 374.846605 -402.233257) (xy 374.847104 -402.259038) (xy 374.846594 -402.285025) (xy 374.838464 -402.33636)
			(xy 374.822403 -402.38579) (xy 374.798807 -402.4321) (xy 374.768257 -402.474148) (xy 374.731506 -402.510899)
			(xy 374.689458 -402.541449) (xy 374.643148 -402.565045) (xy 374.593718 -402.581106) (xy 374.542383 -402.589236)
			(xy 374.490409 -402.589236) (xy 374.439074 -402.581106) (xy 374.389644 -402.565045) (xy 374.343334 -402.541449)
			(xy 374.301286 -402.510899) (xy 374.264535 -402.474148) (xy 374.233985 -402.4321) (xy 374.210389 -402.38579)
			(xy 374.194328 -402.33636) (xy 374.186198 -402.285025) (xy 374.185688 -402.259038) (xy 374.186163 -402.233255)
			(xy 374.19417 -402.182313) (xy 374.209996 -402.133235) (xy 374.233256 -402.087212) (xy 374.247918 -402.065998)
			(xy 374.252998 -402.058886) (xy 374.257824 -402.041868) (xy 374.252236 -401.959572) (xy 374.245124 -401.94357)
			(xy 374.239028 -401.936966) (xy 374.21955 -401.915599) (xy 374.18664 -401.868063) (xy 374.161287 -401.816102)
			(xy 374.144074 -401.760908) (xy 374.135396 -401.703747) (xy 374.134888 -401.674838) (xy 373.698008 -401.674838)
			(xy 373.697533 -401.701001) (xy 373.690383 -401.752835) (xy 373.676223 -401.803208) (xy 373.655318 -401.851176)
			(xy 373.628059 -401.89584) (xy 373.594958 -401.936364) (xy 373.576088 -401.954492) (xy 373.568722 -401.96135)
			(xy 373.560594 -401.978876) (xy 373.55526 -402.069046) (xy 373.561356 -402.087334) (xy 373.56796 -402.094954)
			(xy 373.582854 -402.113003) (xy 373.607921 -402.152519) (xy 373.62717 -402.195172) (xy 373.640219 -402.240111)
			(xy 373.646806 -402.28644) (xy 373.647208 -402.309838) (xy 373.646698 -402.335825) (xy 373.638568 -402.38716)
			(xy 373.622507 -402.43659) (xy 373.598911 -402.4829) (xy 373.568361 -402.524948) (xy 373.53161 -402.561699)
			(xy 373.489562 -402.592249) (xy 373.443252 -402.615845) (xy 373.393822 -402.631906) (xy 373.342487 -402.640036)
			(xy 373.290513 -402.640036) (xy 373.239178 -402.631906) (xy 373.189748 -402.615845) (xy 373.143438 -402.592249)
			(xy 373.10139 -402.561699) (xy 373.064639 -402.524948) (xy 373.034089 -402.4829) (xy 373.010493 -402.43659)
			(xy 372.994432 -402.38716) (xy 372.986302 -402.335825) (xy 372.985792 -402.309838) (xy 372.986231 -402.286442)
			(xy 372.992815 -402.240117) (xy 373.005859 -402.19518) (xy 373.025102 -402.152529) (xy 373.050161 -402.113013)
			(xy 373.06504 -402.094954) (xy 373.071644 -402.087334) (xy 373.07774 -402.069046) (xy 373.072406 -401.978876)
			(xy 373.064278 -401.96135) (xy 373.056912 -401.954492) (xy 373.03802 -401.936384) (xy 373.004902 -401.895864)
			(xy 372.977632 -401.851199) (xy 372.956721 -401.803226) (xy 372.942561 -401.752846) (xy 372.935419 -401.701004)
			(xy 372.934992 -401.674838) (xy 372.498112 -401.674838) (xy 372.497511 -401.704996) (xy 372.488016 -401.764561)
			(xy 372.469269 -401.821891) (xy 372.441736 -401.875557) (xy 372.406103 -401.924223) (xy 372.385082 -401.945856)
			(xy 372.378478 -401.95246) (xy 372.370858 -401.969224) (xy 372.365524 -402.05533) (xy 372.370858 -402.07311)
			(xy 372.3767 -402.080476) (xy 372.393212 -402.10246) (xy 372.419484 -402.150755) (xy 372.437415 -402.202728)
			(xy 372.44651 -402.256949) (xy 372.447058 -402.284438) (xy 372.446548 -402.310425) (xy 372.438418 -402.36176)
			(xy 372.422357 -402.41119) (xy 372.398761 -402.4575) (xy 372.368211 -402.499548) (xy 372.33146 -402.536299)
			(xy 372.289412 -402.566849) (xy 372.243102 -402.590445) (xy 372.193672 -402.606506) (xy 372.142337 -402.614636)
			(xy 372.090363 -402.614636) (xy 372.039028 -402.606506) (xy 371.989598 -402.590445) (xy 371.943288 -402.566849)
			(xy 371.90124 -402.536299) (xy 371.864489 -402.499548) (xy 371.833939 -402.4575) (xy 371.810343 -402.41119)
			(xy 371.794282 -402.36176) (xy 371.786152 -402.310425) (xy 371.785642 -402.284438) (xy 371.786207 -402.256948)
			(xy 371.795281 -402.202723) (xy 371.813203 -402.150747) (xy 371.839478 -402.102453) (xy 371.856 -402.080476)
			(xy 371.861842 -402.07311) (xy 371.867176 -402.05533) (xy 371.861842 -401.969224) (xy 371.854222 -401.95246)
			(xy 371.847618 -401.945856) (xy 371.826582 -401.924234) (xy 371.790934 -401.875572) (xy 371.763392 -401.821905)
			(xy 371.744644 -401.76457) (xy 371.735156 -401.704999) (xy 371.734588 -401.674838) (xy 371.298216 -401.674838)
			(xy 371.297614 -401.704996) (xy 371.288119 -401.764561) (xy 371.269372 -401.82189) (xy 371.241839 -401.875556)
			(xy 371.206207 -401.924223) (xy 371.185186 -401.945856) (xy 371.178582 -401.95246) (xy 371.170962 -401.969224)
			(xy 371.165628 -402.05533) (xy 371.170962 -402.07311) (xy 371.176804 -402.080476) (xy 371.193317 -402.10246)
			(xy 371.219589 -402.150755) (xy 371.237519 -402.202728) (xy 371.246614 -402.256949) (xy 371.247162 -402.284438)
			(xy 371.246652 -402.310425) (xy 371.238522 -402.36176) (xy 371.222461 -402.41119) (xy 371.198865 -402.4575)
			(xy 371.168315 -402.499548) (xy 371.131564 -402.536299) (xy 371.089516 -402.566849) (xy 371.043206 -402.590445)
			(xy 370.993776 -402.606506) (xy 370.942441 -402.614636) (xy 370.890467 -402.614636) (xy 370.839132 -402.606506)
			(xy 370.789702 -402.590445) (xy 370.743392 -402.566849) (xy 370.701344 -402.536299) (xy 370.664593 -402.499548)
			(xy 370.634043 -402.4575) (xy 370.610447 -402.41119) (xy 370.594386 -402.36176) (xy 370.586256 -402.310425)
			(xy 370.585746 -402.284438) (xy 370.58631 -402.256948) (xy 370.595385 -402.202723) (xy 370.613306 -402.150747)
			(xy 370.639582 -402.102453) (xy 370.656104 -402.080476) (xy 370.661946 -402.07311) (xy 370.66728 -402.05533)
			(xy 370.661946 -401.969224) (xy 370.654326 -401.95246) (xy 370.647722 -401.945856) (xy 370.626669 -401.92425)
			(xy 370.591027 -401.875582) (xy 370.56349 -401.82191) (xy 370.544745 -401.764573) (xy 370.535259 -401.705)
			(xy 370.534692 -401.674838) (xy 369.444524 -401.674838) (xy 369.444524 -402.005292) (xy 369.444094 -402.037104)
			(xy 369.436967 -402.100327) (xy 369.422801 -402.162353) (xy 369.401775 -402.222402) (xy 369.374154 -402.279717)
			(xy 369.340286 -402.333577) (xy 369.300596 -402.383303) (xy 369.278408 -402.406104) (xy 368.571526 -403.112986)
			(xy 368.564831 -403.12043) (xy 368.557228 -403.138928) (xy 368.55724 -403.158928) (xy 368.560604 -403.168358)
			(xy 368.566446 -403.182582) (xy 368.591846 -403.1996) (xy 369.36934 -403.1996) (xy 369.379698 -403.19918)
			(xy 369.398769 -403.191107) (xy 369.413078 -403.176135) (xy 369.417092 -403.16658) (xy 369.455954 -403.062694)
			(xy 369.448334 -403.03196) (xy 369.436142 -403.021546) (xy 369.416022 -403.003325) (xy 369.380626 -402.962174)
			(xy 369.351415 -402.916424) (xy 369.328978 -402.866998) (xy 369.313768 -402.814893) (xy 369.306092 -402.761158)
			(xy 369.305586 -402.734018) (xy 369.306072 -402.706767) (xy 369.313828 -402.652819) (xy 369.329183 -402.600524)
			(xy 369.351825 -402.550947) (xy 369.381291 -402.505097) (xy 369.416982 -402.463906) (xy 369.458173 -402.428215)
			(xy 369.504023 -402.398749) (xy 369.5536 -402.376107) (xy 369.605895 -402.360752) (xy 369.659843 -402.352996)
			(xy 369.714345 -402.352996) (xy 369.768293 -402.360752) (xy 369.820588 -402.376107) (xy 369.870165 -402.398749)
			(xy 369.916015 -402.428215) (xy 369.957206 -402.463906) (xy 369.992897 -402.505097) (xy 370.022363 -402.550947)
			(xy 370.045005 -402.600524) (xy 370.06036 -402.652819) (xy 370.068116 -402.706767) (xy 370.068602 -402.734018)
			(xy 370.06808 -402.76239) (xy 370.05967 -402.818508) (xy 370.043039 -402.87276) (xy 370.018553 -402.923949)
			(xy 369.986753 -402.970946) (xy 369.948342 -403.012712) (xy 369.904166 -403.048327) (xy 369.855201 -403.077003)
			(xy 369.82908 -403.088094) (xy 369.816888 -403.09292) (xy 369.800632 -403.112478) (xy 369.781074 -403.208236)
			(xy 369.779202 -403.220696) (xy 369.786398 -403.244811) (xy 369.79479 -403.25421) (xy 370.842794 -404.302214)
			(xy 370.850188 -404.309071) (xy 370.868787 -404.316821) (xy 370.878862 -404.3172)
		)
		(stroke
			(width 0)
			(type solid)
		)
		(fill yes)
		(layer "In4.Cu")
		(net "P0V9_CPU0_RT3_2A_2D")
	)
	(gr_poly
		(pts
			(xy 392.899138 -403.81174) (xy 392.902881 -403.811661) (xy 392.91028 -403.810517) (xy 392.91387 -403.809454)
			(xy 397.528034 -402.40966) (xy 397.537207 -402.406424) (xy 397.552366 -402.394262) (xy 397.561905 -402.377329)
			(xy 397.563594 -402.36775) (xy 397.577818 -402.26107) (xy 397.565118 -402.2344) (xy 397.552418 -402.226526)
			(xy 397.539677 -402.218363) (xy 397.515392 -402.200307) (xy 397.503904 -402.190458) (xy 397.496792 -402.184362)
			(xy 397.479774 -402.178012) (xy 397.39443 -402.178012) (xy 397.377412 -402.184362) (xy 397.3703 -402.190458)
			(xy 397.349369 -402.208102) (xy 397.303404 -402.237831) (xy 397.253657 -402.260677) (xy 397.201153 -402.276169)
			(xy 397.146973 -402.283988) (xy 397.119602 -402.284438) (xy 397.09235 -402.283952) (xy 397.0384 -402.276196)
			(xy 396.986104 -402.260842) (xy 396.936524 -402.238201) (xy 396.890671 -402.208735) (xy 396.849479 -402.173044)
			(xy 396.813784 -402.131854) (xy 396.784314 -402.086004) (xy 396.76167 -402.036426) (xy 396.746311 -401.984131)
			(xy 396.73855 -401.930182) (xy 396.738094 -401.90293) (xy 396.738571 -401.875562) (xy 396.746403 -401.821388)
			(xy 396.761898 -401.76889) (xy 396.784736 -401.719146) (xy 396.814449 -401.673176) (xy 396.832074 -401.652232)
			(xy 396.83817 -401.64512) (xy 396.84452 -401.628102) (xy 396.84452 -401.542758) (xy 396.83817 -401.52574)
			(xy 396.832074 -401.518628) (xy 396.814429 -401.497696) (xy 396.784697 -401.451729) (xy 396.761844 -401.401981)
			(xy 396.746342 -401.349477) (xy 396.738509 -401.295295) (xy 396.738506 -401.24055) (xy 396.746332 -401.186367)
			(xy 396.761828 -401.133861) (xy 396.784675 -401.084111) (xy 396.814402 -401.03814) (xy 396.832074 -401.017232)
			(xy 396.83817 -401.01012) (xy 396.84452 -400.993102) (xy 396.84452 -400.907758) (xy 396.83817 -400.89074)
			(xy 396.832074 -400.883628) (xy 396.814429 -400.862696) (xy 396.784697 -400.816729) (xy 396.761844 -400.766981)
			(xy 396.746342 -400.714477) (xy 396.738509 -400.660295) (xy 396.738506 -400.60555) (xy 396.746332 -400.551367)
			(xy 396.761828 -400.498861) (xy 396.784675 -400.449111) (xy 396.814402 -400.40314) (xy 396.832074 -400.382232)
			(xy 396.83817 -400.37512) (xy 396.84452 -400.358102) (xy 396.84452 -400.272758) (xy 396.83817 -400.25574)
			(xy 396.832074 -400.248628) (xy 396.814432 -400.227697) (xy 396.784704 -400.18173) (xy 396.761859 -400.131984)
			(xy 396.746366 -400.079481) (xy 396.738544 -400.025301) (xy 396.738094 -399.99793) (xy 396.738582 -399.969973)
			(xy 396.746744 -399.914657) (xy 396.762896 -399.861126) (xy 396.786693 -399.810529) (xy 396.817624 -399.763948)
			(xy 396.855026 -399.722385) (xy 396.898097 -399.686729) (xy 396.921736 -399.671794) (xy 396.930372 -399.66646)
			(xy 396.942056 -399.650712) (xy 396.964916 -399.562828) (xy 396.962122 -399.543016) (xy 396.957296 -399.53438)
			(xy 396.945361 -399.512683) (xy 396.92657 -399.466868) (xy 396.913854 -399.419009) (xy 396.907426 -399.369909)
			(xy 396.907004 -399.34515) (xy 396.907591 -399.31525) (xy 396.916911 -399.25618) (xy 396.925546 -399.227548)
			(xy 396.929102 -399.21688) (xy 396.926308 -399.195036) (xy 396.874492 -399.109946) (xy 396.856204 -399.097754)
			(xy 396.845028 -399.095976) (xy 396.818516 -399.091235) (xy 396.767079 -399.075274) (xy 396.718398 -399.052237)
			(xy 396.673442 -399.022581) (xy 396.633104 -398.986895) (xy 396.598187 -398.945891) (xy 396.569385 -398.900383)
			(xy 396.547271 -398.851276) (xy 396.532285 -398.799546) (xy 396.524724 -398.746223) (xy 396.524226 -398.719294)
			(xy 396.524712 -398.692043) (xy 396.532468 -398.638095) (xy 396.547823 -398.5858) (xy 396.570465 -398.536223)
			(xy 396.599931 -398.490373) (xy 396.635622 -398.449182) (xy 396.676813 -398.413491) (xy 396.722663 -398.384025)
			(xy 396.77224 -398.361383) (xy 396.824535 -398.346028) (xy 396.878483 -398.338272) (xy 396.932985 -398.338272)
			(xy 396.986933 -398.346028) (xy 397.039228 -398.361383) (xy 397.088805 -398.384025) (xy 397.134655 -398.413491)
			(xy 397.175846 -398.449182) (xy 397.211537 -398.490373) (xy 397.241003 -398.536223) (xy 397.263645 -398.5858)
			(xy 397.279 -398.638095) (xy 397.286756 -398.692043) (xy 397.287242 -398.719294) (xy 397.286659 -398.749195)
			(xy 397.277346 -398.808267) (xy 397.2687 -398.836896) (xy 397.265144 -398.847564) (xy 397.267938 -398.869408)
			(xy 397.319754 -398.954498) (xy 397.338042 -398.96669) (xy 397.349218 -398.968468) (xy 397.375729 -398.973211)
			(xy 397.427165 -398.989176) (xy 397.475844 -399.012215) (xy 397.5208 -399.041872) (xy 397.561137 -399.077557)
			(xy 397.596055 -399.11856) (xy 397.624859 -399.164067) (xy 397.646976 -399.213172) (xy 397.661968 -399.2649)
			(xy 397.669535 -399.318222) (xy 397.67002 -399.34515) (xy 397.669295 -399.379439) (xy 397.657021 -399.44691)
			(xy 397.645636 -399.479262) (xy 397.641064 -399.491454) (xy 397.644366 -399.516346) (xy 397.708374 -399.605754)
			(xy 397.730726 -399.61693) (xy 397.74368 -399.616676) (xy 397.754602 -399.616422) (xy 397.781972 -399.616894)
			(xy 397.83615 -399.624718) (xy 397.888653 -399.640206) (xy 397.938403 -399.66304) (xy 397.984379 -399.69275)
			(xy 398.0053 -399.710402) (xy 398.012412 -399.716498) (xy 398.02943 -399.722848) (xy 398.114774 -399.722848)
			(xy 398.131792 -399.716498) (xy 398.138904 -399.710402) (xy 398.159837 -399.692761) (xy 398.205805 -399.663037)
			(xy 398.255551 -399.640191) (xy 398.308053 -399.624695) (xy 398.362231 -399.616866) (xy 398.416973 -399.616866)
			(xy 398.471151 -399.624695) (xy 398.523653 -399.640191) (xy 398.573399 -399.663037) (xy 398.619367 -399.692761)
			(xy 398.6403 -399.710402) (xy 398.647412 -399.716498) (xy 398.66443 -399.722848) (xy 398.749774 -399.722848)
			(xy 398.766792 -399.716498) (xy 398.773904 -399.710402) (xy 398.794835 -399.69276) (xy 398.840802 -399.663034)
			(xy 398.890549 -399.640192) (xy 398.943052 -399.624702) (xy 398.997232 -399.616884) (xy 399.024602 -399.616422)
			(xy 399.051854 -399.616885) (xy 399.105803 -399.624643) (xy 399.158099 -399.639999) (xy 399.207677 -399.662642)
			(xy 399.253528 -399.692111) (xy 399.294718 -399.727805) (xy 399.330408 -399.768998) (xy 399.359873 -399.814851)
			(xy 399.382512 -399.864431) (xy 399.397864 -399.916728) (xy 399.405617 -399.970678) (xy 399.40611 -399.99793)
			(xy 399.405636 -400.025299) (xy 399.397809 -400.079476) (xy 399.382319 -400.131977) (xy 399.359484 -400.181726)
			(xy 399.329774 -400.2277) (xy 399.31213 -400.248628) (xy 399.306034 -400.25574) (xy 399.299684 -400.272758)
			(xy 399.299684 -400.358102) (xy 399.306034 -400.37512) (xy 399.31213 -400.382232) (xy 399.3288 -400.402016)
			(xy 399.357215 -400.445249) (xy 399.379538 -400.491919) (xy 399.39536 -400.541175) (xy 399.404394 -400.592115)
			(xy 399.405856 -400.617944) (xy 399.406364 -400.633184) (xy 399.42389 -400.657822) (xy 399.524728 -400.697192)
			(xy 399.534032 -400.700353) (xy 399.553663 -400.70014) (xy 399.571787 -400.692596) (xy 399.579084 -400.686016)
			(xy 399.652998 -400.612102) (xy 399.660618 -400.592798) (xy 399.66011 -400.581876) (xy 399.659856 -400.567652)
			(xy 399.660345 -400.540402) (xy 399.668107 -400.486458) (xy 399.683466 -400.434167) (xy 399.706109 -400.384593)
			(xy 399.735576 -400.338746) (xy 399.771267 -400.297559) (xy 399.812456 -400.261869) (xy 399.858304 -400.232403)
			(xy 399.907878 -400.209762) (xy 399.960169 -400.194404) (xy 400.014114 -400.186644) (xy 400.041364 -400.186144)
			(xy 400.055588 -400.186398) (xy 400.06651 -400.186906) (xy 400.085814 -400.179286) (xy 400.794982 -399.470118)
			(xy 400.798538 -399.463768) (xy 400.802602 -399.456402) (xy 400.805904 -399.45056) (xy 400.80946 -399.43786)
			(xy 400.80946 -399.410174) (xy 400.808995 -399.399518) (xy 400.8003 -399.380063) (xy 400.792696 -399.372582)
			(xy 400.769582 -399.351754) (xy 400.761971 -399.345431) (xy 400.743409 -399.338637) (xy 400.733514 -399.338546)
			(xy 400.721068 -399.3388) (xy 400.695083 -399.338288) (xy 400.643753 -399.330153) (xy 400.594327 -399.31409)
			(xy 400.548022 -399.290492) (xy 400.505979 -399.259941) (xy 400.469233 -399.22319) (xy 400.438687 -399.181144)
			(xy 400.415095 -399.134836) (xy 400.399037 -399.085408) (xy 400.390909 -399.034077) (xy 400.39036 -399.008092)
			(xy 400.390754 -398.984858) (xy 400.397257 -398.938848) (xy 400.410135 -398.8942) (xy 400.429133 -398.851794)
			(xy 400.453878 -398.812463) (xy 400.468592 -398.794478) (xy 400.474688 -398.787366) (xy 400.480784 -398.770856)
			(xy 400.480784 -398.686528) (xy 400.474688 -398.670018) (xy 400.468592 -398.662906) (xy 400.453883 -398.644916)
			(xy 400.429126 -398.60559) (xy 400.410119 -398.563186) (xy 400.397236 -398.518538) (xy 400.390731 -398.472527)
			(xy 400.39036 -398.449292) (xy 400.39087 -398.423304) (xy 400.399001 -398.371969) (xy 400.415063 -398.322537)
			(xy 400.438659 -398.276227) (xy 400.469208 -398.234177) (xy 400.505959 -398.197423) (xy 400.548006 -398.166871)
			(xy 400.594315 -398.143272) (xy 400.643746 -398.127207) (xy 400.69508 -398.119072) (xy 400.721068 -398.118584)
			(xy 400.746492 -398.119055) (xy 400.796738 -398.126845) (xy 400.845202 -398.142232) (xy 400.890739 -398.164854)
			(xy 400.93228 -398.194177) (xy 400.968844 -398.229511) (xy 400.999571 -398.270024) (xy 401.023738 -398.314761)
			(xy 401.032726 -398.338548) (xy 401.037044 -398.351248) (xy 401.056348 -398.368266) (xy 401.153122 -398.39011)
			(xy 401.161567 -398.391671) (xy 401.178618 -398.389708) (xy 401.194069 -398.382234) (xy 401.200366 -398.376394)
			(xy 402.833586 -396.743174) (xy 402.841206 -396.724632) (xy 402.840952 -396.714218) (xy 402.840952 -396.710662)
			(xy 402.841451 -396.685263) (xy 402.84985 -396.635166) (xy 402.866426 -396.58715) (xy 402.890721 -396.54254)
			(xy 402.922066 -396.502567) (xy 402.94052 -396.48511) (xy 402.948902 -396.47749) (xy 402.957538 -396.457424)
			(xy 402.954744 -396.35811) (xy 402.945346 -396.338552) (xy 402.936456 -396.33144) (xy 402.917892 -396.315639)
			(xy 402.88516 -396.279515) (xy 402.858083 -396.238978) (xy 402.837246 -396.194908) (xy 402.823101 -396.148257)
			(xy 402.815954 -396.100036) (xy 402.815552 -396.075662) (xy 402.815991 -396.051546) (xy 402.822997 -396.003827)
			(xy 402.836857 -395.957629) (xy 402.857275 -395.913933) (xy 402.870162 -395.893544) (xy 402.876004 -395.884654)
			(xy 402.87956 -395.864588) (xy 402.858478 -395.772386) (xy 402.846286 -395.755622) (xy 402.837396 -395.750288)
			(xy 402.816592 -395.737434) (xy 402.77867 -395.706558) (xy 402.745715 -395.670429) (xy 402.718447 -395.629835)
			(xy 402.697462 -395.585665) (xy 402.683219 -395.538883) (xy 402.67603 -395.490513) (xy 402.675598 -395.466062)
			(xy 402.676159 -395.438779) (xy 402.68512 -395.384955) (xy 402.702792 -395.333331) (xy 402.728697 -395.285307)
			(xy 402.762131 -395.242185) (xy 402.78177 -395.223238) (xy 402.789222 -395.215748) (xy 402.79777 -395.196452)
			(xy 402.79828 -395.1859) (xy 402.79828 -395.111224) (xy 402.797693 -395.100689) (xy 402.789163 -395.081415)
			(xy 402.78177 -395.073886) (xy 402.762114 -395.054954) (xy 402.728668 -395.011834) (xy 402.702757 -394.963807)
			(xy 402.685085 -394.912178) (xy 402.67613 -394.858347) (xy 402.675598 -394.831062) (xy 402.676029 -394.80739)
			(xy 402.682782 -394.76053) (xy 402.696132 -394.715107) (xy 402.70557 -394.693394) (xy 402.709888 -394.683996)
			(xy 402.71065 -394.66393) (xy 402.678392 -394.57757) (xy 402.664676 -394.562838) (xy 402.655278 -394.55852)
			(xy 402.630907 -394.546828) (xy 402.58602 -394.516719) (xy 402.546629 -394.47971) (xy 402.513784 -394.436784)
			(xy 402.488359 -394.389087) (xy 402.471033 -394.33789) (xy 402.462268 -394.284555) (xy 402.46173 -394.25753)
			(xy 402.46224 -394.231543) (xy 402.47037 -394.180208) (xy 402.486431 -394.130778) (xy 402.510027 -394.084468)
			(xy 402.540577 -394.04242) (xy 402.577328 -394.005669) (xy 402.619376 -393.975119) (xy 402.665686 -393.951523)
			(xy 402.715116 -393.935462) (xy 402.766451 -393.927332) (xy 402.818425 -393.927332) (xy 402.86976 -393.935462)
			(xy 402.91919 -393.951523) (xy 402.9655 -393.975119) (xy 403.007548 -394.005669) (xy 403.044299 -394.04242)
			(xy 403.074849 -394.084468) (xy 403.098445 -394.130778) (xy 403.114506 -394.180208) (xy 403.122636 -394.231543)
			(xy 403.123146 -394.25753) (xy 403.122715 -394.281202) (xy 403.115962 -394.328062) (xy 403.102612 -394.373484)
			(xy 403.093174 -394.395198) (xy 403.088856 -394.404596) (xy 403.088094 -394.424662) (xy 403.120352 -394.511022)
			(xy 403.134068 -394.525754) (xy 403.143466 -394.530072) (xy 403.167834 -394.541766) (xy 403.212717 -394.571878)
			(xy 403.252104 -394.608889) (xy 403.284946 -394.651814) (xy 403.310367 -394.69951) (xy 403.327692 -394.750706)
			(xy 403.336457 -394.804038) (xy 403.337014 -394.831062) (xy 403.336451 -394.858344) (xy 403.327487 -394.912166)
			(xy 403.309813 -394.963788) (xy 403.283907 -395.01181) (xy 403.250472 -395.05493) (xy 403.230842 -395.073886)
			(xy 403.223392 -395.081377) (xy 403.214851 -395.100673) (xy 403.214332 -395.111224) (xy 403.214332 -395.1859)
			(xy 403.214924 -395.196432) (xy 403.223461 -395.215698) (xy 403.230842 -395.223238) (xy 403.250496 -395.242171)
			(xy 403.283938 -395.285292) (xy 403.309844 -395.333319) (xy 403.327512 -395.384948) (xy 403.336463 -395.438778)
			(xy 403.337014 -395.466062) (xy 403.336581 -395.49018) (xy 403.329585 -395.537905) (xy 403.315737 -395.584109)
			(xy 403.29533 -395.627815) (xy 403.282404 -395.64818) (xy 403.276562 -395.65707) (xy 403.273006 -395.677136)
			(xy 403.294088 -395.769338) (xy 403.30628 -395.786102) (xy 403.31517 -395.791436) (xy 403.33597 -395.804293)
			(xy 403.373882 -395.835173) (xy 403.406828 -395.871305) (xy 403.434087 -395.911899) (xy 403.455064 -395.956068)
			(xy 403.469301 -396.002847) (xy 403.476485 -396.051213) (xy 403.476968 -396.075662) (xy 403.47653 -396.100033)
			(xy 403.469375 -396.148246) (xy 403.455227 -396.19489) (xy 403.434394 -396.238955) (xy 403.407324 -396.279489)
			(xy 403.374605 -396.315616) (xy 403.356064 -396.33144) (xy 403.347174 -396.338552) (xy 403.337776 -396.35811)
			(xy 403.334982 -396.457424) (xy 403.343618 -396.47749) (xy 403.352 -396.48511) (xy 403.359901 -396.492391)
			(xy 403.374776 -396.507898) (xy 403.381718 -396.516098) (xy 403.389319 -396.524383) (xy 403.409609 -396.534013)
			(xy 403.420834 -396.53464) (xy 404.071582 -396.53464) (xy 404.08282 -396.534056) (xy 404.103125 -396.524423)
			(xy 404.110698 -396.516098) (xy 404.117644 -396.507901) (xy 404.132518 -396.492395) (xy 404.140416 -396.48511)
			(xy 404.148798 -396.47749) (xy 404.157434 -396.457424) (xy 404.15464 -396.35811) (xy 404.145242 -396.338552)
			(xy 404.136352 -396.33144) (xy 404.117788 -396.315639) (xy 404.085057 -396.279514) (xy 404.05798 -396.238978)
			(xy 404.037143 -396.194908) (xy 404.022999 -396.148257) (xy 404.015852 -396.100036) (xy 404.015448 -396.075662)
			(xy 404.015887 -396.051546) (xy 404.022893 -396.003826) (xy 404.036753 -395.957629) (xy 404.057171 -395.913933)
			(xy 404.070058 -395.893544) (xy 404.0759 -395.884654) (xy 404.079456 -395.864588) (xy 404.058374 -395.772386)
			(xy 404.046182 -395.755622) (xy 404.037292 -395.750288) (xy 404.016488 -395.737434) (xy 403.978567 -395.706558)
			(xy 403.945612 -395.670428) (xy 403.918344 -395.629835) (xy 403.89736 -395.585664) (xy 403.883117 -395.538883)
			(xy 403.875927 -395.490513) (xy 403.875494 -395.466062) (xy 403.876055 -395.438779) (xy 403.885016 -395.384955)
			(xy 403.902688 -395.333331) (xy 403.928592 -395.285306) (xy 403.962026 -395.242184) (xy 403.981666 -395.223238)
			(xy 403.989119 -395.215748) (xy 403.997667 -395.196452) (xy 403.998176 -395.1859) (xy 403.998176 -395.111224)
			(xy 403.997589 -395.100689) (xy 403.989059 -395.081415) (xy 403.981666 -395.073886) (xy 403.96201 -395.054954)
			(xy 403.928565 -395.011834) (xy 403.902654 -394.963807) (xy 403.884982 -394.912178) (xy 403.876027 -394.858347)
			(xy 403.875494 -394.831062) (xy 403.875748 -394.81887) (xy 403.876002 -394.809218) (xy 403.869906 -394.791184)
			(xy 403.811232 -394.723874) (xy 403.794468 -394.715238) (xy 403.784816 -394.714222) (xy 403.7579 -394.710875)
			(xy 403.705593 -394.696537) (xy 403.656328 -394.673853) (xy 403.611427 -394.643432) (xy 403.572093 -394.60609)
			(xy 403.539382 -394.562829) (xy 403.514171 -394.514808) (xy 403.497136 -394.463317) (xy 403.492462 -394.4366)
			(xy 403.490938 -394.427202) (xy 403.218142 -393.95527) (xy 403.210776 -393.949428) (xy 403.192 -393.933623)
			(xy 403.158873 -393.897414) (xy 403.131458 -393.856708) (xy 403.110357 -393.812399) (xy 403.096033 -393.765459)
			(xy 403.088801 -393.716919) (xy 403.088348 -393.69238) (xy 403.088859 -393.666393) (xy 403.096992 -393.615058)
			(xy 403.113054 -393.565627) (xy 403.13665 -393.519317) (xy 403.1672 -393.477268) (xy 403.20395 -393.440515)
			(xy 403.245997 -393.409963) (xy 403.292305 -393.386363) (xy 403.341735 -393.370297) (xy 403.393069 -393.362161)
			(xy 403.419056 -393.361672) (xy 403.445069 -393.362154) (xy 403.496454 -393.370295) (xy 403.545929 -393.386383)
			(xy 403.592275 -393.410021) (xy 403.634347 -393.440626) (xy 403.671106 -393.477442) (xy 403.701646 -393.519561)
			(xy 403.725212 -393.565943) (xy 403.741224 -393.615443) (xy 403.7457 -393.641072) (xy 403.747224 -393.65047)
			(xy 404.02002 -394.122402) (xy 404.027386 -394.128244) (xy 404.046165 -394.144048) (xy 404.079299 -394.180254)
			(xy 404.106721 -394.220959) (xy 404.127828 -394.265268) (xy 404.142157 -394.312209) (xy 404.149395 -394.360752)
			(xy 404.149814 -394.385292) (xy 404.14956 -394.397484) (xy 404.149306 -394.407136) (xy 404.155402 -394.42517)
			(xy 404.214076 -394.49248) (xy 404.23084 -394.501116) (xy 404.240492 -394.502132) (xy 404.267261 -394.505458)
			(xy 404.31929 -394.519681) (xy 404.368322 -394.542157) (xy 404.413057 -394.572292) (xy 404.452309 -394.609286)
			(xy 404.485039 -394.652159) (xy 404.510379 -394.699774) (xy 404.527657 -394.750871) (xy 404.536415 -394.804093)
			(xy 404.53691 -394.831062) (xy 404.536347 -394.858344) (xy 404.527383 -394.912166) (xy 404.509708 -394.963788)
			(xy 404.483802 -395.01181) (xy 404.450367 -395.054929) (xy 404.430738 -395.073886) (xy 404.423289 -395.081377)
			(xy 404.414748 -395.100673) (xy 404.414228 -395.111224) (xy 404.414228 -395.1859) (xy 404.41482 -395.196432)
			(xy 404.423357 -395.215699) (xy 404.430738 -395.223238) (xy 404.450393 -395.242171) (xy 404.483834 -395.285292)
			(xy 404.509741 -395.333319) (xy 404.527409 -395.384948) (xy 404.53636 -395.438778) (xy 404.53691 -395.466062)
			(xy 404.536477 -395.49018) (xy 404.529481 -395.537905) (xy 404.515633 -395.584109) (xy 404.495225 -395.627814)
			(xy 404.4823 -395.64818) (xy 404.476458 -395.65707) (xy 404.472902 -395.677136) (xy 404.493984 -395.769338)
			(xy 404.506176 -395.786102) (xy 404.515066 -395.791436) (xy 404.535866 -395.804293) (xy 404.573779 -395.835173)
			(xy 404.606725 -395.871304) (xy 404.633985 -395.911898) (xy 404.654962 -395.956067) (xy 404.669199 -396.002846)
			(xy 404.676383 -396.051213) (xy 404.676864 -396.075662) (xy 404.676426 -396.100033) (xy 404.669271 -396.148246)
			(xy 404.655123 -396.19489) (xy 404.634289 -396.238954) (xy 404.60722 -396.279488) (xy 404.5745 -396.315615)
			(xy 404.55596 -396.33144) (xy 404.54707 -396.338552) (xy 404.537672 -396.35811) (xy 404.534878 -396.457424)
			(xy 404.543514 -396.47749) (xy 404.551896 -396.48511) (xy 404.559797 -396.492391) (xy 404.574672 -396.507898)
			(xy 404.581614 -396.516098) (xy 404.589215 -396.524384) (xy 404.609505 -396.534015) (xy 404.62073 -396.53464)
			(xy 405.271732 -396.53464) (xy 405.282965 -396.534046) (xy 405.303254 -396.524401) (xy 405.310848 -396.516098)
			(xy 405.317793 -396.5079) (xy 405.332666 -396.492392) (xy 405.340566 -396.48511) (xy 405.348948 -396.47749)
			(xy 405.357584 -396.457424) (xy 405.35479 -396.35811) (xy 405.345392 -396.338552) (xy 405.336502 -396.33144)
			(xy 405.317941 -396.315638) (xy 405.285214 -396.279511) (xy 405.258141 -396.238974) (xy 405.237308 -396.194904)
			(xy 405.223165 -396.148255) (xy 405.21602 -396.100035) (xy 405.215598 -396.075662) (xy 405.216037 -396.051546)
			(xy 405.223042 -396.003826) (xy 405.2369 -395.957627) (xy 405.257315 -395.913929) (xy 405.270208 -395.893544)
			(xy 405.27605 -395.884654) (xy 405.279606 -395.864588) (xy 405.258524 -395.772386) (xy 405.246332 -395.755622)
			(xy 405.237442 -395.750288) (xy 405.21664 -395.737432) (xy 405.178724 -395.706553) (xy 405.145775 -395.670422)
			(xy 405.118512 -395.629829) (xy 405.097531 -395.585659) (xy 405.08329 -395.53888) (xy 405.076102 -395.490512)
			(xy 405.075644 -395.466062) (xy 405.076205 -395.438779) (xy 405.085165 -395.384953) (xy 405.102835 -395.333327)
			(xy 405.128736 -395.285301) (xy 405.162167 -395.242175) (xy 405.181816 -395.223238) (xy 405.189263 -395.215745)
			(xy 405.197803 -395.19645) (xy 405.198326 -395.1859) (xy 405.198326 -395.111224) (xy 405.197741 -395.100688)
			(xy 405.189216 -395.081409) (xy 405.181816 -395.073886) (xy 405.162162 -395.054952) (xy 405.128722 -395.011831)
			(xy 405.102816 -394.963804) (xy 405.085146 -394.912175) (xy 405.076193 -394.858346) (xy 405.075644 -394.831062)
			(xy 405.075898 -394.81887) (xy 405.076152 -394.809218) (xy 405.070056 -394.791184) (xy 405.011382 -394.723874)
			(xy 404.994618 -394.715238) (xy 404.984712 -394.714222) (xy 404.957796 -394.710875) (xy 404.90549 -394.696536)
			(xy 404.856225 -394.673852) (xy 404.811324 -394.643431) (xy 404.771991 -394.606089) (xy 404.739281 -394.562828)
			(xy 404.71407 -394.514807) (xy 404.697036 -394.463316) (xy 404.692358 -394.4366) (xy 404.690834 -394.427202)
			(xy 404.418038 -393.95527) (xy 404.410672 -393.949428) (xy 404.391897 -393.933623) (xy 404.35877 -393.897413)
			(xy 404.331355 -393.856708) (xy 404.310254 -393.812399) (xy 404.295931 -393.765459) (xy 404.288698 -393.716918)
			(xy 404.288244 -393.69238) (xy 404.288755 -393.666392) (xy 404.296888 -393.615058) (xy 404.31295 -393.565627)
			(xy 404.336546 -393.519316) (xy 404.367095 -393.477267) (xy 404.403846 -393.440514) (xy 404.445893 -393.409961)
			(xy 404.492201 -393.386361) (xy 404.54163 -393.370294) (xy 404.592965 -393.362157) (xy 404.618952 -393.361672)
			(xy 404.644965 -393.362153) (xy 404.69635 -393.370294) (xy 404.745827 -393.386382) (xy 404.792173 -393.41002)
			(xy 404.834245 -393.440624) (xy 404.871005 -393.477441) (xy 404.901545 -393.519559) (xy 404.925112 -393.565942)
			(xy 404.941124 -393.615442) (xy 404.945596 -393.641072) (xy 404.94712 -393.65047) (xy 405.219916 -394.122402)
			(xy 405.227282 -394.128244) (xy 405.246061 -394.144048) (xy 405.279196 -394.180254) (xy 405.306618 -394.220959)
			(xy 405.327725 -394.265268) (xy 405.342055 -394.312209) (xy 405.349292 -394.360752) (xy 405.34971 -394.385292)
			(xy 405.349456 -394.397484) (xy 405.349202 -394.407136) (xy 405.355298 -394.42517) (xy 405.413972 -394.49248)
			(xy 405.430736 -394.501116) (xy 405.440642 -394.502132) (xy 405.467413 -394.505454) (xy 405.519449 -394.519671)
			(xy 405.568488 -394.542144) (xy 405.61323 -394.572277) (xy 405.652489 -394.609271) (xy 405.685225 -394.652145)
			(xy 405.710569 -394.699764) (xy 405.72785 -394.750864) (xy 405.73661 -394.804091) (xy 405.73706 -394.831062)
			(xy 405.736497 -394.858344) (xy 405.727534 -394.912168) (xy 405.709862 -394.963791) (xy 405.683958 -395.011816)
			(xy 405.650526 -395.054939) (xy 405.630888 -395.073886) (xy 405.623445 -395.08138) (xy 405.614913 -395.100675)
			(xy 405.614378 -395.111224) (xy 405.614378 -395.1859) (xy 405.614968 -395.196434) (xy 405.623499 -395.215706)
			(xy 405.630888 -395.223238) (xy 405.65054 -395.242172) (xy 405.683977 -395.285295) (xy 405.709879 -395.333322)
			(xy 405.727545 -395.38495) (xy 405.736494 -395.438778) (xy 405.73706 -395.466062) (xy 405.736627 -395.490179)
			(xy 405.72963 -395.537904) (xy 405.71578 -395.584107) (xy 405.69537 -395.627811) (xy 405.68245 -395.64818)
			(xy 405.676608 -395.65707) (xy 405.673052 -395.677136) (xy 405.694134 -395.769338) (xy 405.706326 -395.786102)
			(xy 405.715216 -395.791436) (xy 405.736019 -395.804291) (xy 405.773937 -395.835168) (xy 405.806888 -395.871298)
			(xy 405.834152 -395.911892) (xy 405.855133 -395.956062) (xy 405.869372 -396.002843) (xy 405.876558 -396.051212)
			(xy 405.877014 -396.075662) (xy 405.876576 -396.100032) (xy 405.86942 -396.148245) (xy 405.855271 -396.194887)
			(xy 405.834435 -396.238949) (xy 405.807363 -396.27948) (xy 405.77464 -396.315603) (xy 405.75611 -396.33144)
			(xy 405.74722 -396.338552) (xy 405.737822 -396.35811) (xy 405.735028 -396.457424) (xy 405.743664 -396.47749)
			(xy 405.752046 -396.48511) (xy 405.759946 -396.492392) (xy 405.774819 -396.5079) (xy 405.781764 -396.516098)
			(xy 405.789368 -396.524376) (xy 405.809658 -396.533987) (xy 405.82088 -396.53464) (xy 406.471628 -396.53464)
			(xy 406.482862 -396.534047) (xy 406.503151 -396.524402) (xy 406.510744 -396.516098) (xy 406.517689 -396.5079)
			(xy 406.532562 -396.492392) (xy 406.540462 -396.48511) (xy 406.548844 -396.47749) (xy 406.55748 -396.457424)
			(xy 406.554686 -396.35811) (xy 406.545288 -396.338552) (xy 406.536398 -396.33144) (xy 406.517837 -396.315638)
			(xy 406.48511 -396.279511) (xy 406.458038 -396.238974) (xy 406.437205 -396.194904) (xy 406.423063 -396.148254)
			(xy 406.415917 -396.100035) (xy 406.415494 -396.075662) (xy 406.415933 -396.051546) (xy 406.422938 -396.003826)
			(xy 406.436795 -395.957627) (xy 406.457211 -395.913929) (xy 406.470104 -395.893544) (xy 406.475946 -395.884654)
			(xy 406.479502 -395.864588) (xy 406.45842 -395.772386) (xy 406.446228 -395.755622) (xy 406.437338 -395.750288)
			(xy 406.416537 -395.737432) (xy 406.378621 -395.706553) (xy 406.345672 -395.670422) (xy 406.318409 -395.629828)
			(xy 406.297428 -395.585659) (xy 406.283188 -395.538879) (xy 406.276 -395.490512) (xy 406.27554 -395.466062)
			(xy 406.276101 -395.438779) (xy 406.285061 -395.384953) (xy 406.30273 -395.333327) (xy 406.328632 -395.2853)
			(xy 406.362062 -395.242174) (xy 406.381712 -395.223238) (xy 406.389159 -395.215745) (xy 406.3977 -395.19645)
			(xy 406.398222 -395.1859) (xy 406.398222 -395.111224) (xy 406.397637 -395.100688) (xy 406.389111 -395.081409)
			(xy 406.381712 -395.073886) (xy 406.362059 -395.054952) (xy 406.328619 -395.011831) (xy 406.302713 -394.963804)
			(xy 406.285043 -394.912175) (xy 406.27609 -394.858346) (xy 406.27554 -394.831062) (xy 406.275794 -394.81887)
			(xy 406.276048 -394.809218) (xy 406.269952 -394.791184) (xy 406.211278 -394.723874) (xy 406.194514 -394.715238)
			(xy 406.184608 -394.714222) (xy 406.157692 -394.710875) (xy 406.105386 -394.696535) (xy 406.056123 -394.673851)
			(xy 406.011222 -394.64343) (xy 405.971889 -394.606088) (xy 405.939179 -394.562826) (xy 405.913969 -394.514806)
			(xy 405.896935 -394.463315) (xy 405.892254 -394.4366) (xy 405.89073 -394.427202) (xy 405.61768 -393.954762)
			(xy 405.610568 -393.94892) (xy 405.591835 -393.93314) (xy 405.558781 -393.896997) (xy 405.531422 -393.856371)
			(xy 405.510358 -393.812153) (xy 405.49605 -393.76531) (xy 405.488811 -393.716869) (xy 405.488394 -393.69238)
			(xy 405.488905 -393.666394) (xy 405.497038 -393.615062) (xy 405.513101 -393.565634) (xy 405.536698 -393.519328)
			(xy 405.567248 -393.477282) (xy 405.603999 -393.440534) (xy 405.646046 -393.409986) (xy 405.692355 -393.386392)
			(xy 405.741783 -393.370333) (xy 405.793116 -393.362203) (xy 405.819102 -393.361672) (xy 405.84515 -393.362152)
			(xy 405.896604 -393.370304) (xy 405.946143 -393.386422) (xy 405.992543 -393.410107) (xy 406.034656 -393.440774)
			(xy 406.071441 -393.477663) (xy 406.101987 -393.519864) (xy 406.125539 -393.566331) (xy 406.141516 -393.615916)
			(xy 406.146 -393.64158) (xy 406.14727 -393.650978) (xy 406.171206 -393.69238) (xy 406.68829 -393.69238)
			(xy 406.688783 -393.666392) (xy 406.696917 -393.615057) (xy 406.71298 -393.565627) (xy 406.736578 -393.519317)
			(xy 406.76713 -393.477269) (xy 406.803883 -393.440518) (xy 406.845933 -393.409969) (xy 406.892243 -393.386373)
			(xy 406.941675 -393.370312) (xy 406.99301 -393.362182) (xy 407.018998 -393.361672) (xy 407.045008 -393.362143)
			(xy 407.096385 -393.370302) (xy 407.145851 -393.386402) (xy 407.192187 -393.410048) (xy 407.23425 -393.440655)
			(xy 407.271003 -393.47747) (xy 407.301541 -393.519584) (xy 407.325109 -393.565959) (xy 407.341127 -393.615452)
			(xy 407.345642 -393.641072) (xy 407.347166 -393.65047) (xy 407.619962 -394.122402) (xy 407.627328 -394.128244)
			(xy 407.646115 -394.144035) (xy 407.679231 -394.180255) (xy 407.706639 -394.220966) (xy 407.727738 -394.265276)
			(xy 407.742067 -394.312214) (xy 407.749311 -394.360754) (xy 407.749756 -394.385292) (xy 407.749502 -394.397484)
			(xy 407.749248 -394.407136) (xy 407.755344 -394.42517) (xy 407.814018 -394.49248) (xy 407.830782 -394.501116)
			(xy 407.840434 -394.502132) (xy 407.8672 -394.505464) (xy 407.919223 -394.519691) (xy 407.968249 -394.542171)
			(xy 408.012978 -394.572307) (xy 408.052225 -394.609301) (xy 408.084949 -394.652172) (xy 408.110285 -394.699785)
			(xy 408.12756 -394.750877) (xy 408.136317 -394.804095) (xy 408.136852 -394.831062) (xy 408.136342 -394.857049)
			(xy 408.128212 -394.908384) (xy 408.112151 -394.957814) (xy 408.088555 -395.004124) (xy 408.058005 -395.046172)
			(xy 408.021254 -395.082923) (xy 407.979206 -395.113473) (xy 407.932896 -395.137069) (xy 407.883466 -395.15313)
			(xy 407.832131 -395.16126) (xy 407.780157 -395.16126) (xy 407.728822 -395.15313) (xy 407.679392 -395.137069)
			(xy 407.633082 -395.113473) (xy 407.591034 -395.082923) (xy 407.554283 -395.046172) (xy 407.523733 -395.004124)
			(xy 407.500137 -394.957814) (xy 407.484076 -394.908384) (xy 407.475946 -394.857049) (xy 407.475436 -394.831062)
			(xy 407.47569 -394.81887) (xy 407.475944 -394.809218) (xy 407.469848 -394.791184) (xy 407.411174 -394.723874)
			(xy 407.39441 -394.715238) (xy 407.384758 -394.714222) (xy 407.357851 -394.710852) (xy 407.305565 -394.696488)
			(xy 407.256322 -394.673789) (xy 407.211439 -394.643364) (xy 407.172119 -394.606026) (xy 407.139415 -394.562776)
			(xy 407.114201 -394.514771) (xy 407.097154 -394.463298) (xy 407.092404 -394.4366) (xy 407.09088 -394.427202)
			(xy 406.818084 -393.95527) (xy 406.810718 -393.949428) (xy 406.791975 -393.933587) (xy 406.758854 -393.897379)
			(xy 406.73144 -393.856679) (xy 406.710333 -393.812378) (xy 406.695995 -393.765448) (xy 406.688741 -393.716916)
			(xy 406.68829 -393.69238) (xy 406.171206 -393.69238) (xy 406.419812 -394.122402) (xy 406.427178 -394.128244)
			(xy 406.445957 -394.144047) (xy 406.479092 -394.180254) (xy 406.506515 -394.220958) (xy 406.527622 -394.265267)
			(xy 406.541952 -394.312209) (xy 406.54919 -394.360752) (xy 406.549606 -394.385292) (xy 406.549352 -394.397484)
			(xy 406.549098 -394.407136) (xy 406.555194 -394.42517) (xy 406.613868 -394.49248) (xy 406.630632 -394.501116)
			(xy 406.640538 -394.502132) (xy 406.66731 -394.505454) (xy 406.719346 -394.519671) (xy 406.768385 -394.542143)
			(xy 406.813128 -394.572276) (xy 406.852387 -394.60927) (xy 406.885123 -394.652144) (xy 406.910468 -394.699763)
			(xy 406.927749 -394.750863) (xy 406.936509 -394.80409) (xy 406.936956 -394.831062) (xy 406.936393 -394.858344)
			(xy 406.92743 -394.912168) (xy 406.909757 -394.963791) (xy 406.883854 -395.011815) (xy 406.850421 -395.054938)
			(xy 406.830784 -395.073886) (xy 406.823341 -395.08138) (xy 406.81481 -395.100675) (xy 406.814274 -395.111224)
			(xy 406.814274 -395.1859) (xy 406.814864 -395.196434) (xy 406.823395 -395.215706) (xy 406.830784 -395.223238)
			(xy 406.850436 -395.242172) (xy 406.883873 -395.285294) (xy 406.909776 -395.333322) (xy 406.927442 -395.38495)
			(xy 406.936391 -395.438778) (xy 406.936956 -395.466062) (xy 406.936523 -395.490179) (xy 406.929526 -395.537904)
			(xy 406.915676 -395.584107) (xy 406.895266 -395.627811) (xy 406.882346 -395.64818) (xy 406.876504 -395.65707)
			(xy 406.872948 -395.677136) (xy 406.89403 -395.769338) (xy 406.906222 -395.786102) (xy 406.915112 -395.791436)
			(xy 406.935915 -395.80429) (xy 406.973833 -395.835168) (xy 407.006785 -395.871298) (xy 407.034049 -395.911892)
			(xy 407.05503 -395.956062) (xy 407.06927 -396.002843) (xy 407.076456 -396.051212) (xy 407.07691 -396.075662)
			(xy 407.076472 -396.100032) (xy 407.069316 -396.148245) (xy 407.055166 -396.194886) (xy 407.03433 -396.238949)
			(xy 407.007258 -396.27948) (xy 406.974535 -396.315602) (xy 406.956006 -396.33144) (xy 406.947116 -396.338552)
			(xy 406.937718 -396.35811) (xy 406.934924 -396.457424) (xy 406.94356 -396.47749) (xy 406.951942 -396.48511)
			(xy 406.959842 -396.492392) (xy 406.974715 -396.5079) (xy 406.98166 -396.516098) (xy 406.989264 -396.524377)
			(xy 407.009554 -396.53399) (xy 407.020776 -396.53464) (xy 407.671524 -396.53464) (xy 407.682758 -396.534048)
			(xy 407.703049 -396.524404) (xy 407.71064 -396.516098) (xy 407.728226 -396.495739) (xy 407.76925 -396.460942)
			(xy 407.815731 -396.433862) (xy 407.866234 -396.415337) (xy 407.919201 -396.405938) (xy 407.946098 -396.405354)
			(xy 407.972999 -396.405897) (xy 408.025974 -396.41528) (xy 408.076483 -396.433809) (xy 408.122959 -396.46091)
			(xy 408.163961 -396.495741) (xy 408.181556 -396.516098) (xy 408.189159 -396.524377) (xy 408.20945 -396.533992)
			(xy 408.220672 -396.53464) (xy 408.715972 -396.53464) (xy 408.725591 -396.534231) (xy 408.743477 -396.527146)
			(xy 408.757489 -396.513964) (xy 408.761946 -396.50543) (xy 408.807412 -396.408656) (xy 408.803856 -396.3797)
			(xy 408.794204 -396.368016) (xy 408.774335 -396.34327) (xy 408.740902 -396.289328) (xy 408.71525 -396.231282)
			(xy 408.697871 -396.170246) (xy 408.6891 -396.107393) (xy 408.68854 -396.075662) (xy 408.689143 -396.042342)
			(xy 408.698809 -395.976406) (xy 408.717932 -395.912568) (xy 408.731466 -395.882114) (xy 408.735732 -395.871643)
			(xy 408.735666 -395.849062) (xy 408.72592 -395.828692) (xy 408.717496 -395.821154) (xy 408.695251 -395.802479)
			(xy 408.655192 -395.760423) (xy 408.620776 -395.713635) (xy 408.592556 -395.66287) (xy 408.570986 -395.608942)
			(xy 408.556411 -395.552719) (xy 408.549068 -395.495103) (xy 408.548586 -395.466062) (xy 408.549031 -395.437136)
			(xy 408.556324 -395.379746) (xy 408.570789 -395.323732) (xy 408.592196 -395.269987) (xy 408.620203 -395.219366)
			(xy 408.654364 -395.172678) (xy 408.694136 -395.130665) (xy 408.716226 -395.111986) (xy 408.723301 -395.105722)
			(xy 408.73259 -395.089281) (xy 408.73426 -395.079982) (xy 408.738578 -395.048994) (xy 408.739526 -395.039756)
			(xy 408.73549 -395.021646) (xy 408.730704 -395.013688) (xy 408.717671 -394.99329) (xy 408.697072 -394.949488)
			(xy 408.683087 -394.903148) (xy 408.676014 -394.855264) (xy 408.675586 -394.831062) (xy 408.67584 -394.81887)
			(xy 408.676094 -394.809218) (xy 408.669998 -394.791184) (xy 408.611324 -394.723874) (xy 408.59456 -394.715238)
			(xy 408.584654 -394.714222) (xy 408.557741 -394.710871) (xy 408.505442 -394.696525) (xy 408.456185 -394.673836)
			(xy 408.411292 -394.643413) (xy 408.371966 -394.60607) (xy 408.339262 -394.56281) (xy 408.314057 -394.514793)
			(xy 408.297027 -394.463306) (xy 408.2923 -394.4366) (xy 408.290776 -394.427202) (xy 408.01798 -393.95527)
			(xy 408.010614 -393.949428) (xy 407.991837 -393.933624) (xy 407.958705 -393.897416) (xy 407.931287 -393.856711)
			(xy 407.910184 -393.812402) (xy 407.895858 -393.765461) (xy 407.888625 -393.716919) (xy 407.888186 -393.69238)
			(xy 407.888697 -393.666394) (xy 407.89683 -393.615061) (xy 407.912893 -393.565633) (xy 407.93649 -393.519326)
			(xy 407.96704 -393.47728) (xy 408.003791 -393.44053) (xy 408.045838 -393.409982) (xy 408.092146 -393.386387)
			(xy 408.141575 -393.370327) (xy 408.192908 -393.362196) (xy 408.218894 -393.361672) (xy 408.244905 -393.362157)
			(xy 408.296285 -393.370302) (xy 408.345756 -393.386394) (xy 408.392097 -393.410034) (xy 408.434163 -393.44064)
			(xy 408.470918 -393.477456) (xy 408.501453 -393.519573) (xy 408.525017 -393.565953) (xy 408.541026 -393.615451)
			(xy 408.545538 -393.641072) (xy 408.547062 -393.65047) (xy 408.819858 -394.122402) (xy 408.827224 -394.128244)
			(xy 408.846001 -394.144049) (xy 408.879132 -394.180257) (xy 408.90655 -394.220962) (xy 408.927655 -394.265271)
			(xy 408.941982 -394.312211) (xy 408.949219 -394.360753) (xy 408.949652 -394.385292) (xy 408.949398 -394.397484)
			(xy 408.949144 -394.407136) (xy 408.95524 -394.42517) (xy 409.013914 -394.49248) (xy 409.030678 -394.501116)
			(xy 409.040584 -394.502132) (xy 409.067353 -394.505457) (xy 409.119383 -394.519679) (xy 409.168416 -394.542155)
			(xy 409.213152 -394.57229) (xy 409.252406 -394.609284) (xy 409.285137 -394.652157) (xy 409.310477 -394.699773)
			(xy 409.327756 -394.750869) (xy 409.336514 -394.804093) (xy 409.337002 -394.831062) (xy 409.336535 -394.855259)
			(xy 409.329439 -394.903132) (xy 409.315451 -394.949463) (xy 409.29487 -394.993264) (xy 409.281884 -395.013688)
			(xy 409.277134 -395.021658) (xy 409.273113 -395.039757) (xy 409.27401 -395.048994) (xy 409.278328 -395.079982)
			(xy 409.280133 -395.089234) (xy 409.289394 -395.105635) (xy 409.296362 -395.111986) (xy 409.31846 -395.130658)
			(xy 409.358239 -395.172667) (xy 409.392406 -395.219354) (xy 409.420416 -395.269975) (xy 409.441822 -395.323724)
			(xy 409.456283 -395.379741) (xy 409.463567 -395.437135) (xy 409.464002 -395.466062) (xy 409.463398 -395.499382)
			(xy 409.453729 -395.565317) (xy 409.434605 -395.629154) (xy 409.421076 -395.65961) (xy 409.416813 -395.670079)
			(xy 409.416888 -395.692653) (xy 409.426644 -395.71301) (xy 409.435046 -395.72057) (xy 409.457292 -395.739245)
			(xy 409.497355 -395.781301) (xy 409.531776 -395.828087) (xy 409.560001 -395.878852) (xy 409.581579 -395.932779)
			(xy 409.59616 -395.989003) (xy 409.603513 -396.04662) (xy 409.603956 -396.075662) (xy 409.603392 -396.10739)
			(xy 409.594587 -396.170234) (xy 409.577195 -396.231261) (xy 409.551549 -396.289305) (xy 409.51814 -396.343256)
			(xy 409.498292 -396.368016) (xy 409.48864 -396.3797) (xy 409.485084 -396.408656) (xy 409.53055 -396.50543)
			(xy 409.535016 -396.513952) (xy 409.549034 -396.527109) (xy 409.566911 -396.53418) (xy 409.576524 -396.53464)
			(xy 410.07157 -396.53464) (xy 410.08281 -396.534059) (xy 410.103118 -396.524429) (xy 410.110686 -396.516098)
			(xy 410.117632 -396.507901) (xy 410.132506 -396.492394) (xy 410.140404 -396.48511) (xy 410.148786 -396.47749)
			(xy 410.157422 -396.457424) (xy 410.154628 -396.35811) (xy 410.14523 -396.338552) (xy 410.13634 -396.33144)
			(xy 410.117777 -396.315639) (xy 410.085046 -396.279514) (xy 410.05797 -396.238977) (xy 410.037135 -396.194907)
			(xy 410.022991 -396.148257) (xy 410.015844 -396.100036) (xy 410.015436 -396.075662) (xy 410.015875 -396.051546)
			(xy 410.022881 -396.003826) (xy 410.03674 -395.957629) (xy 410.057157 -395.913932) (xy 410.070046 -395.893544)
			(xy 410.075888 -395.884654) (xy 410.079444 -395.864588) (xy 410.058362 -395.772386) (xy 410.04617 -395.755622)
			(xy 410.03728 -395.750288) (xy 410.016476 -395.737434) (xy 409.978556 -395.706557) (xy 409.945603 -395.670427)
			(xy 409.918337 -395.629833) (xy 409.897353 -395.585663) (xy 409.883111 -395.538882) (xy 409.875921 -395.490513)
			(xy 409.875482 -395.466062) (xy 409.876043 -395.438779) (xy 409.885004 -395.384955) (xy 409.902675 -395.33333)
			(xy 409.928579 -395.285305) (xy 409.962012 -395.242182) (xy 409.981654 -395.223238) (xy 409.989108 -395.215749)
			(xy 409.997659 -395.196453) (xy 409.998164 -395.1859) (xy 409.998164 -395.111224) (xy 409.997577 -395.10069)
			(xy 409.989045 -395.081417) (xy 409.981654 -395.073886) (xy 409.961998 -395.054954) (xy 409.928554 -395.011833)
			(xy 409.902645 -394.963806) (xy 409.884973 -394.912177) (xy 409.876019 -394.858347) (xy 409.875482 -394.831062)
			(xy 409.875736 -394.81887) (xy 409.87599 -394.809218) (xy 409.869894 -394.791184) (xy 409.81122 -394.723874)
			(xy 409.794456 -394.715238) (xy 409.784804 -394.714222) (xy 409.757888 -394.710874) (xy 409.705583 -394.696535)
			(xy 409.65632 -394.67385) (xy 409.61142 -394.643429) (xy 409.572088 -394.606086) (xy 409.539378 -394.562825)
			(xy 409.514168 -394.514805) (xy 409.497134 -394.463314) (xy 409.49245 -394.4366) (xy 409.490926 -394.427202)
			(xy 409.21813 -393.95527) (xy 409.210764 -393.949428) (xy 409.191984 -393.933625) (xy 409.158848 -393.89742)
			(xy 409.131426 -393.856715) (xy 409.110319 -393.812406) (xy 409.095991 -393.765464) (xy 409.088757 -393.71692)
			(xy 409.088336 -393.69238) (xy 409.088821 -393.666393) (xy 409.096955 -393.615059) (xy 409.113019 -393.56563)
			(xy 409.136619 -393.519323) (xy 409.167172 -393.477278) (xy 409.203927 -393.44053) (xy 409.245978 -393.409985)
			(xy 409.29229 -393.386395) (xy 409.341722 -393.37034) (xy 409.393057 -393.362216) (xy 409.419044 -393.361672)
			(xy 409.445057 -393.362153) (xy 409.496444 -393.370292) (xy 409.545921 -393.386379) (xy 409.592268 -393.410017)
			(xy 409.634341 -393.440621) (xy 409.671102 -393.477438) (xy 409.701643 -393.519557) (xy 409.725211 -393.565939)
			(xy 409.741224 -393.615441) (xy 409.745688 -393.641072) (xy 409.747212 -393.65047) (xy 410.020008 -394.122402)
			(xy 410.027374 -394.128244) (xy 410.046153 -394.144047) (xy 410.079289 -394.180254) (xy 410.106711 -394.220958)
			(xy 410.127819 -394.265267) (xy 410.142149 -394.312208) (xy 410.149387 -394.360752) (xy 410.149802 -394.385292)
			(xy 410.149548 -394.397484) (xy 410.149294 -394.407136) (xy 410.15539 -394.42517) (xy 410.214064 -394.49248)
			(xy 410.230828 -394.501116) (xy 410.24048 -394.502132) (xy 410.267249 -394.505457) (xy 410.31928 -394.519678)
			(xy 410.368314 -394.542154) (xy 410.41305 -394.572288) (xy 410.452305 -394.609282) (xy 410.485036 -394.652156)
			(xy 410.510377 -394.699772) (xy 410.527655 -394.750869) (xy 410.536414 -394.804092) (xy 410.536898 -394.831062)
			(xy 410.536335 -394.858344) (xy 410.527371 -394.912166) (xy 410.509696 -394.963787) (xy 410.483789 -395.011808)
			(xy 410.450353 -395.054927) (xy 410.430726 -395.073886) (xy 410.423278 -395.081378) (xy 410.41474 -395.100674)
			(xy 410.414216 -395.111224) (xy 410.414216 -395.1859) (xy 410.414807 -395.196433) (xy 410.423343 -395.215701)
			(xy 410.430726 -395.223238) (xy 410.450381 -395.24217) (xy 410.483824 -395.285291) (xy 410.509732 -395.333318)
			(xy 410.527401 -395.384947) (xy 410.536352 -395.438777) (xy 410.536898 -395.466062) (xy 410.536465 -395.49018)
			(xy 410.529469 -395.537905) (xy 410.51562 -395.584109) (xy 410.495212 -395.627814) (xy 410.482288 -395.64818)
			(xy 410.476446 -395.65707) (xy 410.47289 -395.677136) (xy 410.493972 -395.769338) (xy 410.506164 -395.786102)
			(xy 410.515054 -395.791436) (xy 410.535855 -395.804292) (xy 410.573769 -395.835171) (xy 410.606716 -395.871303)
			(xy 410.633977 -395.911897) (xy 410.654955 -395.956066) (xy 410.669192 -396.002846) (xy 410.676377 -396.051213)
			(xy 410.676852 -396.075662) (xy 410.676414 -396.100033) (xy 410.669259 -396.148246) (xy 410.655111 -396.194889)
			(xy 410.634276 -396.238953) (xy 410.607206 -396.279486) (xy 410.574485 -396.315612) (xy 410.555948 -396.33144)
			(xy 410.547058 -396.338552) (xy 410.53766 -396.35811) (xy 410.534866 -396.457424) (xy 410.543502 -396.47749)
			(xy 410.551884 -396.48511) (xy 410.559783 -396.492393) (xy 410.574655 -396.507902) (xy 410.581602 -396.516098)
			(xy 410.589208 -396.52437) (xy 410.609499 -396.533966) (xy 410.620718 -396.53464) (xy 411.27172 -396.53464)
			(xy 411.282954 -396.534048) (xy 411.303247 -396.524406) (xy 411.310836 -396.516098) (xy 411.317781 -396.5079)
			(xy 411.332653 -396.492391) (xy 411.340554 -396.48511) (xy 411.348936 -396.47749) (xy 411.357572 -396.457424)
			(xy 411.354778 -396.35811) (xy 411.34538 -396.338552) (xy 411.33649 -396.33144) (xy 411.317929 -396.315637)
			(xy 411.285204 -396.27951) (xy 411.258132 -396.238973) (xy 411.237299 -396.194903) (xy 411.223158 -396.148254)
			(xy 411.216012 -396.100035) (xy 411.215586 -396.075662) (xy 411.216025 -396.051546) (xy 411.22303 -396.003826)
			(xy 411.236887 -395.957627) (xy 411.257302 -395.913928) (xy 411.270196 -395.893544) (xy 411.276038 -395.884654)
			(xy 411.279594 -395.864588) (xy 411.258512 -395.772386) (xy 411.24632 -395.755622) (xy 411.23743 -395.750288)
			(xy 411.216629 -395.737432) (xy 411.178714 -395.706552) (xy 411.145766 -395.670421) (xy 411.118504 -395.629827)
			(xy 411.097524 -395.585658) (xy 411.083284 -395.538879) (xy 411.076096 -395.490511) (xy 411.075632 -395.466062)
			(xy 411.076193 -395.438779) (xy 411.085152 -395.384953) (xy 411.102822 -395.333327) (xy 411.128723 -395.285299)
			(xy 411.162153 -395.242172) (xy 411.181804 -395.223238) (xy 411.189252 -395.215746) (xy 411.197794 -395.196451)
			(xy 411.198314 -395.1859) (xy 411.198314 -395.111224) (xy 411.197728 -395.100688) (xy 411.189202 -395.08141)
			(xy 411.181804 -395.073886) (xy 411.162146 -395.054955) (xy 411.128697 -395.011836) (xy 411.102783 -394.96381)
			(xy 411.085109 -394.91218) (xy 411.076153 -394.858348) (xy 411.075632 -394.831062) (xy 411.075886 -394.81887)
			(xy 411.07614 -394.809218) (xy 411.070044 -394.791184) (xy 411.01137 -394.723874) (xy 410.994606 -394.715238)
			(xy 410.9847 -394.714222) (xy 410.957785 -394.710874) (xy 410.90548 -394.696534) (xy 410.856217 -394.673849)
			(xy 410.811318 -394.643427) (xy 410.771986 -394.606085) (xy 410.739277 -394.562824) (xy 410.714067 -394.514804)
			(xy 410.697034 -394.463314) (xy 410.692346 -394.4366) (xy 410.690822 -394.427202) (xy 410.418026 -393.95527)
			(xy 410.41066 -393.949428) (xy 410.39188 -393.933625) (xy 410.358745 -393.897419) (xy 410.331323 -393.856715)
			(xy 410.310216 -393.812405) (xy 410.295889 -393.765464) (xy 410.288654 -393.71692) (xy 410.288232 -393.69238)
			(xy 410.288717 -393.666393) (xy 410.296851 -393.615059) (xy 410.312915 -393.56563) (xy 410.336515 -393.519322)
			(xy 410.367068 -393.477277) (xy 410.403823 -393.440529) (xy 410.445874 -393.409983) (xy 410.492185 -393.386392)
			(xy 410.541618 -393.370337) (xy 410.592953 -393.362212) (xy 410.61894 -393.361672) (xy 410.644954 -393.362153)
			(xy 410.69634 -393.370292) (xy 410.745818 -393.386378) (xy 410.792166 -393.410015) (xy 410.834239 -393.44062)
			(xy 410.871001 -393.477436) (xy 410.901542 -393.519555) (xy 410.925111 -393.565938) (xy 410.941123 -393.61544)
			(xy 410.945584 -393.641072) (xy 410.947108 -393.65047) (xy 411.219904 -394.122402) (xy 411.22727 -394.128244)
			(xy 411.24605 -394.144047) (xy 411.279185 -394.180253) (xy 411.306608 -394.220958) (xy 411.327717 -394.265267)
			(xy 411.342047 -394.312208) (xy 411.349285 -394.360752) (xy 411.349698 -394.385292) (xy 411.349444 -394.397484)
			(xy 411.34919 -394.407136) (xy 411.355286 -394.42517) (xy 411.41396 -394.49248) (xy 411.430724 -394.501116)
			(xy 411.44063 -394.502132) (xy 411.467396 -394.50546) (xy 411.519421 -394.519688) (xy 411.568447 -394.542167)
			(xy 411.613177 -394.572303) (xy 411.652425 -394.609298) (xy 411.685151 -394.652169) (xy 411.710487 -394.699783)
			(xy 411.727762 -394.750876) (xy 411.736519 -394.804095) (xy 411.737048 -394.831062) (xy 411.736485 -394.858344)
			(xy 411.727522 -394.912167) (xy 411.709849 -394.963791) (xy 411.683945 -395.011814) (xy 411.650512 -395.054937)
			(xy 411.630876 -395.073886) (xy 411.623434 -395.081381) (xy 411.614904 -395.100676) (xy 411.614366 -395.111224)
			(xy 411.614366 -395.1859) (xy 411.614958 -395.196431) (xy 411.6235 -395.215694) (xy 411.630876 -395.223238)
			(xy 411.650529 -395.242172) (xy 411.683966 -395.285294) (xy 411.70987 -395.333321) (xy 411.727536 -395.38495)
			(xy 411.736486 -395.438778) (xy 411.737048 -395.466062) (xy 411.736615 -395.490179) (xy 411.729618 -395.537904)
			(xy 411.715768 -395.584107) (xy 411.695357 -395.62781) (xy 411.682438 -395.64818) (xy 411.676596 -395.65707)
			(xy 411.67304 -395.677136) (xy 411.694122 -395.769338) (xy 411.706314 -395.786102) (xy 411.715204 -395.791436)
			(xy 411.736007 -395.80429) (xy 411.773927 -395.835167) (xy 411.806879 -395.871297) (xy 411.834144 -395.911891)
			(xy 411.855126 -395.956061) (xy 411.869365 -396.002842) (xy 411.876552 -396.051212) (xy 411.877002 -396.075662)
			(xy 411.876564 -396.100032) (xy 411.869408 -396.148244) (xy 411.855258 -396.194886) (xy 411.834422 -396.238948)
			(xy 411.807349 -396.279479) (xy 411.774625 -396.315601) (xy 411.756098 -396.33144) (xy 411.747208 -396.338552)
			(xy 411.73781 -396.35811) (xy 411.735016 -396.457424) (xy 411.743652 -396.47749) (xy 411.752034 -396.48511)
			(xy 411.759934 -396.492392) (xy 411.774808 -396.5079) (xy 411.781752 -396.516098) (xy 411.789355 -396.524378)
			(xy 411.809645 -396.533994) (xy 411.820868 -396.53464) (xy 412.471616 -396.53464) (xy 412.482851 -396.534049)
			(xy 412.503145 -396.524408) (xy 412.510732 -396.516098) (xy 412.517677 -396.5079) (xy 412.532549 -396.492391)
			(xy 412.54045 -396.48511) (xy 412.548832 -396.47749) (xy 412.557468 -396.457424) (xy 412.554674 -396.35811)
			(xy 412.545276 -396.338552) (xy 412.536386 -396.33144) (xy 412.517826 -396.315637) (xy 412.4851 -396.27951)
			(xy 412.458029 -396.238973) (xy 412.437197 -396.194903) (xy 412.423055 -396.148254) (xy 412.41591 -396.100035)
			(xy 412.415482 -396.075662) (xy 412.415921 -396.051546) (xy 412.422926 -396.003825) (xy 412.436783 -395.957627)
			(xy 412.457197 -395.913928) (xy 412.470092 -395.893544) (xy 412.475934 -395.884654) (xy 412.47949 -395.864588)
			(xy 412.458408 -395.772386) (xy 412.446216 -395.755622) (xy 412.437326 -395.750288) (xy 412.416525 -395.737431)
			(xy 412.378611 -395.706552) (xy 412.345663 -395.67042) (xy 412.318401 -395.629827) (xy 412.297421 -395.585658)
			(xy 412.283182 -395.538879) (xy 412.275994 -395.490511) (xy 412.275528 -395.466062) (xy 412.276089 -395.43878)
			(xy 412.285051 -395.384956) (xy 412.302724 -395.333333) (xy 412.32863 -395.28531) (xy 412.362066 -395.24219)
			(xy 412.3817 -395.223238) (xy 412.389149 -395.215746) (xy 412.397692 -395.196451) (xy 412.39821 -395.1859)
			(xy 412.39821 -395.111224) (xy 412.397624 -395.100688) (xy 412.389097 -395.081411) (xy 412.3817 -395.073886)
			(xy 412.362042 -395.054955) (xy 412.328594 -395.011836) (xy 412.30268 -394.963809) (xy 412.285006 -394.912179)
			(xy 412.27605 -394.858348) (xy 412.275528 -394.831062) (xy 412.275782 -394.81887) (xy 412.276036 -394.809218)
			(xy 412.26994 -394.791184) (xy 412.211266 -394.723874) (xy 412.194502 -394.715238) (xy 412.184596 -394.714222)
			(xy 412.157681 -394.710874) (xy 412.105377 -394.696533) (xy 412.056114 -394.673848) (xy 412.011216 -394.643426)
			(xy 411.971884 -394.606084) (xy 411.939176 -394.562823) (xy 411.913966 -394.514803) (xy 411.896933 -394.463313)
			(xy 411.892242 -394.4366) (xy 411.890718 -394.427202) (xy 411.617668 -393.954762) (xy 411.610556 -393.94892)
			(xy 411.591823 -393.93314) (xy 411.558771 -393.896996) (xy 411.531413 -393.85637) (xy 411.51035 -393.812152)
			(xy 411.496042 -393.76531) (xy 411.488803 -393.716869) (xy 411.488382 -393.69238) (xy 411.488893 -393.666394)
			(xy 411.497026 -393.615061) (xy 411.513089 -393.565632) (xy 411.536685 -393.519325) (xy 411.567235 -393.477279)
			(xy 411.603986 -393.440529) (xy 411.646033 -393.40998) (xy 411.692342 -393.386385) (xy 411.741771 -393.370324)
			(xy 411.793104 -393.362192) (xy 411.81909 -393.361672) (xy 411.845138 -393.362151) (xy 411.896594 -393.370302)
			(xy 411.946135 -393.386418) (xy 411.992536 -393.410103) (xy 412.034651 -393.440769) (xy 412.071437 -393.477659)
			(xy 412.101984 -393.51986) (xy 412.125538 -393.566328) (xy 412.141515 -393.615914) (xy 412.145988 -393.64158)
			(xy 412.147258 -393.650978) (xy 412.4198 -394.122402) (xy 412.427166 -394.128244) (xy 412.445946 -394.144047)
			(xy 412.479082 -394.180253) (xy 412.506505 -394.220957) (xy 412.527614 -394.265266) (xy 412.541944 -394.312208)
			(xy 412.549182 -394.360752) (xy 412.549594 -394.385292) (xy 412.54934 -394.397484) (xy 412.549086 -394.407136)
			(xy 412.555182 -394.42517) (xy 412.613856 -394.49248) (xy 412.63062 -394.501116) (xy 412.640526 -394.502132)
			(xy 412.667293 -394.50546) (xy 412.719318 -394.519687) (xy 412.768345 -394.542166) (xy 412.813075 -394.572302)
			(xy 412.852323 -394.609296) (xy 412.885049 -394.652168) (xy 412.910386 -394.699782) (xy 412.927662 -394.750875)
			(xy 412.936419 -394.804095) (xy 412.936944 -394.831062) (xy 412.936381 -394.858344) (xy 412.927418 -394.912167)
			(xy 412.909745 -394.96379) (xy 412.88384 -395.011814) (xy 412.850407 -395.054936) (xy 412.830772 -395.073886)
			(xy 412.823331 -395.081381) (xy 412.814802 -395.100676) (xy 412.814262 -395.111224) (xy 412.814262 -395.1859)
			(xy 412.814854 -395.196432) (xy 412.823396 -395.215695) (xy 412.830772 -395.223238) (xy 412.850425 -395.242172)
			(xy 412.883863 -395.285294) (xy 412.909767 -395.333321) (xy 412.927434 -395.384949) (xy 412.936383 -395.438778)
			(xy 412.936944 -395.466062) (xy 412.936511 -395.49018) (xy 412.929516 -395.537905) (xy 412.915669 -395.58411)
			(xy 412.895263 -395.627817) (xy 412.882334 -395.64818) (xy 412.876492 -395.65707) (xy 412.872936 -395.677136)
			(xy 412.894018 -395.769338) (xy 412.90621 -395.786102) (xy 412.9151 -395.791436) (xy 412.935903 -395.80429)
			(xy 412.973823 -395.835166) (xy 413.006776 -395.871296) (xy 413.034041 -395.91189) (xy 413.055023 -395.956061)
			(xy 413.069263 -396.002842) (xy 413.07645 -396.051212) (xy 413.076898 -396.075662) (xy 413.076461 -396.100033)
			(xy 413.069305 -396.148247) (xy 413.055159 -396.194892) (xy 413.034327 -396.238958) (xy 413.007259 -396.279494)
			(xy 412.974541 -396.315623) (xy 412.955994 -396.33144) (xy 412.947104 -396.338552) (xy 412.937706 -396.35811)
			(xy 412.934912 -396.457424) (xy 412.943548 -396.47749) (xy 412.95193 -396.48511) (xy 412.95983 -396.492392)
			(xy 412.974704 -396.507899) (xy 412.981648 -396.516098) (xy 412.989251 -396.524378) (xy 413.009541 -396.533996)
			(xy 413.020764 -396.53464) (xy 413.671512 -396.53464) (xy 413.682747 -396.53405) (xy 413.703042 -396.52441)
			(xy 413.710628 -396.516098) (xy 413.717573 -396.5079) (xy 413.732445 -396.492391) (xy 413.740346 -396.48511)
			(xy 413.748728 -396.47749) (xy 413.757364 -396.457424) (xy 413.75457 -396.35811) (xy 413.745172 -396.338552)
			(xy 413.736282 -396.33144) (xy 413.717722 -396.315637) (xy 413.684997 -396.27951) (xy 413.657925 -396.238973)
			(xy 413.637094 -396.194903) (xy 413.622952 -396.148254) (xy 413.615807 -396.100035) (xy 413.615378 -396.075662)
			(xy 413.615817 -396.051546) (xy 413.622822 -396.003825) (xy 413.636679 -395.957627) (xy 413.657093 -395.913928)
			(xy 413.669988 -395.893544) (xy 413.67583 -395.884654) (xy 413.679386 -395.864588) (xy 413.658304 -395.772386)
			(xy 413.646112 -395.755622) (xy 413.637222 -395.750288) (xy 413.616422 -395.737431) (xy 413.578508 -395.706551)
			(xy 413.54556 -395.67042) (xy 413.518299 -395.629826) (xy 413.497319 -395.585657) (xy 413.48308 -395.538878)
			(xy 413.475892 -395.490511) (xy 413.475424 -395.466062) (xy 413.475985 -395.43878) (xy 413.484947 -395.384956)
			(xy 413.50262 -395.333333) (xy 413.528526 -395.28531) (xy 413.561962 -395.24219) (xy 413.581596 -395.223238)
			(xy 413.589045 -395.215746) (xy 413.597589 -395.196451) (xy 413.598106 -395.1859) (xy 413.598106 -395.111224)
			(xy 413.59752 -395.100689) (xy 413.588993 -395.081412) (xy 413.581596 -395.073886) (xy 413.561938 -395.054955)
			(xy 413.52849 -395.011836) (xy 413.502577 -394.963809) (xy 413.484903 -394.912179) (xy 413.475947 -394.858348)
			(xy 413.475424 -394.831062) (xy 413.475678 -394.81887) (xy 413.475932 -394.809218) (xy 413.469836 -394.791184)
			(xy 413.411162 -394.723874) (xy 413.394398 -394.715238) (xy 413.384746 -394.714222) (xy 413.357833 -394.71087)
			(xy 413.305535 -394.696524) (xy 413.25628 -394.673834) (xy 413.211388 -394.64341) (xy 413.172063 -394.606068)
			(xy 413.13936 -394.562808) (xy 413.114156 -394.514791) (xy 413.097126 -394.463304) (xy 413.092392 -394.4366)
			(xy 413.090868 -394.427202) (xy 412.818072 -393.95527) (xy 412.810706 -393.949428) (xy 412.791929 -393.933624)
			(xy 412.758799 -393.897416) (xy 412.731381 -393.856711) (xy 412.710278 -393.812401) (xy 412.695953 -393.765461)
			(xy 412.68872 -393.716919) (xy 412.688278 -393.69238) (xy 412.688789 -393.666393) (xy 412.696922 -393.615061)
			(xy 412.712985 -393.565632) (xy 412.736581 -393.519324) (xy 412.767131 -393.477277) (xy 412.803882 -393.440527)
			(xy 412.845929 -393.409978) (xy 412.892237 -393.386382) (xy 412.941666 -393.370321) (xy 412.992999 -393.362189)
			(xy 413.018986 -393.361672) (xy 413.044997 -393.362156) (xy 413.096379 -393.370301) (xy 413.145851 -393.386392)
			(xy 413.192192 -393.410032) (xy 413.23426 -393.440637) (xy 413.271015 -393.477453) (xy 413.301552 -393.519571)
			(xy 413.325116 -393.565951) (xy 413.341126 -393.615449) (xy 413.34563 -393.641072) (xy 413.347154 -393.65047)
			(xy 413.61995 -394.122402) (xy 413.627316 -394.128244) (xy 413.646093 -394.144049) (xy 413.679225 -394.180256)
			(xy 413.706644 -394.220961) (xy 413.727749 -394.26527) (xy 413.742077 -394.312211) (xy 413.749314 -394.360753)
			(xy 413.749744 -394.385292) (xy 413.74949 -394.397484) (xy 413.749236 -394.407136) (xy 413.755332 -394.42517)
			(xy 413.814006 -394.49248) (xy 413.83077 -394.501116) (xy 413.840422 -394.502132) (xy 413.867189 -394.50546)
			(xy 413.919214 -394.519686) (xy 413.968242 -394.542165) (xy 414.012973 -394.572301) (xy 414.052222 -394.609295)
			(xy 414.084948 -394.652167) (xy 414.110285 -394.699781) (xy 414.127561 -394.750875) (xy 414.136318 -394.804094)
			(xy 414.13684 -394.831062) (xy 414.136277 -394.858344) (xy 414.127314 -394.912167) (xy 414.10964 -394.96379)
			(xy 414.083736 -395.011813) (xy 414.050302 -395.054935) (xy 414.030668 -395.073886) (xy 414.023227 -395.081381)
			(xy 414.014699 -395.100676) (xy 414.014158 -395.111224) (xy 414.014158 -395.1859) (xy 414.01475 -395.196432)
			(xy 414.023291 -395.215695) (xy 414.030668 -395.223238) (xy 414.050321 -395.242172) (xy 414.08376 -395.285293)
			(xy 414.109664 -395.333321) (xy 414.127331 -395.384949) (xy 414.136281 -395.438778) (xy 414.13684 -395.466062)
			(xy 414.136407 -395.49018) (xy 414.129412 -395.537905) (xy 414.115565 -395.58411) (xy 414.095159 -395.627816)
			(xy 414.08223 -395.64818) (xy 414.076388 -395.65707) (xy 414.072832 -395.677136) (xy 414.093914 -395.769338)
			(xy 414.106106 -395.786102) (xy 414.114996 -395.791436) (xy 414.1358 -395.80429) (xy 414.17372 -395.835166)
			(xy 414.206673 -395.871296) (xy 414.233939 -395.91189) (xy 414.254921 -395.95606) (xy 414.269161 -396.002842)
			(xy 414.276348 -396.051211) (xy 414.276794 -396.075662) (xy 414.276357 -396.100033) (xy 414.269201 -396.148247)
			(xy 414.255055 -396.194891) (xy 414.234222 -396.238957) (xy 414.207154 -396.279493) (xy 414.174436 -396.315622)
			(xy 414.15589 -396.33144) (xy 414.147 -396.338552) (xy 414.137602 -396.35811) (xy 414.134808 -396.457424)
			(xy 414.143444 -396.47749) (xy 414.151826 -396.48511) (xy 414.159726 -396.492392) (xy 414.1746 -396.507899)
			(xy 414.181544 -396.516098) (xy 414.189147 -396.524379) (xy 414.209437 -396.533998) (xy 414.22066 -396.53464)
			(xy 414.71596 -396.53464) (xy 414.72558 -396.534233) (xy 414.74347 -396.527151) (xy 414.757486 -396.513969)
			(xy 414.761934 -396.50543) (xy 414.8074 -396.408656) (xy 414.803844 -396.3797) (xy 414.794192 -396.368016)
			(xy 414.774324 -396.343269) (xy 414.740891 -396.289328) (xy 414.71524 -396.231282) (xy 414.697861 -396.170246)
			(xy 414.689091 -396.107393) (xy 414.688528 -396.075662) (xy 414.689131 -396.042342) (xy 414.698797 -395.976406)
			(xy 414.717919 -395.912568) (xy 414.731454 -395.882114) (xy 414.735721 -395.871643) (xy 414.735655 -395.849062)
			(xy 414.725907 -395.828693) (xy 414.717484 -395.821154) (xy 414.69524 -395.802479) (xy 414.655182 -395.760422)
			(xy 414.620767 -395.713634) (xy 414.592547 -395.662869) (xy 414.570977 -395.608941) (xy 414.556404 -395.552718)
			(xy 414.54906 -395.495103) (xy 414.548574 -395.466062) (xy 414.549019 -395.437136) (xy 414.556312 -395.379746)
			(xy 414.570777 -395.323731) (xy 414.592183 -395.269986) (xy 414.62019 -395.219365) (xy 414.65435 -395.172676)
			(xy 414.694121 -395.130662) (xy 414.716214 -395.111986) (xy 414.72328 -395.105717) (xy 414.732552 -395.089274)
			(xy 414.734248 -395.079982) (xy 414.738566 -395.048994) (xy 414.739514 -395.039755) (xy 414.735484 -395.021642)
			(xy 414.730692 -395.013688) (xy 414.71766 -394.99329) (xy 414.697062 -394.949488) (xy 414.683076 -394.903148)
			(xy 414.676003 -394.855264) (xy 414.675574 -394.831062) (xy 414.675828 -394.81887) (xy 414.676082 -394.809218)
			(xy 414.669986 -394.791184) (xy 414.611312 -394.723874) (xy 414.594548 -394.715238) (xy 414.584642 -394.714222)
			(xy 414.55773 -394.71087) (xy 414.505432 -394.696523) (xy 414.456177 -394.673833) (xy 414.411286 -394.643409)
			(xy 414.371961 -394.606067) (xy 414.339259 -394.562807) (xy 414.314055 -394.51479) (xy 414.297025 -394.463303)
			(xy 414.292288 -394.4366) (xy 414.290764 -394.427202) (xy 414.017968 -393.95527) (xy 414.010602 -393.949428)
			(xy 413.991825 -393.933623) (xy 413.958695 -393.897415) (xy 413.931278 -393.85671) (xy 413.910175 -393.812401)
			(xy 413.89585 -393.765461) (xy 413.888617 -393.716919) (xy 413.888174 -393.69238) (xy 413.888685 -393.666393)
			(xy 413.896818 -393.61506) (xy 413.91288 -393.565631) (xy 413.936477 -393.519323) (xy 413.967027 -393.477276)
			(xy 414.003778 -393.440526) (xy 414.045825 -393.409976) (xy 414.092133 -393.38638) (xy 414.141562 -393.370317)
			(xy 414.192895 -393.362185) (xy 414.218882 -393.361672) (xy 414.244894 -393.362156) (xy 414.296275 -393.3703)
			(xy 414.345748 -393.386391) (xy 414.39209 -393.41003) (xy 414.434158 -393.440636) (xy 414.470914 -393.477452)
			(xy 414.501451 -393.519569) (xy 414.525015 -393.56595) (xy 414.541025 -393.615448) (xy 414.545526 -393.641072)
			(xy 414.54705 -393.65047) (xy 414.571276 -393.69238) (xy 415.088324 -393.69238) (xy 415.088757 -393.666389)
			(xy 415.096892 -393.615046) (xy 415.112959 -393.565609) (xy 415.136562 -393.519293) (xy 415.16712 -393.477241)
			(xy 415.20388 -393.440486) (xy 415.245938 -393.409935) (xy 415.292257 -393.386339) (xy 415.341697 -393.37028)
			(xy 415.393041 -393.362153) (xy 415.419032 -393.361672) (xy 415.445043 -393.362112) (xy 415.496421 -393.370276)
			(xy 415.545888 -393.386381) (xy 415.592224 -393.410031) (xy 415.634287 -393.440642) (xy 415.67104 -393.477461)
			(xy 415.701576 -393.519578) (xy 415.725144 -393.565956) (xy 415.741161 -393.615451) (xy 415.745676 -393.641072)
			(xy 415.7472 -393.65047) (xy 416.019996 -394.122402) (xy 416.027362 -394.128244) (xy 416.046156 -394.144027)
			(xy 416.07927 -394.180249) (xy 416.106676 -394.220962) (xy 416.127774 -394.265273) (xy 416.142101 -394.312213)
			(xy 416.149345 -394.360753) (xy 416.14979 -394.385292) (xy 416.149536 -394.397484) (xy 416.149282 -394.407136)
			(xy 416.155378 -394.42517) (xy 416.214052 -394.49248) (xy 416.230816 -394.501116) (xy 416.240468 -394.502132)
			(xy 416.267226 -394.505517) (xy 416.319249 -394.519735) (xy 416.368275 -394.542206) (xy 416.413005 -394.572334)
			(xy 416.452253 -394.609321) (xy 416.48498 -394.652186) (xy 416.510317 -394.699794) (xy 416.527593 -394.750882)
			(xy 416.53635 -394.804097) (xy 416.536886 -394.831062) (xy 416.536376 -394.857049) (xy 416.528246 -394.908384)
			(xy 416.512185 -394.957814) (xy 416.488589 -395.004124) (xy 416.458039 -395.046172) (xy 416.421288 -395.082923)
			(xy 416.37924 -395.113473) (xy 416.33293 -395.137069) (xy 416.2835 -395.15313) (xy 416.232165 -395.16126)
			(xy 416.180191 -395.16126) (xy 416.128856 -395.15313) (xy 416.079426 -395.137069) (xy 416.033116 -395.113473)
			(xy 415.991068 -395.082923) (xy 415.954317 -395.046172) (xy 415.923767 -395.004124) (xy 415.900171 -394.957814)
			(xy 415.88411 -394.908384) (xy 415.87598 -394.857049) (xy 415.87547 -394.831062) (xy 415.875724 -394.81887)
			(xy 415.875978 -394.809218) (xy 415.869882 -394.791184) (xy 415.811208 -394.723874) (xy 415.794444 -394.715238)
			(xy 415.784792 -394.714222) (xy 415.757889 -394.710825) (xy 415.705603 -394.696466) (xy 415.65636 -394.673772)
			(xy 415.611477 -394.643351) (xy 415.572156 -394.606017) (xy 415.539451 -394.56277) (xy 415.514236 -394.514768)
			(xy 415.497188 -394.463297) (xy 415.492438 -394.4366) (xy 415.490914 -394.427202) (xy 415.218118 -393.95527)
			(xy 415.210752 -393.949428) (xy 415.191995 -393.933603) (xy 415.158878 -393.897389) (xy 415.131467 -393.856686)
			(xy 415.110363 -393.812383) (xy 415.096027 -393.76545) (xy 415.088774 -393.716916) (xy 415.088324 -393.69238)
			(xy 414.571276 -393.69238) (xy 414.819846 -394.122402) (xy 414.827212 -394.128244) (xy 414.84599 -394.144048)
			(xy 414.879121 -394.180256) (xy 414.906541 -394.220961) (xy 414.927646 -394.26527) (xy 414.941974 -394.31221)
			(xy 414.949211 -394.360753) (xy 414.94964 -394.385292) (xy 414.949386 -394.397484) (xy 414.949132 -394.407136)
			(xy 414.955228 -394.42517) (xy 415.013902 -394.49248) (xy 415.030666 -394.501116) (xy 415.040572 -394.502132)
			(xy 415.067342 -394.505456) (xy 415.119373 -394.519677) (xy 415.168408 -394.542152) (xy 415.213146 -394.572286)
			(xy 415.252401 -394.60928) (xy 415.285133 -394.652154) (xy 415.310475 -394.69977) (xy 415.327754 -394.750868)
			(xy 415.336513 -394.804092) (xy 415.33699 -394.831062) (xy 415.336523 -394.855259) (xy 415.329427 -394.903132)
			(xy 415.315439 -394.949463) (xy 415.294856 -394.993264) (xy 415.281872 -395.013688) (xy 415.277115 -395.021656)
			(xy 415.273087 -395.039758) (xy 415.273998 -395.048994) (xy 415.278316 -395.079982) (xy 415.280121 -395.089234)
			(xy 415.28938 -395.105637) (xy 415.29635 -395.111986) (xy 415.318444 -395.130661) (xy 415.358216 -395.172672)
			(xy 415.392377 -395.219361) (xy 415.420381 -395.269982) (xy 415.441783 -395.323729) (xy 415.45624 -395.379745)
			(xy 415.463523 -395.437136) (xy 415.46399 -395.466062) (xy 415.463386 -395.499382) (xy 415.453717 -395.565317)
			(xy 415.434592 -395.629154) (xy 415.421064 -395.65961) (xy 415.416802 -395.670079) (xy 415.416877 -395.692653)
			(xy 415.426631 -395.713011) (xy 415.435034 -395.72057) (xy 415.457281 -395.739244) (xy 415.497345 -395.7813)
			(xy 415.531766 -395.828086) (xy 415.559993 -395.878851) (xy 415.58157 -395.932779) (xy 415.596153 -395.989003)
			(xy 415.603505 -396.04662) (xy 415.603944 -396.075662) (xy 415.60338 -396.10739) (xy 415.594575 -396.170233)
			(xy 415.577182 -396.231261) (xy 415.551536 -396.289304) (xy 415.518126 -396.343254) (xy 415.49828 -396.368016)
			(xy 415.488628 -396.3797) (xy 415.485072 -396.408656) (xy 415.530538 -396.50543) (xy 415.535004 -396.513953)
			(xy 415.549021 -396.527113) (xy 415.566899 -396.534188) (xy 415.576512 -396.53464) (xy 416.071558 -396.53464)
			(xy 416.082799 -396.534061) (xy 416.103111 -396.524434) (xy 416.110674 -396.516098) (xy 416.128259 -396.495735)
			(xy 416.16928 -396.460929) (xy 416.21576 -396.433839) (xy 416.266264 -396.415304) (xy 416.319233 -396.405893)
			(xy 416.346132 -396.405354) (xy 416.373035 -396.405892) (xy 416.426017 -396.415265) (xy 416.476534 -396.433786)
			(xy 416.523019 -396.460881) (xy 416.56403 -396.495709) (xy 416.58159 -396.516098) (xy 416.589196 -396.524372)
			(xy 416.609486 -396.533973) (xy 416.620706 -396.53464) (xy 417.271708 -396.53464) (xy 417.282944 -396.534051)
			(xy 417.30324 -396.524411) (xy 417.310824 -396.516098) (xy 417.317769 -396.5079) (xy 417.332641 -396.492391)
			(xy 417.340542 -396.48511) (xy 417.348924 -396.47749) (xy 417.35756 -396.457424) (xy 417.354766 -396.35811)
			(xy 417.345368 -396.338552) (xy 417.336478 -396.33144) (xy 417.317918 -396.315637) (xy 417.285193 -396.279509)
			(xy 417.258122 -396.238972) (xy 417.237291 -396.194902) (xy 417.22315 -396.148253) (xy 417.216004 -396.100035)
			(xy 417.215574 -396.075662) (xy 417.216013 -396.051546) (xy 417.223018 -396.003825) (xy 417.236874 -395.957627)
			(xy 417.257289 -395.913928) (xy 417.270184 -395.893544) (xy 417.276026 -395.884654) (xy 417.279582 -395.864588)
			(xy 417.2585 -395.772386) (xy 417.246308 -395.755622) (xy 417.237418 -395.750288) (xy 417.216613 -395.737435)
			(xy 417.178688 -395.70656) (xy 417.145731 -395.670431) (xy 417.118462 -395.629838) (xy 417.097475 -395.585667)
			(xy 417.083231 -395.538885) (xy 417.076041 -395.490514) (xy 417.07562 -395.466062) (xy 417.076181 -395.43878)
			(xy 417.085142 -395.384956) (xy 417.102815 -395.333332) (xy 417.128721 -395.285309) (xy 417.162157 -395.242189)
			(xy 417.181792 -395.223238) (xy 417.189242 -395.215746) (xy 417.197786 -395.196451) (xy 417.198302 -395.1859)
			(xy 417.198302 -395.111224) (xy 417.197716 -395.100689) (xy 417.189188 -395.081412) (xy 417.181792 -395.073886)
			(xy 417.162134 -395.054955) (xy 417.128687 -395.011835) (xy 417.102774 -394.963809) (xy 417.0851 -394.912179)
			(xy 417.076145 -394.858348) (xy 417.07562 -394.831062) (xy 417.075874 -394.81887) (xy 417.076128 -394.809218)
			(xy 417.070032 -394.791184) (xy 417.011358 -394.723874) (xy 416.994594 -394.715238) (xy 416.984688 -394.714222)
			(xy 416.957773 -394.710873) (xy 416.90547 -394.696532) (xy 416.856209 -394.673846) (xy 416.811311 -394.643424)
			(xy 416.771981 -394.606081) (xy 416.739273 -394.562821) (xy 416.714065 -394.514801) (xy 416.697032 -394.463312)
			(xy 416.692334 -394.4366) (xy 416.69081 -394.427202) (xy 416.418014 -393.95527) (xy 416.410648 -393.949428)
			(xy 416.391869 -393.933625) (xy 416.358735 -393.897419) (xy 416.331314 -393.856714) (xy 416.310208 -393.812405)
			(xy 416.295881 -393.765463) (xy 416.288647 -393.71692) (xy 416.28822 -393.69238) (xy 416.288705 -393.666393)
			(xy 416.296839 -393.615058) (xy 416.312903 -393.565628) (xy 416.336502 -393.51932) (xy 416.367055 -393.477273)
			(xy 416.40381 -393.440524) (xy 416.445861 -393.409977) (xy 416.492172 -393.386385) (xy 416.541605 -393.370327)
			(xy 416.59294 -393.362201) (xy 416.618928 -393.361672) (xy 416.644942 -393.362152) (xy 416.69633 -393.370289)
			(xy 416.74581 -393.386375) (xy 416.792159 -393.410011) (xy 416.834234 -393.440615) (xy 416.870997 -393.477432)
			(xy 416.90154 -393.519551) (xy 416.925109 -393.565935) (xy 416.941123 -393.615438) (xy 416.945572 -393.641072)
			(xy 416.947096 -393.65047) (xy 417.219892 -394.122402) (xy 417.227258 -394.128244) (xy 417.246038 -394.144047)
			(xy 417.279175 -394.180252) (xy 417.306599 -394.220957) (xy 417.327708 -394.265266) (xy 417.342039 -394.312208)
			(xy 417.349277 -394.360752) (xy 417.349686 -394.385292) (xy 417.349432 -394.397484) (xy 417.349178 -394.407136)
			(xy 417.355274 -394.42517) (xy 417.413948 -394.49248) (xy 417.430712 -394.501116) (xy 417.440618 -394.502132)
			(xy 417.467385 -394.50546) (xy 417.519411 -394.519686) (xy 417.568439 -394.542164) (xy 417.613171 -394.5723)
			(xy 417.65242 -394.609294) (xy 417.685147 -394.652166) (xy 417.710484 -394.69978) (xy 417.727761 -394.750874)
			(xy 417.736518 -394.804094) (xy 417.737036 -394.831062) (xy 417.736473 -394.858344) (xy 417.72751 -394.912167)
			(xy 417.709836 -394.96379) (xy 417.683931 -395.011813) (xy 417.650498 -395.054934) (xy 417.630864 -395.073886)
			(xy 417.623424 -395.081381) (xy 417.614896 -395.100676) (xy 417.614354 -395.111224) (xy 417.614354 -395.1859)
			(xy 417.614946 -395.196432) (xy 417.623487 -395.215696) (xy 417.630864 -395.223238) (xy 417.650517 -395.242172)
			(xy 417.683956 -395.285293) (xy 417.709861 -395.33332) (xy 417.727528 -395.384949) (xy 417.736478 -395.438778)
			(xy 417.737036 -395.466062) (xy 417.736603 -395.49018) (xy 417.729608 -395.537905) (xy 417.715761 -395.58411)
			(xy 417.695354 -395.627816) (xy 417.682426 -395.64818) (xy 417.676584 -395.65707) (xy 417.673028 -395.677136)
			(xy 417.69411 -395.769338) (xy 417.706302 -395.786102) (xy 417.715192 -395.791436) (xy 417.735996 -395.80429)
			(xy 417.773917 -395.835166) (xy 417.80687 -395.871295) (xy 417.834136 -395.911889) (xy 417.855119 -395.95606)
			(xy 417.869359 -396.002841) (xy 417.876545 -396.051211) (xy 417.87699 -396.075662) (xy 417.876553 -396.100033)
			(xy 417.869397 -396.148247) (xy 417.85525 -396.194891) (xy 417.834418 -396.238957) (xy 417.80735 -396.279492)
			(xy 417.774631 -396.315621) (xy 417.756086 -396.33144) (xy 417.747196 -396.338552) (xy 417.737798 -396.35811)
			(xy 417.735004 -396.457424) (xy 417.74364 -396.47749) (xy 417.752022 -396.48511) (xy 417.759922 -396.492392)
			(xy 417.774796 -396.507899) (xy 417.78174 -396.516098) (xy 417.789343 -396.52438) (xy 417.809632 -396.534001)
			(xy 417.820856 -396.53464) (xy 418.471604 -396.53464) (xy 418.48284 -396.534052) (xy 418.503138 -396.524413)
			(xy 418.51072 -396.516098) (xy 418.517665 -396.5079) (xy 418.532537 -396.492391) (xy 418.540438 -396.48511)
			(xy 418.54882 -396.47749) (xy 418.557456 -396.457424) (xy 418.554662 -396.35811) (xy 418.545264 -396.338552)
			(xy 418.536374 -396.33144) (xy 418.517814 -396.315637) (xy 418.48509 -396.279509) (xy 418.458019 -396.238972)
			(xy 418.437188 -396.194902) (xy 418.423047 -396.148253) (xy 418.415902 -396.100035) (xy 418.41547 -396.075662)
			(xy 418.415909 -396.051546) (xy 418.422914 -396.003825) (xy 418.43677 -395.957626) (xy 418.457184 -395.913927)
			(xy 418.47008 -395.893544) (xy 418.475922 -395.884654) (xy 418.479478 -395.864588) (xy 418.458396 -395.772386)
			(xy 418.446204 -395.755622) (xy 418.437314 -395.750288) (xy 418.416509 -395.737435) (xy 418.378585 -395.70656)
			(xy 418.345628 -395.670431) (xy 418.318359 -395.629837) (xy 418.297373 -395.585667) (xy 418.283129 -395.538885)
			(xy 418.275939 -395.490513) (xy 418.275516 -395.466062) (xy 418.276077 -395.43878) (xy 418.285038 -395.384956)
			(xy 418.302711 -395.333332) (xy 418.328617 -395.285309) (xy 418.362052 -395.242188) (xy 418.381688 -395.223238)
			(xy 418.389138 -395.215746) (xy 418.397683 -395.196451) (xy 418.398198 -395.1859) (xy 418.398198 -395.111224)
			(xy 418.397612 -395.100689) (xy 418.389084 -395.081413) (xy 418.381688 -395.073886) (xy 418.362031 -395.054955)
			(xy 418.328583 -395.011835) (xy 418.302671 -394.963809) (xy 418.284997 -394.912179) (xy 418.276042 -394.858348)
			(xy 418.275516 -394.831062) (xy 418.27577 -394.81887) (xy 418.276024 -394.809218) (xy 418.269928 -394.791184)
			(xy 418.211254 -394.723874) (xy 418.19449 -394.715238) (xy 418.184584 -394.714222) (xy 418.157669 -394.710873)
			(xy 418.105367 -394.696531) (xy 418.056106 -394.673845) (xy 418.011209 -394.643422) (xy 417.971879 -394.60608)
			(xy 417.939172 -394.562819) (xy 417.913964 -394.5148) (xy 417.896931 -394.463311) (xy 417.89223 -394.4366)
			(xy 417.890706 -394.427202) (xy 417.617656 -393.954762) (xy 417.610544 -393.94892) (xy 417.591812 -393.93314)
			(xy 417.55876 -393.896995) (xy 417.531404 -393.856369) (xy 417.510341 -393.812151) (xy 417.496034 -393.765309)
			(xy 417.488795 -393.716869) (xy 417.48837 -393.69238) (xy 417.488881 -393.666393) (xy 417.497014 -393.61506)
			(xy 417.513076 -393.565631) (xy 417.536673 -393.519322) (xy 417.567223 -393.477275) (xy 417.603973 -393.440524)
			(xy 417.646021 -393.409974) (xy 417.692329 -393.386377) (xy 417.741758 -393.370314) (xy 417.793091 -393.362181)
			(xy 417.819078 -393.361672) (xy 417.845127 -393.36215) (xy 417.896584 -393.370299) (xy 417.946126 -393.386415)
			(xy 417.992529 -393.410099) (xy 418.034646 -393.440765) (xy 418.071433 -393.477654) (xy 418.101982 -393.519856)
			(xy 418.125537 -393.566325) (xy 418.141515 -393.615912) (xy 418.145976 -393.64158) (xy 418.147246 -393.650978)
			(xy 418.419788 -394.122402) (xy 418.427154 -394.128244) (xy 418.445934 -394.144047) (xy 418.479072 -394.180252)
			(xy 418.506496 -394.220956) (xy 418.527605 -394.265266) (xy 418.541936 -394.312207) (xy 418.549174 -394.360752)
			(xy 418.549582 -394.385292) (xy 418.549328 -394.397484) (xy 418.549074 -394.407136) (xy 418.55517 -394.42517)
			(xy 418.613844 -394.49248) (xy 418.630608 -394.501116) (xy 418.640514 -394.502132) (xy 418.667281 -394.505459)
			(xy 418.719308 -394.519685) (xy 418.768337 -394.542163) (xy 418.813069 -394.572299) (xy 418.852319 -394.609293)
			(xy 418.885046 -394.652165) (xy 418.910384 -394.699779) (xy 418.92766 -394.750874) (xy 418.936417 -394.804094)
			(xy 418.936932 -394.831062) (xy 418.936369 -394.858344) (xy 418.927406 -394.912167) (xy 418.909732 -394.96379)
			(xy 418.883827 -395.011812) (xy 418.850393 -395.054934) (xy 418.83076 -395.073886) (xy 418.82332 -395.081382)
			(xy 418.814793 -395.100676) (xy 418.81425 -395.111224) (xy 418.81425 -395.1859) (xy 418.814842 -395.196432)
			(xy 418.823382 -395.215696) (xy 418.83076 -395.223238) (xy 418.850413 -395.242171) (xy 418.883853 -395.285293)
			(xy 418.909758 -395.33332) (xy 418.927425 -395.384949) (xy 418.936375 -395.438778) (xy 418.936932 -395.466062)
			(xy 418.936499 -395.49018) (xy 418.929504 -395.537905) (xy 418.915656 -395.58411) (xy 418.89525 -395.627816)
			(xy 418.882322 -395.64818) (xy 418.87648 -395.65707) (xy 418.872924 -395.677136) (xy 418.894006 -395.769338)
			(xy 418.906198 -395.786102) (xy 418.915088 -395.791436) (xy 418.935892 -395.80429) (xy 418.973813 -395.835165)
			(xy 419.006767 -395.871295) (xy 419.034033 -395.911889) (xy 419.055016 -395.956059) (xy 419.069257 -396.002841)
			(xy 419.076443 -396.051211) (xy 419.076886 -396.075662) (xy 419.076449 -396.100033) (xy 419.069293 -396.148247)
			(xy 419.055146 -396.194891) (xy 419.034313 -396.238957) (xy 419.007245 -396.279492) (xy 418.974526 -396.31562)
			(xy 418.955982 -396.33144) (xy 418.947092 -396.338552) (xy 418.937694 -396.35811) (xy 418.9349 -396.457424)
			(xy 418.943536 -396.47749) (xy 418.951918 -396.48511) (xy 418.959819 -396.492391) (xy 418.974693 -396.507899)
			(xy 418.981636 -396.516098) (xy 418.989238 -396.52438) (xy 419.009528 -396.534003) (xy 419.020752 -396.53464)
			(xy 419.671754 -396.53464) (xy 419.682995 -396.534062) (xy 419.703309 -396.524436) (xy 419.71087 -396.516098)
			(xy 419.717815 -396.507901) (xy 419.732689 -396.492393) (xy 419.740588 -396.48511) (xy 419.74897 -396.47749)
			(xy 419.757606 -396.457424) (xy 419.754812 -396.35811) (xy 419.745414 -396.338552) (xy 419.736524 -396.33144)
			(xy 419.717962 -396.315638) (xy 419.685233 -396.279513) (xy 419.658158 -396.238976) (xy 419.637323 -396.194906)
			(xy 419.62318 -396.148256) (xy 419.616034 -396.100035) (xy 419.61562 -396.075662) (xy 419.616059 -396.051546)
			(xy 419.623065 -396.003826) (xy 419.636923 -395.957628) (xy 419.65734 -395.913931) (xy 419.67023 -395.893544)
			(xy 419.676072 -395.884654) (xy 419.679628 -395.864588) (xy 419.658546 -395.772386) (xy 419.646354 -395.755622)
			(xy 419.637464 -395.750288) (xy 419.616661 -395.737433) (xy 419.578743 -395.706555) (xy 419.545791 -395.670425)
			(xy 419.518526 -395.629831) (xy 419.497544 -395.585662) (xy 419.483302 -395.538881) (xy 419.476113 -395.490512)
			(xy 419.475666 -395.466062) (xy 419.476227 -395.438779) (xy 419.485187 -395.384954) (xy 419.502858 -395.333329)
			(xy 419.528761 -395.285303) (xy 419.562193 -395.242179) (xy 419.581838 -395.223238) (xy 419.589282 -395.215744)
			(xy 419.597818 -395.196449) (xy 419.598348 -395.1859) (xy 419.598348 -395.111224) (xy 419.59776 -395.10069)
			(xy 419.589226 -395.081419) (xy 419.581838 -395.073886) (xy 419.562183 -395.054953) (xy 419.528741 -395.011832)
			(xy 419.502833 -394.963805) (xy 419.485162 -394.912176) (xy 419.476208 -394.858347) (xy 419.475666 -394.831062)
			(xy 419.47592 -394.81887) (xy 419.476174 -394.809218) (xy 419.470078 -394.791184) (xy 419.411404 -394.723874)
			(xy 419.39464 -394.715238) (xy 419.384734 -394.714222) (xy 419.357822 -394.710869) (xy 419.305525 -394.696521)
			(xy 419.256272 -394.673831) (xy 419.211381 -394.643407) (xy 419.172058 -394.606064) (xy 419.139356 -394.562804)
			(xy 419.114153 -394.514788) (xy 419.097124 -394.463302) (xy 419.09238 -394.4366) (xy 419.090856 -394.427202)
			(xy 418.81806 -393.95527) (xy 418.810694 -393.949428) (xy 418.791918 -393.933623) (xy 418.758788 -393.897415)
			(xy 418.731372 -393.85671) (xy 418.71027 -393.812401) (xy 418.695945 -393.76546) (xy 418.688712 -393.716919)
			(xy 418.688266 -393.69238) (xy 418.688777 -393.666393) (xy 418.69691 -393.61506) (xy 418.712972 -393.56563)
			(xy 418.736569 -393.519321) (xy 418.767118 -393.477274) (xy 418.803869 -393.440522) (xy 418.845916 -393.409972)
			(xy 418.892224 -393.386375) (xy 418.941654 -393.370311) (xy 418.992987 -393.362177) (xy 419.018974 -393.361672)
			(xy 419.044986 -393.362155) (xy 419.096369 -393.370298) (xy 419.145842 -393.386388) (xy 419.192185 -393.410027)
			(xy 419.234254 -393.440633) (xy 419.271012 -393.477449) (xy 419.301549 -393.519567) (xy 419.325114 -393.565948)
			(xy 419.341125 -393.615447) (xy 419.345618 -393.641072) (xy 419.347142 -393.65047) (xy 419.619938 -394.122402)
			(xy 419.627304 -394.128244) (xy 419.646082 -394.144048) (xy 419.679214 -394.180256) (xy 419.706635 -394.22096)
			(xy 419.727741 -394.265269) (xy 419.742069 -394.31221) (xy 419.749306 -394.360752) (xy 419.749732 -394.385292)
			(xy 419.749478 -394.397484) (xy 419.749224 -394.407136) (xy 419.75532 -394.42517) (xy 419.813994 -394.49248)
			(xy 419.830758 -394.501116) (xy 419.840664 -394.502132) (xy 419.867434 -394.505456) (xy 419.919467 -394.519675)
			(xy 419.968503 -394.54215) (xy 420.013242 -394.572284) (xy 420.052498 -394.609278) (xy 420.085231 -394.652151)
			(xy 420.110573 -394.699768) (xy 420.127853 -394.750867) (xy 420.136612 -394.804092) (xy 420.137082 -394.831062)
			(xy 420.136519 -394.858344) (xy 420.127554 -394.912165) (xy 420.109879 -394.963786) (xy 420.083971 -395.011807)
			(xy 420.050534 -395.054924) (xy 420.03091 -395.073886) (xy 420.023464 -395.081379) (xy 420.014929 -395.100674)
			(xy 420.0144 -395.111224) (xy 420.0144 -395.1859) (xy 420.014991 -395.196433) (xy 420.023525 -395.215703)
			(xy 420.03091 -395.223238) (xy 420.050566 -395.24217) (xy 420.08401 -395.28529) (xy 420.109919 -395.333317)
			(xy 420.127589 -395.384946) (xy 420.136541 -395.438777) (xy 420.137082 -395.466062) (xy 420.136649 -395.490179)
			(xy 420.129653 -395.537904) (xy 420.115804 -395.584108) (xy 420.095394 -395.627813) (xy 420.082472 -395.64818)
			(xy 420.07663 -395.65707) (xy 420.073074 -395.677136) (xy 420.094156 -395.769338) (xy 420.106348 -395.786102)
			(xy 420.115238 -395.791436) (xy 420.136039 -395.804292) (xy 420.173955 -395.83517) (xy 420.206904 -395.871301)
			(xy 420.234166 -395.911895) (xy 420.255146 -395.956065) (xy 420.269384 -396.002845) (xy 420.276569 -396.051212)
			(xy 420.277036 -396.075662) (xy 420.276598 -396.100033) (xy 420.269442 -396.148245) (xy 420.255294 -396.194888)
			(xy 420.234459 -396.238952) (xy 420.207388 -396.279484) (xy 420.174666 -396.315609) (xy 420.156132 -396.33144)
			(xy 420.147242 -396.338552) (xy 420.137844 -396.35811) (xy 420.13505 -396.457424) (xy 420.143686 -396.47749)
			(xy 420.152068 -396.48511) (xy 420.159968 -396.492392) (xy 420.17484 -396.507901) (xy 420.181786 -396.516098)
			(xy 420.189391 -396.524372) (xy 420.209682 -396.533975) (xy 420.220902 -396.53464) (xy 420.384478 -396.53464)
			(xy 420.394541 -396.534201) (xy 420.413119 -396.52646) (xy 420.420546 -396.519654) (xy 420.809674 -396.130526)
			(xy 420.81704 -396.110206) (xy 420.816278 -396.09903) (xy 420.815516 -396.075662) (xy 420.815955 -396.051546)
			(xy 420.822961 -396.003826) (xy 420.836819 -395.957628) (xy 420.857235 -395.91393) (xy 420.870126 -395.893544)
			(xy 420.875968 -395.884654) (xy 420.879524 -395.864588) (xy 420.858442 -395.772386) (xy 420.84625 -395.755622)
			(xy 420.83736 -395.750288) (xy 420.816558 -395.737433) (xy 420.77864 -395.706555) (xy 420.745688 -395.670424)
			(xy 420.718423 -395.629831) (xy 420.697441 -395.585661) (xy 420.6832 -395.538881) (xy 420.676011 -395.490512)
			(xy 420.675562 -395.466062) (xy 420.676123 -395.438779) (xy 420.685083 -395.384954) (xy 420.702754 -395.333329)
			(xy 420.728656 -395.285303) (xy 420.762088 -395.242178) (xy 420.781734 -395.223238) (xy 420.789178 -395.215744)
			(xy 420.797715 -395.196449) (xy 420.798244 -395.1859) (xy 420.798244 -395.111224) (xy 420.797656 -395.10069)
			(xy 420.789122 -395.08142) (xy 420.781734 -395.073886) (xy 420.762079 -395.054953) (xy 420.728637 -395.011832)
			(xy 420.70273 -394.963805) (xy 420.685059 -394.912176) (xy 420.676105 -394.858347) (xy 420.675562 -394.831062)
			(xy 420.675816 -394.81887) (xy 420.67607 -394.809218) (xy 420.669974 -394.791184) (xy 420.6113 -394.723874)
			(xy 420.594536 -394.715238) (xy 420.58463 -394.714222) (xy 420.557718 -394.710869) (xy 420.505422 -394.696521)
			(xy 420.456169 -394.67383) (xy 420.411279 -394.643405) (xy 420.371956 -394.606063) (xy 420.339255 -394.562803)
			(xy 420.314052 -394.514787) (xy 420.297023 -394.463301) (xy 420.292276 -394.4366) (xy 420.290752 -394.427202)
			(xy 420.017702 -393.954762) (xy 420.01059 -393.94892) (xy 419.991856 -393.933141) (xy 419.9588 -393.896998)
			(xy 419.931439 -393.856373) (xy 419.910374 -393.812154) (xy 419.896064 -393.765311) (xy 419.888825 -393.71687)
			(xy 419.888416 -393.69238) (xy 419.888901 -393.666392) (xy 419.897035 -393.615058) (xy 419.913099 -393.565627)
			(xy 419.936698 -393.519319) (xy 419.967251 -393.477272) (xy 420.004005 -393.440522) (xy 420.046056 -393.409975)
			(xy 420.092368 -393.386382) (xy 420.141801 -393.370324) (xy 420.193136 -393.362197) (xy 420.219124 -393.361672)
			(xy 420.245171 -393.362154) (xy 420.296622 -393.370308) (xy 420.346159 -393.386428) (xy 420.392556 -393.410115)
			(xy 420.434666 -393.440782) (xy 420.471448 -393.477671) (xy 420.501991 -393.519871) (xy 420.525542 -393.566337)
			(xy 420.541517 -393.615921) (xy 420.546022 -393.64158) (xy 420.547292 -393.650978) (xy 420.819834 -394.122402)
			(xy 420.8272 -394.128244) (xy 420.845978 -394.144048) (xy 420.879111 -394.180255) (xy 420.906532 -394.22096)
			(xy 420.927638 -394.265269) (xy 420.941967 -394.31221) (xy 420.949204 -394.360752) (xy 420.949628 -394.385292)
			(xy 420.949374 -394.397484) (xy 420.94912 -394.407136) (xy 420.955216 -394.42517) (xy 421.01389 -394.49248)
			(xy 421.030654 -394.501116) (xy 421.04056 -394.502132) (xy 421.06733 -394.505455) (xy 421.119364 -394.519675)
			(xy 421.1684 -394.542149) (xy 421.21314 -394.572283) (xy 421.252396 -394.609276) (xy 421.28513 -394.65215)
			(xy 421.310472 -394.699768) (xy 421.327752 -394.750866) (xy 421.336511 -394.804091) (xy 421.336978 -394.831062)
			(xy 421.336415 -394.858344) (xy 421.32745 -394.912165) (xy 421.309774 -394.963786) (xy 421.283866 -395.011806)
			(xy 421.250429 -395.054923) (xy 421.230806 -395.073886) (xy 421.223361 -395.081379) (xy 421.214826 -395.100674)
			(xy 421.214296 -395.111224) (xy 421.214296 -395.1859) (xy 421.214887 -395.196433) (xy 421.22342 -395.215703)
			(xy 421.230806 -395.223238) (xy 421.248661 -395.24038) (xy 421.279588 -395.279024) (xy 421.304415 -395.321843)
			(xy 421.322587 -395.367882) (xy 421.328596 -395.391894) (xy 421.331644 -395.405356) (xy 421.350694 -395.425422)
			(xy 421.4495 -395.453616) (xy 421.458257 -395.455747) (xy 421.476219 -395.45442) (xy 421.492627 -395.44699)
			(xy 421.499284 -395.440916) (xy 421.879014 -395.061186) (xy 421.885868 -395.053791) (xy 421.89361 -395.035192)
			(xy 421.894 -395.025118) (xy 421.894 -394.923772) (xy 421.892222 -394.917422) (xy 421.886876 -394.896234)
			(xy 421.881148 -394.852912) (xy 421.880792 -394.831062) (xy 421.881046 -394.819378) (xy 421.8813 -394.809472)
			(xy 421.87495 -394.791438) (xy 421.815768 -394.724382) (xy 421.798496 -394.715492) (xy 421.788844 -394.71473)
			(xy 421.76465 -394.712085) (xy 421.717358 -394.700596) (xy 421.672263 -394.682294) (xy 421.63034 -394.657574)
			(xy 421.592498 -394.626972) (xy 421.559553 -394.59115) (xy 421.532221 -394.550882) (xy 421.511091 -394.507041)
			(xy 421.49662 -394.460574) (xy 421.492426 -394.4366) (xy 421.490902 -394.427202) (xy 421.218106 -393.95527)
			(xy 421.21074 -393.949428) (xy 421.191961 -393.933625) (xy 421.158828 -393.897418) (xy 421.131407 -393.856713)
			(xy 421.110302 -393.812404) (xy 421.095975 -393.765463) (xy 421.088741 -393.71692) (xy 421.088312 -393.69238)
			(xy 421.088823 -393.666394) (xy 421.096956 -393.615064) (xy 421.113019 -393.565637) (xy 421.136616 -393.519332)
			(xy 421.167167 -393.477288) (xy 421.203918 -393.440541) (xy 421.245966 -393.409996) (xy 421.292274 -393.386404)
			(xy 421.341702 -393.370347) (xy 421.393034 -393.36222) (xy 421.41902 -393.361672) (xy 421.445035 -393.362151)
			(xy 421.496424 -393.370288) (xy 421.545904 -393.386372) (xy 421.592254 -393.410008) (xy 421.634331 -393.440612)
			(xy 421.671095 -393.477429) (xy 421.701638 -393.519549) (xy 421.725208 -393.565933) (xy 421.741222 -393.615436)
			(xy 421.745664 -393.641072) (xy 421.747188 -393.65047) (xy 421.799258 -393.74064) (xy 421.805325 -393.749989)
			(xy 421.823576 -393.762737) (xy 421.845504 -393.766576) (xy 421.856408 -393.764262) (xy 421.873172 -393.75969)
			(xy 421.894 -393.732512) (xy 421.894 -385.882642) (xy 421.893566 -385.872577) (xy 421.885837 -385.853987)
			(xy 421.879014 -385.846574) (xy 420.951406 -384.918966) (xy 420.944011 -384.912111) (xy 420.925412 -384.904364)
			(xy 420.915338 -384.90398) (xy 403.327362 -384.90398) (xy 403.317294 -384.904409) (xy 403.298698 -384.912131)
			(xy 403.291294 -384.918966) (xy 399.37309 -388.83717) (xy 399.366897 -388.843918) (xy 399.35934 -388.860585)
			(xy 399.358113 -388.878846) (xy 399.36039 -388.887716) (xy 399.389854 -388.986776) (xy 399.410428 -389.005572)
			(xy 399.424144 -389.00862) (xy 399.452389 -389.015025) (xy 399.506667 -389.035223) (xy 399.557264 -389.063401)
			(xy 399.603015 -389.098909) (xy 399.642867 -389.140932) (xy 399.675902 -389.1885) (xy 399.70136 -389.240519)
			(xy 399.718654 -389.295791) (xy 399.727387 -389.353043) (xy 399.727928 -389.382) (xy 399.727442 -389.409252)
			(xy 399.719686 -389.463201) (xy 399.704331 -389.515496) (xy 399.68169 -389.565075) (xy 399.652224 -389.610927)
			(xy 399.616533 -389.652119) (xy 399.575343 -389.687812) (xy 399.529493 -389.71728) (xy 399.479915 -389.739924)
			(xy 399.42762 -389.755282) (xy 399.373672 -389.763041) (xy 399.34642 -389.763508) (xy 399.317468 -389.762964)
			(xy 399.260231 -389.754199) (xy 399.204977 -389.736884) (xy 399.152975 -389.711415) (xy 399.10542 -389.678378)
			(xy 399.063405 -389.638533) (xy 399.027896 -389.592794) (xy 398.999709 -389.542214) (xy 398.979491 -389.487954)
			(xy 398.97304 -389.459724) (xy 398.969992 -389.446008) (xy 398.951196 -389.425434) (xy 398.852136 -389.39597)
			(xy 398.843263 -389.393674) (xy 398.82499 -389.39487) (xy 398.808318 -389.402448) (xy 398.80159 -389.40867)
			(xy 397.810482 -390.399778) (xy 397.804643 -390.406023) (xy 397.797167 -390.421387) (xy 397.795212 -390.43836)
			(xy 397.796766 -390.446768) (xy 397.818356 -390.543542) (xy 397.835374 -390.562846) (xy 397.84782 -390.567418)
			(xy 397.875162 -390.577793) (xy 397.926544 -390.605716) (xy 397.973058 -390.641159) (xy 398.013613 -390.68329)
			(xy 398.047257 -390.731121) (xy 398.073202 -390.783529) (xy 398.090838 -390.839285) (xy 398.099751 -390.89708)
			(xy 398.100296 -390.92632) (xy 398.099808 -390.95357) (xy 398.092049 -391.007515) (xy 398.076693 -391.059806)
			(xy 398.05405 -391.10938) (xy 398.024583 -391.155227) (xy 397.988891 -391.196414) (xy 397.947702 -391.232102)
			(xy 397.901852 -391.261565) (xy 397.852276 -391.284204) (xy 397.799984 -391.299556) (xy 397.746038 -391.307311)
			(xy 397.718788 -391.307828) (xy 397.694716 -391.307477) (xy 397.646951 -391.301446) (xy 397.600328 -391.289442)
			(xy 397.577818 -391.280904) (xy 397.565372 -391.275824) (xy 397.539464 -391.279126) (xy 397.490373 -391.315291)
			(xy 400.656761 -391.315291) (xy 400.656761 -391.263309) (xy 400.664893 -391.211968) (xy 400.680956 -391.162531)
			(xy 400.704556 -391.116215) (xy 400.73511 -391.074162) (xy 400.771866 -391.037406) (xy 400.81392 -391.006852)
			(xy 400.860236 -390.983254) (xy 400.909674 -390.967192) (xy 400.961015 -390.959061) (xy 400.987006 -390.958578)
			(xy 401.010204 -390.958963) (xy 401.056144 -390.965454) (xy 401.100728 -390.978295) (xy 401.143084 -390.997234)
			(xy 401.18238 -391.021899) (xy 401.200366 -391.036556) (xy 401.207478 -391.042652) (xy 401.225004 -391.048748)
			(xy 401.310602 -391.04697) (xy 401.327874 -391.039858) (xy 401.334732 -391.033508) (xy 401.353151 -391.017162)
			(xy 401.393931 -390.989558) (xy 401.438354 -390.968305) (xy 401.485436 -390.953873) (xy 401.534138 -390.94658)
			(xy 401.55876 -390.946132) (xy 401.583597 -390.946581) (xy 401.632714 -390.954) (xy 401.680166 -390.968691)
			(xy 401.724882 -390.990322) (xy 401.765854 -391.018407) (xy 401.784312 -391.035032) (xy 401.79139 -391.041056)
			(xy 401.80857 -391.0481) (xy 401.81784 -391.048748) (xy 401.849082 -391.04951) (xy 401.858337 -391.049352)
			(xy 401.87579 -391.043228) (xy 401.883118 -391.037572) (xy 401.905652 -391.019367) (xy 401.955793 -390.990359)
			(xy 402.010216 -390.970517) (xy 402.06726 -390.960444) (xy 402.096224 -390.959848) (xy 402.122206 -390.960448)
			(xy 402.173531 -390.96858) (xy 402.222952 -390.984641) (xy 402.269252 -391.008235) (xy 402.311291 -391.038781)
			(xy 402.348034 -391.075527) (xy 402.378578 -391.117569) (xy 402.402168 -391.16387) (xy 402.418225 -391.213292)
			(xy 402.425768 -391.260917) (xy 403.114004 -391.260917) (xy 403.114004 -391.208943) (xy 403.122134 -391.157608)
			(xy 403.138195 -391.108178) (xy 403.161791 -391.061868) (xy 403.192341 -391.01982) (xy 403.229092 -390.983069)
			(xy 403.27114 -390.952519) (xy 403.31745 -390.928923) (xy 403.36688 -390.912862) (xy 403.418215 -390.904732)
			(xy 403.470189 -390.904732) (xy 403.521524 -390.912862) (xy 403.570954 -390.928923) (xy 403.617264 -390.952519)
			(xy 403.659312 -390.983069) (xy 403.696063 -391.01982) (xy 403.726613 -391.061868) (xy 403.750209 -391.108178)
			(xy 403.76627 -391.157608) (xy 403.7744 -391.208943) (xy 403.77491 -391.23493) (xy 403.7744 -391.260917)
			(xy 404.314154 -391.260917) (xy 404.314154 -391.208943) (xy 404.322284 -391.157608) (xy 404.338345 -391.108178)
			(xy 404.361941 -391.061868) (xy 404.392491 -391.01982) (xy 404.429242 -390.983069) (xy 404.47129 -390.952519)
			(xy 404.5176 -390.928923) (xy 404.56703 -390.912862) (xy 404.618365 -390.904732) (xy 404.670339 -390.904732)
			(xy 404.721674 -390.912862) (xy 404.771104 -390.928923) (xy 404.817414 -390.952519) (xy 404.859462 -390.983069)
			(xy 404.896213 -391.01982) (xy 404.926763 -391.061868) (xy 404.950359 -391.108178) (xy 404.96642 -391.157608)
			(xy 404.97455 -391.208943) (xy 404.97506 -391.23493) (xy 404.97455 -391.260917) (xy 405.51405 -391.260917)
			(xy 405.51405 -391.208943) (xy 405.52218 -391.157608) (xy 405.538241 -391.108178) (xy 405.561837 -391.061868)
			(xy 405.592387 -391.01982) (xy 405.629138 -390.983069) (xy 405.671186 -390.952519) (xy 405.717496 -390.928923)
			(xy 405.766926 -390.912862) (xy 405.818261 -390.904732) (xy 405.870235 -390.904732) (xy 405.92157 -390.912862)
			(xy 405.971 -390.928923) (xy 406.01731 -390.952519) (xy 406.059358 -390.983069) (xy 406.096109 -391.01982)
			(xy 406.126659 -391.061868) (xy 406.150255 -391.108178) (xy 406.166316 -391.157608) (xy 406.174446 -391.208943)
			(xy 406.174956 -391.23493) (xy 406.174446 -391.260917) (xy 406.713946 -391.260917) (xy 406.713946 -391.208943)
			(xy 406.722076 -391.157608) (xy 406.738137 -391.108178) (xy 406.761733 -391.061868) (xy 406.792283 -391.01982)
			(xy 406.829034 -390.983069) (xy 406.871082 -390.952519) (xy 406.917392 -390.928923) (xy 406.966822 -390.912862)
			(xy 407.018157 -390.904732) (xy 407.070131 -390.904732) (xy 407.121466 -390.912862) (xy 407.170896 -390.928923)
			(xy 407.217206 -390.952519) (xy 407.259254 -390.983069) (xy 407.296005 -391.01982) (xy 407.326555 -391.061868)
			(xy 407.350151 -391.108178) (xy 407.366212 -391.157608) (xy 407.374342 -391.208943) (xy 407.374852 -391.23493)
			(xy 407.374342 -391.260917) (xy 407.914096 -391.260917) (xy 407.914096 -391.208943) (xy 407.922226 -391.157608)
			(xy 407.938287 -391.108178) (xy 407.961883 -391.061868) (xy 407.992433 -391.01982) (xy 408.029184 -390.983069)
			(xy 408.071232 -390.952519) (xy 408.117542 -390.928923) (xy 408.166972 -390.912862) (xy 408.218307 -390.904732)
			(xy 408.270281 -390.904732) (xy 408.321616 -390.912862) (xy 408.371046 -390.928923) (xy 408.417356 -390.952519)
			(xy 408.459404 -390.983069) (xy 408.496155 -391.01982) (xy 408.526705 -391.061868) (xy 408.550301 -391.108178)
			(xy 408.566362 -391.157608) (xy 408.574492 -391.208943) (xy 408.575002 -391.23493) (xy 408.574492 -391.260917)
			(xy 409.113992 -391.260917) (xy 409.113992 -391.208943) (xy 409.122122 -391.157608) (xy 409.138183 -391.108178)
			(xy 409.161779 -391.061868) (xy 409.192329 -391.01982) (xy 409.22908 -390.983069) (xy 409.271128 -390.952519)
			(xy 409.317438 -390.928923) (xy 409.366868 -390.912862) (xy 409.418203 -390.904732) (xy 409.470177 -390.904732)
			(xy 409.521512 -390.912862) (xy 409.570942 -390.928923) (xy 409.617252 -390.952519) (xy 409.6593 -390.983069)
			(xy 409.696051 -391.01982) (xy 409.726601 -391.061868) (xy 409.750197 -391.108178) (xy 409.766258 -391.157608)
			(xy 409.774388 -391.208943) (xy 409.774898 -391.23493) (xy 409.774388 -391.260917) (xy 410.314142 -391.260917)
			(xy 410.314142 -391.208943) (xy 410.322272 -391.157608) (xy 410.338333 -391.108178) (xy 410.361929 -391.061868)
			(xy 410.392479 -391.01982) (xy 410.42923 -390.983069) (xy 410.471278 -390.952519) (xy 410.517588 -390.928923)
			(xy 410.567018 -390.912862) (xy 410.618353 -390.904732) (xy 410.670327 -390.904732) (xy 410.721662 -390.912862)
			(xy 410.771092 -390.928923) (xy 410.817402 -390.952519) (xy 410.85945 -390.983069) (xy 410.896201 -391.01982)
			(xy 410.926751 -391.061868) (xy 410.950347 -391.108178) (xy 410.966408 -391.157608) (xy 410.974538 -391.208943)
			(xy 410.975048 -391.23493) (xy 410.974538 -391.260917) (xy 411.514038 -391.260917) (xy 411.514038 -391.208943)
			(xy 411.522168 -391.157608) (xy 411.538229 -391.108178) (xy 411.561825 -391.061868) (xy 411.592375 -391.01982)
			(xy 411.629126 -390.983069) (xy 411.671174 -390.952519) (xy 411.717484 -390.928923) (xy 411.766914 -390.912862)
			(xy 411.818249 -390.904732) (xy 411.870223 -390.904732) (xy 411.921558 -390.912862) (xy 411.970988 -390.928923)
			(xy 412.017298 -390.952519) (xy 412.059346 -390.983069) (xy 412.096097 -391.01982) (xy 412.126647 -391.061868)
			(xy 412.150243 -391.108178) (xy 412.166304 -391.157608) (xy 412.174434 -391.208943) (xy 412.174944 -391.23493)
			(xy 412.174434 -391.260917) (xy 412.713934 -391.260917) (xy 412.713934 -391.208943) (xy 412.722064 -391.157608)
			(xy 412.738125 -391.108178) (xy 412.761721 -391.061868) (xy 412.792271 -391.01982) (xy 412.829022 -390.983069)
			(xy 412.87107 -390.952519) (xy 412.91738 -390.928923) (xy 412.96681 -390.912862) (xy 413.018145 -390.904732)
			(xy 413.070119 -390.904732) (xy 413.121454 -390.912862) (xy 413.170884 -390.928923) (xy 413.217194 -390.952519)
			(xy 413.259242 -390.983069) (xy 413.295993 -391.01982) (xy 413.326543 -391.061868) (xy 413.350139 -391.108178)
			(xy 413.3662 -391.157608) (xy 413.37433 -391.208943) (xy 413.37484 -391.23493) (xy 413.37433 -391.260917)
			(xy 413.914084 -391.260917) (xy 413.914084 -391.208943) (xy 413.922214 -391.157608) (xy 413.938275 -391.108178)
			(xy 413.961871 -391.061868) (xy 413.992421 -391.01982) (xy 414.029172 -390.983069) (xy 414.07122 -390.952519)
			(xy 414.11753 -390.928923) (xy 414.16696 -390.912862) (xy 414.218295 -390.904732) (xy 414.270269 -390.904732)
			(xy 414.321604 -390.912862) (xy 414.371034 -390.928923) (xy 414.417344 -390.952519) (xy 414.459392 -390.983069)
			(xy 414.496143 -391.01982) (xy 414.526693 -391.061868) (xy 414.550289 -391.108178) (xy 414.56635 -391.157608)
			(xy 414.57448 -391.208943) (xy 414.57499 -391.23493) (xy 414.57448 -391.260917) (xy 415.11398 -391.260917)
			(xy 415.11398 -391.208943) (xy 415.12211 -391.157608) (xy 415.138171 -391.108178) (xy 415.161767 -391.061868)
			(xy 415.192317 -391.01982) (xy 415.229068 -390.983069) (xy 415.271116 -390.952519) (xy 415.317426 -390.928923)
			(xy 415.366856 -390.912862) (xy 415.418191 -390.904732) (xy 415.470165 -390.904732) (xy 415.5215 -390.912862)
			(xy 415.57093 -390.928923) (xy 415.61724 -390.952519) (xy 415.659288 -390.983069) (xy 415.696039 -391.01982)
			(xy 415.726589 -391.061868) (xy 415.750185 -391.108178) (xy 415.766246 -391.157608) (xy 415.774376 -391.208943)
			(xy 415.774886 -391.23493) (xy 415.774376 -391.260917) (xy 416.31413 -391.260917) (xy 416.31413 -391.208943)
			(xy 416.32226 -391.157608) (xy 416.338321 -391.108178) (xy 416.361917 -391.061868) (xy 416.392467 -391.01982)
			(xy 416.429218 -390.983069) (xy 416.471266 -390.952519) (xy 416.517576 -390.928923) (xy 416.567006 -390.912862)
			(xy 416.618341 -390.904732) (xy 416.670315 -390.904732) (xy 416.72165 -390.912862) (xy 416.77108 -390.928923)
			(xy 416.81739 -390.952519) (xy 416.859438 -390.983069) (xy 416.896189 -391.01982) (xy 416.926739 -391.061868)
			(xy 416.950335 -391.108178) (xy 416.966396 -391.157608) (xy 416.974526 -391.208943) (xy 416.975036 -391.23493)
			(xy 416.974526 -391.260917) (xy 417.514026 -391.260917) (xy 417.514026 -391.208943) (xy 417.522156 -391.157608)
			(xy 417.538217 -391.108178) (xy 417.561813 -391.061868) (xy 417.592363 -391.01982) (xy 417.629114 -390.983069)
			(xy 417.671162 -390.952519) (xy 417.717472 -390.928923) (xy 417.766902 -390.912862) (xy 417.818237 -390.904732)
			(xy 417.870211 -390.904732) (xy 417.921546 -390.912862) (xy 417.970976 -390.928923) (xy 418.017286 -390.952519)
			(xy 418.059334 -390.983069) (xy 418.096085 -391.01982) (xy 418.126635 -391.061868) (xy 418.150231 -391.108178)
			(xy 418.166292 -391.157608) (xy 418.174422 -391.208943) (xy 418.174932 -391.23493) (xy 418.174422 -391.260917)
			(xy 418.713922 -391.260917) (xy 418.713922 -391.208943) (xy 418.722052 -391.157608) (xy 418.738113 -391.108178)
			(xy 418.761709 -391.061868) (xy 418.792259 -391.01982) (xy 418.82901 -390.983069) (xy 418.871058 -390.952519)
			(xy 418.917368 -390.928923) (xy 418.966798 -390.912862) (xy 419.018133 -390.904732) (xy 419.070107 -390.904732)
			(xy 419.121442 -390.912862) (xy 419.170872 -390.928923) (xy 419.217182 -390.952519) (xy 419.25923 -390.983069)
			(xy 419.295981 -391.01982) (xy 419.326531 -391.061868) (xy 419.350127 -391.108178) (xy 419.366188 -391.157608)
			(xy 419.374318 -391.208943) (xy 419.374828 -391.23493) (xy 419.374318 -391.260917) (xy 419.914072 -391.260917)
			(xy 419.914072 -391.208943) (xy 419.922202 -391.157608) (xy 419.938263 -391.108178) (xy 419.961859 -391.061868)
			(xy 419.992409 -391.01982) (xy 420.02916 -390.983069) (xy 420.071208 -390.952519) (xy 420.117518 -390.928923)
			(xy 420.166948 -390.912862) (xy 420.218283 -390.904732) (xy 420.270257 -390.904732) (xy 420.321592 -390.912862)
			(xy 420.371022 -390.928923) (xy 420.417332 -390.952519) (xy 420.45938 -390.983069) (xy 420.496131 -391.01982)
			(xy 420.526681 -391.061868) (xy 420.550277 -391.108178) (xy 420.566338 -391.157608) (xy 420.574468 -391.208943)
			(xy 420.574978 -391.23493) (xy 420.574468 -391.260917) (xy 421.113968 -391.260917) (xy 421.113968 -391.208943)
			(xy 421.122098 -391.157608) (xy 421.138159 -391.108178) (xy 421.161755 -391.061868) (xy 421.192305 -391.01982)
			(xy 421.229056 -390.983069) (xy 421.271104 -390.952519) (xy 421.317414 -390.928923) (xy 421.366844 -390.912862)
			(xy 421.418179 -390.904732) (xy 421.470153 -390.904732) (xy 421.521488 -390.912862) (xy 421.570918 -390.928923)
			(xy 421.617228 -390.952519) (xy 421.659276 -390.983069) (xy 421.696027 -391.01982) (xy 421.726577 -391.061868)
			(xy 421.750173 -391.108178) (xy 421.766234 -391.157608) (xy 421.774364 -391.208943) (xy 421.774874 -391.23493)
			(xy 421.774364 -391.260917) (xy 421.766234 -391.312252) (xy 421.750173 -391.361682) (xy 421.726577 -391.407992)
			(xy 421.696027 -391.45004) (xy 421.659276 -391.486791) (xy 421.617228 -391.517341) (xy 421.570918 -391.540937)
			(xy 421.521488 -391.556998) (xy 421.470153 -391.565128) (xy 421.418179 -391.565128) (xy 421.366844 -391.556998)
			(xy 421.317414 -391.540937) (xy 421.271104 -391.517341) (xy 421.229056 -391.486791) (xy 421.192305 -391.45004)
			(xy 421.161755 -391.407992) (xy 421.138159 -391.361682) (xy 421.122098 -391.312252) (xy 421.113968 -391.260917)
			(xy 420.574468 -391.260917) (xy 420.566338 -391.312252) (xy 420.550277 -391.361682) (xy 420.526681 -391.407992)
			(xy 420.496131 -391.45004) (xy 420.45938 -391.486791) (xy 420.417332 -391.517341) (xy 420.371022 -391.540937)
			(xy 420.321592 -391.556998) (xy 420.270257 -391.565128) (xy 420.218283 -391.565128) (xy 420.166948 -391.556998)
			(xy 420.117518 -391.540937) (xy 420.071208 -391.517341) (xy 420.02916 -391.486791) (xy 419.992409 -391.45004)
			(xy 419.961859 -391.407992) (xy 419.938263 -391.361682) (xy 419.922202 -391.312252) (xy 419.914072 -391.260917)
			(xy 419.374318 -391.260917) (xy 419.366188 -391.312252) (xy 419.350127 -391.361682) (xy 419.326531 -391.407992)
			(xy 419.295981 -391.45004) (xy 419.25923 -391.486791) (xy 419.217182 -391.517341) (xy 419.170872 -391.540937)
			(xy 419.121442 -391.556998) (xy 419.070107 -391.565128) (xy 419.018133 -391.565128) (xy 418.966798 -391.556998)
			(xy 418.917368 -391.540937) (xy 418.871058 -391.517341) (xy 418.82901 -391.486791) (xy 418.792259 -391.45004)
			(xy 418.761709 -391.407992) (xy 418.738113 -391.361682) (xy 418.722052 -391.312252) (xy 418.713922 -391.260917)
			(xy 418.174422 -391.260917) (xy 418.166292 -391.312252) (xy 418.150231 -391.361682) (xy 418.126635 -391.407992)
			(xy 418.096085 -391.45004) (xy 418.059334 -391.486791) (xy 418.017286 -391.517341) (xy 417.970976 -391.540937)
			(xy 417.921546 -391.556998) (xy 417.870211 -391.565128) (xy 417.818237 -391.565128) (xy 417.766902 -391.556998)
			(xy 417.717472 -391.540937) (xy 417.671162 -391.517341) (xy 417.629114 -391.486791) (xy 417.592363 -391.45004)
			(xy 417.561813 -391.407992) (xy 417.538217 -391.361682) (xy 417.522156 -391.312252) (xy 417.514026 -391.260917)
			(xy 416.974526 -391.260917) (xy 416.966396 -391.312252) (xy 416.950335 -391.361682) (xy 416.926739 -391.407992)
			(xy 416.896189 -391.45004) (xy 416.859438 -391.486791) (xy 416.81739 -391.517341) (xy 416.77108 -391.540937)
			(xy 416.72165 -391.556998) (xy 416.670315 -391.565128) (xy 416.618341 -391.565128) (xy 416.567006 -391.556998)
			(xy 416.517576 -391.540937) (xy 416.471266 -391.517341) (xy 416.429218 -391.486791) (xy 416.392467 -391.45004)
			(xy 416.361917 -391.407992) (xy 416.338321 -391.361682) (xy 416.32226 -391.312252) (xy 416.31413 -391.260917)
			(xy 415.774376 -391.260917) (xy 415.766246 -391.312252) (xy 415.750185 -391.361682) (xy 415.726589 -391.407992)
			(xy 415.696039 -391.45004) (xy 415.659288 -391.486791) (xy 415.61724 -391.517341) (xy 415.57093 -391.540937)
			(xy 415.5215 -391.556998) (xy 415.470165 -391.565128) (xy 415.418191 -391.565128) (xy 415.366856 -391.556998)
			(xy 415.317426 -391.540937) (xy 415.271116 -391.517341) (xy 415.229068 -391.486791) (xy 415.192317 -391.45004)
			(xy 415.161767 -391.407992) (xy 415.138171 -391.361682) (xy 415.12211 -391.312252) (xy 415.11398 -391.260917)
			(xy 414.57448 -391.260917) (xy 414.56635 -391.312252) (xy 414.550289 -391.361682) (xy 414.526693 -391.407992)
			(xy 414.496143 -391.45004) (xy 414.459392 -391.486791) (xy 414.417344 -391.517341) (xy 414.371034 -391.540937)
			(xy 414.321604 -391.556998) (xy 414.270269 -391.565128) (xy 414.218295 -391.565128) (xy 414.16696 -391.556998)
			(xy 414.11753 -391.540937) (xy 414.07122 -391.517341) (xy 414.029172 -391.486791) (xy 413.992421 -391.45004)
			(xy 413.961871 -391.407992) (xy 413.938275 -391.361682) (xy 413.922214 -391.312252) (xy 413.914084 -391.260917)
			(xy 413.37433 -391.260917) (xy 413.3662 -391.312252) (xy 413.350139 -391.361682) (xy 413.326543 -391.407992)
			(xy 413.295993 -391.45004) (xy 413.259242 -391.486791) (xy 413.217194 -391.517341) (xy 413.170884 -391.540937)
			(xy 413.121454 -391.556998) (xy 413.070119 -391.565128) (xy 413.018145 -391.565128) (xy 412.96681 -391.556998)
			(xy 412.91738 -391.540937) (xy 412.87107 -391.517341) (xy 412.829022 -391.486791) (xy 412.792271 -391.45004)
			(xy 412.761721 -391.407992) (xy 412.738125 -391.361682) (xy 412.722064 -391.312252) (xy 412.713934 -391.260917)
			(xy 412.174434 -391.260917) (xy 412.166304 -391.312252) (xy 412.150243 -391.361682) (xy 412.126647 -391.407992)
			(xy 412.096097 -391.45004) (xy 412.059346 -391.486791) (xy 412.017298 -391.517341) (xy 411.970988 -391.540937)
			(xy 411.921558 -391.556998) (xy 411.870223 -391.565128) (xy 411.818249 -391.565128) (xy 411.766914 -391.556998)
			(xy 411.717484 -391.540937) (xy 411.671174 -391.517341) (xy 411.629126 -391.486791) (xy 411.592375 -391.45004)
			(xy 411.561825 -391.407992) (xy 411.538229 -391.361682) (xy 411.522168 -391.312252) (xy 411.514038 -391.260917)
			(xy 410.974538 -391.260917) (xy 410.966408 -391.312252) (xy 410.950347 -391.361682) (xy 410.926751 -391.407992)
			(xy 410.896201 -391.45004) (xy 410.85945 -391.486791) (xy 410.817402 -391.517341) (xy 410.771092 -391.540937)
			(xy 410.721662 -391.556998) (xy 410.670327 -391.565128) (xy 410.618353 -391.565128) (xy 410.567018 -391.556998)
			(xy 410.517588 -391.540937) (xy 410.471278 -391.517341) (xy 410.42923 -391.486791) (xy 410.392479 -391.45004)
			(xy 410.361929 -391.407992) (xy 410.338333 -391.361682) (xy 410.322272 -391.312252) (xy 410.314142 -391.260917)
			(xy 409.774388 -391.260917) (xy 409.766258 -391.312252) (xy 409.750197 -391.361682) (xy 409.726601 -391.407992)
			(xy 409.696051 -391.45004) (xy 409.6593 -391.486791) (xy 409.617252 -391.517341) (xy 409.570942 -391.540937)
			(xy 409.521512 -391.556998) (xy 409.470177 -391.565128) (xy 409.418203 -391.565128) (xy 409.366868 -391.556998)
			(xy 409.317438 -391.540937) (xy 409.271128 -391.517341) (xy 409.22908 -391.486791) (xy 409.192329 -391.45004)
			(xy 409.161779 -391.407992) (xy 409.138183 -391.361682) (xy 409.122122 -391.312252) (xy 409.113992 -391.260917)
			(xy 408.574492 -391.260917) (xy 408.566362 -391.312252) (xy 408.550301 -391.361682) (xy 408.526705 -391.407992)
			(xy 408.496155 -391.45004) (xy 408.459404 -391.486791) (xy 408.417356 -391.517341) (xy 408.371046 -391.540937)
			(xy 408.321616 -391.556998) (xy 408.270281 -391.565128) (xy 408.218307 -391.565128) (xy 408.166972 -391.556998)
			(xy 408.117542 -391.540937) (xy 408.071232 -391.517341) (xy 408.029184 -391.486791) (xy 407.992433 -391.45004)
			(xy 407.961883 -391.407992) (xy 407.938287 -391.361682) (xy 407.922226 -391.312252) (xy 407.914096 -391.260917)
			(xy 407.374342 -391.260917) (xy 407.366212 -391.312252) (xy 407.350151 -391.361682) (xy 407.326555 -391.407992)
			(xy 407.296005 -391.45004) (xy 407.259254 -391.486791) (xy 407.217206 -391.517341) (xy 407.170896 -391.540937)
			(xy 407.121466 -391.556998) (xy 407.070131 -391.565128) (xy 407.018157 -391.565128) (xy 406.966822 -391.556998)
			(xy 406.917392 -391.540937) (xy 406.871082 -391.517341) (xy 406.829034 -391.486791) (xy 406.792283 -391.45004)
			(xy 406.761733 -391.407992) (xy 406.738137 -391.361682) (xy 406.722076 -391.312252) (xy 406.713946 -391.260917)
			(xy 406.174446 -391.260917) (xy 406.166316 -391.312252) (xy 406.150255 -391.361682) (xy 406.126659 -391.407992)
			(xy 406.096109 -391.45004) (xy 406.059358 -391.486791) (xy 406.01731 -391.517341) (xy 405.971 -391.540937)
			(xy 405.92157 -391.556998) (xy 405.870235 -391.565128) (xy 405.818261 -391.565128) (xy 405.766926 -391.556998)
			(xy 405.717496 -391.540937) (xy 405.671186 -391.517341) (xy 405.629138 -391.486791) (xy 405.592387 -391.45004)
			(xy 405.561837 -391.407992) (xy 405.538241 -391.361682) (xy 405.52218 -391.312252) (xy 405.51405 -391.260917)
			(xy 404.97455 -391.260917) (xy 404.96642 -391.312252) (xy 404.950359 -391.361682) (xy 404.926763 -391.407992)
			(xy 404.896213 -391.45004) (xy 404.859462 -391.486791) (xy 404.817414 -391.517341) (xy 404.771104 -391.540937)
			(xy 404.721674 -391.556998) (xy 404.670339 -391.565128) (xy 404.618365 -391.565128) (xy 404.56703 -391.556998)
			(xy 404.5176 -391.540937) (xy 404.47129 -391.517341) (xy 404.429242 -391.486791) (xy 404.392491 -391.45004)
			(xy 404.361941 -391.407992) (xy 404.338345 -391.361682) (xy 404.322284 -391.312252) (xy 404.314154 -391.260917)
			(xy 403.7744 -391.260917) (xy 403.76627 -391.312252) (xy 403.750209 -391.361682) (xy 403.726613 -391.407992)
			(xy 403.696063 -391.45004) (xy 403.659312 -391.486791) (xy 403.617264 -391.517341) (xy 403.570954 -391.540937)
			(xy 403.521524 -391.556998) (xy 403.470189 -391.565128) (xy 403.418215 -391.565128) (xy 403.36688 -391.556998)
			(xy 403.31745 -391.540937) (xy 403.27114 -391.517341) (xy 403.229092 -391.486791) (xy 403.192341 -391.45004)
			(xy 403.161791 -391.407992) (xy 403.138195 -391.361682) (xy 403.122134 -391.312252) (xy 403.114004 -391.260917)
			(xy 402.425768 -391.260917) (xy 402.426354 -391.264618) (xy 402.426354 -391.316582) (xy 402.418225 -391.367908)
			(xy 402.402168 -391.41733) (xy 402.378578 -391.463631) (xy 402.348034 -391.505673) (xy 402.311291 -391.542419)
			(xy 402.269252 -391.572965) (xy 402.222952 -391.596559) (xy 402.173531 -391.61262) (xy 402.122206 -391.620752)
			(xy 402.096224 -391.621264) (xy 402.071386 -391.620825) (xy 402.022269 -391.613404) (xy 401.974817 -391.598711)
			(xy 401.930101 -391.577077) (xy 401.889129 -391.54899) (xy 401.870672 -391.532364) (xy 401.8636 -391.526333)
			(xy 401.846415 -391.519293) (xy 401.837144 -391.518648) (xy 401.805902 -391.517886) (xy 401.796646 -391.518037)
			(xy 401.779193 -391.524166) (xy 401.771866 -391.529824) (xy 401.749302 -391.54799) (xy 401.699172 -391.577006)
			(xy 401.644758 -391.596859) (xy 401.587721 -391.606945) (xy 401.55876 -391.607548) (xy 401.535564 -391.607119)
			(xy 401.489626 -391.600637) (xy 401.445042 -391.587807) (xy 401.402686 -391.568878) (xy 401.363387 -391.544222)
			(xy 401.3454 -391.52957) (xy 401.338288 -391.523474) (xy 401.320762 -391.517378) (xy 401.235164 -391.519156)
			(xy 401.217892 -391.526268) (xy 401.211034 -391.532618) (xy 401.192593 -391.548937) (xy 401.151818 -391.576545)
			(xy 401.107401 -391.597802) (xy 401.060324 -391.612241) (xy 401.011627 -391.619541) (xy 400.987006 -391.619994)
			(xy 400.961015 -391.619539) (xy 400.909674 -391.611408) (xy 400.860236 -391.595346) (xy 400.81392 -391.571748)
			(xy 400.771866 -391.541194) (xy 400.73511 -391.504438) (xy 400.704556 -391.462385) (xy 400.680956 -391.416069)
			(xy 400.664893 -391.366632) (xy 400.656761 -391.315291) (xy 397.490373 -391.315291) (xy 397.448786 -391.345928)
			(xy 397.437864 -391.36955) (xy 397.43888 -391.382758) (xy 397.439896 -391.41146) (xy 397.439435 -391.438714)
			(xy 397.431683 -391.492669) (xy 397.41633 -391.544971) (xy 397.39369 -391.594555) (xy 397.364223 -391.640413)
			(xy 397.328529 -391.681609) (xy 397.287335 -391.717306) (xy 397.24148 -391.746776) (xy 397.191897 -391.76942)
			(xy 397.139596 -391.784777) (xy 397.085642 -391.792533) (xy 397.058388 -391.792968) (xy 397.032319 -391.792548)
			(xy 396.980666 -391.785456) (xy 396.930462 -391.771391) (xy 396.882642 -391.750617) (xy 396.838099 -391.72352)
			(xy 396.797664 -391.690607) (xy 396.76209 -391.652491) (xy 396.74673 -391.631424) (xy 396.740126 -391.62228)
			(xy 396.721076 -391.611104) (xy 396.632176 -391.603738) (xy 396.621111 -391.603346) (xy 396.600304 -391.610845)
			(xy 396.592044 -391.618216) (xy 396.08506 -392.1252) (xy 399.31162 -392.1252) (xy 399.315691 -392.069578)
			(xy 399.327817 -392.015141) (xy 399.34774 -391.96305) (xy 399.375036 -391.914415) (xy 399.409122 -391.870272)
			(xy 399.449271 -391.831563) (xy 399.494629 -391.799112) (xy 399.544229 -391.773611) (xy 399.597013 -391.755604)
			(xy 399.651856 -391.745474) (xy 399.70759 -391.743437) (xy 399.763027 -391.749537) (xy 399.816984 -391.763643)
			(xy 399.868313 -391.785455) (xy 399.915919 -391.814509) (xy 399.958787 -391.850184) (xy 399.996004 -391.891721)
			(xy 400.026777 -391.938234) (xy 400.050449 -391.988731) (xy 400.066517 -392.042138) (xy 400.074637 -392.097314)
			(xy 400.075146 -392.1252) (xy 400.074637 -392.153086) (xy 400.066517 -392.208262) (xy 400.050449 -392.261669)
			(xy 400.026777 -392.312166) (xy 399.996004 -392.358679) (xy 399.958787 -392.400216) (xy 399.915919 -392.435891)
			(xy 399.868313 -392.464945) (xy 399.816984 -392.486757) (xy 399.763027 -392.500863) (xy 399.70759 -392.506963)
			(xy 399.651856 -392.504926) (xy 399.597013 -392.494796) (xy 399.544229 -392.476789) (xy 399.494629 -392.451288)
			(xy 399.449271 -392.418837) (xy 399.409122 -392.380128) (xy 399.375036 -392.335985) (xy 399.34774 -392.28735)
			(xy 399.327817 -392.235259) (xy 399.315691 -392.180822) (xy 399.31162 -392.1252) (xy 396.08506 -392.1252)
			(xy 395.757908 -392.452352) (xy 395.750288 -392.46937) (xy 395.74978 -392.478768) (xy 395.747195 -392.51337)
			(xy 395.73376 -392.581444) (xy 395.711179 -392.647054) (xy 395.679875 -392.708978) (xy 395.660626 -392.737848)
			(xy 395.655153 -392.746599) (xy 395.651023 -392.766803) (xy 395.655155 -392.787007) (xy 395.660626 -392.79576)
			(xy 395.677681 -392.821287) (xy 395.706212 -392.875649) (xy 395.727985 -392.933053) (xy 395.742682 -392.992662)
			(xy 395.749006 -393.04468) (xy 399.31162 -393.04468) (xy 399.315691 -392.989058) (xy 399.327817 -392.934621)
			(xy 399.34774 -392.88253) (xy 399.375036 -392.833895) (xy 399.409122 -392.789752) (xy 399.449271 -392.751043)
			(xy 399.494629 -392.718592) (xy 399.544229 -392.693091) (xy 399.597013 -392.675084) (xy 399.651856 -392.664954)
			(xy 399.70759 -392.662917) (xy 399.763027 -392.669017) (xy 399.816984 -392.683123) (xy 399.868313 -392.704935)
			(xy 399.915919 -392.733989) (xy 399.953614 -392.765359) (xy 400.698718 -392.765359) (xy 400.698718 -392.713385)
			(xy 400.706848 -392.66205) (xy 400.722909 -392.61262) (xy 400.746505 -392.56631) (xy 400.777055 -392.524262)
			(xy 400.813806 -392.487511) (xy 400.855854 -392.456961) (xy 400.902164 -392.433365) (xy 400.951594 -392.417304)
			(xy 401.002929 -392.409174) (xy 401.054903 -392.409174) (xy 401.106238 -392.417304) (xy 401.155668 -392.433365)
			(xy 401.201978 -392.456961) (xy 401.244026 -392.487511) (xy 401.280777 -392.524262) (xy 401.311327 -392.56631)
			(xy 401.334923 -392.61262) (xy 401.350984 -392.66205) (xy 401.359114 -392.713385) (xy 401.359624 -392.739372)
			(xy 401.359114 -392.765359) (xy 401.350984 -392.816694) (xy 401.334923 -392.866124) (xy 401.311327 -392.912434)
			(xy 401.280777 -392.954482) (xy 401.244026 -392.991233) (xy 401.201978 -393.021783) (xy 401.194273 -393.025709)
			(xy 402.759928 -393.025709) (xy 402.759928 -392.973735) (xy 402.768058 -392.9224) (xy 402.784119 -392.87297)
			(xy 402.807715 -392.82666) (xy 402.838265 -392.784612) (xy 402.875016 -392.747861) (xy 402.917064 -392.717311)
			(xy 402.963374 -392.693715) (xy 403.012804 -392.677654) (xy 403.064139 -392.669524) (xy 403.116113 -392.669524)
			(xy 403.167448 -392.677654) (xy 403.216878 -392.693715) (xy 403.263188 -392.717311) (xy 403.305236 -392.747861)
			(xy 403.341987 -392.784612) (xy 403.372537 -392.82666) (xy 403.396133 -392.87297) (xy 403.412194 -392.9224)
			(xy 403.420324 -392.973735) (xy 403.420834 -392.999722) (xy 403.420324 -393.025709) (xy 403.959824 -393.025709)
			(xy 403.959824 -392.973735) (xy 403.967954 -392.9224) (xy 403.984015 -392.87297) (xy 404.007611 -392.82666)
			(xy 404.038161 -392.784612) (xy 404.074912 -392.747861) (xy 404.11696 -392.717311) (xy 404.16327 -392.693715)
			(xy 404.2127 -392.677654) (xy 404.264035 -392.669524) (xy 404.316009 -392.669524) (xy 404.367344 -392.677654)
			(xy 404.416774 -392.693715) (xy 404.463084 -392.717311) (xy 404.505132 -392.747861) (xy 404.541883 -392.784612)
			(xy 404.572433 -392.82666) (xy 404.596029 -392.87297) (xy 404.61209 -392.9224) (xy 404.62022 -392.973735)
			(xy 404.62073 -392.999722) (xy 404.62022 -393.025709) (xy 405.159974 -393.025709) (xy 405.159974 -392.973735)
			(xy 405.168104 -392.9224) (xy 405.184165 -392.87297) (xy 405.207761 -392.82666) (xy 405.238311 -392.784612)
			(xy 405.275062 -392.747861) (xy 405.31711 -392.717311) (xy 405.36342 -392.693715) (xy 405.41285 -392.677654)
			(xy 405.464185 -392.669524) (xy 405.516159 -392.669524) (xy 405.567494 -392.677654) (xy 405.616924 -392.693715)
			(xy 405.663234 -392.717311) (xy 405.705282 -392.747861) (xy 405.742033 -392.784612) (xy 405.772583 -392.82666)
			(xy 405.796179 -392.87297) (xy 405.81224 -392.9224) (xy 405.82037 -392.973735) (xy 405.82088 -392.999722)
			(xy 405.82037 -393.025709) (xy 406.35987 -393.025709) (xy 406.35987 -392.973735) (xy 406.368 -392.9224)
			(xy 406.384061 -392.87297) (xy 406.407657 -392.82666) (xy 406.438207 -392.784612) (xy 406.474958 -392.747861)
			(xy 406.517006 -392.717311) (xy 406.563316 -392.693715) (xy 406.612746 -392.677654) (xy 406.664081 -392.669524)
			(xy 406.716055 -392.669524) (xy 406.76739 -392.677654) (xy 406.81682 -392.693715) (xy 406.86313 -392.717311)
			(xy 406.905178 -392.747861) (xy 406.941929 -392.784612) (xy 406.972479 -392.82666) (xy 406.996075 -392.87297)
			(xy 407.012136 -392.9224) (xy 407.020266 -392.973735) (xy 407.020776 -392.999722) (xy 407.020266 -393.025709)
			(xy 407.56002 -393.025709) (xy 407.56002 -392.973735) (xy 407.56815 -392.9224) (xy 407.584211 -392.87297)
			(xy 407.607807 -392.82666) (xy 407.638357 -392.784612) (xy 407.675108 -392.747861) (xy 407.717156 -392.717311)
			(xy 407.763466 -392.693715) (xy 407.812896 -392.677654) (xy 407.864231 -392.669524) (xy 407.916205 -392.669524)
			(xy 407.96754 -392.677654) (xy 408.01697 -392.693715) (xy 408.06328 -392.717311) (xy 408.105328 -392.747861)
			(xy 408.142079 -392.784612) (xy 408.172629 -392.82666) (xy 408.196225 -392.87297) (xy 408.212286 -392.9224)
			(xy 408.220416 -392.973735) (xy 408.220926 -392.999722) (xy 408.220416 -393.025709) (xy 408.759916 -393.025709)
			(xy 408.759916 -392.973735) (xy 408.768046 -392.9224) (xy 408.784107 -392.87297) (xy 408.807703 -392.82666)
			(xy 408.838253 -392.784612) (xy 408.875004 -392.747861) (xy 408.917052 -392.717311) (xy 408.963362 -392.693715)
			(xy 409.012792 -392.677654) (xy 409.064127 -392.669524) (xy 409.116101 -392.669524) (xy 409.167436 -392.677654)
			(xy 409.216866 -392.693715) (xy 409.263176 -392.717311) (xy 409.305224 -392.747861) (xy 409.341975 -392.784612)
			(xy 409.372525 -392.82666) (xy 409.396121 -392.87297) (xy 409.412182 -392.9224) (xy 409.420312 -392.973735)
			(xy 409.420822 -392.999722) (xy 409.420312 -393.025709) (xy 409.959812 -393.025709) (xy 409.959812 -392.973735)
			(xy 409.967942 -392.9224) (xy 409.984003 -392.87297) (xy 410.007599 -392.82666) (xy 410.038149 -392.784612)
			(xy 410.0749 -392.747861) (xy 410.116948 -392.717311) (xy 410.163258 -392.693715) (xy 410.212688 -392.677654)
			(xy 410.264023 -392.669524) (xy 410.315997 -392.669524) (xy 410.367332 -392.677654) (xy 410.416762 -392.693715)
			(xy 410.463072 -392.717311) (xy 410.50512 -392.747861) (xy 410.541871 -392.784612) (xy 410.572421 -392.82666)
			(xy 410.596017 -392.87297) (xy 410.612078 -392.9224) (xy 410.620208 -392.973735) (xy 410.620718 -392.999722)
			(xy 410.620208 -393.025709) (xy 411.159962 -393.025709) (xy 411.159962 -392.973735) (xy 411.168092 -392.9224)
			(xy 411.184153 -392.87297) (xy 411.207749 -392.82666) (xy 411.238299 -392.784612) (xy 411.27505 -392.747861)
			(xy 411.317098 -392.717311) (xy 411.363408 -392.693715) (xy 411.412838 -392.677654) (xy 411.464173 -392.669524)
			(xy 411.516147 -392.669524) (xy 411.567482 -392.677654) (xy 411.616912 -392.693715) (xy 411.663222 -392.717311)
			(xy 411.70527 -392.747861) (xy 411.742021 -392.784612) (xy 411.772571 -392.82666) (xy 411.796167 -392.87297)
			(xy 411.812228 -392.9224) (xy 411.820358 -392.973735) (xy 411.820868 -392.999722) (xy 411.820358 -393.025709)
			(xy 412.359858 -393.025709) (xy 412.359858 -392.973735) (xy 412.367988 -392.9224) (xy 412.384049 -392.87297)
			(xy 412.407645 -392.82666) (xy 412.438195 -392.784612) (xy 412.474946 -392.747861) (xy 412.516994 -392.717311)
			(xy 412.563304 -392.693715) (xy 412.612734 -392.677654) (xy 412.664069 -392.669524) (xy 412.716043 -392.669524)
			(xy 412.767378 -392.677654) (xy 412.816808 -392.693715) (xy 412.863118 -392.717311) (xy 412.905166 -392.747861)
			(xy 412.941917 -392.784612) (xy 412.972467 -392.82666) (xy 412.996063 -392.87297) (xy 413.012124 -392.9224)
			(xy 413.020254 -392.973735) (xy 413.020764 -392.999722) (xy 413.020254 -393.025709) (xy 413.560008 -393.025709)
			(xy 413.560008 -392.973735) (xy 413.568138 -392.9224) (xy 413.584199 -392.87297) (xy 413.607795 -392.82666)
			(xy 413.638345 -392.784612) (xy 413.675096 -392.747861) (xy 413.717144 -392.717311) (xy 413.763454 -392.693715)
			(xy 413.812884 -392.677654) (xy 413.864219 -392.669524) (xy 413.916193 -392.669524) (xy 413.967528 -392.677654)
			(xy 414.016958 -392.693715) (xy 414.063268 -392.717311) (xy 414.105316 -392.747861) (xy 414.142067 -392.784612)
			(xy 414.172617 -392.82666) (xy 414.196213 -392.87297) (xy 414.212274 -392.9224) (xy 414.220404 -392.973735)
			(xy 414.220914 -392.999722) (xy 414.220404 -393.025709) (xy 414.759904 -393.025709) (xy 414.759904 -392.973735)
			(xy 414.768034 -392.9224) (xy 414.784095 -392.87297) (xy 414.807691 -392.82666) (xy 414.838241 -392.784612)
			(xy 414.874992 -392.747861) (xy 414.91704 -392.717311) (xy 414.96335 -392.693715) (xy 415.01278 -392.677654)
			(xy 415.064115 -392.669524) (xy 415.116089 -392.669524) (xy 415.167424 -392.677654) (xy 415.216854 -392.693715)
			(xy 415.263164 -392.717311) (xy 415.305212 -392.747861) (xy 415.341963 -392.784612) (xy 415.372513 -392.82666)
			(xy 415.396109 -392.87297) (xy 415.41217 -392.9224) (xy 415.4203 -392.973735) (xy 415.42081 -392.999722)
			(xy 415.4203 -393.025709) (xy 415.9598 -393.025709) (xy 415.9598 -392.973735) (xy 415.96793 -392.9224)
			(xy 415.983991 -392.87297) (xy 416.007587 -392.82666) (xy 416.038137 -392.784612) (xy 416.074888 -392.747861)
			(xy 416.116936 -392.717311) (xy 416.163246 -392.693715) (xy 416.212676 -392.677654) (xy 416.264011 -392.669524)
			(xy 416.315985 -392.669524) (xy 416.36732 -392.677654) (xy 416.41675 -392.693715) (xy 416.46306 -392.717311)
			(xy 416.505108 -392.747861) (xy 416.541859 -392.784612) (xy 416.572409 -392.82666) (xy 416.596005 -392.87297)
			(xy 416.612066 -392.9224) (xy 416.620196 -392.973735) (xy 416.620706 -392.999722) (xy 416.620196 -393.025709)
			(xy 417.15995 -393.025709) (xy 417.15995 -392.973735) (xy 417.16808 -392.9224) (xy 417.184141 -392.87297)
			(xy 417.207737 -392.82666) (xy 417.238287 -392.784612) (xy 417.275038 -392.747861) (xy 417.317086 -392.717311)
			(xy 417.363396 -392.693715) (xy 417.412826 -392.677654) (xy 417.464161 -392.669524) (xy 417.516135 -392.669524)
			(xy 417.56747 -392.677654) (xy 417.6169 -392.693715) (xy 417.66321 -392.717311) (xy 417.705258 -392.747861)
			(xy 417.742009 -392.784612) (xy 417.772559 -392.82666) (xy 417.796155 -392.87297) (xy 417.812216 -392.9224)
			(xy 417.820346 -392.973735) (xy 417.820856 -392.999722) (xy 417.820346 -393.025709) (xy 418.359846 -393.025709)
			(xy 418.359846 -392.973735) (xy 418.367976 -392.9224) (xy 418.384037 -392.87297) (xy 418.407633 -392.82666)
			(xy 418.438183 -392.784612) (xy 418.474934 -392.747861) (xy 418.516982 -392.717311) (xy 418.563292 -392.693715)
			(xy 418.612722 -392.677654) (xy 418.664057 -392.669524) (xy 418.716031 -392.669524) (xy 418.767366 -392.677654)
			(xy 418.816796 -392.693715) (xy 418.863106 -392.717311) (xy 418.905154 -392.747861) (xy 418.941905 -392.784612)
			(xy 418.972455 -392.82666) (xy 418.996051 -392.87297) (xy 419.012112 -392.9224) (xy 419.020242 -392.973735)
			(xy 419.020752 -392.999722) (xy 419.020242 -393.025709) (xy 419.559996 -393.025709) (xy 419.559996 -392.973735)
			(xy 419.568126 -392.9224) (xy 419.584187 -392.87297) (xy 419.607783 -392.82666) (xy 419.638333 -392.784612)
			(xy 419.675084 -392.747861) (xy 419.717132 -392.717311) (xy 419.763442 -392.693715) (xy 419.812872 -392.677654)
			(xy 419.864207 -392.669524) (xy 419.916181 -392.669524) (xy 419.967516 -392.677654) (xy 420.016946 -392.693715)
			(xy 420.063256 -392.717311) (xy 420.105304 -392.747861) (xy 420.142055 -392.784612) (xy 420.172605 -392.82666)
			(xy 420.196201 -392.87297) (xy 420.212262 -392.9224) (xy 420.220392 -392.973735) (xy 420.220902 -392.999722)
			(xy 420.220392 -393.025709) (xy 420.759892 -393.025709) (xy 420.759892 -392.973735) (xy 420.768022 -392.9224)
			(xy 420.784083 -392.87297) (xy 420.807679 -392.82666) (xy 420.838229 -392.784612) (xy 420.87498 -392.747861)
			(xy 420.917028 -392.717311) (xy 420.963338 -392.693715) (xy 421.012768 -392.677654) (xy 421.064103 -392.669524)
			(xy 421.116077 -392.669524) (xy 421.167412 -392.677654) (xy 421.216842 -392.693715) (xy 421.263152 -392.717311)
			(xy 421.3052 -392.747861) (xy 421.341951 -392.784612) (xy 421.372501 -392.82666) (xy 421.396097 -392.87297)
			(xy 421.412158 -392.9224) (xy 421.420288 -392.973735) (xy 421.420798 -392.999722) (xy 421.420288 -393.025709)
			(xy 421.412158 -393.077044) (xy 421.396097 -393.126474) (xy 421.372501 -393.172784) (xy 421.341951 -393.214832)
			(xy 421.3052 -393.251583) (xy 421.263152 -393.282133) (xy 421.216842 -393.305729) (xy 421.167412 -393.32179)
			(xy 421.116077 -393.32992) (xy 421.064103 -393.32992) (xy 421.012768 -393.32179) (xy 420.963338 -393.305729)
			(xy 420.917028 -393.282133) (xy 420.87498 -393.251583) (xy 420.838229 -393.214832) (xy 420.807679 -393.172784)
			(xy 420.784083 -393.126474) (xy 420.768022 -393.077044) (xy 420.759892 -393.025709) (xy 420.220392 -393.025709)
			(xy 420.212262 -393.077044) (xy 420.196201 -393.126474) (xy 420.172605 -393.172784) (xy 420.142055 -393.214832)
			(xy 420.105304 -393.251583) (xy 420.063256 -393.282133) (xy 420.016946 -393.305729) (xy 419.967516 -393.32179)
			(xy 419.916181 -393.32992) (xy 419.864207 -393.32992) (xy 419.812872 -393.32179) (xy 419.763442 -393.305729)
			(xy 419.717132 -393.282133) (xy 419.675084 -393.251583) (xy 419.638333 -393.214832) (xy 419.607783 -393.172784)
			(xy 419.584187 -393.126474) (xy 419.568126 -393.077044) (xy 419.559996 -393.025709) (xy 419.020242 -393.025709)
			(xy 419.012112 -393.077044) (xy 418.996051 -393.126474) (xy 418.972455 -393.172784) (xy 418.941905 -393.214832)
			(xy 418.905154 -393.251583) (xy 418.863106 -393.282133) (xy 418.816796 -393.305729) (xy 418.767366 -393.32179)
			(xy 418.716031 -393.32992) (xy 418.664057 -393.32992) (xy 418.612722 -393.32179) (xy 418.563292 -393.305729)
			(xy 418.516982 -393.282133) (xy 418.474934 -393.251583) (xy 418.438183 -393.214832) (xy 418.407633 -393.172784)
			(xy 418.384037 -393.126474) (xy 418.367976 -393.077044) (xy 418.359846 -393.025709) (xy 417.820346 -393.025709)
			(xy 417.812216 -393.077044) (xy 417.796155 -393.126474) (xy 417.772559 -393.172784) (xy 417.742009 -393.214832)
			(xy 417.705258 -393.251583) (xy 417.66321 -393.282133) (xy 417.6169 -393.305729) (xy 417.56747 -393.32179)
			(xy 417.516135 -393.32992) (xy 417.464161 -393.32992) (xy 417.412826 -393.32179) (xy 417.363396 -393.305729)
			(xy 417.317086 -393.282133) (xy 417.275038 -393.251583) (xy 417.238287 -393.214832) (xy 417.207737 -393.172784)
			(xy 417.184141 -393.126474) (xy 417.16808 -393.077044) (xy 417.15995 -393.025709) (xy 416.620196 -393.025709)
			(xy 416.612066 -393.077044) (xy 416.596005 -393.126474) (xy 416.572409 -393.172784) (xy 416.541859 -393.214832)
			(xy 416.505108 -393.251583) (xy 416.46306 -393.282133) (xy 416.41675 -393.305729) (xy 416.36732 -393.32179)
			(xy 416.315985 -393.32992) (xy 416.264011 -393.32992) (xy 416.212676 -393.32179) (xy 416.163246 -393.305729)
			(xy 416.116936 -393.282133) (xy 416.074888 -393.251583) (xy 416.038137 -393.214832) (xy 416.007587 -393.172784)
			(xy 415.983991 -393.126474) (xy 415.96793 -393.077044) (xy 415.9598 -393.025709) (xy 415.4203 -393.025709)
			(xy 415.41217 -393.077044) (xy 415.396109 -393.126474) (xy 415.372513 -393.172784) (xy 415.341963 -393.214832)
			(xy 415.305212 -393.251583) (xy 415.263164 -393.282133) (xy 415.216854 -393.305729) (xy 415.167424 -393.32179)
			(xy 415.116089 -393.32992) (xy 415.064115 -393.32992) (xy 415.01278 -393.32179) (xy 414.96335 -393.305729)
			(xy 414.91704 -393.282133) (xy 414.874992 -393.251583) (xy 414.838241 -393.214832) (xy 414.807691 -393.172784)
			(xy 414.784095 -393.126474) (xy 414.768034 -393.077044) (xy 414.759904 -393.025709) (xy 414.220404 -393.025709)
			(xy 414.212274 -393.077044) (xy 414.196213 -393.126474) (xy 414.172617 -393.172784) (xy 414.142067 -393.214832)
			(xy 414.105316 -393.251583) (xy 414.063268 -393.282133) (xy 414.016958 -393.305729) (xy 413.967528 -393.32179)
			(xy 413.916193 -393.32992) (xy 413.864219 -393.32992) (xy 413.812884 -393.32179) (xy 413.763454 -393.305729)
			(xy 413.717144 -393.282133) (xy 413.675096 -393.251583) (xy 413.638345 -393.214832) (xy 413.607795 -393.172784)
			(xy 413.584199 -393.126474) (xy 413.568138 -393.077044) (xy 413.560008 -393.025709) (xy 413.020254 -393.025709)
			(xy 413.012124 -393.077044) (xy 412.996063 -393.126474) (xy 412.972467 -393.172784) (xy 412.941917 -393.214832)
			(xy 412.905166 -393.251583) (xy 412.863118 -393.282133) (xy 412.816808 -393.305729) (xy 412.767378 -393.32179)
			(xy 412.716043 -393.32992) (xy 412.664069 -393.32992) (xy 412.612734 -393.32179) (xy 412.563304 -393.305729)
			(xy 412.516994 -393.282133) (xy 412.474946 -393.251583) (xy 412.438195 -393.214832) (xy 412.407645 -393.172784)
			(xy 412.384049 -393.126474) (xy 412.367988 -393.077044) (xy 412.359858 -393.025709) (xy 411.820358 -393.025709)
			(xy 411.812228 -393.077044) (xy 411.796167 -393.126474) (xy 411.772571 -393.172784) (xy 411.742021 -393.214832)
			(xy 411.70527 -393.251583) (xy 411.663222 -393.282133) (xy 411.616912 -393.305729) (xy 411.567482 -393.32179)
			(xy 411.516147 -393.32992) (xy 411.464173 -393.32992) (xy 411.412838 -393.32179) (xy 411.363408 -393.305729)
			(xy 411.317098 -393.282133) (xy 411.27505 -393.251583) (xy 411.238299 -393.214832) (xy 411.207749 -393.172784)
			(xy 411.184153 -393.126474) (xy 411.168092 -393.077044) (xy 411.159962 -393.025709) (xy 410.620208 -393.025709)
			(xy 410.612078 -393.077044) (xy 410.596017 -393.126474) (xy 410.572421 -393.172784) (xy 410.541871 -393.214832)
			(xy 410.50512 -393.251583) (xy 410.463072 -393.282133) (xy 410.416762 -393.305729) (xy 410.367332 -393.32179)
			(xy 410.315997 -393.32992) (xy 410.264023 -393.32992) (xy 410.212688 -393.32179) (xy 410.163258 -393.305729)
			(xy 410.116948 -393.282133) (xy 410.0749 -393.251583) (xy 410.038149 -393.214832) (xy 410.007599 -393.172784)
			(xy 409.984003 -393.126474) (xy 409.967942 -393.077044) (xy 409.959812 -393.025709) (xy 409.420312 -393.025709)
			(xy 409.412182 -393.077044) (xy 409.396121 -393.126474) (xy 409.372525 -393.172784) (xy 409.341975 -393.214832)
			(xy 409.305224 -393.251583) (xy 409.263176 -393.282133) (xy 409.216866 -393.305729) (xy 409.167436 -393.32179)
			(xy 409.116101 -393.32992) (xy 409.064127 -393.32992) (xy 409.012792 -393.32179) (xy 408.963362 -393.305729)
			(xy 408.917052 -393.282133) (xy 408.875004 -393.251583) (xy 408.838253 -393.214832) (xy 408.807703 -393.172784)
			(xy 408.784107 -393.126474) (xy 408.768046 -393.077044) (xy 408.759916 -393.025709) (xy 408.220416 -393.025709)
			(xy 408.212286 -393.077044) (xy 408.196225 -393.126474) (xy 408.172629 -393.172784) (xy 408.142079 -393.214832)
			(xy 408.105328 -393.251583) (xy 408.06328 -393.282133) (xy 408.01697 -393.305729) (xy 407.96754 -393.32179)
			(xy 407.916205 -393.32992) (xy 407.864231 -393.32992) (xy 407.812896 -393.32179) (xy 407.763466 -393.305729)
			(xy 407.717156 -393.282133) (xy 407.675108 -393.251583) (xy 407.638357 -393.214832) (xy 407.607807 -393.172784)
			(xy 407.584211 -393.126474) (xy 407.56815 -393.077044) (xy 407.56002 -393.025709) (xy 407.020266 -393.025709)
			(xy 407.012136 -393.077044) (xy 406.996075 -393.126474) (xy 406.972479 -393.172784) (xy 406.941929 -393.214832)
			(xy 406.905178 -393.251583) (xy 406.86313 -393.282133) (xy 406.81682 -393.305729) (xy 406.76739 -393.32179)
			(xy 406.716055 -393.32992) (xy 406.664081 -393.32992) (xy 406.612746 -393.32179) (xy 406.563316 -393.305729)
			(xy 406.517006 -393.282133) (xy 406.474958 -393.251583) (xy 406.438207 -393.214832) (xy 406.407657 -393.172784)
			(xy 406.384061 -393.126474) (xy 406.368 -393.077044) (xy 406.35987 -393.025709) (xy 405.82037 -393.025709)
			(xy 405.81224 -393.077044) (xy 405.796179 -393.126474) (xy 405.772583 -393.172784) (xy 405.742033 -393.214832)
			(xy 405.705282 -393.251583) (xy 405.663234 -393.282133) (xy 405.616924 -393.305729) (xy 405.567494 -393.32179)
			(xy 405.516159 -393.32992) (xy 405.464185 -393.32992) (xy 405.41285 -393.32179) (xy 405.36342 -393.305729)
			(xy 405.31711 -393.282133) (xy 405.275062 -393.251583) (xy 405.238311 -393.214832) (xy 405.207761 -393.172784)
			(xy 405.184165 -393.126474) (xy 405.168104 -393.077044) (xy 405.159974 -393.025709) (xy 404.62022 -393.025709)
			(xy 404.61209 -393.077044) (xy 404.596029 -393.126474) (xy 404.572433 -393.172784) (xy 404.541883 -393.214832)
			(xy 404.505132 -393.251583) (xy 404.463084 -393.282133) (xy 404.416774 -393.305729) (xy 404.367344 -393.32179)
			(xy 404.316009 -393.32992) (xy 404.264035 -393.32992) (xy 404.2127 -393.32179) (xy 404.16327 -393.305729)
			(xy 404.11696 -393.282133) (xy 404.074912 -393.251583) (xy 404.038161 -393.214832) (xy 404.007611 -393.172784)
			(xy 403.984015 -393.126474) (xy 403.967954 -393.077044) (xy 403.959824 -393.025709) (xy 403.420324 -393.025709)
			(xy 403.412194 -393.077044) (xy 403.396133 -393.126474) (xy 403.372537 -393.172784) (xy 403.341987 -393.214832)
			(xy 403.305236 -393.251583) (xy 403.263188 -393.282133) (xy 403.216878 -393.305729) (xy 403.167448 -393.32179)
			(xy 403.116113 -393.32992) (xy 403.064139 -393.32992) (xy 403.012804 -393.32179) (xy 402.963374 -393.305729)
			(xy 402.917064 -393.282133) (xy 402.875016 -393.251583) (xy 402.838265 -393.214832) (xy 402.807715 -393.172784)
			(xy 402.784119 -393.126474) (xy 402.768058 -393.077044) (xy 402.759928 -393.025709) (xy 401.194273 -393.025709)
			(xy 401.155668 -393.045379) (xy 401.106238 -393.06144) (xy 401.054903 -393.06957) (xy 401.002929 -393.06957)
			(xy 400.951594 -393.06144) (xy 400.902164 -393.045379) (xy 400.855854 -393.021783) (xy 400.813806 -392.991233)
			(xy 400.777055 -392.954482) (xy 400.746505 -392.912434) (xy 400.722909 -392.866124) (xy 400.706848 -392.816694)
			(xy 400.698718 -392.765359) (xy 399.953614 -392.765359) (xy 399.958787 -392.769664) (xy 399.996004 -392.811201)
			(xy 400.026777 -392.857714) (xy 400.050449 -392.908211) (xy 400.066517 -392.961618) (xy 400.074637 -393.016794)
			(xy 400.075146 -393.04468) (xy 400.074637 -393.072566) (xy 400.066517 -393.127742) (xy 400.050449 -393.181149)
			(xy 400.026777 -393.231646) (xy 399.996004 -393.278159) (xy 399.958787 -393.319696) (xy 399.915919 -393.355371)
			(xy 399.868313 -393.384425) (xy 399.816984 -393.406237) (xy 399.763027 -393.420343) (xy 399.70759 -393.426443)
			(xy 399.651856 -393.424406) (xy 399.597013 -393.414276) (xy 399.544229 -393.396269) (xy 399.494629 -393.370768)
			(xy 399.449271 -393.338317) (xy 399.409122 -393.299608) (xy 399.375036 -393.255465) (xy 399.34774 -393.20683)
			(xy 399.327817 -393.154739) (xy 399.315691 -393.100302) (xy 399.31162 -393.04468) (xy 395.749006 -393.04468)
			(xy 395.750091 -393.053607) (xy 395.750542 -393.084304) (xy 395.750078 -393.115036) (xy 395.742669 -393.176051)
			(xy 395.727961 -393.235728) (xy 395.706166 -393.293197) (xy 395.677603 -393.347621) (xy 395.642689 -393.398205)
			(xy 395.601933 -393.444212) (xy 395.555928 -393.484971) (xy 395.505346 -393.519888) (xy 395.450925 -393.548454)
			(xy 395.393457 -393.570252) (xy 395.33378 -393.584964) (xy 395.272766 -393.592376) (xy 395.242034 -393.592812)
			(xy 395.210089 -393.592308) (xy 395.146703 -393.584299) (xy 395.084819 -393.568417) (xy 395.025411 -393.54491)
			(xy 394.969414 -393.514149) (xy 394.91771 -393.476619) (xy 394.894054 -393.455144) (xy 394.886942 -393.44854)
			(xy 394.8684 -393.441174) (xy 394.787882 -393.442698) (xy 394.778114 -393.443291) (xy 394.76009 -393.450868)
			(xy 394.75283 -393.45743) (xy 394.672566 -393.537694) (xy 394.665454 -393.55141) (xy 394.664184 -393.559538)
			(xy 394.658084 -393.592913) (xy 394.638194 -393.657778) (xy 394.609857 -393.719423) (xy 394.573576 -393.776754)
			(xy 394.529995 -393.828752) (xy 394.479888 -393.874495) (xy 394.452348 -393.89431) (xy 394.44295 -393.900914)
			(xy 394.43152 -393.920726) (xy 394.428271 -393.96416) (xy 399.31162 -393.96416) (xy 399.315691 -393.908538)
			(xy 399.327817 -393.854101) (xy 399.34774 -393.80201) (xy 399.375036 -393.753375) (xy 399.409122 -393.709232)
			(xy 399.449271 -393.670523) (xy 399.494629 -393.638072) (xy 399.544229 -393.612571) (xy 399.597013 -393.594564)
			(xy 399.651856 -393.584434) (xy 399.70759 -393.582397) (xy 399.763027 -393.588497) (xy 399.816984 -393.602603)
			(xy 399.868313 -393.624415) (xy 399.915919 -393.653469) (xy 399.958787 -393.689144) (xy 399.996004 -393.730681)
			(xy 400.026777 -393.777194) (xy 400.050449 -393.827691) (xy 400.066517 -393.881098) (xy 400.074637 -393.936274)
			(xy 400.075146 -393.96416) (xy 400.074637 -393.992046) (xy 400.071889 -394.010721) (xy 400.277332 -394.010721)
			(xy 400.277332 -393.958747) (xy 400.285462 -393.907412) (xy 400.301523 -393.857982) (xy 400.325119 -393.811672)
			(xy 400.355669 -393.769624) (xy 400.39242 -393.732873) (xy 400.434468 -393.702323) (xy 400.480778 -393.678727)
			(xy 400.530208 -393.662666) (xy 400.581543 -393.654536) (xy 400.633517 -393.654536) (xy 400.684852 -393.662666)
			(xy 400.734282 -393.678727) (xy 400.780592 -393.702323) (xy 400.82264 -393.732873) (xy 400.859391 -393.769624)
			(xy 400.889941 -393.811672) (xy 400.913537 -393.857982) (xy 400.929598 -393.907412) (xy 400.937728 -393.958747)
			(xy 400.938238 -393.984734) (xy 400.937728 -394.010721) (xy 400.929598 -394.062056) (xy 400.913537 -394.111486)
			(xy 400.889941 -394.157796) (xy 400.859391 -394.199844) (xy 400.82264 -394.236595) (xy 400.780592 -394.267145)
			(xy 400.734282 -394.290741) (xy 400.684852 -394.306802) (xy 400.633517 -394.314932) (xy 400.581543 -394.314932)
			(xy 400.530208 -394.306802) (xy 400.480778 -394.290741) (xy 400.434468 -394.267145) (xy 400.39242 -394.236595)
			(xy 400.355669 -394.199844) (xy 400.325119 -394.157796) (xy 400.301523 -394.111486) (xy 400.285462 -394.062056)
			(xy 400.277332 -394.010721) (xy 400.071889 -394.010721) (xy 400.066517 -394.047222) (xy 400.050449 -394.100629)
			(xy 400.026777 -394.151126) (xy 399.996004 -394.197639) (xy 399.958787 -394.239176) (xy 399.915919 -394.274851)
			(xy 399.868313 -394.303905) (xy 399.816984 -394.325717) (xy 399.763027 -394.339823) (xy 399.70759 -394.345923)
			(xy 399.651856 -394.343886) (xy 399.597013 -394.333756) (xy 399.544229 -394.315749) (xy 399.494629 -394.290248)
			(xy 399.449271 -394.257797) (xy 399.409122 -394.219088) (xy 399.375036 -394.174945) (xy 399.34774 -394.12631)
			(xy 399.327817 -394.074219) (xy 399.315691 -394.019782) (xy 399.31162 -393.96416) (xy 394.428271 -393.96416)
			(xy 394.4239 -394.02258) (xy 394.432282 -394.043916) (xy 394.440664 -394.05179) (xy 394.462028 -394.072414)
			(xy 394.500303 -394.117817) (xy 394.533026 -394.167371) (xy 394.559754 -394.2204) (xy 394.58012 -394.276182)
			(xy 394.593849 -394.333957) (xy 394.600753 -394.392938) (xy 394.601192 -394.42263) (xy 394.600726 -394.453359)
			(xy 394.593315 -394.51437) (xy 394.578603 -394.574042) (xy 394.556807 -394.631506) (xy 394.528242 -394.685924)
			(xy 394.493327 -394.736502) (xy 394.45257 -394.782503) (xy 394.406566 -394.823256) (xy 394.355985 -394.858166)
			(xy 394.301564 -394.886725) (xy 394.244098 -394.908517) (xy 394.184425 -394.923223) (xy 394.123414 -394.930629)
			(xy 394.092684 -394.931138) (xy 394.061825 -394.930673) (xy 394.000566 -394.923161) (xy 393.97051 -394.916152)
			(xy 393.960858 -394.913866) (xy 393.942316 -394.916406) (xy 393.864592 -394.959586) (xy 393.8524 -394.974064)
			(xy 393.849352 -394.983462) (xy 393.838456 -395.015428) (xy 393.809382 -395.076384) (xy 393.772487 -395.13295)
			(xy 393.72842 -395.184127) (xy 393.703556 -395.206982) (xy 393.695141 -395.215241) (xy 393.686316 -395.237075)
			(xy 393.688159 -395.260553) (xy 393.69365 -395.27099) (xy 393.706378 -395.29321) (xy 393.726423 -395.340331)
			(xy 393.739988 -395.389709) (xy 393.746827 -395.440458) (xy 393.747244 -395.466062) (xy 393.746784 -395.493318)
			(xy 393.739031 -395.547275) (xy 393.723679 -395.599579) (xy 393.701039 -395.649166) (xy 393.671573 -395.695027)
			(xy 393.63588 -395.736227) (xy 393.594686 -395.771928) (xy 393.548831 -395.801404) (xy 393.499249 -395.824053)
			(xy 393.446947 -395.839416) (xy 393.392992 -395.847178) (xy 393.365736 -395.84757) (xy 393.338671 -395.847093)
			(xy 393.285084 -395.839434) (xy 393.233118 -395.824279) (xy 393.183816 -395.801931) (xy 393.138166 -395.77284)
			(xy 393.097086 -395.73759) (xy 393.0614 -395.696887) (xy 393.031825 -395.65155) (xy 393.008954 -395.602488)
			(xy 392.993246 -395.550686) (xy 392.985017 -395.497185) (xy 392.984228 -395.470126) (xy 392.983974 -395.454632)
			(xy 392.966956 -395.429486) (xy 392.865864 -395.388338) (xy 392.856451 -395.385056) (xy 392.836535 -395.385177)
			(xy 392.818151 -395.392838) (xy 392.810746 -395.399514) (xy 392.03376 -396.1765) (xy 395.05712 -396.1765)
			(xy 395.061191 -396.120878) (xy 395.073317 -396.066441) (xy 395.09324 -396.01435) (xy 395.120536 -395.965715)
			(xy 395.154622 -395.921572) (xy 395.194771 -395.882863) (xy 395.240129 -395.850412) (xy 395.289729 -395.824911)
			(xy 395.342513 -395.806904) (xy 395.397356 -395.796774) (xy 395.45309 -395.794737) (xy 395.508527 -395.800837)
			(xy 395.562484 -395.814943) (xy 395.613813 -395.836755) (xy 395.661419 -395.865809) (xy 395.704287 -395.901484)
			(xy 395.741504 -395.943021) (xy 395.772277 -395.989534) (xy 395.795949 -396.040031) (xy 395.812017 -396.093438)
			(xy 395.820137 -396.148614) (xy 395.820646 -396.1765) (xy 395.820137 -396.204386) (xy 395.812017 -396.259562)
			(xy 395.795949 -396.312969) (xy 395.772277 -396.363466) (xy 395.741504 -396.409979) (xy 395.704287 -396.451516)
			(xy 395.661419 -396.487191) (xy 395.613813 -396.516245) (xy 395.562484 -396.538057) (xy 395.508527 -396.552163)
			(xy 395.45309 -396.558263) (xy 395.397356 -396.556226) (xy 395.342513 -396.546096) (xy 395.289729 -396.528089)
			(xy 395.240129 -396.502588) (xy 395.194771 -396.470137) (xy 395.154622 -396.431428) (xy 395.120536 -396.387285)
			(xy 395.09324 -396.33865) (xy 395.073317 -396.286559) (xy 395.061191 -396.232122) (xy 395.05712 -396.1765)
			(xy 392.03376 -396.1765) (xy 391.17905 -397.03121) (xy 391.172164 -397.03866) (xy 391.164424 -397.057394)
			(xy 391.164064 -397.067532) (xy 391.164826 -397.150082) (xy 391.1727 -397.168624) (xy 391.180066 -397.17599)
			(xy 391.19865 -397.1948) (xy 391.230194 -397.237234) (xy 391.254588 -397.284144) (xy 391.260419 -397.301751)
			(xy 391.481797 -397.301751) (xy 391.481797 -397.247249) (xy 391.489554 -397.193303) (xy 391.504909 -397.141009)
			(xy 391.52755 -397.091433) (xy 391.557017 -397.045584) (xy 391.592709 -397.004396) (xy 391.633899 -396.968706)
			(xy 391.679749 -396.939242) (xy 391.729326 -396.916603) (xy 391.78162 -396.90125) (xy 391.835567 -396.893496)
			(xy 391.862818 -396.893034) (xy 391.890189 -396.893481) (xy 391.944369 -396.901302) (xy 391.996873 -396.916795)
			(xy 392.046619 -396.939641) (xy 392.092585 -396.969371) (xy 392.113516 -396.987014) (xy 392.120628 -396.99311)
			(xy 392.137646 -396.99946) (xy 392.22299 -396.99946) (xy 392.240008 -396.99311) (xy 392.24712 -396.987014)
			(xy 392.268053 -396.969373) (xy 392.314021 -396.939649) (xy 392.363767 -396.916803) (xy 392.416269 -396.901307)
			(xy 392.470447 -396.893478) (xy 392.525189 -396.893478) (xy 392.579367 -396.901307) (xy 392.631869 -396.916803)
			(xy 392.681615 -396.939649) (xy 392.727583 -396.969373) (xy 392.748516 -396.987014) (xy 392.755628 -396.99311)
			(xy 392.772646 -396.99946) (xy 392.85799 -396.99946) (xy 392.875008 -396.99311) (xy 392.88212 -396.987014)
			(xy 392.903073 -396.969401) (xy 392.94904 -396.939685) (xy 392.998782 -396.916844) (xy 393.051278 -396.901346)
			(xy 393.10545 -396.893512) (xy 393.132818 -396.893034) (xy 393.160071 -396.893437) (xy 393.214023 -396.901197)
			(xy 393.266321 -396.916555) (xy 393.315902 -396.9392) (xy 393.361755 -396.96867) (xy 393.402948 -397.004365)
			(xy 393.438641 -397.045559) (xy 393.468109 -397.091414) (xy 393.490751 -397.140995) (xy 393.502307 -397.180352)
			(xy 394.841185 -397.180352) (xy 394.841185 -397.125848) (xy 394.848942 -397.0719) (xy 394.864298 -397.019604)
			(xy 394.886941 -396.970026) (xy 394.916408 -396.924176) (xy 394.952101 -396.882986) (xy 394.993294 -396.847295)
			(xy 395.039146 -396.81783) (xy 395.088725 -396.79519) (xy 395.141021 -396.779838) (xy 395.19497 -396.772084)
			(xy 395.222222 -396.771622) (xy 395.249593 -396.77207) (xy 395.303773 -396.779891) (xy 395.356277 -396.795384)
			(xy 395.406023 -396.81823) (xy 395.451989 -396.847959) (xy 395.47292 -396.865602) (xy 395.480032 -396.871698)
			(xy 395.49705 -396.878048) (xy 395.582394 -396.878048) (xy 395.599412 -396.871698) (xy 395.606524 -396.865602)
			(xy 395.627474 -396.847985) (xy 395.673442 -396.81827) (xy 395.723185 -396.79543) (xy 395.775682 -396.779933)
			(xy 395.829854 -396.772099) (xy 395.857222 -396.771622) (xy 395.884474 -396.772049) (xy 395.938424 -396.779809)
			(xy 395.99072 -396.795167) (xy 396.040299 -396.817811) (xy 396.08615 -396.847281) (xy 396.127341 -396.882975)
			(xy 396.163033 -396.924168) (xy 396.192499 -396.970021) (xy 396.21514 -397.0196) (xy 396.230496 -397.071898)
			(xy 396.238252 -397.125848) (xy 396.238252 -397.180352) (xy 396.230496 -397.234302) (xy 396.21514 -397.2866)
			(xy 396.192499 -397.336179) (xy 396.163033 -397.382032) (xy 396.127341 -397.423225) (xy 396.112535 -397.436055)
			(xy 396.522618 -397.436055) (xy 396.530375 -397.382097) (xy 396.545731 -397.329793) (xy 396.568376 -397.280207)
			(xy 396.597846 -397.234348) (xy 396.633544 -397.19315) (xy 396.674741 -397.157452) (xy 396.720599 -397.12798)
			(xy 396.770185 -397.105334) (xy 396.822489 -397.089977) (xy 396.876446 -397.082219) (xy 396.903702 -397.081756)
			(xy 396.936722 -397.08328) (xy 396.949676 -397.084296) (xy 396.973044 -397.074136) (xy 397.041624 -396.987014)
			(xy 397.045942 -396.961868) (xy 397.041878 -396.949676) (xy 397.03262 -396.920181) (xy 397.022665 -396.859172)
			(xy 397.022066 -396.828264) (xy 397.022391 -396.804647) (xy 397.028199 -396.757773) (xy 397.039747 -396.711974)
			(xy 397.047974 -396.689834) (xy 397.0528 -396.677388) (xy 397.049244 -396.65148) (xy 396.981426 -396.56131)
			(xy 396.95755 -396.550642) (xy 396.944342 -396.551912) (xy 396.91056 -396.553436) (xy 396.883296 -396.552982)
			(xy 396.829324 -396.545213) (xy 396.777007 -396.529841) (xy 396.727412 -396.507177) (xy 396.681548 -396.477684)
			(xy 396.64035 -396.441962) (xy 396.604656 -396.400739) (xy 396.575195 -396.354855) (xy 396.552566 -396.305243)
			(xy 396.53723 -396.252916) (xy 396.529499 -396.198938) (xy 396.529052 -396.171674) (xy 396.529052 -395.308074)
			(xy 396.529499 -395.280815) (xy 396.537258 -395.226852) (xy 396.552615 -395.174541) (xy 396.575257 -395.124946)
			(xy 396.604723 -395.079077) (xy 396.640415 -395.037866) (xy 396.681606 -395.002151) (xy 396.727458 -394.972659)
			(xy 396.77704 -394.94999) (xy 396.829342 -394.934604) (xy 396.883301 -394.926815) (xy 396.91056 -394.926312)
			(xy 396.925675 -394.92647) (xy 396.95581 -394.928889) (xy 396.970758 -394.931138) (xy 396.981426 -394.932916)
			(xy 397.002254 -394.927328) (xy 397.077946 -394.866622) (xy 397.087598 -394.847572) (xy 397.088106 -394.83665)
			(xy 397.090323 -394.807843) (xy 397.102314 -394.751327) (xy 397.122684 -394.697264) (xy 397.15097 -394.646888)
			(xy 397.186524 -394.60135) (xy 397.228535 -394.56169) (xy 397.276043 -394.528814) (xy 397.327962 -394.503473)
			(xy 397.383107 -394.486245) (xy 397.440219 -394.477525) (xy 397.469106 -394.476986) (xy 397.496357 -394.477484)
			(xy 397.550303 -394.485241) (xy 397.602596 -394.500597) (xy 397.652172 -394.523238) (xy 397.698021 -394.552704)
			(xy 397.739209 -394.588395) (xy 397.7749 -394.629584) (xy 397.804365 -394.675434) (xy 397.827005 -394.72501)
			(xy 397.84236 -394.777303) (xy 397.850116 -394.831249) (xy 397.850116 -394.871448) (xy 400.378676 -394.871448)
			(xy 400.379186 -394.845461) (xy 400.387316 -394.794126) (xy 400.403377 -394.744696) (xy 400.426973 -394.698386)
			(xy 400.457523 -394.656338) (xy 400.494274 -394.619587) (xy 400.536322 -394.589037) (xy 400.582632 -394.565441)
			(xy 400.632062 -394.54938) (xy 400.683397 -394.54125) (xy 400.735371 -394.54125) (xy 400.786706 -394.54938)
			(xy 400.836136 -394.565441) (xy 400.882446 -394.589037) (xy 400.924494 -394.619587) (xy 400.961245 -394.656338)
			(xy 400.991795 -394.698386) (xy 401.015391 -394.744696) (xy 401.031452 -394.794126) (xy 401.039582 -394.845461)
			(xy 401.040092 -394.871448) (xy 401.039556 -394.898777) (xy 401.030561 -394.952691) (xy 401.012823 -395.004392)
			(xy 400.986826 -395.052473) (xy 400.970496 -395.074394) (xy 400.964908 -395.08176) (xy 400.95932 -395.098524)
			(xy 400.962876 -395.182598) (xy 400.969734 -395.198854) (xy 400.97583 -395.205712) (xy 400.992214 -395.22411)
			(xy 401.019865 -395.264883) (xy 401.041166 -395.309305) (xy 401.055647 -395.356393) (xy 401.062988 -395.405108)
			(xy 401.06346 -395.42974) (xy 401.06295 -395.455727) (xy 401.05482 -395.507062) (xy 401.038759 -395.556492)
			(xy 401.015163 -395.602802) (xy 400.984613 -395.64485) (xy 400.947862 -395.681601) (xy 400.905814 -395.712151)
			(xy 400.859504 -395.735747) (xy 400.810074 -395.751808) (xy 400.758739 -395.759938) (xy 400.706765 -395.759938)
			(xy 400.65543 -395.751808) (xy 400.606 -395.735747) (xy 400.55969 -395.712151) (xy 400.517642 -395.681601)
			(xy 400.480891 -395.64485) (xy 400.450341 -395.602802) (xy 400.426745 -395.556492) (xy 400.410684 -395.507062)
			(xy 400.402554 -395.455727) (xy 400.402044 -395.42974) (xy 400.40264 -395.402413) (xy 400.411619 -395.348503)
			(xy 400.429339 -395.296802) (xy 400.455318 -395.248718) (xy 400.47164 -395.226794) (xy 400.477228 -395.219428)
			(xy 400.482816 -395.202664) (xy 400.47926 -395.11859) (xy 400.472402 -395.102334) (xy 400.466306 -395.095476)
			(xy 400.44997 -395.077037) (xy 400.422311 -395.036276) (xy 400.401 -394.991865) (xy 400.386508 -394.944785)
			(xy 400.379154 -394.896077) (xy 400.378676 -394.871448) (xy 397.850116 -394.871448) (xy 397.850116 -394.885751)
			(xy 397.84236 -394.939697) (xy 397.827005 -394.99199) (xy 397.804365 -395.041566) (xy 397.7749 -395.087416)
			(xy 397.739209 -395.128605) (xy 397.698021 -395.164296) (xy 397.652172 -395.193762) (xy 397.602596 -395.216403)
			(xy 397.550303 -395.231759) (xy 397.496357 -395.239516) (xy 397.469106 -395.240002) (xy 397.4466 -395.239651)
			(xy 397.401905 -395.234304) (xy 397.379952 -395.229334) (xy 397.368467 -395.227177) (xy 397.345702 -395.232348)
			(xy 397.336264 -395.23924) (xy 397.311118 -395.25956) (xy 397.30232 -395.267293) (xy 397.292405 -395.28849)
			(xy 397.292068 -395.3002) (xy 397.292068 -395.308074) (xy 397.292068 -396.171674) (xy 397.291722 -396.19529)
			(xy 397.285922 -396.242163) (xy 397.274382 -396.287963) (xy 397.26616 -396.310104) (xy 397.261334 -396.32255)
			(xy 397.26489 -396.348458) (xy 397.332708 -396.438882) (xy 397.356584 -396.44955) (xy 397.369792 -396.44828)
			(xy 397.403574 -396.446756) (xy 397.431965 -396.447293) (xy 397.488119 -396.455724) (xy 397.542402 -396.472389)
			(xy 397.593613 -396.496919) (xy 397.640621 -396.528771) (xy 397.682386 -396.567242) (xy 397.717985 -396.611481)
			(xy 397.732758 -396.635732) (xy 397.737584 -396.643606) (xy 397.7513 -396.654782) (xy 397.830802 -396.682722)
			(xy 397.848582 -396.682468) (xy 397.857218 -396.679166) (xy 397.886561 -396.668316) (xy 397.947238 -396.65307)
			(xy 398.009325 -396.645371) (xy 398.040606 -396.644876) (xy 398.072566 -396.64541) (xy 398.135981 -396.653422)
			(xy 398.197893 -396.669319) (xy 398.224046 -396.679674) (xy 399.436588 -396.679674) (xy 399.440659 -396.624052)
			(xy 399.452785 -396.569615) (xy 399.472708 -396.517524) (xy 399.500004 -396.468889) (xy 399.53409 -396.424746)
			(xy 399.574239 -396.386037) (xy 399.619597 -396.353586) (xy 399.669197 -396.328085) (xy 399.721981 -396.310078)
			(xy 399.776824 -396.299948) (xy 399.832558 -396.297911) (xy 399.887995 -396.304011) (xy 399.941952 -396.318117)
			(xy 399.993281 -396.339929) (xy 400.040887 -396.368983) (xy 400.083755 -396.404658) (xy 400.120972 -396.446195)
			(xy 400.151745 -396.492708) (xy 400.175417 -396.543205) (xy 400.191485 -396.596612) (xy 400.199605 -396.651788)
			(xy 400.200114 -396.679674) (xy 400.199667 -396.704137) (xy 400.402554 -396.704137) (xy 400.402554 -396.652163)
			(xy 400.410684 -396.600828) (xy 400.426745 -396.551398) (xy 400.450341 -396.505088) (xy 400.480891 -396.46304)
			(xy 400.517642 -396.426289) (xy 400.55969 -396.395739) (xy 400.606 -396.372143) (xy 400.65543 -396.356082)
			(xy 400.706765 -396.347952) (xy 400.758739 -396.347952) (xy 400.810074 -396.356082) (xy 400.859504 -396.372143)
			(xy 400.905814 -396.395739) (xy 400.947862 -396.426289) (xy 400.984613 -396.46304) (xy 401.015163 -396.505088)
			(xy 401.038759 -396.551398) (xy 401.05482 -396.600828) (xy 401.06295 -396.652163) (xy 401.06346 -396.67815)
			(xy 401.06295 -396.704137) (xy 401.05482 -396.755472) (xy 401.038759 -396.804902) (xy 401.015163 -396.851212)
			(xy 400.984613 -396.89326) (xy 400.947862 -396.930011) (xy 400.905814 -396.960561) (xy 400.859504 -396.984157)
			(xy 400.810074 -397.000218) (xy 400.758739 -397.008348) (xy 400.706765 -397.008348) (xy 400.65543 -397.000218)
			(xy 400.606 -396.984157) (xy 400.55969 -396.960561) (xy 400.517642 -396.930011) (xy 400.480891 -396.89326)
			(xy 400.450341 -396.851212) (xy 400.426745 -396.804902) (xy 400.410684 -396.755472) (xy 400.402554 -396.704137)
			(xy 400.199667 -396.704137) (xy 400.199605 -396.70756) (xy 400.191485 -396.762736) (xy 400.175417 -396.816143)
			(xy 400.151745 -396.86664) (xy 400.120972 -396.913153) (xy 400.083755 -396.95469) (xy 400.040887 -396.990365)
			(xy 399.993281 -397.019419) (xy 399.941952 -397.041231) (xy 399.887995 -397.055337) (xy 399.832558 -397.061437)
			(xy 399.776824 -397.0594) (xy 399.721981 -397.04927) (xy 399.669197 -397.031263) (xy 399.619597 -397.005762)
			(xy 399.574239 -396.973311) (xy 399.53409 -396.934602) (xy 399.500004 -396.890459) (xy 399.472708 -396.841824)
			(xy 399.452785 -396.789733) (xy 399.440659 -396.735296) (xy 399.436588 -396.679674) (xy 398.224046 -396.679674)
			(xy 398.257323 -396.69285) (xy 398.313336 -396.723644) (xy 398.365048 -396.761215) (xy 398.411643 -396.804971)
			(xy 398.452387 -396.854222) (xy 398.486636 -396.908192) (xy 398.513852 -396.966028) (xy 398.533604 -397.026819)
			(xy 398.545581 -397.089607) (xy 398.549595 -397.1534) (xy 398.545581 -397.217193) (xy 398.533604 -397.279981)
			(xy 398.513852 -397.340772) (xy 398.486636 -397.398608) (xy 398.452387 -397.452578) (xy 398.411643 -397.501829)
			(xy 398.365048 -397.545585) (xy 398.313336 -397.583156) (xy 398.257323 -397.61395) (xy 398.197893 -397.637481)
			(xy 398.135981 -397.653378) (xy 398.072566 -397.66139) (xy 398.040606 -397.661892) (xy 398.007212 -397.661342)
			(xy 397.940997 -397.652623) (xy 397.876493 -397.635308) (xy 397.814813 -397.609696) (xy 397.757017 -397.576228)
			(xy 397.704101 -397.535479) (xy 397.656977 -397.488152) (xy 397.616457 -397.435062) (xy 397.583237 -397.377123)
			(xy 397.557891 -397.315332) (xy 397.548862 -397.283178) (xy 397.546576 -397.274034) (xy 397.536416 -397.25981)
			(xy 397.467074 -397.21155) (xy 397.450056 -397.206978) (xy 397.440912 -397.207994) (xy 397.403574 -397.209772)
			(xy 397.370554 -397.208248) (xy 397.3576 -397.207232) (xy 397.334232 -397.217392) (xy 397.265652 -397.304514)
			(xy 397.261334 -397.32966) (xy 397.265398 -397.341852) (xy 397.274661 -397.371345) (xy 397.284613 -397.432356)
			(xy 397.28521 -397.463264) (xy 397.284784 -397.49052) (xy 397.277031 -397.544478) (xy 397.261677 -397.596783)
			(xy 397.239037 -397.646371) (xy 397.209569 -397.692232) (xy 397.173874 -397.733432) (xy 397.13268 -397.769133)
			(xy 397.086823 -397.798608) (xy 397.037239 -397.821257) (xy 396.984936 -397.836618) (xy 396.930979 -397.844379)
			(xy 396.876467 -397.844383) (xy 396.82251 -397.836628) (xy 396.770205 -397.821273) (xy 396.720618 -397.79863)
			(xy 396.674758 -397.769161) (xy 396.633559 -397.733465) (xy 396.597859 -397.692269) (xy 396.568386 -397.646412)
			(xy 396.545739 -397.596827) (xy 396.530379 -397.544524) (xy 396.52262 -397.490567) (xy 396.522618 -397.436055)
			(xy 396.112535 -397.436055) (xy 396.08615 -397.458919) (xy 396.040299 -397.488389) (xy 395.99072 -397.511033)
			(xy 395.938424 -397.526391) (xy 395.884474 -397.534151) (xy 395.857222 -397.534638) (xy 395.829852 -397.534174)
			(xy 395.775672 -397.526358) (xy 395.723168 -397.510869) (xy 395.673421 -397.488027) (xy 395.627455 -397.4583)
			(xy 395.606524 -397.440658) (xy 395.599412 -397.434562) (xy 395.582394 -397.428212) (xy 395.49705 -397.428212)
			(xy 395.480032 -397.434562) (xy 395.47292 -397.440658) (xy 395.451986 -397.458295) (xy 395.406014 -397.488008)
			(xy 395.356267 -397.510845) (xy 395.303767 -397.526337) (xy 395.249591 -397.534165) (xy 395.222222 -397.534638)
			(xy 395.19497 -397.534116) (xy 395.141021 -397.526362) (xy 395.088725 -397.511009) (xy 395.039146 -397.48837)
			(xy 394.993294 -397.458905) (xy 394.952101 -397.423214) (xy 394.916408 -397.382024) (xy 394.886941 -397.336174)
			(xy 394.864298 -397.286596) (xy 394.848942 -397.2343) (xy 394.841185 -397.180352) (xy 393.502307 -397.180352)
			(xy 393.506107 -397.193294) (xy 393.513864 -397.247247) (xy 393.513864 -397.301753) (xy 393.506107 -397.355706)
			(xy 393.490751 -397.408005) (xy 393.468109 -397.457586) (xy 393.438641 -397.503441) (xy 393.402948 -397.544635)
			(xy 393.361755 -397.58033) (xy 393.315902 -397.6098) (xy 393.266321 -397.632445) (xy 393.214023 -397.647803)
			(xy 393.160071 -397.655563) (xy 393.132818 -397.65605) (xy 393.105448 -397.655586) (xy 393.051268 -397.647769)
			(xy 392.998764 -397.63228) (xy 392.949017 -397.609438) (xy 392.903051 -397.579712) (xy 392.88212 -397.56207)
			(xy 392.875008 -397.555974) (xy 392.85799 -397.549624) (xy 392.772646 -397.549624) (xy 392.755628 -397.555974)
			(xy 392.748516 -397.56207) (xy 392.727583 -397.579711) (xy 392.681615 -397.609435) (xy 392.631869 -397.632281)
			(xy 392.579367 -397.647777) (xy 392.525189 -397.655606) (xy 392.470447 -397.655606) (xy 392.416269 -397.647777)
			(xy 392.363767 -397.632281) (xy 392.314021 -397.609435) (xy 392.268053 -397.579711) (xy 392.24712 -397.56207)
			(xy 392.240008 -397.555974) (xy 392.22299 -397.549624) (xy 392.137646 -397.549624) (xy 392.120628 -397.555974)
			(xy 392.113516 -397.56207) (xy 392.092585 -397.57971) (xy 392.046612 -397.609423) (xy 391.996865 -397.632259)
			(xy 391.944364 -397.64775) (xy 391.890187 -397.655577) (xy 391.862818 -397.65605) (xy 391.835567 -397.655504)
			(xy 391.78162 -397.64775) (xy 391.729326 -397.632397) (xy 391.679749 -397.609758) (xy 391.633899 -397.580294)
			(xy 391.592709 -397.544604) (xy 391.557017 -397.503416) (xy 391.52755 -397.457567) (xy 391.504909 -397.407991)
			(xy 391.489554 -397.355697) (xy 391.481797 -397.301751) (xy 391.260419 -397.301751) (xy 391.271211 -397.334337)
			(xy 391.27964 -397.386535) (xy 391.280142 -397.412972) (xy 391.279706 -397.437382) (xy 391.27253 -397.485671)
			(xy 391.258329 -397.532379) (xy 391.237412 -397.57649) (xy 391.210234 -397.617045) (xy 391.177387 -397.653161)
			(xy 391.139586 -397.684054) (xy 391.118852 -397.696944) (xy 391.107422 -397.703802) (xy 391.094214 -397.726916)
			(xy 391.094214 -397.841216) (xy 391.107168 -397.86433) (xy 391.118852 -397.871442) (xy 391.139563 -397.884318)
			(xy 391.177303 -397.915201) (xy 391.210095 -397.951295) (xy 391.237228 -397.991816) (xy 391.258111 -398.035883)
			(xy 391.272293 -398.082542) (xy 391.279465 -398.130777) (xy 391.279888 -398.15516) (xy 391.279472 -398.178932)
			(xy 391.272654 -398.225986) (xy 391.259168 -398.271578) (xy 391.239292 -398.314769) (xy 391.213435 -398.354668)
			(xy 391.1981 -398.372838) (xy 391.19242 -398.37996) (xy 391.186044 -398.397011) (xy 391.185654 -398.406112)
			(xy 391.185654 -398.437608) (xy 391.186034 -398.44671) (xy 391.192421 -398.463758) (xy 391.1981 -398.470882)
			(xy 391.213446 -398.489043) (xy 391.239308 -398.52894) (xy 391.259181 -398.572133) (xy 391.272654 -398.61773)
			(xy 391.279449 -398.664787) (xy 391.279888 -398.68856) (xy 391.279331 -398.716149) (xy 391.274125 -398.74705)
			(xy 393.22198 -398.74705) (xy 393.22198 -398.69255) (xy 393.229735 -398.638605) (xy 393.245089 -398.586313)
			(xy 393.267728 -398.536738) (xy 393.297192 -398.490889) (xy 393.33288 -398.4497) (xy 393.374067 -398.414008)
			(xy 393.419913 -398.384541) (xy 393.469487 -398.361899) (xy 393.521778 -398.346541) (xy 393.575722 -398.338782)
			(xy 393.602972 -398.338294) (xy 393.630342 -398.338778) (xy 393.68452 -398.346592) (xy 393.737023 -398.362077)
			(xy 393.78677 -398.384914) (xy 393.832738 -398.414635) (xy 393.85367 -398.432274) (xy 393.860782 -398.43837)
			(xy 393.8778 -398.44472) (xy 393.963144 -398.44472) (xy 393.980162 -398.43837) (xy 393.987274 -398.432274)
			(xy 394.008202 -398.41463) (xy 394.054176 -398.384919) (xy 394.103925 -398.362085) (xy 394.156426 -398.346595)
			(xy 394.210603 -398.338768) (xy 394.237972 -398.338294) (xy 394.265226 -398.338751) (xy 394.319181 -398.346505)
			(xy 394.371482 -398.361859) (xy 394.421066 -398.3845) (xy 394.466923 -398.413967) (xy 394.508119 -398.449661)
			(xy 394.543816 -398.490855) (xy 394.573287 -398.536709) (xy 394.595931 -398.586292) (xy 394.611289 -398.638592)
			(xy 394.619047 -398.692546) (xy 394.619047 -398.747054) (xy 394.611289 -398.801008) (xy 394.595931 -398.853308)
			(xy 394.573287 -398.902891) (xy 394.543816 -398.948745) (xy 394.508119 -398.989939) (xy 394.466923 -399.025633)
			(xy 394.421066 -399.0551) (xy 394.371482 -399.077741) (xy 394.319181 -399.093095) (xy 394.265226 -399.100849)
			(xy 394.237972 -399.10131) (xy 394.210601 -399.100858) (xy 394.156422 -399.093036) (xy 394.103919 -399.077544)
			(xy 394.054172 -399.054699) (xy 394.008206 -399.024972) (xy 393.987274 -399.00733) (xy 393.980162 -399.001234)
			(xy 393.963144 -398.994884) (xy 393.8778 -398.994884) (xy 393.860782 -399.001234) (xy 393.85367 -399.00733)
			(xy 393.832726 -399.024954) (xy 393.786756 -399.054667) (xy 393.737012 -399.077506) (xy 393.684514 -399.093)
			(xy 393.63034 -399.100833) (xy 393.602972 -399.10131) (xy 393.575722 -399.100818) (xy 393.521778 -399.093059)
			(xy 393.469487 -399.077701) (xy 393.419913 -399.055059) (xy 393.374067 -399.025592) (xy 393.33288 -398.9899)
			(xy 393.297192 -398.948711) (xy 393.267728 -398.902862) (xy 393.245089 -398.853287) (xy 393.229735 -398.800995)
			(xy 393.22198 -398.74705) (xy 391.274125 -398.74705) (xy 391.270165 -398.770559) (xy 391.252099 -398.822695)
			(xy 391.225632 -398.871111) (xy 391.191499 -398.914464) (xy 391.150645 -398.951552) (xy 391.127742 -398.966944)
			(xy 391.120179 -398.972205) (xy 391.109122 -398.986924) (xy 391.106152 -398.995646) (xy 391.097516 -399.025618)
			(xy 391.095322 -399.034568) (xy 391.096766 -399.052924) (xy 391.10031 -399.061432) (xy 391.110086 -399.083411)
			(xy 391.123889 -399.129489) (xy 391.13087 -399.177081) (xy 391.131298 -399.201132) (xy 391.130786 -399.227117)
			(xy 391.122651 -399.278447) (xy 391.106588 -399.327873) (xy 391.08299 -399.374177) (xy 391.052439 -399.41622)
			(xy 391.015688 -399.452967) (xy 390.973641 -399.483512) (xy 390.927334 -399.507104) (xy 390.877906 -399.523161)
			(xy 390.826575 -399.531289) (xy 390.80059 -399.53184) (xy 390.783706 -399.531625) (xy 390.750113 -399.528185)
			(xy 390.733534 -399.524982) (xy 390.722104 -399.522696) (xy 390.70026 -399.52803) (xy 390.630156 -399.58518)
			(xy 390.621749 -399.592793) (xy 390.611972 -399.613227) (xy 390.61136 -399.62455) (xy 390.61136 -400.80438)
			(xy 390.611776 -400.813673) (xy 390.618392 -400.831044) (xy 390.630735 -400.844943) (xy 390.638792 -400.849592)
			(xy 390.73201 -400.897598) (xy 390.760204 -400.895566) (xy 390.771888 -400.887184) (xy 390.796274 -400.870478)
			(xy 390.84912 -400.843997) (xy 390.905418 -400.825987) (xy 390.963821 -400.816879) (xy 390.993376 -400.816318)
			(xy 391.020628 -400.81678) (xy 391.074578 -400.824533) (xy 391.126875 -400.839886) (xy 391.176455 -400.862526)
			(xy 391.222308 -400.891991) (xy 391.263501 -400.927682) (xy 391.299194 -400.968873) (xy 391.328663 -401.014724)
			(xy 391.351305 -401.064302) (xy 391.366662 -401.116599) (xy 391.374419 -401.170548) (xy 391.374419 -401.225052)
			(xy 391.366662 -401.279001) (xy 391.351305 -401.331298) (xy 391.328663 -401.380876) (xy 391.299194 -401.426727)
			(xy 391.263501 -401.467918) (xy 391.222308 -401.503609) (xy 391.176455 -401.533074) (xy 391.126875 -401.555714)
			(xy 391.074578 -401.571067) (xy 391.020628 -401.57882) (xy 390.993376 -401.579334) (xy 390.963822 -401.578778)
			(xy 390.90542 -401.569661) (xy 390.849123 -401.551648) (xy 390.796276 -401.525171) (xy 390.771888 -401.508468)
			(xy 390.760204 -401.500086) (xy 390.73201 -401.498054) (xy 390.638792 -401.54606) (xy 390.63071 -401.550686)
			(xy 390.61832 -401.564566) (xy 390.611736 -401.581967) (xy 390.61136 -401.591272) (xy 390.61136 -401.717002)
			(xy 391.333226 -401.717002) (xy 391.337297 -401.66138) (xy 391.349423 -401.606943) (xy 391.369346 -401.554852)
			(xy 391.396642 -401.506217) (xy 391.430728 -401.462074) (xy 391.470877 -401.423365) (xy 391.516235 -401.390914)
			(xy 391.565835 -401.365413) (xy 391.618619 -401.347406) (xy 391.673462 -401.337276) (xy 391.729196 -401.335239)
			(xy 391.784633 -401.341339) (xy 391.83859 -401.355445) (xy 391.889919 -401.377257) (xy 391.937525 -401.406311)
			(xy 391.980393 -401.441986) (xy 392.01761 -401.483523) (xy 392.048383 -401.530036) (xy 392.072055 -401.580533)
			(xy 392.088123 -401.63394) (xy 392.096243 -401.689116) (xy 392.096752 -401.717002) (xy 392.096243 -401.744888)
			(xy 392.088123 -401.800064) (xy 392.072055 -401.853471) (xy 392.04887 -401.90293) (xy 392.326114 -401.90293)
			(xy 392.326568 -401.872233) (xy 392.333975 -401.811287) (xy 392.348671 -401.751678) (xy 392.370443 -401.694275)
			(xy 392.398974 -401.639913) (xy 392.41603 -401.614386) (xy 392.421474 -401.60562) (xy 392.425609 -401.585425)
			(xy 392.421494 -401.565226) (xy 392.41603 -401.556474) (xy 392.398989 -401.53094) (xy 392.37048 -401.476571)
			(xy 392.348718 -401.419168) (xy 392.334018 -401.359564) (xy 392.326594 -401.298625) (xy 392.326114 -401.26793)
			(xy 392.326566 -401.237198) (xy 392.333971 -401.176181) (xy 392.348678 -401.116502) (xy 392.370472 -401.05903)
			(xy 392.399034 -401.004606) (xy 392.433949 -400.95402) (xy 392.474707 -400.908013) (xy 392.520714 -400.867254)
			(xy 392.571299 -400.832339) (xy 392.625723 -400.803775) (xy 392.683194 -400.781981) (xy 392.742873 -400.767273)
			(xy 392.80389 -400.759866) (xy 392.834622 -400.759422) (xy 392.865318 -400.759899) (xy 392.926263 -400.7673)
			(xy 392.985872 -400.781991) (xy 393.043276 -400.803758) (xy 393.097639 -400.832284) (xy 393.123166 -400.849338)
			(xy 393.131918 -400.854809) (xy 393.152122 -400.858937) (xy 393.172326 -400.854809) (xy 393.181078 -400.849338)
			(xy 393.206598 -400.832276) (xy 393.260971 -400.80377) (xy 393.318378 -400.782012) (xy 393.377985 -400.767317)
			(xy 393.438926 -400.759899) (xy 393.469622 -400.759422) (xy 393.500318 -400.759899) (xy 393.561263 -400.7673)
			(xy 393.620872 -400.781991) (xy 393.678276 -400.803758) (xy 393.732639 -400.832284) (xy 393.758166 -400.849338)
			(xy 393.766918 -400.854809) (xy 393.787122 -400.858937) (xy 393.807326 -400.854809) (xy 393.816078 -400.849338)
			(xy 393.841598 -400.832276) (xy 393.895971 -400.80377) (xy 393.953378 -400.782012) (xy 394.012985 -400.767317)
			(xy 394.073926 -400.759899) (xy 394.104622 -400.759422) (xy 394.125704 -400.75993) (xy 394.136626 -400.760438)
			(xy 394.156184 -400.752818) (xy 394.22451 -400.684492) (xy 394.23213 -400.664934) (xy 394.231622 -400.654012)
			(xy 394.231114 -400.63293) (xy 394.231568 -400.602233) (xy 394.238975 -400.541287) (xy 394.253671 -400.481678)
			(xy 394.275443 -400.424275) (xy 394.303974 -400.369913) (xy 394.32103 -400.344386) (xy 394.326474 -400.33562)
			(xy 394.330609 -400.315425) (xy 394.326494 -400.295226) (xy 394.32103 -400.286474) (xy 394.303989 -400.26094)
			(xy 394.27548 -400.206571) (xy 394.253718 -400.149168) (xy 394.239018 -400.089564) (xy 394.231594 -400.028625)
			(xy 394.231114 -399.99793) (xy 394.231686 -399.964706) (xy 394.240349 -399.898824) (xy 394.25752 -399.834632)
			(xy 394.282904 -399.773223) (xy 394.316071 -399.715643) (xy 394.356454 -399.662874) (xy 394.403366 -399.615813)
			(xy 394.456008 -399.575264) (xy 394.513483 -399.541916) (xy 394.574812 -399.516337) (xy 394.638949 -399.498965)
			(xy 394.671804 -399.493994) (xy 394.683234 -399.49247) (xy 394.701776 -399.480532) (xy 394.755624 -399.395188)
			(xy 394.758418 -399.373344) (xy 394.754862 -399.362422) (xy 394.743561 -399.324624) (xy 394.731437 -399.246673)
			(xy 394.730732 -399.207228) (xy 394.731164 -399.176495) (xy 394.73857 -399.115477) (xy 394.753278 -399.055796)
			(xy 394.775073 -398.998324) (xy 394.803637 -398.943898) (xy 394.838553 -398.893312) (xy 394.879313 -398.847305)
			(xy 394.925322 -398.806546) (xy 394.975908 -398.77163) (xy 395.030335 -398.743068) (xy 395.087808 -398.721274)
			(xy 395.147489 -398.706568) (xy 395.208507 -398.699163) (xy 395.23924 -398.69872) (xy 395.269936 -398.699189)
			(xy 395.330882 -398.706591) (xy 395.390491 -398.721285) (xy 395.447894 -398.743054) (xy 395.502257 -398.771581)
			(xy 395.527784 -398.788636) (xy 395.536536 -398.794107) (xy 395.55674 -398.798235) (xy 395.576944 -398.794107)
			(xy 395.585696 -398.788636) (xy 395.611239 -398.771609) (xy 395.665605 -398.743097) (xy 395.723006 -398.721332)
			(xy 395.782608 -398.706629) (xy 395.843546 -398.699202) (xy 395.87424 -398.69872) (xy 395.904973 -398.699118)
			(xy 395.96599 -398.706532) (xy 396.025669 -398.721246) (xy 396.083139 -398.743046) (xy 396.137562 -398.771615)
			(xy 396.188145 -398.806535) (xy 396.234151 -398.847298) (xy 396.274907 -398.893308) (xy 396.30982 -398.943896)
			(xy 396.338382 -398.998323) (xy 396.360174 -399.055796) (xy 396.374881 -399.115477) (xy 396.382286 -399.176495)
			(xy 396.382748 -399.207228) (xy 396.382173 -399.242074) (xy 396.372658 -399.311113) (xy 396.35381 -399.378208)
			(xy 396.325982 -399.442103) (xy 396.308326 -399.47215) (xy 396.3035 -399.480024) (xy 396.299944 -399.497804)
			(xy 396.314422 -399.582132) (xy 396.323566 -399.59788) (xy 396.330932 -399.603722) (xy 396.3556 -399.624468)
			(xy 396.400007 -399.671187) (xy 396.438156 -399.723143) (xy 396.469434 -399.779502) (xy 396.493342 -399.839361)
			(xy 396.509495 -399.901761) (xy 396.517634 -399.965702) (xy 396.51813 -399.99793) (xy 396.517648 -400.028626)
			(xy 396.510247 -400.08957) (xy 396.495556 -400.149179) (xy 396.47379 -400.206583) (xy 396.445266 -400.260946)
			(xy 396.428214 -400.286474) (xy 396.422715 -400.295212) (xy 396.418594 -400.315425) (xy 396.422735 -400.335634)
			(xy 396.428214 -400.344386) (xy 396.445231 -400.369936) (xy 396.473745 -400.4243) (xy 396.495513 -400.481699)
			(xy 396.510218 -400.541299) (xy 396.517647 -400.602236) (xy 396.51813 -400.63293) (xy 396.517672 -400.663661)
			(xy 396.510261 -400.724674) (xy 396.495549 -400.784349) (xy 396.473753 -400.841816) (xy 396.445189 -400.896237)
			(xy 396.410273 -400.946818) (xy 396.369516 -400.992822) (xy 396.323511 -401.033578) (xy 396.27293 -401.068493)
			(xy 396.218508 -401.097056) (xy 396.161041 -401.118852) (xy 396.101366 -401.133562) (xy 396.040353 -401.140973)
			(xy 396.009622 -401.141438) (xy 395.98854 -401.14093) (xy 395.977618 -401.140422) (xy 395.95806 -401.148042)
			(xy 395.889734 -401.216368) (xy 395.882114 -401.235926) (xy 395.882622 -401.246848) (xy 395.88313 -401.26793)
			(xy 395.882648 -401.298626) (xy 395.875247 -401.35957) (xy 395.860556 -401.419179) (xy 395.83879 -401.476583)
			(xy 395.810266 -401.530946) (xy 395.793214 -401.556474) (xy 395.787715 -401.565212) (xy 395.783594 -401.585425)
			(xy 395.787735 -401.605634) (xy 395.793214 -401.614386) (xy 395.810231 -401.639936) (xy 395.838745 -401.6943)
			(xy 395.860513 -401.751699) (xy 395.875218 -401.811299) (xy 395.882647 -401.872236) (xy 395.88313 -401.90293)
			(xy 395.882672 -401.933661) (xy 395.875261 -401.994674) (xy 395.860549 -402.054349) (xy 395.838753 -402.111816)
			(xy 395.810189 -402.166237) (xy 395.775273 -402.216818) (xy 395.734516 -402.262822) (xy 395.688511 -402.303578)
			(xy 395.63793 -402.338493) (xy 395.583508 -402.367056) (xy 395.526041 -402.388852) (xy 395.466366 -402.403562)
			(xy 395.405353 -402.410973) (xy 395.374622 -402.411438) (xy 395.343925 -402.410979) (xy 395.28298 -402.403572)
			(xy 395.223372 -402.388876) (xy 395.165968 -402.367105) (xy 395.111605 -402.338577) (xy 395.086078 -402.321522)
			(xy 395.077326 -402.316051) (xy 395.057122 -402.311923) (xy 395.036918 -402.316051) (xy 395.028166 -402.321522)
			(xy 395.00263 -402.338561) (xy 394.948262 -402.367071) (xy 394.89086 -402.388834) (xy 394.831256 -402.403535)
			(xy 394.770317 -402.410958) (xy 394.739622 -402.411438) (xy 394.708925 -402.410979) (xy 394.64798 -402.403572)
			(xy 394.588372 -402.388876) (xy 394.530968 -402.367105) (xy 394.476605 -402.338577) (xy 394.451078 -402.321522)
			(xy 394.442326 -402.316051) (xy 394.422122 -402.311923) (xy 394.401918 -402.316051) (xy 394.393166 -402.321522)
			(xy 394.36763 -402.338561) (xy 394.313262 -402.367071) (xy 394.25586 -402.388834) (xy 394.196256 -402.403535)
			(xy 394.135317 -402.410958) (xy 394.104622 -402.411438) (xy 394.073925 -402.410979) (xy 394.01298 -402.403572)
			(xy 393.953372 -402.388876) (xy 393.895968 -402.367105) (xy 393.841605 -402.338577) (xy 393.816078 -402.321522)
			(xy 393.807326 -402.316051) (xy 393.787122 -402.311923) (xy 393.766918 -402.316051) (xy 393.758166 -402.321522)
			(xy 393.73263 -402.338561) (xy 393.678262 -402.367071) (xy 393.62086 -402.388834) (xy 393.561256 -402.403535)
			(xy 393.500317 -402.410958) (xy 393.469622 -402.411438) (xy 393.438925 -402.410979) (xy 393.37798 -402.403572)
			(xy 393.318372 -402.388876) (xy 393.260968 -402.367105) (xy 393.206605 -402.338577) (xy 393.181078 -402.321522)
			(xy 393.172326 -402.316051) (xy 393.152122 -402.311923) (xy 393.131918 -402.316051) (xy 393.123166 -402.321522)
			(xy 393.09763 -402.338561) (xy 393.043262 -402.367071) (xy 392.98586 -402.388834) (xy 392.926256 -402.403535)
			(xy 392.865317 -402.410958) (xy 392.834622 -402.411438) (xy 392.803893 -402.410923) (xy 392.742882 -402.403518)
			(xy 392.683208 -402.388813) (xy 392.625742 -402.367022) (xy 392.571322 -402.338463) (xy 392.520741 -402.303553)
			(xy 392.474736 -402.262801) (xy 392.433979 -402.2168) (xy 392.399064 -402.166223) (xy 392.3705 -402.111805)
			(xy 392.348703 -402.054342) (xy 392.333991 -401.99467) (xy 392.32658 -401.933659) (xy 392.326114 -401.90293)
			(xy 392.04887 -401.90293) (xy 392.048383 -401.903968) (xy 392.01761 -401.950481) (xy 391.980393 -401.992018)
			(xy 391.937525 -402.027693) (xy 391.889919 -402.056747) (xy 391.83859 -402.078559) (xy 391.784633 -402.092665)
			(xy 391.729196 -402.098765) (xy 391.673462 -402.096728) (xy 391.618619 -402.086598) (xy 391.565835 -402.068591)
			(xy 391.516235 -402.04309) (xy 391.470877 -402.010639) (xy 391.430728 -401.97193) (xy 391.396642 -401.927787)
			(xy 391.369346 -401.879152) (xy 391.349423 -401.827061) (xy 391.337297 -401.772624) (xy 391.333226 -401.717002)
			(xy 390.61136 -401.717002) (xy 390.61136 -402.833078) (xy 390.611799 -402.843141) (xy 390.61954 -402.861719)
			(xy 390.626346 -402.869146) (xy 391.553954 -403.796754) (xy 391.561353 -403.803597) (xy 391.579952 -403.811319)
			(xy 391.590022 -403.81174)
		)
		(stroke
			(width 0)
			(type solid)
		)
		(fill yes)
		(layer "In4.Cu")
		(net "P0V9_CPU0_RT2_2A_2D")
	)
	(gr_poly
		(pts
			(xy 15.9512 -414.985708) (xy 15.962962 -414.985124) (xy 15.984039 -414.97468) (xy 15.991586 -414.965642)
			(xy 16.04772 -414.891728) (xy 16.052292 -414.868614) (xy 16.04899 -414.85693) (xy 16.042573 -414.832087)
			(xy 16.035693 -414.781239) (xy 16.035274 -414.755584) (xy 16.03576 -414.728333) (xy 16.043516 -414.674385)
			(xy 16.058871 -414.62209) (xy 16.081513 -414.572513) (xy 16.110979 -414.526663) (xy 16.14667 -414.485472)
			(xy 16.187861 -414.449781) (xy 16.233711 -414.420315) (xy 16.283288 -414.397673) (xy 16.335583 -414.382318)
			(xy 16.389531 -414.374562) (xy 16.444033 -414.374562) (xy 16.497981 -414.382318) (xy 16.550276 -414.397673)
			(xy 16.599853 -414.420315) (xy 16.645703 -414.449781) (xy 16.686894 -414.485472) (xy 16.722585 -414.526663)
			(xy 16.752051 -414.572513) (xy 16.774693 -414.62209) (xy 16.790048 -414.674385) (xy 16.797804 -414.728333)
			(xy 16.79829 -414.755584) (xy 16.797873 -414.78124) (xy 16.790994 -414.832087) (xy 16.784574 -414.85693)
			(xy 16.781272 -414.868614) (xy 16.785844 -414.891728) (xy 16.841978 -414.965642) (xy 16.849574 -414.974621)
			(xy 16.870619 -414.985065) (xy 16.882364 -414.985708) (xy 17.822164 -414.985708) (xy 17.829811 -414.985455)
			(xy 17.844423 -414.980942) (xy 17.850866 -414.976818) (xy 17.85493 -414.974024) (xy 18.497042 -414.331912)
			(xy 18.517634 -414.312097) (xy 18.56385 -414.278489) (xy 18.614751 -414.252519) (xy 18.669086 -414.234826)
			(xy 18.725519 -414.225845) (xy 18.75409 -414.225232) (xy 21.572728 -414.225232) (xy 21.582797 -414.224805)
			(xy 21.601397 -414.217087) (xy 21.608796 -414.210246) (xy 23.442676 -412.376366) (xy 23.463279 -412.356577)
			(xy 23.509508 -412.323021) (xy 23.560413 -412.297102) (xy 23.614742 -412.279456) (xy 23.671162 -412.270517)
			(xy 23.699724 -412.26994) (xy 28.771088 -412.26994) (xy 28.781158 -412.269517) (xy 28.79976 -412.261799)
			(xy 28.807156 -412.254954) (xy 30.221682 -410.840428) (xy 30.229084 -410.833591) (xy 30.247682 -410.825882)
			(xy 30.25775 -410.825442) (xy 32.12465 -410.825442) (xy 32.133032 -410.82468) (xy 32.140634 -410.82316)
			(xy 32.15446 -410.816165) (xy 32.16021 -410.810964) (xy 34.078672 -408.892502) (xy 34.085353 -408.88509)
			(xy 34.092945 -408.866659) (xy 34.092942 -408.846725) (xy 34.085344 -408.828295) (xy 34.078672 -408.820874)
			(xy 34.076894 -408.819096) (xy 34.076894 -404.48484) (xy 34.077197 -404.476644) (xy 34.082369 -404.46109)
			(xy 34.087054 -404.45436) (xy 34.087308 -404.454106) (xy 34.092134 -404.447502) (xy 34.094674 -404.440136)
			(xy 34.095958 -404.436129) (xy 34.097363 -404.427833) (xy 34.097468 -404.423626) (xy 34.097468 -396.573248)
			(xy 34.097035 -396.563183) (xy 34.089303 -396.544595) (xy 34.082482 -396.53718) (xy 31.28137 -393.736068)
			(xy 31.260112 -393.713815) (xy 31.22595 -393.662635) (xy 31.213552 -393.634468) (xy 31.071058 -393.290298)
			(xy 31.068994 -393.28572) (xy 31.063367 -393.277403) (xy 31.059882 -393.273788) (xy 30.277054 -392.49096)
			(xy 30.270208 -392.483562) (xy 30.26248 -392.464963) (xy 30.262068 -392.454892) (xy 30.262068 -379.451108)
			(xy 30.26029 -379.437138) (xy 30.258258 -379.431296) (xy 28.68549 -375.634758) (xy 28.681426 -375.62536)
			(xy 22.69871 -369.642898) (xy 22.691598 -369.635532) (xy 22.672802 -369.627912) (xy 18.020284 -369.627912)
			(xy 17.997248 -369.627425) (xy 17.951695 -369.620508) (xy 17.907653 -369.606973) (xy 17.88668 -369.597432)
			(xy 17.881346 -369.594892) (xy 17.870678 -369.592606) (xy 17.066768 -369.592606) (xy 17.06372 -369.595908)
			(xy 4.836922 -369.595908) (xy 4.818126 -369.603528) (xy 4.811014 -369.610894) (xy 4.78409 -369.637818)
			(xy 4.776695 -369.644672) (xy 4.758096 -369.652415) (xy 4.748022 -369.652804) (xy 4.694428 -369.652804)
			(xy 4.684403 -369.653219) (xy 4.665877 -369.660884) (xy 4.651697 -369.675057) (xy 4.644023 -369.693579)
			(xy 4.643628 -369.703604) (xy 4.643628 -376.70105) (xy 8.208781 -376.70105) (xy 8.21251 -376.647799)
			(xy 8.223627 -376.595587) (xy 8.241913 -376.545435) (xy 8.267012 -376.498321) (xy 8.298433 -376.455167)
			(xy 8.335563 -376.416813) (xy 8.356346 -376.40006) (xy 8.365129 -376.392519) (xy 8.375299 -376.371744)
			(xy 8.375904 -376.360182) (xy 8.375904 -376.279918) (xy 8.375322 -376.268352) (xy 8.365135 -376.247581)
			(xy 8.356346 -376.24004) (xy 8.335563 -376.223287) (xy 8.298433 -376.184933) (xy 8.267012 -376.141779)
			(xy 8.241913 -376.094665) (xy 8.223627 -376.044513) (xy 8.21251 -375.992301) (xy 8.208781 -375.93905)
			(xy 8.21251 -375.885799) (xy 8.223627 -375.833587) (xy 8.241913 -375.783435) (xy 8.267012 -375.736321)
			(xy 8.298433 -375.693167) (xy 8.335563 -375.654813) (xy 8.356346 -375.63806) (xy 8.365129 -375.630519)
			(xy 8.375299 -375.609744) (xy 8.375904 -375.598182) (xy 8.375904 -375.517918) (xy 8.375322 -375.506352)
			(xy 8.365135 -375.485581) (xy 8.356346 -375.47804) (xy 8.33387 -375.45984) (xy 8.294137 -375.417821)
			(xy 8.261199 -375.370287) (xy 8.23581 -375.318328) (xy 8.218551 -375.263133) (xy 8.209818 -375.205965)
			(xy 8.20928 -375.17705) (xy 8.209766 -375.149799) (xy 8.217522 -375.095851) (xy 8.232877 -375.043556)
			(xy 8.255519 -374.993979) (xy 8.284985 -374.948129) (xy 8.320676 -374.906938) (xy 8.361867 -374.871247)
			(xy 8.407717 -374.841781) (xy 8.457294 -374.819139) (xy 8.509589 -374.803784) (xy 8.563537 -374.796028)
			(xy 8.618039 -374.796028) (xy 8.671987 -374.803784) (xy 8.724282 -374.819139) (xy 8.773859 -374.841781)
			(xy 8.819709 -374.871247) (xy 8.8609 -374.906938) (xy 8.896591 -374.948129) (xy 8.926057 -374.993979)
			(xy 8.948699 -375.043556) (xy 8.964054 -375.095851) (xy 8.97181 -375.149799) (xy 8.972296 -375.17705)
			(xy 8.971743 -375.205966) (xy 8.963022 -375.263135) (xy 8.945771 -375.318334) (xy 8.920385 -375.370295)
			(xy 8.887448 -375.41783) (xy 8.847713 -375.459849) (xy 8.82523 -375.47804) (xy 8.816443 -375.485577)
			(xy 8.806276 -375.506355) (xy 8.805672 -375.517918) (xy 8.805672 -375.598182) (xy 8.806228 -375.609752)
			(xy 8.81643 -375.630525) (xy 8.82523 -375.63806) (xy 8.846013 -375.654813) (xy 8.883144 -375.693166)
			(xy 8.914565 -375.736321) (xy 8.939664 -375.783435) (xy 8.95795 -375.833587) (xy 8.969067 -375.885798)
			(xy 8.972797 -375.93905) (xy 8.969067 -375.992302) (xy 8.95795 -376.044513) (xy 8.939664 -376.094665)
			(xy 8.914565 -376.141779) (xy 8.883144 -376.184934) (xy 8.846013 -376.223287) (xy 8.82523 -376.24004)
			(xy 8.816443 -376.247577) (xy 8.806276 -376.268355) (xy 8.805672 -376.279918) (xy 8.805672 -376.360182)
			(xy 8.806228 -376.371752) (xy 8.81643 -376.392525) (xy 8.82523 -376.40006) (xy 8.846013 -376.416813)
			(xy 8.883144 -376.455166) (xy 8.914565 -376.498321) (xy 8.939664 -376.545435) (xy 8.95795 -376.595587)
			(xy 8.969067 -376.647798) (xy 8.972797 -376.70105) (xy 10.494781 -376.70105) (xy 10.49851 -376.647799)
			(xy 10.509627 -376.595587) (xy 10.527913 -376.545435) (xy 10.553012 -376.498321) (xy 10.584433 -376.455167)
			(xy 10.621563 -376.416813) (xy 10.642346 -376.40006) (xy 10.651129 -376.392519) (xy 10.661299 -376.371744)
			(xy 10.661904 -376.360182) (xy 10.661904 -376.279918) (xy 10.661322 -376.268352) (xy 10.651135 -376.247581)
			(xy 10.642346 -376.24004) (xy 10.621563 -376.223287) (xy 10.584433 -376.184933) (xy 10.553012 -376.141779)
			(xy 10.527913 -376.094665) (xy 10.509627 -376.044513) (xy 10.49851 -375.992301) (xy 10.494781 -375.93905)
			(xy 10.49851 -375.885799) (xy 10.509627 -375.833587) (xy 10.527913 -375.783435) (xy 10.553012 -375.736321)
			(xy 10.584433 -375.693167) (xy 10.621563 -375.654813) (xy 10.642346 -375.63806) (xy 10.651129 -375.630519)
			(xy 10.661299 -375.609744) (xy 10.661904 -375.598182) (xy 10.661904 -375.517918) (xy 10.661322 -375.506352)
			(xy 10.651135 -375.485581) (xy 10.642346 -375.47804) (xy 10.61987 -375.45984) (xy 10.580137 -375.417821)
			(xy 10.547199 -375.370287) (xy 10.52181 -375.318328) (xy 10.504551 -375.263133) (xy 10.495818 -375.205965)
			(xy 10.49528 -375.17705) (xy 10.495766 -375.149799) (xy 10.503522 -375.095851) (xy 10.518877 -375.043556)
			(xy 10.541519 -374.993979) (xy 10.570985 -374.948129) (xy 10.606676 -374.906938) (xy 10.647867 -374.871247)
			(xy 10.693717 -374.841781) (xy 10.743294 -374.819139) (xy 10.795589 -374.803784) (xy 10.849537 -374.796028)
			(xy 10.904039 -374.796028) (xy 10.957987 -374.803784) (xy 11.010282 -374.819139) (xy 11.059859 -374.841781)
			(xy 11.105709 -374.871247) (xy 11.1469 -374.906938) (xy 11.182591 -374.948129) (xy 11.212057 -374.993979)
			(xy 11.234699 -375.043556) (xy 11.250054 -375.095851) (xy 11.25781 -375.149799) (xy 11.258296 -375.17705)
			(xy 11.257743 -375.205966) (xy 11.249022 -375.263135) (xy 11.231771 -375.318334) (xy 11.206385 -375.370295)
			(xy 11.173448 -375.41783) (xy 11.133713 -375.459849) (xy 11.11123 -375.47804) (xy 11.102443 -375.485577)
			(xy 11.092276 -375.506355) (xy 11.091672 -375.517918) (xy 11.091672 -375.598182) (xy 11.092228 -375.609752)
			(xy 11.10243 -375.630525) (xy 11.11123 -375.63806) (xy 11.132013 -375.654813) (xy 11.169144 -375.693166)
			(xy 11.200565 -375.736321) (xy 11.225664 -375.783435) (xy 11.24395 -375.833587) (xy 11.255067 -375.885798)
			(xy 11.258797 -375.93905) (xy 11.255067 -375.992302) (xy 11.24395 -376.044513) (xy 11.225664 -376.094665)
			(xy 11.200565 -376.141779) (xy 11.169144 -376.184934) (xy 11.132013 -376.223287) (xy 11.11123 -376.24004)
			(xy 11.102443 -376.247577) (xy 11.092276 -376.268355) (xy 11.091672 -376.279918) (xy 11.091672 -376.360182)
			(xy 11.092228 -376.371752) (xy 11.10243 -376.392525) (xy 11.11123 -376.40006) (xy 11.132013 -376.416813)
			(xy 11.169144 -376.455166) (xy 11.200565 -376.498321) (xy 11.225664 -376.545435) (xy 11.24395 -376.595587)
			(xy 11.255067 -376.647798) (xy 11.258797 -376.70105) (xy 11.255067 -376.754302) (xy 11.24395 -376.806513)
			(xy 11.225664 -376.856665) (xy 11.200565 -376.903779) (xy 11.169144 -376.946934) (xy 11.132013 -376.985287)
			(xy 11.11123 -377.00204) (xy 11.102443 -377.009577) (xy 11.092276 -377.030355) (xy 11.091672 -377.041918)
			(xy 11.091672 -377.122182) (xy 11.092228 -377.133752) (xy 11.10243 -377.154525) (xy 11.11123 -377.16206)
			(xy 11.133701 -377.180266) (xy 11.173435 -377.222284) (xy 11.206375 -377.269816) (xy 11.231765 -377.321774)
			(xy 11.249025 -377.376968) (xy 11.257758 -377.434135) (xy 11.258296 -377.46305) (xy 11.25781 -377.490301)
			(xy 11.250054 -377.544249) (xy 11.234699 -377.596544) (xy 11.212057 -377.646121) (xy 11.182591 -377.691971)
			(xy 11.1469 -377.733162) (xy 11.105709 -377.768853) (xy 11.059859 -377.798319) (xy 11.010282 -377.820961)
			(xy 10.957987 -377.836316) (xy 10.904039 -377.844072) (xy 10.849537 -377.844072) (xy 10.795589 -377.836316)
			(xy 10.743294 -377.820961) (xy 10.693717 -377.798319) (xy 10.647867 -377.768853) (xy 10.606676 -377.733162)
			(xy 10.570985 -377.691971) (xy 10.541519 -377.646121) (xy 10.518877 -377.596544) (xy 10.503522 -377.544249)
			(xy 10.495766 -377.490301) (xy 10.49528 -377.46305) (xy 10.495804 -377.434133) (xy 10.504528 -377.376961)
			(xy 10.521783 -377.321761) (xy 10.547173 -377.269798) (xy 10.580117 -377.222265) (xy 10.61986 -377.180249)
			(xy 10.642346 -377.16206) (xy 10.651129 -377.154519) (xy 10.661299 -377.133744) (xy 10.661904 -377.122182)
			(xy 10.661904 -377.041918) (xy 10.661322 -377.030352) (xy 10.651135 -377.009581) (xy 10.642346 -377.00204)
			(xy 10.621563 -376.985287) (xy 10.584433 -376.946933) (xy 10.553012 -376.903779) (xy 10.527913 -376.856665)
			(xy 10.509627 -376.806513) (xy 10.49851 -376.754301) (xy 10.494781 -376.70105) (xy 8.972797 -376.70105)
			(xy 8.969067 -376.754302) (xy 8.95795 -376.806513) (xy 8.939664 -376.856665) (xy 8.914565 -376.903779)
			(xy 8.883144 -376.946934) (xy 8.846013 -376.985287) (xy 8.82523 -377.00204) (xy 8.816443 -377.009577)
			(xy 8.806276 -377.030355) (xy 8.805672 -377.041918) (xy 8.805672 -377.122182) (xy 8.806228 -377.133752)
			(xy 8.81643 -377.154525) (xy 8.82523 -377.16206) (xy 8.847701 -377.180266) (xy 8.887435 -377.222284)
			(xy 8.920375 -377.269816) (xy 8.945765 -377.321774) (xy 8.963025 -377.376968) (xy 8.971758 -377.434135)
			(xy 8.972296 -377.46305) (xy 8.97181 -377.490301) (xy 8.964054 -377.544249) (xy 8.948699 -377.596544)
			(xy 8.926057 -377.646121) (xy 8.896591 -377.691971) (xy 8.8609 -377.733162) (xy 8.819709 -377.768853)
			(xy 8.773859 -377.798319) (xy 8.724282 -377.820961) (xy 8.671987 -377.836316) (xy 8.618039 -377.844072)
			(xy 8.563537 -377.844072) (xy 8.509589 -377.836316) (xy 8.457294 -377.820961) (xy 8.407717 -377.798319)
			(xy 8.361867 -377.768853) (xy 8.320676 -377.733162) (xy 8.284985 -377.691971) (xy 8.255519 -377.646121)
			(xy 8.232877 -377.596544) (xy 8.217522 -377.544249) (xy 8.209766 -377.490301) (xy 8.20928 -377.46305)
			(xy 8.209804 -377.434133) (xy 8.218528 -377.376961) (xy 8.235783 -377.321761) (xy 8.261173 -377.269798)
			(xy 8.294117 -377.222265) (xy 8.33386 -377.180249) (xy 8.356346 -377.16206) (xy 8.365129 -377.154519)
			(xy 8.375299 -377.133744) (xy 8.375904 -377.122182) (xy 8.375904 -377.041918) (xy 8.375322 -377.030352)
			(xy 8.365135 -377.009581) (xy 8.356346 -377.00204) (xy 8.335563 -376.985287) (xy 8.298433 -376.946933)
			(xy 8.267012 -376.903779) (xy 8.241913 -376.856665) (xy 8.223627 -376.806513) (xy 8.21251 -376.754301)
			(xy 8.208781 -376.70105) (xy 4.643628 -376.70105) (xy 4.643628 -377.963938) (xy 14.292072 -377.963938)
			(xy 14.292535 -377.937592) (xy 14.299764 -377.885398) (xy 14.314103 -377.834694) (xy 14.335281 -377.786445)
			(xy 14.362894 -377.741567) (xy 14.396418 -377.700914) (xy 14.415516 -377.68276) (xy 14.42339 -377.675648)
			(xy 14.431772 -377.656852) (xy 14.43355 -377.562364) (xy 14.42593 -377.543314) (xy 14.41831 -377.535694)
			(xy 14.397291 -377.514057) (xy 14.361641 -377.465399) (xy 14.334096 -377.411735) (xy 14.315343 -377.354404)
			(xy 14.30585 -377.294836) (xy 14.30528 -377.264676) (xy 14.305729 -377.23727) (xy 14.313582 -377.183025)
			(xy 14.329122 -377.130463) (xy 14.352029 -377.080668) (xy 14.38183 -377.034666) (xy 14.399514 -377.013724)
			(xy 14.40561 -377.006612) (xy 14.41196 -376.989594) (xy 14.41196 -376.903996) (xy 14.40561 -376.886978)
			(xy 14.399514 -376.879866) (xy 14.381832 -376.858924) (xy 14.352039 -376.812919) (xy 14.329139 -376.763124)
			(xy 14.313605 -376.710562) (xy 14.305756 -376.656318) (xy 14.30528 -376.628914) (xy 14.305825 -376.598573)
			(xy 14.315443 -376.538657) (xy 14.334423 -376.481018) (xy 14.362287 -376.427111) (xy 14.398332 -376.378293)
			(xy 14.41958 -376.356626) (xy 14.4272 -376.34926) (xy 14.43482 -376.330718) (xy 14.43482 -376.237246)
			(xy 14.4272 -376.218704) (xy 14.41958 -376.211338) (xy 14.39832 -376.189683) (xy 14.362282 -376.140862)
			(xy 14.334429 -376.08695) (xy 14.315462 -376.029309) (xy 14.305862 -375.969391) (xy 14.30528 -375.93905)
			(xy 14.305804 -375.910133) (xy 14.314528 -375.852961) (xy 14.331783 -375.797761) (xy 14.357173 -375.745798)
			(xy 14.390117 -375.698265) (xy 14.42986 -375.656249) (xy 14.452346 -375.63806) (xy 14.461129 -375.630519)
			(xy 14.471299 -375.609744) (xy 14.471904 -375.598182) (xy 14.471904 -375.517918) (xy 14.471322 -375.506352)
			(xy 14.461135 -375.485581) (xy 14.452346 -375.47804) (xy 14.42987 -375.45984) (xy 14.390137 -375.417821)
			(xy 14.357199 -375.370287) (xy 14.33181 -375.318328) (xy 14.314551 -375.263133) (xy 14.305818 -375.205965)
			(xy 14.30528 -375.17705) (xy 14.305766 -375.149799) (xy 14.313522 -375.095851) (xy 14.328877 -375.043556)
			(xy 14.351519 -374.993979) (xy 14.380985 -374.948129) (xy 14.416676 -374.906938) (xy 14.457867 -374.871247)
			(xy 14.503717 -374.841781) (xy 14.553294 -374.819139) (xy 14.605589 -374.803784) (xy 14.659537 -374.796028)
			(xy 14.714039 -374.796028) (xy 14.767987 -374.803784) (xy 14.820282 -374.819139) (xy 14.869859 -374.841781)
			(xy 14.915709 -374.871247) (xy 14.9569 -374.906938) (xy 14.992591 -374.948129) (xy 15.022057 -374.993979)
			(xy 15.044699 -375.043556) (xy 15.060054 -375.095851) (xy 15.06781 -375.149799) (xy 15.068296 -375.17705)
			(xy 15.067743 -375.205966) (xy 15.059022 -375.263135) (xy 15.041771 -375.318334) (xy 15.016385 -375.370295)
			(xy 14.983448 -375.41783) (xy 14.943713 -375.459849) (xy 14.92123 -375.47804) (xy 14.912443 -375.485577)
			(xy 14.902276 -375.506355) (xy 14.901672 -375.517918) (xy 14.901672 -375.598182) (xy 14.902228 -375.609752)
			(xy 14.91243 -375.630525) (xy 14.92123 -375.63806) (xy 14.943701 -375.656266) (xy 14.983435 -375.698284)
			(xy 15.016375 -375.745816) (xy 15.041765 -375.797774) (xy 15.059025 -375.852968) (xy 15.067758 -375.910135)
			(xy 15.068296 -375.93905) (xy 15.067706 -375.969389) (xy 15.058096 -376.029302) (xy 15.039125 -376.086939)
			(xy 15.011272 -376.140847) (xy 14.975238 -376.189668) (xy 14.953996 -376.211338) (xy 14.946376 -376.218704)
			(xy 14.938756 -376.237246) (xy 14.938756 -376.330718) (xy 14.946376 -376.34926) (xy 14.953996 -376.356626)
			(xy 14.975234 -376.378301) (xy 15.011276 -376.427116) (xy 15.039134 -376.481023) (xy 15.058105 -376.53866)
			(xy 15.067711 -376.598574) (xy 15.068296 -376.628914) (xy 15.067847 -376.65632) (xy 15.059995 -376.710566)
			(xy 15.044456 -376.763128) (xy 15.021548 -376.812923) (xy 14.991746 -376.858924) (xy 14.974062 -376.879866)
			(xy 14.967966 -376.886978) (xy 14.961616 -376.903996) (xy 14.961616 -376.989594) (xy 14.967966 -377.006612)
			(xy 14.974062 -377.013724) (xy 14.991735 -377.034673) (xy 15.021531 -377.080675) (xy 15.044432 -377.130469)
			(xy 15.059969 -377.183029) (xy 15.06782 -377.237272) (xy 15.068296 -377.264676) (xy 15.067853 -377.291023)
			(xy 15.060621 -377.343219) (xy 15.046279 -377.393923) (xy 15.025097 -377.442172) (xy 14.99748 -377.48705)
			(xy 14.963953 -377.527701) (xy 14.944852 -377.545854) (xy 14.936978 -377.552966) (xy 14.928596 -377.571762)
			(xy 14.926818 -377.66625) (xy 14.934438 -377.6853) (xy 14.942058 -377.69292) (xy 14.963096 -377.71454)
			(xy 14.998741 -377.763204) (xy 15.026281 -377.816872) (xy 15.045029 -377.874206) (xy 15.054519 -377.933777)
			(xy 15.054911 -377.95454) (xy 16.559276 -377.95454) (xy 16.559865 -377.924417) (xy 16.56934 -377.864921)
			(xy 16.588047 -377.807653) (xy 16.615519 -377.754036) (xy 16.651074 -377.705401) (xy 16.672052 -377.683776)
			(xy 16.679418 -377.67641) (xy 16.687038 -377.658376) (xy 16.687546 -377.56592) (xy 16.68018 -377.547632)
			(xy 16.672814 -377.540266) (xy 16.652346 -377.5187) (xy 16.617644 -377.470424) (xy 16.590855 -377.417347)
			(xy 16.572626 -377.360757) (xy 16.563401 -377.302023) (xy 16.562832 -377.272296) (xy 16.563335 -377.243378)
			(xy 16.572066 -377.186206) (xy 16.589326 -377.131006) (xy 16.61472 -377.079044) (xy 16.647667 -377.031511)
			(xy 16.687411 -376.989495) (xy 16.709898 -376.971306) (xy 16.718652 -376.963737) (xy 16.72884 -376.942984)
			(xy 16.729456 -376.931428) (xy 16.729456 -376.851164) (xy 16.728864 -376.839599) (xy 16.718686 -376.818826)
			(xy 16.709898 -376.811286) (xy 16.687407 -376.793103) (xy 16.647673 -376.751082) (xy 16.614735 -376.703545)
			(xy 16.589347 -376.651582) (xy 16.572093 -376.596383) (xy 16.563366 -376.539212) (xy 16.562832 -376.510296)
			(xy 16.563308 -376.483052) (xy 16.571066 -376.429118) (xy 16.586423 -376.376839) (xy 16.609066 -376.327278)
			(xy 16.638534 -376.281445) (xy 16.674227 -376.240275) (xy 16.715418 -376.204605) (xy 16.738092 -376.189494)
			(xy 16.74876 -376.182382) (xy 16.760952 -376.160538) (xy 16.763746 -376.051064) (xy 16.752316 -376.028458)
			(xy 16.742156 -376.021092) (xy 16.721253 -376.00571) (xy 16.68343 -375.970175) (xy 16.650778 -375.929836)
			(xy 16.623903 -375.885439) (xy 16.6033 -375.837806) (xy 16.589352 -375.787818) (xy 16.582316 -375.736399)
			(xy 16.581882 -375.71045) (xy 16.582315 -375.684786) (xy 16.589185 -375.633921) (xy 16.602819 -375.584437)
			(xy 16.622972 -375.537232) (xy 16.649278 -375.493158) (xy 16.681262 -375.453015) (xy 16.718345 -375.417527)
			(xy 16.738854 -375.402094) (xy 16.747998 -375.39549) (xy 16.758666 -375.376186) (xy 16.76654 -375.276618)
			(xy 16.75892 -375.256044) (xy 16.750792 -375.247916) (xy 16.729976 -375.226332) (xy 16.694724 -375.177826)
			(xy 16.667497 -375.124401) (xy 16.648966 -375.067374) (xy 16.639587 -375.008149) (xy 16.639032 -374.978168)
			(xy 16.639518 -374.950917) (xy 16.647274 -374.896969) (xy 16.662629 -374.844674) (xy 16.685271 -374.795097)
			(xy 16.714737 -374.749247) (xy 16.750428 -374.708056) (xy 16.791619 -374.672365) (xy 16.837469 -374.642899)
			(xy 16.887046 -374.620257) (xy 16.939341 -374.604902) (xy 16.993289 -374.597146) (xy 17.047791 -374.597146)
			(xy 17.101739 -374.604902) (xy 17.154034 -374.620257) (xy 17.203611 -374.642899) (xy 17.249461 -374.672365)
			(xy 17.290652 -374.708056) (xy 17.326343 -374.749247) (xy 17.355809 -374.795097) (xy 17.378451 -374.844674)
			(xy 17.393806 -374.896969) (xy 17.401562 -374.950917) (xy 17.402048 -374.978168) (xy 17.401616 -375.003832)
			(xy 17.394745 -375.054697) (xy 17.38111 -375.10418) (xy 17.360956 -375.151385) (xy 17.33465 -375.195458)
			(xy 17.302666 -375.235602) (xy 17.265584 -375.27109) (xy 17.245076 -375.286524) (xy 17.235932 -375.293128)
			(xy 17.225264 -375.312432) (xy 17.21739 -375.412) (xy 17.22501 -375.432574) (xy 17.233138 -375.440702)
			(xy 17.25395 -375.46229) (xy 17.289205 -375.510794) (xy 17.316434 -375.564217) (xy 17.334966 -375.621244)
			(xy 17.344343 -375.680469) (xy 17.344898 -375.71045) (xy 17.344444 -375.737695) (xy 17.33668 -375.791629)
			(xy 17.321318 -375.843908) (xy 17.298671 -375.893469) (xy 17.2692 -375.939301) (xy 17.233505 -375.980471)
			(xy 17.192313 -376.016141) (xy 17.169638 -376.031252) (xy 17.15897 -376.038364) (xy 17.146778 -376.060208)
			(xy 17.143984 -376.169682) (xy 17.155414 -376.192288) (xy 17.165574 -376.199654) (xy 17.186458 -376.21506)
			(xy 17.224281 -376.250592) (xy 17.256933 -376.290928) (xy 17.28381 -376.33532) (xy 17.304416 -376.382949)
			(xy 17.318368 -376.432933) (xy 17.32541 -376.484348) (xy 17.325848 -376.510296) (xy 17.325346 -376.539214)
			(xy 17.316617 -376.596387) (xy 17.299357 -376.651587) (xy 17.273962 -376.703549) (xy 17.241015 -376.751082)
			(xy 17.20127 -376.793097) (xy 17.178782 -376.811286) (xy 17.170028 -376.818855) (xy 17.159841 -376.839608)
			(xy 17.159224 -376.851164) (xy 17.159224 -376.931428) (xy 17.159827 -376.942992) (xy 17.169998 -376.963764)
			(xy 17.178782 -376.971306) (xy 17.201265 -376.989498) (xy 17.241001 -377.031517) (xy 17.27394 -377.079052)
			(xy 17.299329 -377.131013) (xy 17.316585 -377.18621) (xy 17.325314 -377.24338) (xy 17.325848 -377.272296)
			(xy 17.325275 -377.302419) (xy 17.315795 -377.361916) (xy 17.297085 -377.419184) (xy 17.269609 -377.472801)
			(xy 17.234051 -377.521435) (xy 17.213072 -377.54306) (xy 17.205706 -377.550426) (xy 17.198086 -377.56846)
			(xy 17.197578 -377.660916) (xy 17.204944 -377.679204) (xy 17.21231 -377.68657) (xy 17.232799 -377.708117)
			(xy 17.267497 -377.756399) (xy 17.294282 -377.80948) (xy 17.312506 -377.866075) (xy 17.321726 -377.924812)
			(xy 17.322292 -377.95454) (xy 17.321806 -377.981791) (xy 17.31405 -378.035739) (xy 17.298695 -378.088034)
			(xy 17.276053 -378.137611) (xy 17.246587 -378.183461) (xy 17.210896 -378.224652) (xy 17.169705 -378.260343)
			(xy 17.123855 -378.289809) (xy 17.074278 -378.312451) (xy 17.021983 -378.327806) (xy 16.968035 -378.335562)
			(xy 16.913533 -378.335562) (xy 16.859585 -378.327806) (xy 16.80729 -378.312451) (xy 16.757713 -378.289809)
			(xy 16.711863 -378.260343) (xy 16.670672 -378.224652) (xy 16.634981 -378.183461) (xy 16.605515 -378.137611)
			(xy 16.582873 -378.088034) (xy 16.567518 -378.035739) (xy 16.559762 -377.981791) (xy 16.559276 -377.95454)
			(xy 15.054911 -377.95454) (xy 15.055088 -377.963938) (xy 15.054596 -377.991648) (xy 15.046568 -378.046482)
			(xy 15.030685 -378.099577) (xy 15.007284 -378.149813) (xy 14.976857 -378.196133) (xy 14.958822 -378.217176)
			(xy 14.952726 -378.224288) (xy 14.946122 -378.24156) (xy 14.946376 -378.328174) (xy 14.95298 -378.345446)
			(xy 14.95933 -378.352558) (xy 14.977614 -378.373652) (xy 15.00844 -378.420193) (xy 15.032153 -378.470729)
			(xy 15.048248 -378.524181) (xy 15.056381 -378.579408) (xy 15.056866 -378.60732) (xy 15.05638 -378.634571)
			(xy 15.048624 -378.688519) (xy 15.033269 -378.740814) (xy 15.010627 -378.790391) (xy 14.981161 -378.836241)
			(xy 14.94547 -378.877432) (xy 14.904279 -378.913123) (xy 14.858429 -378.942589) (xy 14.808852 -378.965231)
			(xy 14.756557 -378.980586) (xy 14.702609 -378.988342) (xy 14.648107 -378.988342) (xy 14.594159 -378.980586)
			(xy 14.541864 -378.965231) (xy 14.492287 -378.942589) (xy 14.446437 -378.913123) (xy 14.405246 -378.877432)
			(xy 14.369555 -378.836241) (xy 14.340089 -378.790391) (xy 14.317447 -378.740814) (xy 14.302092 -378.688519)
			(xy 14.294336 -378.634571) (xy 14.29385 -378.60732) (xy 14.294333 -378.57961) (xy 14.302366 -378.524776)
			(xy 14.318251 -378.471681) (xy 14.341654 -378.421445) (xy 14.372081 -378.375126) (xy 14.390116 -378.354082)
			(xy 14.396212 -378.34697) (xy 14.402816 -378.329698) (xy 14.402562 -378.243084) (xy 14.395958 -378.225812)
			(xy 14.389608 -378.2187) (xy 14.371357 -378.197578) (xy 14.340525 -378.151046) (xy 14.316805 -378.100517)
			(xy 14.300702 -378.047071) (xy 14.292561 -377.991848) (xy 14.292072 -377.963938) (xy 4.643628 -377.963938)
			(xy 4.643628 -381.41402) (xy 6.528562 -381.41402) (xy 6.528988 -381.38764) (xy 6.536251 -381.335383)
			(xy 6.55064 -381.284623) (xy 6.571882 -381.236329) (xy 6.599573 -381.19142) (xy 6.633183 -381.150752)
			(xy 6.672074 -381.115099) (xy 6.715503 -381.085142) (xy 6.738874 -381.072898) (xy 6.751214 -381.066166)
			(xy 6.77194 -381.047195) (xy 6.786699 -381.023287) (xy 6.794371 -380.996257) (xy 6.794374 -380.96816)
			(xy 6.786706 -380.94113) (xy 6.771951 -380.917219) (xy 6.751229 -380.898244) (xy 6.738874 -380.891542)
			(xy 6.715506 -380.879296) (xy 6.672083 -380.849334) (xy 6.633198 -380.813679) (xy 6.599593 -380.77301)
			(xy 6.571906 -380.728102) (xy 6.550665 -380.679809) (xy 6.536274 -380.629053) (xy 6.529009 -380.576799)
			(xy 6.528562 -380.55042) (xy 6.529048 -380.523169) (xy 6.536804 -380.469221) (xy 6.552159 -380.416926)
			(xy 6.574801 -380.367349) (xy 6.604267 -380.321499) (xy 6.639958 -380.280308) (xy 6.681149 -380.244617)
			(xy 6.726999 -380.215151) (xy 6.776576 -380.192509) (xy 6.828871 -380.177154) (xy 6.882819 -380.169398)
			(xy 6.937321 -380.169398) (xy 6.991269 -380.177154) (xy 7.043564 -380.192509) (xy 7.093141 -380.215151)
			(xy 7.138991 -380.244617) (xy 7.180182 -380.280308) (xy 7.215873 -380.321499) (xy 7.245339 -380.367349)
			(xy 7.267981 -380.416926) (xy 7.283336 -380.469221) (xy 7.291092 -380.523169) (xy 7.291578 -380.55042)
			(xy 7.291135 -380.5768) (xy 7.283879 -380.629058) (xy 7.269495 -380.679818) (xy 7.248257 -380.728114)
			(xy 7.220568 -380.773024) (xy 7.186959 -380.813693) (xy 7.148068 -380.849344) (xy 7.138344 -380.856051)
			(xy 9.436082 -380.856051) (xy 9.436082 -380.801549) (xy 9.443838 -380.747602) (xy 9.459193 -380.695308)
			(xy 9.481834 -380.645731) (xy 9.5113 -380.599881) (xy 9.546991 -380.558691) (xy 9.588181 -380.523)
			(xy 9.634031 -380.493534) (xy 9.683608 -380.470893) (xy 9.735902 -380.455538) (xy 9.789849 -380.447782)
			(xy 9.8171 -380.447296) (xy 9.842716 -380.447723) (xy 9.893486 -380.454584) (xy 9.942881 -380.46818)
			(xy 9.990009 -380.488269) (xy 10.034024 -380.514487) (xy 10.054336 -380.5301) (xy 10.062464 -380.53645)
			(xy 10.082276 -380.542038) (xy 10.17524 -380.529846) (xy 10.19302 -380.519432) (xy 10.199116 -380.51105)
			(xy 10.208935 -380.498203) (xy 10.230428 -380.474041) (xy 10.242042 -380.46279) (xy 10.249916 -380.45517)
			(xy 10.25779 -380.435866) (xy 10.256012 -380.3396) (xy 10.247376 -380.32055) (xy 10.239248 -380.313184)
			(xy 10.219468 -380.294997) (xy 10.184674 -380.254051) (xy 10.155972 -380.208626) (xy 10.133932 -380.159621)
			(xy 10.118989 -380.108008) (xy 10.11144 -380.054808) (xy 10.110978 -380.027942) (xy 10.111464 -380.000691)
			(xy 10.11922 -379.946743) (xy 10.134575 -379.894448) (xy 10.157217 -379.844871) (xy 10.186683 -379.799021)
			(xy 10.222374 -379.75783) (xy 10.263565 -379.722139) (xy 10.309415 -379.692673) (xy 10.358992 -379.670031)
			(xy 10.411287 -379.654676) (xy 10.465235 -379.64692) (xy 10.519737 -379.64692) (xy 10.573685 -379.654676)
			(xy 10.62598 -379.670031) (xy 10.675557 -379.692673) (xy 10.721407 -379.722139) (xy 10.762598 -379.75783)
			(xy 10.798289 -379.799021) (xy 10.827755 -379.844871) (xy 10.850397 -379.894448) (xy 10.865752 -379.946743)
			(xy 10.873508 -380.000691) (xy 10.873994 -380.027942) (xy 10.873606 -380.053088) (xy 12.10945 -380.053088)
			(xy 12.109966 -380.025484) (xy 12.117913 -379.97085) (xy 12.133654 -379.917933) (xy 12.15686 -379.867839)
			(xy 12.187045 -379.821613) (xy 12.22358 -379.780222) (xy 12.244324 -379.762004) (xy 12.252452 -379.755146)
			(xy 12.26185 -379.735842) (xy 12.264898 -379.63856) (xy 12.25677 -379.619002) (xy 12.248896 -379.611382)
			(xy 12.230736 -379.593319) (xy 12.198897 -379.553199) (xy 12.17271 -379.50918) (xy 12.152646 -379.462055)
			(xy 12.139067 -379.412668) (xy 12.132215 -379.36191) (xy 12.131802 -379.3363) (xy 12.132268 -379.30893)
			(xy 12.140085 -379.254751) (xy 12.155575 -379.202247) (xy 12.178416 -379.152501) (xy 12.208141 -379.106534)
			(xy 12.225782 -379.085602) (xy 12.231878 -379.07849) (xy 12.238228 -379.061472) (xy 12.238228 -378.976128)
			(xy 12.231878 -378.95911) (xy 12.225782 -378.951998) (xy 12.208126 -378.93108) (xy 12.178417 -378.885103)
			(xy 12.155585 -378.835352) (xy 12.140098 -378.782848) (xy 12.132274 -378.72867) (xy 12.131802 -378.7013)
			(xy 12.132288 -378.674049) (xy 12.140044 -378.620101) (xy 12.155399 -378.567806) (xy 12.178041 -378.518229)
			(xy 12.207507 -378.472379) (xy 12.243198 -378.431188) (xy 12.284389 -378.395497) (xy 12.330239 -378.366031)
			(xy 12.379816 -378.343389) (xy 12.432111 -378.328034) (xy 12.486059 -378.320278) (xy 12.540561 -378.320278)
			(xy 12.594509 -378.328034) (xy 12.646804 -378.343389) (xy 12.696381 -378.366031) (xy 12.742231 -378.395497)
			(xy 12.783422 -378.431188) (xy 12.819113 -378.472379) (xy 12.848579 -378.518229) (xy 12.871221 -378.567806)
			(xy 12.886576 -378.620101) (xy 12.894332 -378.674049) (xy 12.894818 -378.7013) (xy 12.894372 -378.728671)
			(xy 12.886552 -378.782852) (xy 12.87106 -378.835356) (xy 12.848213 -378.885103) (xy 12.818482 -378.931068)
			(xy 12.800838 -378.951998) (xy 12.794742 -378.95911) (xy 12.788392 -378.976128) (xy 12.788392 -379.061472)
			(xy 12.794742 -379.07849) (xy 12.800838 -379.085602) (xy 12.818498 -379.106517) (xy 12.848205 -379.152495)
			(xy 12.871037 -379.202247) (xy 12.886523 -379.254751) (xy 12.894347 -379.30893) (xy 12.894818 -379.3363)
			(xy 12.894374 -379.363907) (xy 12.886414 -379.418544) (xy 12.870659 -379.471463) (xy 12.84744 -379.521558)
			(xy 12.817241 -379.567781) (xy 12.780694 -379.609168) (xy 12.759944 -379.627384) (xy 12.751816 -379.634242)
			(xy 12.742418 -379.653546) (xy 12.73937 -379.750828) (xy 12.747498 -379.770386) (xy 12.755372 -379.778006)
			(xy 12.773568 -379.796033) (xy 12.805406 -379.836161) (xy 12.831589 -379.880187) (xy 12.851646 -379.927319)
			(xy 12.865217 -379.976712) (xy 12.872058 -380.027476) (xy 12.872466 -380.053088) (xy 12.872004 -380.080663)
			(xy 12.864052 -380.135236) (xy 12.848327 -380.188097) (xy 12.825157 -380.238143) (xy 12.795023 -380.284332)
			(xy 12.758554 -380.325703) (xy 12.737846 -380.343918) (xy 12.72921 -380.351284) (xy 12.719812 -380.37135)
			(xy 12.72032 -380.471934) (xy 12.729718 -380.492) (xy 12.738354 -380.499366) (xy 12.759369 -380.517586)
			(xy 12.796408 -380.559077) (xy 12.827037 -380.605502) (xy 12.850607 -380.655879) (xy 12.866619 -380.709142)
			(xy 12.874734 -380.764165) (xy 12.87526 -380.791974) (xy 12.874774 -380.819225) (xy 12.867018 -380.873173)
			(xy 12.851663 -380.925468) (xy 12.829021 -380.975045) (xy 12.799555 -381.020895) (xy 12.763864 -381.062086)
			(xy 12.722673 -381.097777) (xy 12.676823 -381.127243) (xy 12.627246 -381.149885) (xy 12.574951 -381.16524)
			(xy 12.521003 -381.172996) (xy 12.466501 -381.172996) (xy 12.412553 -381.16524) (xy 12.360258 -381.149885)
			(xy 12.310681 -381.127243) (xy 12.264831 -381.097777) (xy 12.22364 -381.062086) (xy 12.187949 -381.020895)
			(xy 12.158483 -380.975045) (xy 12.135841 -380.925468) (xy 12.120486 -380.873173) (xy 12.11273 -380.819225)
			(xy 12.112244 -380.791974) (xy 12.112745 -380.764401) (xy 12.120688 -380.709829) (xy 12.136405 -380.656969)
			(xy 12.159569 -380.606922) (xy 12.189696 -380.560732) (xy 12.226159 -380.51936) (xy 12.246864 -380.501144)
			(xy 12.2555 -380.493778) (xy 12.264898 -380.473712) (xy 12.26439 -380.373128) (xy 12.254992 -380.353062)
			(xy 12.246356 -380.345696) (xy 12.225325 -380.327494) (xy 12.188286 -380.286) (xy 12.157659 -380.239571)
			(xy 12.134092 -380.18919) (xy 12.118084 -380.135924) (xy 12.109973 -380.080898) (xy 12.10945 -380.053088)
			(xy 10.873606 -380.053088) (xy 10.873597 -380.053653) (xy 10.866669 -380.104608) (xy 10.852958 -380.154169)
			(xy 10.832712 -380.20144) (xy 10.806299 -380.245561) (xy 10.774197 -380.285734) (xy 10.755884 -380.303786)
			(xy 10.74801 -380.311406) (xy 10.740136 -380.33071) (xy 10.741914 -380.426976) (xy 10.75055 -380.446026)
			(xy 10.758678 -380.453392) (xy 10.7785 -380.471535) (xy 10.81329 -380.512491) (xy 10.841985 -380.557926)
			(xy 10.864018 -380.606939) (xy 10.878952 -380.658559) (xy 10.886491 -380.711765) (xy 10.886948 -380.738634)
			(xy 10.886454 -380.765884) (xy 10.878694 -380.81983) (xy 10.863336 -380.872122) (xy 10.840694 -380.921696)
			(xy 10.811228 -380.967545) (xy 10.775538 -381.008734) (xy 10.73435 -381.044425) (xy 10.688502 -381.073891)
			(xy 10.638927 -381.096534) (xy 10.586635 -381.111893) (xy 10.53269 -381.119654) (xy 10.50544 -381.120142)
			(xy 10.479824 -381.119706) (xy 10.429054 -381.11285) (xy 10.379659 -381.099256) (xy 10.33253 -381.079169)
			(xy 10.288516 -381.052951) (xy 10.268204 -381.037338) (xy 10.260076 -381.030988) (xy 10.240264 -381.0254)
			(xy 10.1473 -381.037592) (xy 10.12952 -381.048006) (xy 10.123424 -381.056388) (xy 10.105294 -381.079848)
			(xy 10.062978 -381.121375) (xy 10.014752 -381.155861) (xy 9.961775 -381.182479) (xy 9.90532 -381.200587)
			(xy 9.846744 -381.209752) (xy 9.8171 -381.210312) (xy 9.789849 -381.209818) (xy 9.735902 -381.202062)
			(xy 9.683608 -381.186707) (xy 9.634031 -381.164066) (xy 9.588181 -381.1346) (xy 9.546991 -381.098909)
			(xy 9.5113 -381.057719) (xy 9.481834 -381.011869) (xy 9.459193 -380.962292) (xy 9.443838 -380.909998)
			(xy 9.436082 -380.856051) (xy 7.138344 -380.856051) (xy 7.104637 -380.8793) (xy 7.081266 -380.891542)
			(xy 7.068887 -380.898211) (xy 7.04815 -380.91719) (xy 7.033383 -380.94111) (xy 7.025709 -380.968153)
			(xy 7.025712 -380.996264) (xy 7.03339 -381.023306) (xy 7.048161 -381.047224) (xy 7.068902 -381.066199)
			(xy 7.081266 -381.072898) (xy 7.104634 -381.085144) (xy 7.148057 -381.115106) (xy 7.186942 -381.150761)
			(xy 7.220547 -381.19143) (xy 7.248234 -381.236338) (xy 7.269475 -381.284631) (xy 7.283866 -381.335387)
			(xy 7.291131 -381.387641) (xy 7.291427 -381.40513) (xy 15.882112 -381.40513) (xy 15.882593 -381.37776)
			(xy 15.890407 -381.323582) (xy 15.905892 -381.271079) (xy 15.928731 -381.221332) (xy 15.958452 -381.175364)
			(xy 15.976092 -381.154432) (xy 15.982188 -381.14732) (xy 15.988538 -381.130302) (xy 15.988538 -381.044958)
			(xy 15.982188 -381.02794) (xy 15.976092 -381.020828) (xy 15.958482 -380.999871) (xy 15.928759 -380.953906)
			(xy 15.905914 -380.904164) (xy 15.890417 -380.851666) (xy 15.882586 -380.797491) (xy 15.882583 -380.742754)
			(xy 15.890407 -380.688578) (xy 15.905898 -380.636078) (xy 15.928737 -380.586333) (xy 15.958455 -380.540365)
			(xy 15.976092 -380.519432) (xy 15.982188 -380.51232) (xy 15.988538 -380.495302) (xy 15.988538 -380.409958)
			(xy 15.982188 -380.39294) (xy 15.976092 -380.385828) (xy 15.958482 -380.364871) (xy 15.928759 -380.318906)
			(xy 15.905914 -380.269164) (xy 15.890417 -380.216666) (xy 15.882586 -380.162491) (xy 15.882583 -380.107754)
			(xy 15.890407 -380.053578) (xy 15.905898 -380.001078) (xy 15.928737 -379.951333) (xy 15.958455 -379.905365)
			(xy 15.976092 -379.884432) (xy 15.982188 -379.87732) (xy 15.988538 -379.860302) (xy 15.988538 -379.774958)
			(xy 15.982188 -379.75794) (xy 15.976092 -379.750828) (xy 15.958482 -379.729871) (xy 15.928759 -379.683906)
			(xy 15.905914 -379.634164) (xy 15.890417 -379.581666) (xy 15.882586 -379.527491) (xy 15.882583 -379.472754)
			(xy 15.890407 -379.418578) (xy 15.905898 -379.366078) (xy 15.928737 -379.316333) (xy 15.958455 -379.270365)
			(xy 15.976092 -379.249432) (xy 15.982188 -379.24232) (xy 15.988538 -379.225302) (xy 15.988538 -379.139958)
			(xy 15.982188 -379.12294) (xy 15.976092 -379.115828) (xy 15.958451 -379.094897) (xy 15.92874 -379.048924)
			(xy 15.905904 -378.999176) (xy 15.890414 -378.946675) (xy 15.882586 -378.892499) (xy 15.882112 -378.86513)
			(xy 15.882598 -378.837879) (xy 15.890354 -378.783931) (xy 15.905709 -378.731636) (xy 15.928351 -378.682059)
			(xy 15.957817 -378.636209) (xy 15.993508 -378.595018) (xy 16.034699 -378.559327) (xy 16.080549 -378.529861)
			(xy 16.130126 -378.507219) (xy 16.182421 -378.491864) (xy 16.236369 -378.484108) (xy 16.290871 -378.484108)
			(xy 16.344819 -378.491864) (xy 16.397114 -378.507219) (xy 16.446691 -378.529861) (xy 16.492541 -378.559327)
			(xy 16.533732 -378.595018) (xy 16.569423 -378.636209) (xy 16.598889 -378.682059) (xy 16.621531 -378.731636)
			(xy 16.636886 -378.783931) (xy 16.644642 -378.837879) (xy 16.645128 -378.86513) (xy 16.644697 -378.892502)
			(xy 16.636873 -378.946683) (xy 16.621377 -378.999187) (xy 16.598527 -379.048934) (xy 16.568794 -379.094898)
			(xy 16.551148 -379.115828) (xy 16.545052 -379.12294) (xy 16.538702 -379.139958) (xy 16.538702 -379.225302)
			(xy 16.545052 -379.24232) (xy 16.551148 -379.249432) (xy 16.568819 -379.27034) (xy 16.598545 -379.316312)
			(xy 16.62139 -379.366062) (xy 16.636885 -379.418568) (xy 16.644711 -379.47275) (xy 16.644708 -379.527495)
			(xy 16.636875 -379.581676) (xy 16.621374 -379.63418) (xy 16.598523 -379.683928) (xy 16.568792 -379.729896)
			(xy 16.551148 -379.750828) (xy 16.545052 -379.75794) (xy 16.538702 -379.774958) (xy 16.538702 -379.860302)
			(xy 16.545052 -379.87732) (xy 16.551148 -379.884432) (xy 16.568819 -379.90534) (xy 16.598545 -379.951312)
			(xy 16.62139 -380.001062) (xy 16.636885 -380.053568) (xy 16.644711 -380.10775) (xy 16.644708 -380.162495)
			(xy 16.636875 -380.216676) (xy 16.621374 -380.26918) (xy 16.598523 -380.318928) (xy 16.568792 -380.364896)
			(xy 16.551148 -380.385828) (xy 16.545052 -380.39294) (xy 16.538702 -380.409958) (xy 16.538702 -380.495302)
			(xy 16.545052 -380.51232) (xy 16.551148 -380.519432) (xy 16.568819 -380.54034) (xy 16.598545 -380.586312)
			(xy 16.62139 -380.636062) (xy 16.636885 -380.688568) (xy 16.644711 -380.74275) (xy 16.644708 -380.797495)
			(xy 16.644405 -380.799594) (xy 18.005552 -380.799594) (xy 18.005939 -380.774164) (xy 18.012698 -380.723755)
			(xy 18.026095 -380.674691) (xy 18.045893 -380.627843) (xy 18.071741 -380.584041) (xy 18.103179 -380.544061)
			(xy 18.121122 -380.526036) (xy 18.128488 -380.518924) (xy 18.136362 -380.500382) (xy 18.136616 -380.406656)
			(xy 18.128742 -380.388114) (xy 18.121376 -380.380748) (xy 18.10012 -380.35909) (xy 18.064082 -380.310269)
			(xy 18.036228 -380.256358) (xy 18.01726 -380.198718) (xy 18.007659 -380.138801) (xy 18.007076 -380.10846)
			(xy 18.007582 -380.079721) (xy 18.01621 -380.022893) (xy 18.033264 -379.968002) (xy 18.05836 -379.916291)
			(xy 18.090928 -379.868929) (xy 18.1102 -379.847602) (xy 18.116804 -379.84049) (xy 18.123916 -379.822964)
			(xy 18.123916 -379.733556) (xy 18.116804 -379.71603) (xy 18.1102 -379.708918) (xy 18.090929 -379.687591)
			(xy 18.058364 -379.640229) (xy 18.033273 -379.588517) (xy 18.016223 -379.533626) (xy 18.007601 -379.476799)
			(xy 18.007601 -379.419321) (xy 18.016223 -379.362494) (xy 18.033273 -379.307603) (xy 18.058364 -379.255891)
			(xy 18.090929 -379.208529) (xy 18.1102 -379.187202) (xy 18.116804 -379.18009) (xy 18.123916 -379.162564)
			(xy 18.123916 -379.073156) (xy 18.116804 -379.05563) (xy 18.1102 -379.048518) (xy 18.090921 -379.027198)
			(xy 18.058354 -378.979835) (xy 18.033262 -378.928122) (xy 18.016213 -378.873229) (xy 18.007595 -378.8164)
			(xy 18.007076 -378.78766) (xy 18.007541 -378.760408) (xy 18.015302 -378.706461) (xy 18.030661 -378.654167)
			(xy 18.053306 -378.60459) (xy 18.082775 -378.558741) (xy 18.118469 -378.517552) (xy 18.15966 -378.481861)
			(xy 18.205511 -378.452395) (xy 18.255089 -378.429753) (xy 18.307384 -378.414397) (xy 18.361332 -378.406639)
			(xy 18.388584 -378.406152) (xy 18.417229 -378.406637) (xy 18.473874 -378.415214) (xy 18.528601 -378.432164)
			(xy 18.580178 -378.457104) (xy 18.627447 -378.489474) (xy 18.669346 -378.528548) (xy 18.687542 -378.550678)
			(xy 18.6944 -378.559314) (xy 18.713704 -378.56922) (xy 18.811748 -378.574554) (xy 18.832068 -378.56668)
			(xy 18.839688 -378.558806) (xy 18.861356 -378.537509) (xy 18.910208 -378.501392) (xy 18.964166 -378.473475)
			(xy 19.021868 -378.454464) (xy 19.081854 -378.444839) (xy 19.11223 -378.444252) (xy 19.14149 -378.444813)
			(xy 19.199321 -378.453759) (xy 19.255112 -378.471422) (xy 19.307555 -378.497388) (xy 19.355424 -378.53105)
			(xy 19.376898 -378.550932) (xy 19.38401 -378.55779) (xy 19.402044 -378.565156) (xy 19.492468 -378.565156)
			(xy 19.510502 -378.55779) (xy 19.517614 -378.550932) (xy 19.539048 -378.531001) (xy 19.586919 -378.497327)
			(xy 19.639371 -378.471358) (xy 19.695174 -378.453703) (xy 19.753018 -378.444778) (xy 19.782282 -378.444252)
			(xy 19.811862 -378.444836) (xy 19.870315 -378.453966) (xy 19.926657 -378.472009) (xy 19.979539 -378.498533)
			(xy 20.027693 -378.532901) (xy 20.069964 -378.574291) (xy 20.088098 -378.597668) (xy 20.095686 -378.606789)
			(xy 20.116888 -378.617376) (xy 20.128738 -378.617988) (xy 20.210272 -378.617988) (xy 20.222117 -378.617357)
			(xy 20.243308 -378.60677) (xy 20.250912 -378.597668) (xy 20.260074 -378.585618) (xy 20.280037 -378.562857)
			(xy 20.29079 -378.552202) (xy 20.298664 -378.544582) (xy 20.306538 -378.525024) (xy 20.303744 -378.428504)
			(xy 20.294854 -378.409454) (xy 20.286726 -378.402342) (xy 20.266449 -378.384128) (xy 20.230747 -378.342943)
			(xy 20.201264 -378.297102) (xy 20.178597 -378.247534) (xy 20.163208 -378.195247) (xy 20.155409 -378.141304)
			(xy 20.1549 -378.114052) (xy 20.155347 -378.086223) (xy 20.163428 -378.031153) (xy 20.179427 -377.977844)
			(xy 20.203003 -377.927425) (xy 20.233657 -377.880968) (xy 20.270736 -377.839458) (xy 20.313455 -377.803779)
			(xy 20.360905 -377.774686) (xy 20.386294 -377.763278) (xy 20.395946 -377.759214) (xy 20.41017 -377.744482)
			(xy 20.443444 -377.656344) (xy 20.442428 -377.63577) (xy 20.43811 -377.626372) (xy 20.42649 -377.600731)
			(xy 20.410102 -377.546875) (xy 20.4018 -377.491197) (xy 20.40128 -377.46305) (xy 20.401804 -377.434133)
			(xy 20.410528 -377.376961) (xy 20.427783 -377.321761) (xy 20.453173 -377.269798) (xy 20.486117 -377.222265)
			(xy 20.52586 -377.180249) (xy 20.548346 -377.16206) (xy 20.557129 -377.154519) (xy 20.567299 -377.133744)
			(xy 20.567904 -377.122182) (xy 20.567904 -377.041918) (xy 20.567322 -377.030352) (xy 20.557135 -377.009581)
			(xy 20.548346 -377.00204) (xy 20.527563 -376.985287) (xy 20.490433 -376.946933) (xy 20.459012 -376.903779)
			(xy 20.433913 -376.856665) (xy 20.415627 -376.806513) (xy 20.40451 -376.754301) (xy 20.400781 -376.70105)
			(xy 20.40451 -376.647799) (xy 20.415627 -376.595587) (xy 20.433913 -376.545435) (xy 20.459012 -376.498321)
			(xy 20.490433 -376.455167) (xy 20.527563 -376.416813) (xy 20.548346 -376.40006) (xy 20.557129 -376.392519)
			(xy 20.567299 -376.371744) (xy 20.567904 -376.360182) (xy 20.567904 -376.279918) (xy 20.567322 -376.268352)
			(xy 20.557135 -376.247581) (xy 20.548346 -376.24004) (xy 20.527563 -376.223287) (xy 20.490433 -376.184933)
			(xy 20.459012 -376.141779) (xy 20.433913 -376.094665) (xy 20.415627 -376.044513) (xy 20.40451 -375.992301)
			(xy 20.400781 -375.93905) (xy 20.40451 -375.885799) (xy 20.415627 -375.833587) (xy 20.433913 -375.783435)
			(xy 20.459012 -375.736321) (xy 20.490433 -375.693167) (xy 20.527563 -375.654813) (xy 20.548346 -375.63806)
			(xy 20.557129 -375.630519) (xy 20.567299 -375.609744) (xy 20.567904 -375.598182) (xy 20.567904 -375.517918)
			(xy 20.567322 -375.506352) (xy 20.557135 -375.485581) (xy 20.548346 -375.47804) (xy 20.52587 -375.45984)
			(xy 20.486137 -375.417821) (xy 20.453199 -375.370287) (xy 20.42781 -375.318328) (xy 20.410551 -375.263133)
			(xy 20.401818 -375.205965) (xy 20.40128 -375.17705) (xy 20.401766 -375.149799) (xy 20.409522 -375.095851)
			(xy 20.424877 -375.043556) (xy 20.447519 -374.993979) (xy 20.476985 -374.948129) (xy 20.512676 -374.906938)
			(xy 20.553867 -374.871247) (xy 20.599717 -374.841781) (xy 20.649294 -374.819139) (xy 20.701589 -374.803784)
			(xy 20.755537 -374.796028) (xy 20.810039 -374.796028) (xy 20.863987 -374.803784) (xy 20.916282 -374.819139)
			(xy 20.965859 -374.841781) (xy 21.011709 -374.871247) (xy 21.0529 -374.906938) (xy 21.088591 -374.948129)
			(xy 21.118057 -374.993979) (xy 21.140699 -375.043556) (xy 21.156054 -375.095851) (xy 21.16381 -375.149799)
			(xy 21.164296 -375.17705) (xy 21.163743 -375.205966) (xy 21.155022 -375.263135) (xy 21.137771 -375.318334)
			(xy 21.112385 -375.370295) (xy 21.079448 -375.41783) (xy 21.039713 -375.459849) (xy 21.01723 -375.47804)
			(xy 21.008443 -375.485577) (xy 20.998276 -375.506355) (xy 20.997672 -375.517918) (xy 20.997672 -375.598182)
			(xy 20.998228 -375.609752) (xy 21.00843 -375.630525) (xy 21.01723 -375.63806) (xy 21.038013 -375.654813)
			(xy 21.075144 -375.693166) (xy 21.106565 -375.736321) (xy 21.131664 -375.783435) (xy 21.14995 -375.833587)
			(xy 21.161067 -375.885798) (xy 21.164797 -375.93905) (xy 21.161067 -375.992302) (xy 21.14995 -376.044513)
			(xy 21.131664 -376.094665) (xy 21.106565 -376.141779) (xy 21.075144 -376.184934) (xy 21.038013 -376.223287)
			(xy 21.01723 -376.24004) (xy 21.008443 -376.247577) (xy 20.998276 -376.268355) (xy 20.997672 -376.279918)
			(xy 20.997672 -376.360182) (xy 20.998228 -376.371752) (xy 21.00843 -376.392525) (xy 21.01723 -376.40006)
			(xy 21.038013 -376.416813) (xy 21.075144 -376.455166) (xy 21.106565 -376.498321) (xy 21.131664 -376.545435)
			(xy 21.14995 -376.595587) (xy 21.154341 -376.616209) (xy 22.153395 -376.616209) (xy 22.157124 -376.562959)
			(xy 22.168239 -376.510749) (xy 22.186523 -376.460598) (xy 22.211619 -376.413485) (xy 22.243037 -376.370331)
			(xy 22.280165 -376.331978) (xy 22.300946 -376.315224) (xy 22.3097 -376.307655) (xy 22.319886 -376.286901)
			(xy 22.320504 -376.275346) (xy 22.320504 -376.195082) (xy 22.319942 -376.183513) (xy 22.309741 -376.162742)
			(xy 22.300946 -376.155204) (xy 22.280177 -376.138434) (xy 22.243048 -376.100082) (xy 22.211628 -376.056929)
			(xy 22.18653 -376.009818) (xy 22.168243 -375.959668) (xy 22.157126 -375.907458) (xy 22.153395 -375.854209)
			(xy 22.157124 -375.800959) (xy 22.168239 -375.748749) (xy 22.186523 -375.698598) (xy 22.211619 -375.651485)
			(xy 22.243037 -375.608331) (xy 22.280165 -375.569978) (xy 22.300946 -375.553224) (xy 22.3097 -375.545655)
			(xy 22.319886 -375.524901) (xy 22.320504 -375.513346) (xy 22.320504 -375.433082) (xy 22.319942 -375.421513)
			(xy 22.309741 -375.400742) (xy 22.300946 -375.393204) (xy 22.278453 -375.375024) (xy 22.238721 -375.333001)
			(xy 22.205785 -375.285463) (xy 22.180398 -375.2335) (xy 22.163144 -375.178301) (xy 22.154415 -375.12113)
			(xy 22.15388 -375.092214) (xy 22.154366 -375.064963) (xy 22.162122 -375.011015) (xy 22.177477 -374.95872)
			(xy 22.200119 -374.909143) (xy 22.229585 -374.863293) (xy 22.265276 -374.822102) (xy 22.306467 -374.786411)
			(xy 22.352317 -374.756945) (xy 22.401894 -374.734303) (xy 22.454189 -374.718948) (xy 22.508137 -374.711192)
			(xy 22.562639 -374.711192) (xy 22.616587 -374.718948) (xy 22.668882 -374.734303) (xy 22.718459 -374.756945)
			(xy 22.764309 -374.786411) (xy 22.8055 -374.822102) (xy 22.841191 -374.863293) (xy 22.870657 -374.909143)
			(xy 22.893299 -374.95872) (xy 22.908654 -375.011015) (xy 22.91641 -375.064963) (xy 22.916896 -375.092214)
			(xy 22.916318 -375.121129) (xy 22.907601 -375.178297) (xy 22.890355 -375.233495) (xy 22.864975 -375.285457)
			(xy 22.832042 -375.332992) (xy 22.792311 -375.375012) (xy 22.76983 -375.393204) (xy 22.761059 -375.400757)
			(xy 22.750883 -375.421523) (xy 22.750272 -375.433082) (xy 22.750272 -375.513346) (xy 22.750848 -375.524914)
			(xy 22.761036 -375.545686) (xy 22.76983 -375.553224) (xy 22.790627 -375.569961) (xy 22.827759 -375.608315)
			(xy 22.859181 -375.651472) (xy 22.884281 -375.698587) (xy 22.902567 -375.748741) (xy 22.913683 -375.800955)
			(xy 22.917412 -375.854209) (xy 22.913681 -375.907462) (xy 22.902562 -375.959675) (xy 22.884274 -376.009829)
			(xy 22.859172 -376.056943) (xy 22.827748 -376.100098) (xy 22.790614 -376.138451) (xy 22.76983 -376.155204)
			(xy 22.761059 -376.162757) (xy 22.750883 -376.183523) (xy 22.750272 -376.195082) (xy 22.750272 -376.275346)
			(xy 22.750848 -376.286914) (xy 22.761036 -376.307686) (xy 22.76983 -376.315224) (xy 22.790627 -376.331961)
			(xy 22.827759 -376.370315) (xy 22.859181 -376.413472) (xy 22.884281 -376.460587) (xy 22.902567 -376.510741)
			(xy 22.913683 -376.562955) (xy 22.917412 -376.616209) (xy 22.913681 -376.669462) (xy 22.902562 -376.721675)
			(xy 22.884274 -376.771829) (xy 22.859172 -376.818943) (xy 22.827748 -376.862098) (xy 22.790614 -376.900451)
			(xy 22.76983 -376.917204) (xy 22.761059 -376.924757) (xy 22.750883 -376.945523) (xy 22.750272 -376.957082)
			(xy 22.750272 -377.037346) (xy 22.750848 -377.048914) (xy 22.761036 -377.069686) (xy 22.76983 -377.077224)
			(xy 22.792331 -377.095394) (xy 22.832064 -377.137419) (xy 22.865 -377.184958) (xy 22.890385 -377.236924)
			(xy 22.907638 -377.292125) (xy 22.916363 -377.349297) (xy 22.916896 -377.378214) (xy 22.916393 -377.405147)
			(xy 22.908811 -377.458476) (xy 22.8938 -377.510208) (xy 22.87166 -377.559313) (xy 22.84283 -377.604813)
			(xy 22.82571 -377.62561) (xy 22.818852 -377.633738) (xy 22.812756 -377.653804) (xy 22.823678 -377.7488)
			(xy 22.834346 -377.767088) (xy 22.842982 -377.773438) (xy 22.866608 -377.791547) (xy 22.908468 -377.833868)
			(xy 22.943245 -377.882178) (xy 22.970093 -377.935305) (xy 22.983421 -377.976638) (xy 25.762966 -377.976638)
			(xy 25.763465 -377.949665) (xy 25.771047 -377.896255) (xy 25.78608 -377.844446) (xy 25.808263 -377.795272)
			(xy 25.837154 -377.749715) (xy 25.872176 -377.708683) (xy 25.912631 -377.672996) (xy 25.95771 -377.643366)
			(xy 25.981914 -377.631452) (xy 25.992836 -377.626372) (xy 26.007314 -377.60783) (xy 26.029158 -377.50496)
			(xy 26.023062 -377.4821) (xy 26.015188 -377.472956) (xy 25.997606 -377.452022) (xy 25.967967 -377.406087)
			(xy 25.945189 -377.356391) (xy 25.929738 -377.303953) (xy 25.921932 -377.249846) (xy 25.921462 -377.222512)
			(xy 25.921965 -377.193594) (xy 25.930694 -377.136421) (xy 25.947954 -377.081221) (xy 25.973348 -377.029259)
			(xy 26.006295 -376.981726) (xy 26.04604 -376.939711) (xy 26.068528 -376.921522) (xy 26.07728 -376.913951)
			(xy 26.087468 -376.893199) (xy 26.088086 -376.881644) (xy 26.088086 -376.80138) (xy 26.087475 -376.789817)
			(xy 26.07731 -376.769045) (xy 26.068528 -376.761502) (xy 26.047758 -376.744734) (xy 26.010631 -376.706381)
			(xy 25.979212 -376.663227) (xy 25.954115 -376.616116) (xy 25.93583 -376.565966) (xy 25.924713 -376.513756)
			(xy 25.920983 -376.460507) (xy 25.924711 -376.407258) (xy 25.935826 -376.355049) (xy 25.954109 -376.304898)
			(xy 25.979204 -376.257785) (xy 26.010621 -376.21463) (xy 26.047747 -376.176276) (xy 26.068528 -376.159522)
			(xy 26.07728 -376.151951) (xy 26.087468 -376.131199) (xy 26.088086 -376.119644) (xy 26.088086 -376.03938)
			(xy 26.087475 -376.027817) (xy 26.07731 -376.007045) (xy 26.068528 -375.999502) (xy 26.046051 -375.981303)
			(xy 26.006314 -375.939286) (xy 25.973374 -375.891753) (xy 25.947984 -375.839793) (xy 25.930727 -375.784596)
			(xy 25.921997 -375.727428) (xy 25.921462 -375.698512) (xy 25.922035 -375.668964) (xy 25.931145 -375.610575)
			(xy 25.949149 -375.554289) (xy 25.975617 -375.501453) (xy 26.009916 -375.453329) (xy 26.030174 -375.431812)
			(xy 26.037286 -375.424446) (xy 26.044652 -375.406666) (xy 26.04516 -375.315988) (xy 26.038048 -375.297954)
			(xy 26.030936 -375.290588) (xy 26.011249 -375.269175) (xy 25.977978 -375.221464) (xy 25.952327 -375.169258)
			(xy 25.93489 -375.113767) (xy 25.926071 -375.056273) (xy 25.925526 -375.02719) (xy 25.926012 -374.999939)
			(xy 25.933768 -374.945991) (xy 25.949123 -374.893696) (xy 25.971765 -374.844119) (xy 26.001231 -374.798269)
			(xy 26.036922 -374.757078) (xy 26.078113 -374.721387) (xy 26.123963 -374.691921) (xy 26.17354 -374.669279)
			(xy 26.225835 -374.653924) (xy 26.279783 -374.646168) (xy 26.334285 -374.646168) (xy 26.388233 -374.653924)
			(xy 26.440528 -374.669279) (xy 26.490105 -374.691921) (xy 26.535955 -374.721387) (xy 26.577146 -374.757078)
			(xy 26.612837 -374.798269) (xy 26.642303 -374.844119) (xy 26.664945 -374.893696) (xy 26.6803 -374.945991)
			(xy 26.688056 -374.999939) (xy 26.688542 -375.02719) (xy 26.68797 -375.056738) (xy 26.678859 -375.115127)
			(xy 26.660855 -375.171413) (xy 26.634386 -375.224249) (xy 26.600088 -375.272373) (xy 26.57983 -375.29389)
			(xy 26.572718 -375.301256) (xy 26.565352 -375.319036) (xy 26.564844 -375.409714) (xy 26.571956 -375.427748)
			(xy 26.579068 -375.435114) (xy 26.598757 -375.456526) (xy 26.632027 -375.504237) (xy 26.657678 -375.556443)
			(xy 26.675114 -375.611935) (xy 26.683933 -375.669429) (xy 26.684478 -375.698512) (xy 26.683905 -375.727427)
			(xy 26.675188 -375.784596) (xy 26.657942 -375.839794) (xy 26.63256 -375.891756) (xy 26.599626 -375.939291)
			(xy 26.559893 -375.98131) (xy 26.537412 -375.999502) (xy 26.528655 -376.007069) (xy 26.518469 -376.027824)
			(xy 26.517854 -376.03938) (xy 26.517854 -376.119644) (xy 26.518438 -376.131211) (xy 26.528621 -376.151983)
			(xy 26.537412 -376.159522) (xy 26.55165 -376.170897) (xy 26.578109 -376.195963) (xy 26.590244 -376.20956)
			(xy 26.597356 -376.217688) (xy 26.61666 -376.226578) (xy 26.713434 -376.228356) (xy 26.733246 -376.220228)
			(xy 26.740612 -376.212354) (xy 26.758715 -376.193795) (xy 26.799041 -376.161212) (xy 26.84341 -376.134395)
			(xy 26.891005 -376.113838) (xy 26.940946 -376.099921) (xy 26.992312 -376.092899) (xy 27.018234 -376.092466)
			(xy 27.046973 -376.092978) (xy 27.103801 -376.101605) (xy 27.158691 -376.118658) (xy 27.210403 -376.143752)
			(xy 27.257765 -376.176319) (xy 27.279092 -376.19559) (xy 27.286204 -376.202194) (xy 27.30373 -376.209306)
			(xy 27.393138 -376.209306) (xy 27.410664 -376.202194) (xy 27.417776 -376.19559) (xy 27.439097 -376.176312)
			(xy 27.48646 -376.143745) (xy 27.538173 -376.118653) (xy 27.593065 -376.101604) (xy 27.649894 -376.092985)
			(xy 27.678634 -376.092466) (xy 27.705885 -376.092946) (xy 27.759831 -376.100707) (xy 27.812125 -376.116065)
			(xy 27.8617 -376.138708) (xy 27.907549 -376.168175) (xy 27.948738 -376.203867) (xy 27.984429 -376.245057)
			(xy 28.013896 -376.290907) (xy 28.036538 -376.340483) (xy 28.051895 -376.392776) (xy 28.059654 -376.446723)
			(xy 28.060142 -376.473974) (xy 28.059678 -376.501703) (xy 28.051658 -376.556577) (xy 28.035782 -376.609714)
			(xy 28.012386 -376.659995) (xy 27.98196 -376.706361) (xy 27.945146 -376.747838) (xy 27.924252 -376.766074)
			(xy 27.915362 -376.77344) (xy 27.905964 -376.79376) (xy 27.906726 -376.895106) (xy 27.916632 -376.915426)
			(xy 27.925522 -376.922538) (xy 27.94716 -376.940735) (xy 27.985293 -376.982476) (xy 28.016851 -377.029386)
			(xy 28.041144 -377.080438) (xy 28.057641 -377.134515) (xy 28.06598 -377.190433) (xy 28.066492 -377.218702)
			(xy 28.065908 -377.249398) (xy 28.056111 -377.310001) (xy 28.036738 -377.368255) (xy 28.023058 -377.39574)
			(xy 28.016708 -377.407424) (xy 28.017216 -377.433332) (xy 28.073604 -377.530614) (xy 28.095702 -377.543822)
			(xy 28.10891 -377.54433) (xy 28.135429 -377.545853) (xy 28.187695 -377.555325) (xy 28.238142 -377.571955)
			(xy 28.285796 -377.595421) (xy 28.329733 -377.625269) (xy 28.369107 -377.660923) (xy 28.403154 -377.701694)
			(xy 28.431218 -377.746793) (xy 28.452755 -377.795348) (xy 28.467349 -377.846421) (xy 28.474719 -377.899025)
			(xy 28.475178 -377.925584) (xy 28.47473 -377.952838) (xy 28.466974 -378.006791) (xy 28.451619 -378.059091)
			(xy 28.428976 -378.108673) (xy 28.399507 -378.154528) (xy 28.363811 -378.195721) (xy 28.322616 -378.231415)
			(xy 28.276761 -378.260883) (xy 28.227178 -378.283524) (xy 28.174877 -378.298877) (xy 28.120924 -378.306631)
			(xy 28.09367 -378.307092) (xy 28.065559 -378.306574) (xy 28.009945 -378.298337) (xy 27.956141 -378.28203)
			(xy 27.905311 -378.258006) (xy 27.858555 -378.226786) (xy 27.837384 -378.208286) (xy 27.830272 -378.201682)
			(xy 27.813 -378.195078) (xy 27.725624 -378.194824) (xy 27.708352 -378.201682) (xy 27.700986 -378.208032)
			(xy 27.679871 -378.226454) (xy 27.633232 -378.257517) (xy 27.582549 -378.281417) (xy 27.528913 -378.29764)
			(xy 27.47348 -378.305838) (xy 27.445462 -378.30633) (xy 27.416723 -378.305821) (xy 27.359895 -378.297194)
			(xy 27.305004 -378.28014) (xy 27.253293 -378.255045) (xy 27.205931 -378.222478) (xy 27.184604 -378.203206)
			(xy 27.177492 -378.196602) (xy 27.159966 -378.18949) (xy 27.070558 -378.18949) (xy 27.053032 -378.196602)
			(xy 27.04592 -378.203206) (xy 27.0246 -378.222485) (xy 26.977237 -378.255052) (xy 26.925524 -378.280144)
			(xy 26.870631 -378.297192) (xy 26.813802 -378.305811) (xy 26.785062 -378.30633) (xy 26.754197 -378.305705)
			(xy 26.693278 -378.295729) (xy 26.63476 -378.276075) (xy 26.58017 -378.247256) (xy 26.555192 -378.229114)
			(xy 26.547572 -378.223526) (xy 26.529792 -378.218446) (xy 26.443686 -378.225304) (xy 26.426922 -378.233178)
			(xy 26.420318 -378.240036) (xy 26.402257 -378.258341) (xy 26.362093 -378.290451) (xy 26.317974 -378.316868)
			(xy 26.270704 -378.337111) (xy 26.221141 -378.350813) (xy 26.170185 -378.357725) (xy 26.144474 -378.358146)
			(xy 26.117224 -378.357647) (xy 26.063279 -378.349887) (xy 26.010986 -378.334531) (xy 25.961412 -378.31189)
			(xy 25.915563 -378.282424) (xy 25.874374 -378.246734) (xy 25.838683 -378.205546) (xy 25.809216 -378.159699)
			(xy 25.786573 -378.110125) (xy 25.771215 -378.057833) (xy 25.763454 -378.003888) (xy 25.762966 -377.976638)
			(xy 22.983421 -377.976638) (xy 22.988361 -377.991958) (xy 22.997606 -378.050761) (xy 22.998176 -378.080524)
			(xy 22.997696 -378.10853) (xy 22.989523 -378.163942) (xy 22.973341 -378.217566) (xy 22.949498 -378.26825)
			(xy 22.918505 -378.314906) (xy 22.900132 -378.336048) (xy 22.893528 -378.343414) (xy 22.886924 -378.36094)
			(xy 22.888448 -378.450348) (xy 22.895814 -378.46762) (xy 22.902672 -378.474732) (xy 22.922864 -378.496215)
			(xy 22.957006 -378.544279) (xy 22.983348 -378.597023) (xy 23.001265 -378.653191) (xy 23.010329 -378.711446)
			(xy 23.010876 -378.740924) (xy 23.01039 -378.768175) (xy 23.002634 -378.822123) (xy 22.987279 -378.874418)
			(xy 22.964637 -378.923995) (xy 22.935171 -378.969845) (xy 22.89948 -379.011036) (xy 22.858289 -379.046727)
			(xy 22.812439 -379.076193) (xy 22.762862 -379.098835) (xy 22.710567 -379.11419) (xy 22.656619 -379.121946)
			(xy 22.602117 -379.121946) (xy 22.548169 -379.11419) (xy 22.495874 -379.098835) (xy 22.446297 -379.076193)
			(xy 22.400447 -379.046727) (xy 22.359256 -379.011036) (xy 22.323565 -378.969845) (xy 22.294099 -378.923995)
			(xy 22.271457 -378.874418) (xy 22.256102 -378.822123) (xy 22.248346 -378.768175) (xy 22.24786 -378.740924)
			(xy 22.248385 -378.71292) (xy 22.256549 -378.65751) (xy 22.272722 -378.603888) (xy 22.296554 -378.553203)
			(xy 22.327536 -378.506545) (xy 22.345904 -378.4854) (xy 22.352508 -378.478034) (xy 22.359112 -378.460508)
			(xy 22.357588 -378.3711) (xy 22.350222 -378.353828) (xy 22.343364 -378.346716) (xy 22.323201 -378.325207)
			(xy 22.289054 -378.277151) (xy 22.262705 -378.224414) (xy 22.244782 -378.168251) (xy 22.23571 -378.11)
			(xy 22.23516 -378.080524) (xy 22.235614 -378.053589) (xy 22.243206 -378.000258) (xy 22.258227 -377.948525)
			(xy 22.280379 -377.899421) (xy 22.30922 -377.853922) (xy 22.326346 -377.833128) (xy 22.333204 -377.825)
			(xy 22.3393 -377.804934) (xy 22.328378 -377.709938) (xy 22.31771 -377.69165) (xy 22.309074 -377.6853)
			(xy 22.28543 -377.667212) (xy 22.243569 -377.624889) (xy 22.208792 -377.576575) (xy 22.181946 -377.523443)
			(xy 22.163683 -377.466786) (xy 22.154445 -377.407978) (xy 22.15388 -377.378214) (xy 22.154378 -377.349296)
			(xy 22.163107 -377.292122) (xy 22.180367 -377.236922) (xy 22.205762 -377.18496) (xy 22.238711 -377.137426)
			(xy 22.278458 -377.095412) (xy 22.300946 -377.077224) (xy 22.3097 -377.069655) (xy 22.319886 -377.048901)
			(xy 22.320504 -377.037346) (xy 22.320504 -376.957082) (xy 22.319942 -376.945513) (xy 22.309741 -376.924742)
			(xy 22.300946 -376.917204) (xy 22.280177 -376.900434) (xy 22.243048 -376.862082) (xy 22.211628 -376.818929)
			(xy 22.18653 -376.771818) (xy 22.168243 -376.721668) (xy 22.157126 -376.669458) (xy 22.153395 -376.616209)
			(xy 21.154341 -376.616209) (xy 21.161067 -376.647798) (xy 21.164797 -376.70105) (xy 21.161067 -376.754302)
			(xy 21.14995 -376.806513) (xy 21.131664 -376.856665) (xy 21.106565 -376.903779) (xy 21.075144 -376.946934)
			(xy 21.038013 -376.985287) (xy 21.01723 -377.00204) (xy 21.008443 -377.009577) (xy 20.998276 -377.030355)
			(xy 20.997672 -377.041918) (xy 20.997672 -377.122182) (xy 20.998228 -377.133752) (xy 21.00843 -377.154525)
			(xy 21.01723 -377.16206) (xy 21.039701 -377.180266) (xy 21.079435 -377.222284) (xy 21.112375 -377.269816)
			(xy 21.137765 -377.321774) (xy 21.155025 -377.376968) (xy 21.163758 -377.434135) (xy 21.164296 -377.46305)
			(xy 21.163853 -377.49088) (xy 21.155772 -377.545949) (xy 21.139772 -377.599259) (xy 21.116195 -377.649678)
			(xy 21.085541 -377.696135) (xy 21.048461 -377.737644) (xy 21.005742 -377.773324) (xy 20.958291 -377.802416)
			(xy 20.932902 -377.813824) (xy 20.92325 -377.817888) (xy 20.909026 -377.83262) (xy 20.875752 -377.920758)
			(xy 20.876768 -377.941332) (xy 20.881086 -377.95073) (xy 20.888452 -377.966986) (xy 20.892425 -377.975526)
			(xy 20.905503 -377.989068) (xy 20.922589 -377.996973) (xy 20.941376 -377.998175) (xy 20.959329 -377.992513)
			(xy 20.974027 -377.980749) (xy 20.97913 -377.972828) (xy 20.993908 -377.94856) (xy 21.029543 -377.904305)
			(xy 21.071346 -377.865824) (xy 21.118394 -377.833968) (xy 21.169645 -377.809441) (xy 21.223967 -377.792785)
			(xy 21.280159 -377.78437) (xy 21.308568 -377.783852) (xy 21.335817 -377.784408) (xy 21.38976 -377.792159)
			(xy 21.442051 -377.807508) (xy 21.491625 -377.830143) (xy 21.537474 -377.859602) (xy 21.578663 -377.895286)
			(xy 21.614355 -377.936469) (xy 21.643823 -377.982312) (xy 21.666467 -378.031882) (xy 21.681826 -378.08417)
			(xy 21.689587 -378.138111) (xy 21.690076 -378.16536) (xy 21.689633 -378.19266) (xy 21.681852 -378.246704)
			(xy 21.666445 -378.299085) (xy 21.643725 -378.348734) (xy 21.614157 -378.394636) (xy 21.596604 -378.41555)
			(xy 21.59 -378.422916) (xy 21.583904 -378.44095) (xy 21.587206 -378.530104) (xy 21.594826 -378.547376)
			(xy 21.601938 -378.554488) (xy 21.623017 -378.576118) (xy 21.658744 -378.624811) (xy 21.686349 -378.678527)
			(xy 21.705141 -378.735923) (xy 21.714652 -378.795563) (xy 21.715222 -378.82576) (xy 21.714729 -378.8545)
			(xy 21.706098 -378.911328) (xy 21.68904 -378.966219) (xy 21.663942 -379.01793) (xy 21.631371 -379.065292)
			(xy 21.612098 -379.086618) (xy 21.605494 -379.09373) (xy 21.598382 -379.111256) (xy 21.598382 -379.200664)
			(xy 21.605494 -379.21819) (xy 21.612098 -379.225302) (xy 21.631339 -379.246655) (xy 21.663911 -379.294009)
			(xy 21.689011 -379.345714) (xy 21.706068 -379.400599) (xy 21.714697 -379.457423) (xy 21.715222 -379.48616)
			(xy 21.714752 -379.51353) (xy 21.706938 -379.56771) (xy 21.691451 -379.620214) (xy 21.668609 -379.669961)
			(xy 21.638884 -379.715927) (xy 21.621242 -379.736858) (xy 21.615146 -379.74397) (xy 21.608796 -379.760988)
			(xy 21.608796 -379.846332) (xy 21.615146 -379.86335) (xy 21.621242 -379.870462) (xy 21.638884 -379.891392)
			(xy 21.668594 -379.937366) (xy 21.691429 -379.987114) (xy 21.706919 -380.039615) (xy 21.714748 -380.093791)
			(xy 21.715222 -380.12116) (xy 21.714631 -380.151355) (xy 21.705111 -380.210989) (xy 21.686316 -380.26838)
			(xy 21.658718 -380.322094) (xy 21.623003 -380.370792) (xy 21.601938 -380.392432) (xy 21.594826 -380.399544)
			(xy 21.587206 -380.416816) (xy 21.583904 -380.50597) (xy 21.59 -380.524004) (xy 21.596604 -380.53137)
			(xy 21.614134 -380.552301) (xy 21.643695 -380.598202) (xy 21.666411 -380.647848) (xy 21.68182 -380.700224)
			(xy 21.689607 -380.754262) (xy 21.690076 -380.78156) (xy 21.689631 -380.807303) (xy 21.68954 -380.807976)
			(xy 25.408128 -380.807976) (xy 25.408547 -380.781076) (xy 25.416102 -380.727809) (xy 25.431074 -380.676133)
			(xy 25.453165 -380.627077) (xy 25.481935 -380.581616) (xy 25.516812 -380.540652) (xy 25.536652 -380.52248)
			(xy 25.544526 -380.515368) (xy 25.553416 -380.496826) (xy 25.556718 -380.402084) (xy 25.549352 -380.383034)
			(xy 25.541986 -380.375414) (xy 25.521744 -380.353929) (xy 25.487525 -380.305831) (xy 25.461121 -380.253037)
			(xy 25.443162 -380.196807) (xy 25.434077 -380.138482) (xy 25.433528 -380.108968) (xy 25.433968 -380.081597)
			(xy 25.441791 -380.027416) (xy 25.457286 -379.974913) (xy 25.480134 -379.925166) (xy 25.509864 -379.879201)
			(xy 25.527508 -379.85827) (xy 25.533604 -379.851158) (xy 25.539954 -379.83414) (xy 25.539954 -379.748796)
			(xy 25.533604 -379.731778) (xy 25.527508 -379.724666) (xy 25.509888 -379.703719) (xy 25.480173 -379.65775)
			(xy 25.457333 -379.608007) (xy 25.441838 -379.555509) (xy 25.434005 -379.501336) (xy 25.433528 -379.473968)
			(xy 25.434095 -379.444527) (xy 25.443132 -379.386344) (xy 25.461004 -379.33024) (xy 25.487284 -379.277549)
			(xy 25.521349 -379.229522) (xy 25.541478 -379.20803) (xy 25.54859 -379.200918) (xy 25.555956 -379.182122)
			(xy 25.554178 -379.089412) (xy 25.54605 -379.071124) (xy 25.538684 -379.064012) (xy 25.520399 -379.045947)
			(xy 25.488359 -379.005753) (xy 25.462003 -378.961624) (xy 25.441808 -378.914356) (xy 25.428139 -378.864805)
			(xy 25.421245 -378.813869) (xy 25.420828 -378.788168) (xy 25.421225 -378.760913) (xy 25.428987 -378.706957)
			(xy 25.444349 -378.654656) (xy 25.466998 -378.605073) (xy 25.496473 -378.559219) (xy 25.532174 -378.518025)
			(xy 25.573373 -378.482332) (xy 25.619233 -378.452866) (xy 25.66882 -378.430226) (xy 25.721124 -378.414873)
			(xy 25.775081 -378.40712) (xy 25.802336 -378.40666) (xy 25.831075 -378.407173) (xy 25.887903 -378.415799)
			(xy 25.942793 -378.432853) (xy 25.994505 -378.457947) (xy 26.041867 -378.490513) (xy 26.063194 -378.509784)
			(xy 26.070306 -378.516388) (xy 26.087832 -378.5235) (xy 26.17724 -378.5235) (xy 26.194766 -378.516388)
			(xy 26.201878 -378.509784) (xy 26.223205 -378.490514) (xy 26.270568 -378.457949) (xy 26.322279 -378.432858)
			(xy 26.37717 -378.415808) (xy 26.433997 -378.407186) (xy 26.491475 -378.407186) (xy 26.548302 -378.415808)
			(xy 26.603193 -378.432858) (xy 26.654904 -378.457949) (xy 26.702267 -378.490514) (xy 26.723594 -378.509784)
			(xy 26.730706 -378.516388) (xy 26.748232 -378.5235) (xy 26.83764 -378.5235) (xy 26.855166 -378.516388)
			(xy 26.862278 -378.509784) (xy 26.883597 -378.490504) (xy 26.93096 -378.457937) (xy 26.982674 -378.432846)
			(xy 27.037567 -378.415797) (xy 27.094396 -378.407178) (xy 27.123136 -378.40666) (xy 27.152189 -378.40722)
			(xy 27.209625 -378.416011) (xy 27.265063 -378.433414) (xy 27.317218 -378.459027) (xy 27.364884 -378.492256)
			(xy 27.406957 -378.532332) (xy 27.425142 -378.554996) (xy 27.432254 -378.56414) (xy 27.45232 -378.5743)
			(xy 27.554428 -378.57684) (xy 27.575002 -378.567696) (xy 27.582622 -378.558806) (xy 27.600825 -378.538308)
			(xy 27.642111 -378.502243) (xy 27.688133 -378.472457) (xy 27.737943 -378.449563) (xy 27.790517 -378.434032)
			(xy 27.844772 -378.426185) (xy 27.872182 -378.42571) (xy 27.899435 -378.426172) (xy 27.953387 -378.433927)
			(xy 28.005686 -378.449282) (xy 28.055267 -378.471923) (xy 28.101121 -378.501391) (xy 28.142315 -378.537085)
			(xy 28.178009 -378.578279) (xy 28.207477 -378.624133) (xy 28.230118 -378.673714) (xy 28.245473 -378.726013)
			(xy 28.253228 -378.779965) (xy 28.25369 -378.807218) (xy 28.25318 -378.835957) (xy 28.244554 -378.892786)
			(xy 28.227501 -378.947677) (xy 28.202407 -378.999388) (xy 28.169838 -379.04675) (xy 28.150566 -379.068076)
			(xy 28.143962 -379.075188) (xy 28.13685 -379.092714) (xy 28.13685 -379.182122) (xy 28.143962 -379.199648)
			(xy 28.150566 -379.20676) (xy 28.169855 -379.228071) (xy 28.202421 -379.275436) (xy 28.227512 -379.32715)
			(xy 28.244561 -379.382043) (xy 28.253182 -379.438873) (xy 28.25318 -379.496353) (xy 28.244555 -379.553182)
			(xy 28.227502 -379.608074) (xy 28.202407 -379.659787) (xy 28.169839 -379.707149) (xy 28.150566 -379.728476)
			(xy 28.143962 -379.735588) (xy 28.13685 -379.753114) (xy 28.13685 -379.842522) (xy 28.143962 -379.860048)
			(xy 28.150566 -379.86716) (xy 28.169846 -379.888479) (xy 28.202411 -379.935843) (xy 28.227501 -379.987557)
			(xy 28.24455 -380.04245) (xy 28.25317 -380.099278) (xy 28.25369 -380.128018) (xy 28.25311 -380.157458)
			(xy 28.244074 -380.215641) (xy 28.226206 -380.271744) (xy 28.199929 -380.324436) (xy 28.165867 -380.372464)
			(xy 28.14574 -380.393956) (xy 28.138882 -380.401068) (xy 28.131516 -380.418848) (xy 28.130754 -380.509018)
			(xy 28.137866 -380.527052) (xy 28.144724 -380.534418) (xy 28.164114 -380.555734) (xy 28.196836 -380.603167)
			(xy 28.222048 -380.654983) (xy 28.239178 -380.710002) (xy 28.247835 -380.766972) (xy 28.248356 -380.795784)
			(xy 28.247898 -380.823389) (xy 28.239929 -380.87802) (xy 28.224171 -380.930933) (xy 28.200952 -380.981023)
			(xy 28.170757 -381.027244) (xy 28.152852 -381.04826) (xy 28.146248 -381.05588) (xy 28.139644 -381.07493)
			(xy 28.145486 -381.166624) (xy 28.154122 -381.184912) (xy 28.161742 -381.191516) (xy 28.181621 -381.209687)
			(xy 28.216553 -381.250681) (xy 28.245368 -381.296182) (xy 28.267495 -381.345285) (xy 28.282492 -381.397013)
			(xy 28.290061 -381.450337) (xy 28.29052 -381.477266) (xy 28.290013 -381.504517) (xy 28.282261 -381.558466)
			(xy 28.26691 -381.610763) (xy 28.244272 -381.660342) (xy 28.214809 -381.706194) (xy 28.17912 -381.747387)
			(xy 28.137931 -381.783081) (xy 28.092082 -381.81255) (xy 28.042506 -381.835194) (xy 27.990211 -381.850551)
			(xy 27.936263 -381.85831) (xy 27.909012 -381.858774) (xy 27.882656 -381.858307) (xy 27.830447 -381.851041)
			(xy 27.779735 -381.836659) (xy 27.731484 -381.815435) (xy 27.686613 -381.787773) (xy 27.645976 -381.754199)
			(xy 27.627834 -381.735076) (xy 27.620722 -381.727456) (xy 27.602942 -381.719074) (xy 27.51074 -381.714756)
			(xy 27.492198 -381.721614) (xy 27.484578 -381.728472) (xy 27.463411 -381.747032) (xy 27.41662 -381.778333)
			(xy 27.365739 -381.802421) (xy 27.311871 -381.818773) (xy 27.256186 -381.827034) (xy 27.228038 -381.827532)
			(xy 27.200375 -381.827041) (xy 27.145625 -381.819074) (xy 27.0926 -381.803286) (xy 27.042409 -381.780008)
			(xy 26.996104 -381.749729) (xy 26.975054 -381.731774) (xy 26.967942 -381.72517) (xy 26.950162 -381.71882)
			(xy 26.86177 -381.720598) (xy 26.844244 -381.727964) (xy 26.837386 -381.734568) (xy 26.81591 -381.754503)
			(xy 26.768013 -381.788255) (xy 26.71552 -381.814291) (xy 26.659666 -381.831999) (xy 26.601761 -381.840963)
			(xy 26.572464 -381.841502) (xy 26.546974 -381.84109) (xy 26.496449 -381.834307) (xy 26.447277 -381.820855)
			(xy 26.400335 -381.800972) (xy 26.35646 -381.775012) (xy 26.316435 -381.74344) (xy 26.298398 -381.725424)
			(xy 26.291032 -381.717804) (xy 26.271728 -381.709676) (xy 26.17597 -381.711454) (xy 26.15692 -381.720344)
			(xy 26.149808 -381.728218) (xy 26.131629 -381.747742) (xy 26.090799 -381.782074) (xy 26.045582 -381.810379)
			(xy 25.996861 -381.832107) (xy 25.945588 -381.846831) (xy 25.892763 -381.854265) (xy 25.86609 -381.85471)
			(xy 25.838839 -381.854232) (xy 25.784891 -381.846474) (xy 25.732596 -381.831117) (xy 25.683019 -381.808475)
			(xy 25.637169 -381.779008) (xy 25.595978 -381.743316) (xy 25.560287 -381.702125) (xy 25.530821 -381.656274)
			(xy 25.50818 -381.606697) (xy 25.492825 -381.554401) (xy 25.485068 -381.500453) (xy 25.484582 -381.473202)
			(xy 25.485165 -381.442144) (xy 25.495229 -381.38085) (xy 25.515091 -381.321996) (xy 25.544226 -381.267138)
			(xy 25.56256 -381.242062) (xy 25.568656 -381.233934) (xy 25.57399 -381.215392) (xy 25.563576 -381.125476)
			(xy 25.554432 -381.108458) (xy 25.546558 -381.102108) (xy 25.52529 -381.083892) (xy 25.487817 -381.042282)
			(xy 25.456825 -380.995644) (xy 25.432982 -380.944977) (xy 25.416797 -380.891371) (xy 25.408618 -380.835974)
			(xy 25.408128 -380.807976) (xy 21.68954 -380.807976) (xy 21.682701 -380.85832) (xy 21.668976 -380.907942)
			(xy 21.648705 -380.955269) (xy 21.622254 -380.999441) (xy 21.60651 -381.019812) (xy 21.600668 -381.027178)
			(xy 21.59508 -381.044958) (xy 21.600414 -381.132334) (xy 21.608034 -381.149098) (xy 21.615146 -381.155956)
			(xy 21.633035 -381.17399) (xy 21.664398 -381.213947) (xy 21.690182 -381.257712) (xy 21.709931 -381.304511)
			(xy 21.723296 -381.353517) (xy 21.730041 -381.403862) (xy 21.730462 -381.42926) (xy 21.729976 -381.456511)
			(xy 21.72222 -381.510459) (xy 21.706865 -381.562754) (xy 21.684223 -381.612331) (xy 21.654757 -381.658181)
			(xy 21.619066 -381.699372) (xy 21.577875 -381.735063) (xy 21.532025 -381.764529) (xy 21.482448 -381.787171)
			(xy 21.430153 -381.802526) (xy 21.376205 -381.810282) (xy 21.321703 -381.810282) (xy 21.267755 -381.802526)
			(xy 21.21546 -381.787171) (xy 21.165883 -381.764529) (xy 21.120033 -381.735063) (xy 21.078842 -381.699372)
			(xy 21.043151 -381.658181) (xy 21.013685 -381.612331) (xy 20.991043 -381.562754) (xy 20.975688 -381.510459)
			(xy 20.967932 -381.456511) (xy 20.967446 -381.42926) (xy 20.967897 -381.403517) (xy 20.974825 -381.3525)
			(xy 20.988548 -381.302878) (xy 21.008819 -381.255551) (xy 21.035268 -381.211379) (xy 21.051012 -381.191008)
			(xy 21.056854 -381.183642) (xy 21.062442 -381.165862) (xy 21.057108 -381.078486) (xy 21.049488 -381.061722)
			(xy 21.042376 -381.054864) (xy 21.033534 -381.046143) (xy 21.016883 -381.027713) (xy 21.009102 -381.018034)
			(xy 21.001736 -381.008382) (xy 20.979892 -380.998222) (xy 20.87372 -381.001778) (xy 20.852638 -381.013208)
			(xy 20.84578 -381.023368) (xy 20.830474 -381.044859) (xy 20.794837 -381.083769) (xy 20.754179 -381.117397)
			(xy 20.709276 -381.145103) (xy 20.660984 -381.166358) (xy 20.610223 -381.180756) (xy 20.557963 -381.188023)
			(xy 20.531582 -381.188468) (xy 20.503346 -381.187942) (xy 20.447491 -381.179616) (xy 20.393474 -381.163148)
			(xy 20.342474 -381.138898) (xy 20.295605 -381.107396) (xy 20.253891 -381.06933) (xy 20.235672 -381.047752)
			(xy 20.228068 -381.039366) (xy 20.20761 -381.029744) (xy 20.196302 -381.02921) (xy 20.117562 -381.02921)
			(xy 20.106274 -381.02982) (xy 20.085845 -381.039433) (xy 20.078192 -381.047752) (xy 20.059979 -381.069337)
			(xy 20.018268 -381.107409) (xy 19.971399 -381.138916) (xy 19.920397 -381.163168) (xy 19.866377 -381.179636)
			(xy 19.810519 -381.187959) (xy 19.782282 -381.188468) (xy 19.753023 -381.187894) (xy 19.695192 -381.178951)
			(xy 19.639402 -381.161291) (xy 19.586959 -381.135327) (xy 19.539089 -381.101669) (xy 19.517614 -381.081788)
			(xy 19.510502 -381.07493) (xy 19.492468 -381.067564) (xy 19.402044 -381.067564) (xy 19.38401 -381.07493)
			(xy 19.376898 -381.081788) (xy 19.355462 -381.101717) (xy 19.307591 -381.135391) (xy 19.25514 -381.16136)
			(xy 19.199338 -381.179014) (xy 19.141494 -381.187941) (xy 19.11223 -381.188468) (xy 19.08491 -381.188023)
			(xy 19.03083 -381.180225) (xy 18.978417 -381.164786) (xy 18.928746 -381.142022) (xy 18.882833 -381.112399)
			(xy 18.841621 -381.076524) (xy 18.823432 -381.056134) (xy 18.816066 -381.047752) (xy 18.796508 -381.038608)
			(xy 18.69821 -381.037592) (xy 18.678144 -381.046482) (xy 18.670778 -381.05461) (xy 18.652632 -381.074166)
			(xy 18.611793 -381.108492) (xy 18.566569 -381.136791) (xy 18.517842 -381.158512) (xy 18.466563 -381.17323)
			(xy 18.413734 -381.180659) (xy 18.38706 -381.181102) (xy 18.359807 -381.180659) (xy 18.305858 -381.172897)
			(xy 18.253562 -381.157537) (xy 18.203984 -381.134891) (xy 18.158134 -381.10542) (xy 18.116944 -381.069724)
			(xy 18.081253 -381.028529) (xy 18.051787 -380.982675) (xy 18.029147 -380.933095) (xy 18.013793 -380.880797)
			(xy 18.006037 -380.826847) (xy 18.005552 -380.799594) (xy 16.644405 -380.799594) (xy 16.636875 -380.851676)
			(xy 16.621374 -380.90418) (xy 16.598523 -380.953928) (xy 16.568792 -380.999896) (xy 16.551148 -381.020828)
			(xy 16.545052 -381.02794) (xy 16.538702 -381.044958) (xy 16.538702 -381.130302) (xy 16.545052 -381.14732)
			(xy 16.551148 -381.154432) (xy 16.568761 -381.175386) (xy 16.598478 -381.221352) (xy 16.62132 -381.271094)
			(xy 16.636817 -381.32359) (xy 16.644651 -381.377762) (xy 16.645128 -381.40513) (xy 16.644642 -381.432381)
			(xy 16.636886 -381.486329) (xy 16.621531 -381.538624) (xy 16.598889 -381.588201) (xy 16.569423 -381.634051)
			(xy 16.533732 -381.675242) (xy 16.492541 -381.710933) (xy 16.446691 -381.740399) (xy 16.397114 -381.763041)
			(xy 16.344819 -381.778396) (xy 16.290871 -381.786152) (xy 16.236369 -381.786152) (xy 16.182421 -381.778396)
			(xy 16.130126 -381.763041) (xy 16.080549 -381.740399) (xy 16.034699 -381.710933) (xy 15.993508 -381.675242)
			(xy 15.957817 -381.634051) (xy 15.928351 -381.588201) (xy 15.905709 -381.538624) (xy 15.890354 -381.486329)
			(xy 15.882598 -381.432381) (xy 15.882112 -381.40513) (xy 7.291427 -381.40513) (xy 7.291578 -381.41402)
			(xy 7.291092 -381.441271) (xy 7.283336 -381.495219) (xy 7.267981 -381.547514) (xy 7.245339 -381.597091)
			(xy 7.215873 -381.642941) (xy 7.180182 -381.684132) (xy 7.138991 -381.719823) (xy 7.093141 -381.749289)
			(xy 7.043564 -381.771931) (xy 6.991269 -381.787286) (xy 6.937321 -381.795042) (xy 6.882819 -381.795042)
			(xy 6.828871 -381.787286) (xy 6.776576 -381.771931) (xy 6.726999 -381.749289) (xy 6.681149 -381.719823)
			(xy 6.639958 -381.684132) (xy 6.604267 -381.642941) (xy 6.574801 -381.597091) (xy 6.552159 -381.547514)
			(xy 6.536804 -381.495219) (xy 6.529048 -381.441271) (xy 6.528562 -381.41402) (xy 4.643628 -381.41402)
			(xy 4.643628 -381.874776) (xy 4.643883 -381.882422) (xy 4.648402 -381.89703) (xy 4.652518 -381.903478)
			(xy 4.655312 -381.907542) (xy 10.959338 -388.211568) (xy 10.979127 -388.232171) (xy 11.012684 -388.2784)
			(xy 11.038604 -388.329304) (xy 11.056251 -388.383634) (xy 11.065191 -388.440054) (xy 11.065764 -388.468616)
			(xy 11.065764 -389.22833) (xy 11.907264 -389.22833) (xy 11.911335 -389.172708) (xy 11.923461 -389.118271)
			(xy 11.943384 -389.06618) (xy 11.97068 -389.017545) (xy 12.004766 -388.973402) (xy 12.044915 -388.934693)
			(xy 12.090273 -388.902242) (xy 12.139873 -388.876741) (xy 12.192657 -388.858734) (xy 12.2475 -388.848604)
			(xy 12.303234 -388.846567) (xy 12.358671 -388.852667) (xy 12.412628 -388.866773) (xy 12.463957 -388.888585)
			(xy 12.511563 -388.917639) (xy 12.554431 -388.953314) (xy 12.591648 -388.994851) (xy 12.622421 -389.041364)
			(xy 12.646093 -389.091861) (xy 12.662161 -389.145268) (xy 12.670281 -389.200444) (xy 12.67079 -389.22833)
			(xy 12.670281 -389.256216) (xy 12.662161 -389.311392) (xy 12.646093 -389.364799) (xy 12.622421 -389.415296)
			(xy 12.591648 -389.461809) (xy 12.554431 -389.503346) (xy 12.511563 -389.539021) (xy 12.463957 -389.568075)
			(xy 12.455935 -389.571484) (xy 20.902166 -389.571484) (xy 20.906237 -389.515862) (xy 20.918363 -389.461425)
			(xy 20.938286 -389.409334) (xy 20.965582 -389.360699) (xy 20.999668 -389.316556) (xy 21.039817 -389.277847)
			(xy 21.085175 -389.245396) (xy 21.134775 -389.219895) (xy 21.187559 -389.201888) (xy 21.242402 -389.191758)
			(xy 21.298136 -389.189721) (xy 21.353573 -389.195821) (xy 21.40753 -389.209927) (xy 21.458859 -389.231739)
			(xy 21.506465 -389.260793) (xy 21.549333 -389.296468) (xy 21.58655 -389.338005) (xy 21.617323 -389.384518)
			(xy 21.640995 -389.435015) (xy 21.657063 -389.488422) (xy 21.665183 -389.543598) (xy 21.665692 -389.571484)
			(xy 21.665183 -389.59937) (xy 21.657063 -389.654546) (xy 21.640995 -389.707953) (xy 21.617323 -389.75845)
			(xy 21.58655 -389.804963) (xy 21.549333 -389.8465) (xy 21.506465 -389.882175) (xy 21.458859 -389.911229)
			(xy 21.40753 -389.933041) (xy 21.353573 -389.947147) (xy 21.298136 -389.953247) (xy 21.242402 -389.95121)
			(xy 21.187559 -389.94108) (xy 21.134775 -389.923073) (xy 21.085175 -389.897572) (xy 21.039817 -389.865121)
			(xy 20.999668 -389.826412) (xy 20.965582 -389.782269) (xy 20.938286 -389.733634) (xy 20.918363 -389.681543)
			(xy 20.906237 -389.627106) (xy 20.902166 -389.571484) (xy 12.455935 -389.571484) (xy 12.412628 -389.589887)
			(xy 12.358671 -389.603993) (xy 12.303234 -389.610093) (xy 12.2475 -389.608056) (xy 12.192657 -389.597926)
			(xy 12.139873 -389.579919) (xy 12.090273 -389.554418) (xy 12.044915 -389.521967) (xy 12.004766 -389.483258)
			(xy 11.97068 -389.439115) (xy 11.943384 -389.39048) (xy 11.923461 -389.338389) (xy 11.911335 -389.283952)
			(xy 11.907264 -389.22833) (xy 11.065764 -389.22833) (xy 11.065764 -390.219184) (xy 11.84986 -390.219184)
			(xy 11.853931 -390.163562) (xy 11.866057 -390.109125) (xy 11.88598 -390.057034) (xy 11.913276 -390.008399)
			(xy 11.947362 -389.964256) (xy 11.987511 -389.925547) (xy 12.032869 -389.893096) (xy 12.082469 -389.867595)
			(xy 12.135253 -389.849588) (xy 12.190096 -389.839458) (xy 12.24583 -389.837421) (xy 12.301267 -389.843521)
			(xy 12.355224 -389.857627) (xy 12.406553 -389.879439) (xy 12.454159 -389.908493) (xy 12.497027 -389.944168)
			(xy 12.534244 -389.985705) (xy 12.565017 -390.032218) (xy 12.588689 -390.082715) (xy 12.604757 -390.136122)
			(xy 12.612877 -390.191298) (xy 12.613386 -390.219184) (xy 12.612877 -390.24707) (xy 12.604757 -390.302246)
			(xy 12.588689 -390.355653) (xy 12.565017 -390.40615) (xy 12.534244 -390.452663) (xy 12.497027 -390.4942)
			(xy 12.454159 -390.529875) (xy 12.406553 -390.558929) (xy 12.355224 -390.580741) (xy 12.301267 -390.594847)
			(xy 12.24583 -390.600947) (xy 12.190096 -390.59891) (xy 12.135253 -390.58878) (xy 12.082469 -390.570773)
			(xy 12.032869 -390.545272) (xy 11.987511 -390.512821) (xy 11.947362 -390.474112) (xy 11.913276 -390.429969)
			(xy 11.88598 -390.381334) (xy 11.866057 -390.329243) (xy 11.853931 -390.274806) (xy 11.84986 -390.219184)
			(xy 11.065764 -390.219184) (xy 11.065764 -390.89228) (xy 16.845547 -390.89228) (xy 16.849529 -390.839131)
			(xy 16.861389 -390.787169) (xy 16.880861 -390.737556) (xy 16.90751 -390.691398) (xy 16.940741 -390.649728)
			(xy 16.979811 -390.613476) (xy 17.023848 -390.583452) (xy 17.071868 -390.560327) (xy 17.122798 -390.544617)
			(xy 17.175501 -390.536674) (xy 17.20215 -390.536176) (xy 17.228474 -390.536688) (xy 17.280548 -390.544441)
			(xy 17.33091 -390.559786) (xy 17.37846 -390.582386) (xy 17.422159 -390.611749) (xy 17.441926 -390.62914)
			(xy 17.449038 -390.635744) (xy 17.458182 -390.6393) (xy 17.46259 -390.640863) (xy 17.471794 -390.642521)
			(xy 17.47647 -390.642602) (xy 17.54505 -390.642602) (xy 17.549727 -390.642538) (xy 17.55893 -390.640866)
			(xy 17.563338 -390.6393) (xy 17.572482 -390.635744) (xy 17.579594 -390.62914) (xy 17.599361 -390.611751)
			(xy 17.643074 -390.582412) (xy 17.690625 -390.559818) (xy 17.740981 -390.54446) (xy 17.793047 -390.536672)
			(xy 17.81937 -390.536176) (xy 17.845694 -390.536676) (xy 17.897769 -390.544432) (xy 17.948131 -390.559779)
			(xy 17.995681 -390.582383) (xy 18.039379 -390.611748) (xy 18.059146 -390.62914) (xy 18.066258 -390.635744)
			(xy 18.075402 -390.6393) (xy 18.079808 -390.640868) (xy 18.089013 -390.642523) (xy 18.09369 -390.642602)
			(xy 18.16227 -390.642602) (xy 18.166946 -390.642516) (xy 18.176149 -390.640859) (xy 18.180558 -390.6393)
			(xy 18.189702 -390.635744) (xy 18.196814 -390.62914) (xy 18.216573 -390.611742) (xy 18.260288 -390.582404)
			(xy 18.307841 -390.559811) (xy 18.358199 -390.544456) (xy 18.410267 -390.53667) (xy 18.43659 -390.536176)
			(xy 18.461586 -390.536601) (xy 18.511085 -390.543597) (xy 18.559123 -390.55744) (xy 18.604755 -390.577857)
			(xy 18.647087 -390.604449) (xy 18.66646 -390.62025) (xy 18.673318 -390.626092) (xy 18.690336 -390.632442)
			(xy 18.773902 -390.632442) (xy 18.79092 -390.626092) (xy 18.797778 -390.62025) (xy 18.817138 -390.604432)
			(xy 18.85947 -390.577833) (xy 18.905105 -390.557415) (xy 18.953146 -390.543578) (xy 19.002651 -390.536595)
			(xy 19.027648 -390.536176) (xy 19.053974 -390.536628) (xy 19.106051 -390.544396) (xy 19.156413 -390.559754)
			(xy 19.203962 -390.582368) (xy 19.247659 -390.611743) (xy 19.267424 -390.62914) (xy 19.267678 -390.629394)
			(xy 19.272403 -390.633377) (xy 19.283315 -390.639168) (xy 19.289268 -390.640824) (xy 19.289522 -390.640824)
			(xy 19.295549 -390.642137) (xy 19.307879 -390.642137) (xy 19.313906 -390.640824) (xy 19.396202 -390.619996)
			(xy 19.402231 -390.618287) (xy 19.413277 -390.612377) (xy 19.418046 -390.608312) (xy 19.4183 -390.608058)
			(xy 19.422737 -390.603699) (xy 19.429544 -390.593294) (xy 19.431762 -390.587484) (xy 19.440837 -390.562977)
			(xy 19.464777 -390.516523) (xy 19.494831 -390.47377) (xy 19.530437 -390.435517) (xy 19.570929 -390.40248)
			(xy 19.61555 -390.375276) (xy 19.663466 -390.354414) (xy 19.713779 -390.340285) (xy 19.76555 -390.333152)
			(xy 19.79168 -390.332722) (xy 19.818936 -390.333124) (xy 19.872893 -390.340879) (xy 19.925198 -390.356234)
			(xy 19.974784 -390.378878) (xy 20.020644 -390.408347) (xy 20.061842 -390.444044) (xy 20.087094 -390.473184)
			(xy 20.905976 -390.473184) (xy 20.910047 -390.417562) (xy 20.922173 -390.363125) (xy 20.942096 -390.311034)
			(xy 20.969392 -390.262399) (xy 21.003478 -390.218256) (xy 21.043627 -390.179547) (xy 21.088985 -390.147096)
			(xy 21.138585 -390.121595) (xy 21.191369 -390.103588) (xy 21.246212 -390.093458) (xy 21.301946 -390.091421)
			(xy 21.357383 -390.097521) (xy 21.41134 -390.111627) (xy 21.462669 -390.133439) (xy 21.510275 -390.162493)
			(xy 21.553143 -390.198168) (xy 21.59036 -390.239705) (xy 21.621133 -390.286218) (xy 21.644805 -390.336715)
			(xy 21.660873 -390.390122) (xy 21.668993 -390.445298) (xy 21.669502 -390.473184) (xy 21.668993 -390.50107)
			(xy 21.660873 -390.556246) (xy 21.644805 -390.609653) (xy 21.621133 -390.66015) (xy 21.59036 -390.706663)
			(xy 21.553143 -390.7482) (xy 21.510275 -390.783875) (xy 21.462669 -390.812929) (xy 21.41134 -390.834741)
			(xy 21.357383 -390.848847) (xy 21.301946 -390.854947) (xy 21.246212 -390.85291) (xy 21.191369 -390.84278)
			(xy 21.138585 -390.824773) (xy 21.088985 -390.799272) (xy 21.043627 -390.766821) (xy 21.003478 -390.728112)
			(xy 20.969392 -390.683969) (xy 20.942096 -390.635334) (xy 20.922173 -390.583243) (xy 20.910047 -390.528806)
			(xy 20.905976 -390.473184) (xy 20.087094 -390.473184) (xy 20.097541 -390.48524) (xy 20.127013 -390.531098)
			(xy 20.149659 -390.580683) (xy 20.165017 -390.632987) (xy 20.172775 -390.686944) (xy 20.172775 -390.741456)
			(xy 20.165017 -390.795413) (xy 20.149659 -390.847717) (xy 20.129297 -390.8923) (xy 25.924276 -390.8923)
			(xy 25.928259 -390.839151) (xy 25.940119 -390.787188) (xy 25.95959 -390.737574) (xy 25.986238 -390.691416)
			(xy 26.019467 -390.649744) (xy 26.058536 -390.613491) (xy 26.102572 -390.583464) (xy 26.150591 -390.560336)
			(xy 26.20152 -390.544623) (xy 26.254223 -390.536676) (xy 26.280872 -390.536176) (xy 26.307232 -390.536658)
			(xy 26.359374 -390.544448) (xy 26.409796 -390.559846) (xy 26.457393 -390.582515) (xy 26.501125 -390.611959)
			(xy 26.520902 -390.629394) (xy 26.528014 -390.635744) (xy 26.545794 -390.642602) (xy 26.63317 -390.642602)
			(xy 26.65095 -390.635744) (xy 26.658062 -390.629394) (xy 26.677848 -390.611973) (xy 26.721588 -390.582548)
			(xy 26.769185 -390.559887) (xy 26.8196 -390.544484) (xy 26.871734 -390.536674) (xy 26.898092 -390.536176)
			(xy 26.924453 -390.536646) (xy 26.976595 -390.544439) (xy 27.027017 -390.55984) (xy 27.074614 -390.582511)
			(xy 27.118346 -390.611958) (xy 27.138122 -390.629394) (xy 27.145234 -390.635744) (xy 27.163014 -390.642602)
			(xy 27.25039 -390.642602) (xy 27.26817 -390.635744) (xy 27.275282 -390.629394) (xy 27.29506 -390.611964)
			(xy 27.338802 -390.58254) (xy 27.386401 -390.559881) (xy 27.436818 -390.54448) (xy 27.488954 -390.536672)
			(xy 27.515312 -390.536176) (xy 27.540308 -390.536589) (xy 27.589808 -390.543588) (xy 27.637846 -390.557433)
			(xy 27.683478 -390.577853) (xy 27.72581 -390.604448) (xy 27.745182 -390.62025) (xy 27.752294 -390.626346)
			(xy 27.768804 -390.632442) (xy 27.852878 -390.632442) (xy 27.869388 -390.626346) (xy 27.8765 -390.62025)
			(xy 27.895852 -390.604422) (xy 27.938186 -390.577825) (xy 27.983823 -390.557409) (xy 28.031866 -390.543574)
			(xy 28.081372 -390.536593) (xy 28.10637 -390.536176) (xy 28.133805 -390.53668) (xy 28.188024 -390.545101)
			(xy 28.21432 -390.55294) (xy 28.22575 -390.556496) (xy 28.24861 -390.553194) (xy 28.334462 -390.49452)
			(xy 28.345892 -390.4742) (xy 28.346654 -390.462516) (xy 28.348971 -390.433797) (xy 28.361097 -390.377473)
			(xy 28.381556 -390.323614) (xy 28.409882 -390.273444) (xy 28.445432 -390.228105) (xy 28.487397 -390.188628)
			(xy 28.534821 -390.155912) (xy 28.586626 -390.130701) (xy 28.641634 -390.113568) (xy 28.698593 -390.104903)
			(xy 28.7274 -390.104376) (xy 28.75465 -390.104894) (xy 28.808595 -390.11265) (xy 28.860888 -390.128005)
			(xy 28.910463 -390.150645) (xy 28.956311 -390.18011) (xy 28.9975 -390.2158) (xy 29.03319 -390.256989)
			(xy 29.062655 -390.302837) (xy 29.085295 -390.352412) (xy 29.10065 -390.404705) (xy 29.108406 -390.45865)
			(xy 29.108406 -390.51315) (xy 29.10065 -390.567095) (xy 29.085295 -390.619388) (xy 29.062655 -390.668963)
			(xy 29.03319 -390.714811) (xy 28.9975 -390.756) (xy 28.956311 -390.79169) (xy 28.910463 -390.821155)
			(xy 28.860888 -390.843795) (xy 28.808595 -390.85915) (xy 28.75465 -390.866906) (xy 28.7274 -390.867392)
			(xy 28.693996 -390.866697) (xy 28.628208 -390.855075) (xy 28.59659 -390.844278) (xy 28.585414 -390.840214)
			(xy 28.5623 -390.8425) (xy 28.474162 -390.897618) (xy 28.461716 -390.91743) (xy 28.460446 -390.929114)
			(xy 28.457324 -390.955063) (xy 28.444379 -391.0057) (xy 28.424171 -391.053902) (xy 28.397134 -391.098631)
			(xy 28.36385 -391.138928) (xy 28.325032 -391.173926) (xy 28.281516 -391.202875) (xy 28.234235 -391.225151)
			(xy 28.184206 -391.240277) (xy 28.132503 -391.247927) (xy 28.10637 -391.248392) (xy 28.081375 -391.24794)
			(xy 28.031876 -391.240951) (xy 27.983839 -391.227115) (xy 27.938206 -391.206704) (xy 27.895873 -391.180117)
			(xy 27.8765 -391.164318) (xy 27.869388 -391.158222) (xy 27.852878 -391.152126) (xy 27.768804 -391.152126)
			(xy 27.752294 -391.158222) (xy 27.745182 -391.164318) (xy 27.725796 -391.180103) (xy 27.683472 -391.206708)
			(xy 27.637844 -391.227133) (xy 27.589808 -391.240977) (xy 27.540308 -391.247969) (xy 27.515312 -391.248392)
			(xy 27.488951 -391.247927) (xy 27.436808 -391.240135) (xy 27.386386 -391.224733) (xy 27.338788 -391.20206)
			(xy 27.295058 -391.172611) (xy 27.275282 -391.155174) (xy 27.26817 -391.148824) (xy 27.25039 -391.141966)
			(xy 27.163014 -391.141966) (xy 27.145234 -391.148824) (xy 27.138122 -391.155174) (xy 27.118352 -391.172614)
			(xy 27.074607 -391.202033) (xy 27.027006 -391.22469) (xy 26.976587 -391.24009) (xy 26.924451 -391.247896)
			(xy 26.898092 -391.248392) (xy 26.871731 -391.247939) (xy 26.819587 -391.240144) (xy 26.769165 -391.22474)
			(xy 26.721567 -391.202064) (xy 26.677837 -391.172612) (xy 26.658062 -391.155174) (xy 26.65095 -391.148824)
			(xy 26.63317 -391.141966) (xy 26.545794 -391.141966) (xy 26.528014 -391.148824) (xy 26.520902 -391.155174)
			(xy 26.50114 -391.172623) (xy 26.457393 -391.202042) (xy 26.40979 -391.224696) (xy 26.359369 -391.240094)
			(xy 26.307231 -391.247897) (xy 26.280872 -391.248392) (xy 26.254223 -391.247924) (xy 26.20152 -391.239977)
			(xy 26.150591 -391.224264) (xy 26.102572 -391.201136) (xy 26.058536 -391.171109) (xy 26.019467 -391.134856)
			(xy 25.986238 -391.093184) (xy 25.95959 -391.047026) (xy 25.940119 -390.997412) (xy 25.928259 -390.945449)
			(xy 25.924276 -390.8923) (xy 20.129297 -390.8923) (xy 20.127013 -390.897302) (xy 20.097541 -390.94316)
			(xy 20.061842 -390.984356) (xy 20.020644 -391.020053) (xy 19.974784 -391.049522) (xy 19.925198 -391.072166)
			(xy 19.872893 -391.087521) (xy 19.818936 -391.095276) (xy 19.79168 -391.095738) (xy 19.762096 -391.095179)
			(xy 19.703637 -391.086042) (xy 19.64729 -391.06799) (xy 19.594405 -391.041455) (xy 19.546251 -391.007075)
			(xy 19.524726 -390.986772) (xy 19.515582 -390.977882) (xy 19.491198 -390.97077) (xy 19.395948 -390.99109)
			(xy 19.389754 -390.992623) (xy 19.37832 -390.998275) (xy 19.373342 -391.002266) (xy 19.368829 -391.006341)
			(xy 19.361764 -391.016233) (xy 19.359372 -391.021824) (xy 19.359118 -391.022332) (xy 19.359118 -391.022586)
			(xy 19.348917 -391.047198) (xy 19.32224 -391.093315) (xy 19.288993 -391.134945) (xy 19.249919 -391.17116)
			(xy 19.205887 -391.201153) (xy 19.15788 -391.224256) (xy 19.106968 -391.239952) (xy 19.054286 -391.247892)
			(xy 19.027648 -391.248392) (xy 19.002653 -391.247952) (xy 18.953153 -391.240961) (xy 18.905116 -391.227122)
			(xy 18.859484 -391.206708) (xy 18.817151 -391.180118) (xy 18.797778 -391.164318) (xy 18.79092 -391.158476)
			(xy 18.773902 -391.152126) (xy 18.690336 -391.152126) (xy 18.673318 -391.158476) (xy 18.66646 -391.164318)
			(xy 18.647082 -391.180114) (xy 18.604756 -391.206717) (xy 18.559125 -391.22714) (xy 18.511088 -391.240982)
			(xy 18.461586 -391.247971) (xy 18.43659 -391.248392) (xy 18.410264 -391.247925) (xy 18.358188 -391.240162)
			(xy 18.307825 -391.224807) (xy 18.260276 -391.202197) (xy 18.216579 -391.172823) (xy 18.196814 -391.155428)
			(xy 18.189702 -391.148824) (xy 18.180558 -391.145268) (xy 18.176147 -391.143715) (xy 18.166946 -391.14205)
			(xy 18.16227 -391.141966) (xy 18.09369 -391.141966) (xy 18.089014 -391.142043) (xy 18.079811 -391.143706)
			(xy 18.075402 -391.145268) (xy 18.066258 -391.148824) (xy 18.059146 -391.155428) (xy 18.039359 -391.172793)
			(xy 17.995652 -391.202137) (xy 17.948106 -391.224736) (xy 17.897755 -391.2401) (xy 17.845691 -391.247893)
			(xy 17.81937 -391.248392) (xy 17.793044 -391.247937) (xy 17.740967 -391.240171) (xy 17.690604 -391.224814)
			(xy 17.643055 -391.2022) (xy 17.599359 -391.172825) (xy 17.579594 -391.155428) (xy 17.572482 -391.148824)
			(xy 17.563338 -391.145268) (xy 17.558929 -391.143709) (xy 17.549726 -391.142049) (xy 17.54505 -391.141966)
			(xy 17.47647 -391.141966) (xy 17.471793 -391.142038) (xy 17.462591 -391.143705) (xy 17.458182 -391.145268)
			(xy 17.449038 -391.148824) (xy 17.441926 -391.155428) (xy 17.422147 -391.172802) (xy 17.378438 -391.202145)
			(xy 17.33089 -391.224742) (xy 17.280537 -391.240104) (xy 17.228472 -391.247895) (xy 17.20215 -391.248392)
			(xy 17.175501 -391.247886) (xy 17.122798 -391.239943) (xy 17.071868 -391.224233) (xy 17.023848 -391.201108)
			(xy 16.979811 -391.171084) (xy 16.940741 -391.134832) (xy 16.90751 -391.093162) (xy 16.880861 -391.047004)
			(xy 16.861389 -390.997391) (xy 16.849529 -390.945429) (xy 16.845547 -390.89228) (xy 11.065764 -390.89228)
			(xy 11.065764 -391.761726) (xy 18.769076 -391.761726) (xy 18.769579 -391.734475) (xy 18.777332 -391.680526)
			(xy 18.792684 -391.62823) (xy 18.815323 -391.578651) (xy 18.844787 -391.532798) (xy 18.880476 -391.491606)
			(xy 18.921665 -391.455912) (xy 18.967514 -391.426443) (xy 19.01709 -391.403799) (xy 19.069385 -391.388441)
			(xy 19.123333 -391.380682) (xy 19.150584 -391.380218) (xy 19.176567 -391.380641) (xy 19.22805 -391.387704)
			(xy 19.278098 -391.401688) (xy 19.325786 -391.422335) (xy 19.370231 -391.449262) (xy 19.410611 -391.481971)
			(xy 19.428714 -391.500614) (xy 19.435826 -391.50798) (xy 19.454114 -391.516362) (xy 19.546824 -391.519156)
			(xy 19.56562 -391.51179) (xy 19.572986 -391.504678) (xy 19.594416 -391.48501) (xy 19.642122 -391.451735)
			(xy 19.694323 -391.42608) (xy 19.749811 -391.408639) (xy 19.807302 -391.399815) (xy 19.836384 -391.399268)
			(xy 19.863634 -391.399793) (xy 19.917579 -391.407547) (xy 19.969871 -391.422899) (xy 20.019447 -391.445536)
			(xy 20.065296 -391.474998) (xy 20.106486 -391.510686) (xy 20.142178 -391.551872) (xy 20.171645 -391.597718)
			(xy 20.194287 -391.647291) (xy 20.209645 -391.699582) (xy 20.215843 -391.742676) (xy 20.730716 -391.742676)
			(xy 20.734787 -391.687054) (xy 20.746913 -391.632617) (xy 20.766836 -391.580526) (xy 20.794132 -391.531891)
			(xy 20.828218 -391.487748) (xy 20.868367 -391.449039) (xy 20.913725 -391.416588) (xy 20.963325 -391.391087)
			(xy 21.016109 -391.37308) (xy 21.070952 -391.36295) (xy 21.126686 -391.360913) (xy 21.182123 -391.367013)
			(xy 21.23608 -391.381119) (xy 21.287409 -391.402931) (xy 21.335015 -391.431985) (xy 21.377883 -391.46766)
			(xy 21.4151 -391.509197) (xy 21.445873 -391.55571) (xy 21.469545 -391.606207) (xy 21.485613 -391.659614)
			(xy 21.493733 -391.71479) (xy 21.494242 -391.742676) (xy 21.493733 -391.770562) (xy 21.487557 -391.812526)
			(xy 27.862276 -391.812526) (xy 27.862779 -391.785275) (xy 27.870532 -391.731326) (xy 27.885884 -391.67903)
			(xy 27.908523 -391.629451) (xy 27.937987 -391.583598) (xy 27.973676 -391.542406) (xy 28.014865 -391.506712)
			(xy 28.060714 -391.477243) (xy 28.11029 -391.454599) (xy 28.162585 -391.439241) (xy 28.216533 -391.431482)
			(xy 28.243784 -391.431018) (xy 28.273907 -391.431608) (xy 28.333402 -391.441086) (xy 28.390669 -391.459793)
			(xy 28.444286 -391.487264) (xy 28.492922 -391.522818) (xy 28.514548 -391.543794) (xy 28.522422 -391.551668)
			(xy 28.542234 -391.559288) (xy 28.640024 -391.554208) (xy 28.659074 -391.544302) (xy 28.665932 -391.535666)
			(xy 28.68415 -391.513789) (xy 28.725992 -391.475185) (xy 28.773102 -391.443223) (xy 28.824436 -391.41861)
			(xy 28.878856 -391.401893) (xy 28.935155 -391.393442) (xy 28.96362 -391.392918) (xy 28.990875 -391.393336)
			(xy 29.044828 -391.401097) (xy 29.097129 -391.416457) (xy 29.146711 -391.439103) (xy 29.192565 -391.468576)
			(xy 29.233758 -391.504274) (xy 29.269452 -391.545472) (xy 29.298919 -391.59133) (xy 29.321559 -391.640914)
			(xy 29.336913 -391.693217) (xy 29.344667 -391.747171) (xy 29.345128 -391.774426) (xy 29.344717 -391.800035)
			(xy 29.337855 -391.850792) (xy 29.324271 -391.900177) (xy 29.304209 -391.947303) (xy 29.278029 -391.991325)
			(xy 29.246201 -392.031453) (xy 29.228034 -392.049508) (xy 29.218636 -392.058398) (xy 29.211016 -392.082782)
			(xy 29.231082 -392.191494) (xy 29.247084 -392.211306) (xy 29.259022 -392.216386) (xy 29.284595 -392.227703)
			(xy 29.332418 -392.256689) (xy 29.375495 -392.292347) (xy 29.412903 -392.333914) (xy 29.443839 -392.380499)
			(xy 29.46764 -392.431103) (xy 29.483795 -392.484639) (xy 29.491959 -392.539961) (xy 29.492448 -392.567922)
			(xy 29.491943 -392.595172) (xy 29.484184 -392.649117) (xy 29.468828 -392.701409) (xy 29.446188 -392.750983)
			(xy 29.416723 -392.796832) (xy 29.381034 -392.838021) (xy 29.339846 -392.873712) (xy 29.293999 -392.903179)
			(xy 29.244426 -392.925822) (xy 29.192135 -392.94118) (xy 29.13819 -392.948942) (xy 29.11094 -392.94943)
			(xy 29.080673 -392.948837) (xy 29.0209 -392.939271) (xy 28.963386 -392.920389) (xy 28.909575 -392.892664)
			(xy 28.860815 -392.856792) (xy 28.83916 -392.835638) (xy 28.832048 -392.828272) (xy 28.813506 -392.820652)
			(xy 28.720288 -392.820652) (xy 28.701746 -392.828272) (xy 28.694634 -392.835638) (xy 28.672998 -392.856814)
			(xy 28.624238 -392.892693) (xy 28.570422 -392.92042) (xy 28.512903 -392.939298) (xy 28.453123 -392.948853)
			(xy 28.422854 -392.94943) (xy 28.395603 -392.948965) (xy 28.341655 -392.941203) (xy 28.289362 -392.925843)
			(xy 28.239786 -392.903198) (xy 28.193936 -392.873729) (xy 28.152747 -392.838036) (xy 28.117057 -392.796844)
			(xy 28.08759 -392.750993) (xy 28.064949 -392.701416) (xy 28.049592 -392.649121) (xy 28.041833 -392.595173)
			(xy 28.041346 -392.567922) (xy 28.041819 -392.541189) (xy 28.049324 -392.488253) (xy 28.064134 -392.436879)
			(xy 28.085961 -392.38807) (xy 28.114378 -392.342781) (xy 28.131262 -392.32205) (xy 28.138882 -392.312652)
			(xy 28.14447 -392.289284) (xy 28.120086 -392.186414) (xy 28.104592 -392.167872) (xy 28.093416 -392.1633)
			(xy 28.068068 -392.151839) (xy 28.020679 -392.122711) (xy 27.978019 -392.087013) (xy 27.940992 -392.045501)
			(xy 27.910382 -391.999054) (xy 27.886838 -391.948656) (xy 27.870858 -391.895375) (xy 27.862781 -391.840339)
			(xy 27.862276 -391.812526) (xy 21.487557 -391.812526) (xy 21.485613 -391.825738) (xy 21.469545 -391.879145)
			(xy 21.445873 -391.929642) (xy 21.4151 -391.976155) (xy 21.377883 -392.017692) (xy 21.335015 -392.053367)
			(xy 21.287409 -392.082421) (xy 21.23608 -392.104233) (xy 21.182123 -392.118339) (xy 21.126686 -392.124439)
			(xy 21.070952 -392.122402) (xy 21.016109 -392.112272) (xy 20.963325 -392.094265) (xy 20.913725 -392.068764)
			(xy 20.868367 -392.036313) (xy 20.828218 -391.997604) (xy 20.794132 -391.953461) (xy 20.766836 -391.904826)
			(xy 20.746913 -391.852735) (xy 20.734787 -391.798298) (xy 20.730716 -391.742676) (xy 20.215843 -391.742676)
			(xy 20.217404 -391.753526) (xy 20.217892 -391.780776) (xy 20.217405 -391.807356) (xy 20.210023 -391.860001)
			(xy 20.195399 -391.91111) (xy 20.173817 -391.959692) (xy 20.145695 -392.004805) (xy 20.111578 -392.045573)
			(xy 20.092162 -392.063732) (xy 20.082002 -392.072876) (xy 20.07362 -392.099038) (xy 20.098004 -392.211814)
			(xy 20.116292 -392.232134) (xy 20.1295 -392.236198) (xy 20.154903 -392.244743) (xy 20.203216 -392.267948)
			(xy 20.247807 -392.297683) (xy 20.2878 -392.333364) (xy 20.322409 -392.374289) (xy 20.350951 -392.419653)
			(xy 20.372867 -392.468564) (xy 20.387726 -392.52006) (xy 20.395234 -392.573128) (xy 20.395692 -392.599926)
			(xy 20.395246 -392.627179) (xy 20.387486 -392.681129) (xy 20.372127 -392.733425) (xy 20.349481 -392.783003)
			(xy 20.341544 -392.795352) (xy 24.261552 -392.795352) (xy 24.261552 -392.740848) (xy 24.269308 -392.686899)
			(xy 24.284663 -392.634603) (xy 24.307303 -392.585024) (xy 24.336769 -392.539172) (xy 24.37246 -392.49798)
			(xy 24.41365 -392.462286) (xy 24.4595 -392.432817) (xy 24.509077 -392.410173) (xy 24.561372 -392.394814)
			(xy 24.61532 -392.387054) (xy 24.642572 -392.386566) (xy 24.668493 -392.386996) (xy 24.719856 -392.394035)
			(xy 24.769793 -392.407961) (xy 24.817387 -392.428516) (xy 24.861761 -392.455323) (xy 24.902098 -392.487889)
			(xy 24.920194 -392.506454) (xy 24.92756 -392.514328) (xy 24.946864 -392.522456) (xy 25.043384 -392.521186)
			(xy 25.062434 -392.51255) (xy 25.0698 -392.504422) (xy 25.087992 -392.484869) (xy 25.128845 -392.450472)
			(xy 25.174096 -392.42211) (xy 25.222861 -392.400337) (xy 25.274187 -392.385579) (xy 25.327069 -392.378126)
			(xy 25.353772 -392.377676) (xy 25.381025 -392.378169) (xy 25.434977 -392.385923) (xy 25.487276 -392.401276)
			(xy 25.536857 -392.423916) (xy 25.582712 -392.453382) (xy 25.623906 -392.489074) (xy 25.659601 -392.530266)
			(xy 25.689071 -392.576118) (xy 25.711714 -392.625698) (xy 25.727071 -392.677996) (xy 25.734829 -392.731947)
			(xy 25.734829 -392.786453) (xy 25.727071 -392.840404) (xy 25.711714 -392.892702) (xy 25.689071 -392.942282)
			(xy 25.659601 -392.988134) (xy 25.623906 -393.029326) (xy 25.582712 -393.065018) (xy 25.536857 -393.094484)
			(xy 25.487276 -393.117124) (xy 25.434977 -393.132477) (xy 25.381025 -393.140231) (xy 25.353772 -393.140692)
			(xy 25.327851 -393.140246) (xy 25.276489 -393.133212) (xy 25.226551 -393.119291) (xy 25.178957 -393.098738)
			(xy 25.134583 -393.071933) (xy 25.094245 -393.039369) (xy 25.07615 -393.020804) (xy 25.068784 -393.01293)
			(xy 25.04948 -393.004802) (xy 24.95296 -393.006072) (xy 24.93391 -393.014708) (xy 24.926544 -393.022836)
			(xy 24.908391 -393.042427) (xy 24.867529 -393.076819) (xy 24.822269 -393.105175) (xy 24.773496 -393.126941)
			(xy 24.722164 -393.14169) (xy 24.669277 -393.149136) (xy 24.642572 -393.149582) (xy 24.61532 -393.149146)
			(xy 24.561372 -393.141386) (xy 24.509077 -393.126027) (xy 24.4595 -393.103383) (xy 24.41365 -393.073914)
			(xy 24.37246 -393.03822) (xy 24.336769 -392.997028) (xy 24.307303 -392.951176) (xy 24.284663 -392.901597)
			(xy 24.269308 -392.849301) (xy 24.261552 -392.795352) (xy 20.341544 -392.795352) (xy 20.320011 -392.828855)
			(xy 20.284315 -392.870045) (xy 20.243121 -392.905736) (xy 20.197267 -392.935201) (xy 20.147686 -392.957841)
			(xy 20.095388 -392.973195) (xy 20.041437 -392.980949) (xy 20.014184 -392.981434) (xy 19.985268 -392.98088)
			(xy 19.928097 -392.972162) (xy 19.872898 -392.954913) (xy 19.820936 -392.929528) (xy 19.773401 -392.896589)
			(xy 19.731384 -392.856852) (xy 19.713194 -392.834368) (xy 19.706926 -392.826968) (xy 19.6902 -392.817182)
			(xy 19.680682 -392.815318) (xy 19.673062 -392.81481) (xy 19.593306 -392.81481) (xy 19.585686 -392.815318)
			(xy 19.576174 -392.817194) (xy 19.559458 -392.826985) (xy 19.553174 -392.834368) (xy 19.53499 -392.856857)
			(xy 19.492969 -392.896594) (xy 19.445433 -392.929533) (xy 19.393471 -392.954921) (xy 19.338272 -392.972175)
			(xy 19.281101 -392.980901) (xy 19.252184 -392.981434) (xy 19.224934 -392.980937) (xy 19.170988 -392.973179)
			(xy 19.118695 -392.957823) (xy 19.069119 -392.935182) (xy 19.02327 -392.905717) (xy 18.982081 -392.870026)
			(xy 18.946389 -392.828838) (xy 18.916923 -392.78299) (xy 18.89428 -392.733415) (xy 18.878923 -392.681122)
			(xy 18.871164 -392.627176) (xy 18.870676 -392.599926) (xy 18.871129 -392.574237) (xy 18.878021 -392.523325)
			(xy 18.891684 -392.473798) (xy 18.91187 -392.426553) (xy 18.938215 -392.382444) (xy 18.970241 -392.342271)
			(xy 19.007369 -392.306759) (xy 19.027902 -392.291316) (xy 19.033227 -392.287209) (xy 19.041714 -392.276784)
			(xy 19.044666 -392.270742) (xy 19.044666 -392.270488) (xy 19.04714 -392.264194) (xy 19.04906 -392.25081)
			(xy 19.048476 -392.244072) (xy 19.036284 -392.142218) (xy 19.01952 -392.120374) (xy 19.006566 -392.11504)
			(xy 18.980604 -392.103918) (xy 18.932023 -392.07511) (xy 18.888218 -392.039457) (xy 18.850147 -391.997737)
			(xy 18.81864 -391.950861) (xy 18.794387 -391.899854) (xy 18.777916 -391.845829) (xy 18.769588 -391.789966)
			(xy 18.769076 -391.761726) (xy 11.065764 -391.761726) (xy 11.065764 -392.568176) (xy 11.065206 -392.596739)
			(xy 11.056275 -392.653164) (xy 11.049477 -392.674094) (xy 11.892278 -392.674094) (xy 11.896349 -392.618472)
			(xy 11.908475 -392.564035) (xy 11.928398 -392.511944) (xy 11.955694 -392.463309) (xy 11.98978 -392.419166)
			(xy 12.029929 -392.380457) (xy 12.075287 -392.348006) (xy 12.124887 -392.322505) (xy 12.177671 -392.304498)
			(xy 12.232514 -392.294368) (xy 12.288248 -392.292331) (xy 12.343685 -392.298431) (xy 12.397642 -392.312537)
			(xy 12.448971 -392.334349) (xy 12.496577 -392.363403) (xy 12.539445 -392.399078) (xy 12.576662 -392.440615)
			(xy 12.607435 -392.487128) (xy 12.631107 -392.537625) (xy 12.647175 -392.591032) (xy 12.655295 -392.646208)
			(xy 12.655804 -392.674094) (xy 12.655295 -392.70198) (xy 12.647175 -392.757156) (xy 12.631107 -392.810563)
			(xy 12.607435 -392.86106) (xy 12.576662 -392.907573) (xy 12.562991 -392.922831) (xy 15.26665 -392.922831)
			(xy 15.26665 -392.868329) (xy 15.274406 -392.814381) (xy 15.289761 -392.762087) (xy 15.312402 -392.71251)
			(xy 15.341868 -392.66666) (xy 15.37756 -392.62547) (xy 15.41875 -392.589778) (xy 15.4646 -392.560312)
			(xy 15.514177 -392.537671) (xy 15.566471 -392.522316) (xy 15.620419 -392.51456) (xy 15.64767 -392.514074)
			(xy 15.676293 -392.514562) (xy 15.732896 -392.523107) (xy 15.787589 -392.540011) (xy 15.839143 -392.564893)
			(xy 15.863062 -392.580622) (xy 15.871719 -392.585956) (xy 15.89162 -392.59003) (xy 15.90167 -392.588496)
			(xy 15.983204 -392.571986) (xy 15.999968 -392.560556) (xy 16.005556 -392.55192) (xy 16.020677 -392.529346)
			(xy 16.056374 -392.488382) (xy 16.097522 -392.452896) (xy 16.143288 -392.423608) (xy 16.192746 -392.401109)
			(xy 16.244896 -392.385854) (xy 16.298682 -392.378152) (xy 16.32585 -392.377676) (xy 16.353102 -392.378154)
			(xy 16.40705 -392.38591) (xy 16.459345 -392.401266) (xy 16.508923 -392.423907) (xy 16.554774 -392.453374)
			(xy 16.595964 -392.489066) (xy 16.631656 -392.530256) (xy 16.661123 -392.576107) (xy 16.683764 -392.625685)
			(xy 16.69912 -392.67798) (xy 16.706876 -392.731928) (xy 16.706876 -392.786432) (xy 16.69912 -392.84038)
			(xy 16.683764 -392.892675) (xy 16.661123 -392.942253) (xy 16.631656 -392.988104) (xy 16.595964 -393.029294)
			(xy 16.554774 -393.064986) (xy 16.508923 -393.094453) (xy 16.459345 -393.117094) (xy 16.40705 -393.13245)
			(xy 16.353102 -393.140206) (xy 16.32585 -393.140692) (xy 16.297228 -393.1402) (xy 16.240624 -393.131657)
			(xy 16.185931 -393.114755) (xy 16.134377 -393.089873) (xy 16.110458 -393.074144) (xy 16.101825 -393.068766)
			(xy 16.081904 -393.06472) (xy 16.07185 -393.06627) (xy 15.990316 -393.08278) (xy 15.973552 -393.09421)
			(xy 15.967964 -393.102846) (xy 15.952818 -393.125403) (xy 15.917126 -393.166369) (xy 15.875984 -393.201857)
			(xy 15.830222 -393.231148) (xy 15.780767 -393.25365) (xy 15.728621 -393.268907) (xy 15.674837 -393.276612)
			(xy 15.64767 -393.27709) (xy 15.620419 -393.2766) (xy 15.566471 -393.268844) (xy 15.514177 -393.253489)
			(xy 15.4646 -393.230848) (xy 15.41875 -393.201382) (xy 15.37756 -393.16569) (xy 15.341868 -393.1245)
			(xy 15.312402 -393.07865) (xy 15.289761 -393.029073) (xy 15.274406 -392.976779) (xy 15.26665 -392.922831)
			(xy 12.562991 -392.922831) (xy 12.539445 -392.94911) (xy 12.496577 -392.984785) (xy 12.448971 -393.013839)
			(xy 12.397642 -393.035651) (xy 12.343685 -393.049757) (xy 12.288248 -393.055857) (xy 12.232514 -393.05382)
			(xy 12.177671 -393.04369) (xy 12.124887 -393.025683) (xy 12.075287 -393.000182) (xy 12.029929 -392.967731)
			(xy 11.98978 -392.929022) (xy 11.955694 -392.884879) (xy 11.928398 -392.836244) (xy 11.908475 -392.784153)
			(xy 11.896349 -392.729716) (xy 11.892278 -392.674094) (xy 11.049477 -392.674094) (xy 11.038629 -392.707497)
			(xy 11.012702 -392.758401) (xy 10.979132 -392.804624) (xy 10.959338 -392.825224) (xy 9.755886 -394.028676)
			(xy 12.113766 -394.028676) (xy 12.117837 -393.973054) (xy 12.129963 -393.918617) (xy 12.149886 -393.866526)
			(xy 12.177182 -393.817891) (xy 12.211268 -393.773748) (xy 12.251417 -393.735039) (xy 12.296775 -393.702588)
			(xy 12.346375 -393.677087) (xy 12.399159 -393.65908) (xy 12.454002 -393.64895) (xy 12.509736 -393.646913)
			(xy 12.565173 -393.653013) (xy 12.61913 -393.667119) (xy 12.670459 -393.688931) (xy 12.718065 -393.717985)
			(xy 12.760933 -393.75366) (xy 12.79815 -393.795197) (xy 12.828923 -393.84171) (xy 12.852595 -393.892207)
			(xy 12.868663 -393.945614) (xy 12.876783 -394.00079) (xy 12.877292 -394.028676) (xy 12.877028 -394.043154)
			(xy 13.681962 -394.043154) (xy 13.686033 -393.987532) (xy 13.698159 -393.933095) (xy 13.718082 -393.881004)
			(xy 13.745378 -393.832369) (xy 13.779464 -393.788226) (xy 13.819613 -393.749517) (xy 13.864971 -393.717066)
			(xy 13.914571 -393.691565) (xy 13.967355 -393.673558) (xy 14.022198 -393.663428) (xy 14.077932 -393.661391)
			(xy 14.133369 -393.667491) (xy 14.187326 -393.681597) (xy 14.238655 -393.703409) (xy 14.286261 -393.732463)
			(xy 14.329129 -393.768138) (xy 14.366346 -393.809675) (xy 14.397119 -393.856188) (xy 14.420791 -393.906685)
			(xy 14.436859 -393.960092) (xy 14.444979 -394.015268) (xy 14.445488 -394.043154) (xy 14.444979 -394.07104)
			(xy 14.436859 -394.126216) (xy 14.420791 -394.179623) (xy 14.397119 -394.23012) (xy 14.366346 -394.276633)
			(xy 14.329129 -394.31817) (xy 14.286261 -394.353845) (xy 14.238655 -394.382899) (xy 14.187326 -394.404711)
			(xy 14.133369 -394.418817) (xy 14.077932 -394.424917) (xy 14.022198 -394.42288) (xy 13.967355 -394.41275)
			(xy 13.914571 -394.394743) (xy 13.864971 -394.369242) (xy 13.819613 -394.336791) (xy 13.779464 -394.298082)
			(xy 13.745378 -394.253939) (xy 13.718082 -394.205304) (xy 13.698159 -394.153213) (xy 13.686033 -394.098776)
			(xy 13.681962 -394.043154) (xy 12.877028 -394.043154) (xy 12.876783 -394.056562) (xy 12.868663 -394.111738)
			(xy 12.852595 -394.165145) (xy 12.828923 -394.215642) (xy 12.79815 -394.262155) (xy 12.760933 -394.303692)
			(xy 12.718065 -394.339367) (xy 12.670459 -394.368421) (xy 12.61913 -394.390233) (xy 12.565173 -394.404339)
			(xy 12.509736 -394.410439) (xy 12.454002 -394.408402) (xy 12.399159 -394.398272) (xy 12.346375 -394.380265)
			(xy 12.296775 -394.354764) (xy 12.251417 -394.322313) (xy 12.211268 -394.283604) (xy 12.177182 -394.239461)
			(xy 12.149886 -394.190826) (xy 12.129963 -394.138735) (xy 12.117837 -394.084298) (xy 12.113766 -394.028676)
			(xy 9.755886 -394.028676) (xy 8.821674 -394.962888) (xy 12.04036 -394.962888) (xy 12.044431 -394.907266)
			(xy 12.056557 -394.852829) (xy 12.07648 -394.800738) (xy 12.103776 -394.752103) (xy 12.137862 -394.70796)
			(xy 12.178011 -394.669251) (xy 12.223369 -394.6368) (xy 12.272969 -394.611299) (xy 12.325753 -394.593292)
			(xy 12.380596 -394.583162) (xy 12.43633 -394.581125) (xy 12.491767 -394.587225) (xy 12.545724 -394.601331)
			(xy 12.597053 -394.623143) (xy 12.644659 -394.652197) (xy 12.687527 -394.687872) (xy 12.724744 -394.729409)
			(xy 12.755517 -394.775922) (xy 12.779189 -394.826419) (xy 12.795257 -394.879826) (xy 12.803377 -394.935002)
			(xy 12.803886 -394.962888) (xy 12.803377 -394.990774) (xy 12.795257 -395.04595) (xy 12.779189 -395.099357)
			(xy 12.755517 -395.149854) (xy 12.724744 -395.196367) (xy 12.687527 -395.237904) (xy 12.644659 -395.273579)
			(xy 12.597053 -395.302633) (xy 12.545724 -395.324445) (xy 12.491767 -395.338551) (xy 12.43633 -395.344651)
			(xy 12.380596 -395.342614) (xy 12.325753 -395.332484) (xy 12.272969 -395.314477) (xy 12.223369 -395.288976)
			(xy 12.178011 -395.256525) (xy 12.137862 -395.217816) (xy 12.103776 -395.173673) (xy 12.07648 -395.125038)
			(xy 12.056557 -395.072947) (xy 12.044431 -395.01851) (xy 12.04036 -394.962888) (xy 8.821674 -394.962888)
			(xy 7.723632 -396.06093) (xy 12.002514 -396.06093) (xy 12.006585 -396.005308) (xy 12.018711 -395.950871)
			(xy 12.038634 -395.89878) (xy 12.06593 -395.850145) (xy 12.100016 -395.806002) (xy 12.140165 -395.767293)
			(xy 12.185523 -395.734842) (xy 12.235123 -395.709341) (xy 12.287907 -395.691334) (xy 12.34275 -395.681204)
			(xy 12.398484 -395.679167) (xy 12.453921 -395.685267) (xy 12.507878 -395.699373) (xy 12.559207 -395.721185)
			(xy 12.606813 -395.750239) (xy 12.649681 -395.785914) (xy 12.686898 -395.827451) (xy 12.717671 -395.873964)
			(xy 12.741343 -395.924461) (xy 12.757411 -395.977868) (xy 12.765531 -396.033044) (xy 12.76604 -396.06093)
			(xy 12.765531 -396.088816) (xy 12.757411 -396.143992) (xy 12.741343 -396.197399) (xy 12.717671 -396.247896)
			(xy 12.686898 -396.294409) (xy 12.649681 -396.335946) (xy 12.606813 -396.371621) (xy 12.559207 -396.400675)
			(xy 12.507878 -396.422487) (xy 12.453921 -396.436593) (xy 12.398484 -396.442693) (xy 12.34275 -396.440656)
			(xy 12.287907 -396.430526) (xy 12.235123 -396.412519) (xy 12.185523 -396.387018) (xy 12.140165 -396.354567)
			(xy 12.100016 -396.315858) (xy 12.06593 -396.271715) (xy 12.038634 -396.22308) (xy 12.018711 -396.170989)
			(xy 12.006585 -396.116552) (xy 12.002514 -396.06093) (xy 7.723632 -396.06093) (xy 4.715256 -399.069306)
			(xy 4.708484 -399.076733) (xy 4.700899 -399.095329) (xy 4.700524 -399.105374) (xy 4.700524 -402.56079)
			(xy 11.742672 -402.56079) (xy 11.746743 -402.505168) (xy 11.758869 -402.450731) (xy 11.778792 -402.39864)
			(xy 11.806088 -402.350005) (xy 11.840174 -402.305862) (xy 11.880323 -402.267153) (xy 11.925681 -402.234702)
			(xy 11.975281 -402.209201) (xy 12.028065 -402.191194) (xy 12.082908 -402.181064) (xy 12.138642 -402.179027)
			(xy 12.194079 -402.185127) (xy 12.248036 -402.199233) (xy 12.299365 -402.221045) (xy 12.346971 -402.250099)
			(xy 12.389839 -402.285774) (xy 12.427056 -402.327311) (xy 12.457829 -402.373824) (xy 12.481501 -402.424321)
			(xy 12.497569 -402.477728) (xy 12.505689 -402.532904) (xy 12.506198 -402.56079) (xy 12.505689 -402.588676)
			(xy 12.497569 -402.643852) (xy 12.481501 -402.697259) (xy 12.457829 -402.747756) (xy 12.427056 -402.794269)
			(xy 12.389839 -402.835806) (xy 12.346971 -402.871481) (xy 12.299365 -402.900535) (xy 12.248036 -402.922347)
			(xy 12.194079 -402.936453) (xy 12.138642 -402.942553) (xy 12.082908 -402.940516) (xy 12.028065 -402.930386)
			(xy 11.975281 -402.912379) (xy 11.925681 -402.886878) (xy 11.880323 -402.854427) (xy 11.840174 -402.815718)
			(xy 11.806088 -402.771575) (xy 11.778792 -402.72294) (xy 11.758869 -402.670849) (xy 11.746743 -402.616412)
			(xy 11.742672 -402.56079) (xy 4.700524 -402.56079) (xy 4.700524 -402.726906) (xy 4.700949 -402.736975)
			(xy 4.708667 -402.755576) (xy 4.71551 -402.762974) (xy 6.169406 -404.21687) (xy 9.284714 -404.21687)
			(xy 9.288785 -404.161248) (xy 9.300911 -404.106811) (xy 9.320834 -404.05472) (xy 9.34813 -404.006085)
			(xy 9.382216 -403.961942) (xy 9.422365 -403.923233) (xy 9.467723 -403.890782) (xy 9.517323 -403.865281)
			(xy 9.570107 -403.847274) (xy 9.62495 -403.837144) (xy 9.680684 -403.835107) (xy 9.736121 -403.841207)
			(xy 9.789546 -403.855174) (xy 11.803124 -403.855174) (xy 11.807195 -403.799552) (xy 11.819321 -403.745115)
			(xy 11.839244 -403.693024) (xy 11.86654 -403.644389) (xy 11.900626 -403.600246) (xy 11.940775 -403.561537)
			(xy 11.986133 -403.529086) (xy 12.035733 -403.503585) (xy 12.088517 -403.485578) (xy 12.14336 -403.475448)
			(xy 12.199094 -403.473411) (xy 12.254531 -403.479511) (xy 12.308488 -403.493617) (xy 12.359817 -403.515429)
			(xy 12.407423 -403.544483) (xy 12.450291 -403.580158) (xy 12.487508 -403.621695) (xy 12.518281 -403.668208)
			(xy 12.541953 -403.718705) (xy 12.558021 -403.772112) (xy 12.566141 -403.827288) (xy 12.56665 -403.855174)
			(xy 12.566141 -403.88306) (xy 12.558021 -403.938236) (xy 12.541953 -403.991643) (xy 12.518281 -404.04214)
			(xy 12.487508 -404.088653) (xy 12.450291 -404.13019) (xy 12.407423 -404.165865) (xy 12.359817 -404.194919)
			(xy 12.308488 -404.216731) (xy 12.254531 -404.230837) (xy 12.199094 -404.236937) (xy 12.14336 -404.2349)
			(xy 12.088517 -404.22477) (xy 12.035733 -404.206763) (xy 11.986133 -404.181262) (xy 11.940775 -404.148811)
			(xy 11.900626 -404.110102) (xy 11.86654 -404.065959) (xy 11.839244 -404.017324) (xy 11.819321 -403.965233)
			(xy 11.807195 -403.910796) (xy 11.803124 -403.855174) (xy 9.789546 -403.855174) (xy 9.790078 -403.855313)
			(xy 9.841407 -403.877125) (xy 9.889013 -403.906179) (xy 9.931881 -403.941854) (xy 9.969098 -403.983391)
			(xy 9.999871 -404.029904) (xy 10.023543 -404.080401) (xy 10.039611 -404.133808) (xy 10.047731 -404.188984)
			(xy 10.04824 -404.21687) (xy 10.047731 -404.244756) (xy 10.039611 -404.299932) (xy 10.023543 -404.353339)
			(xy 9.999871 -404.403836) (xy 9.969098 -404.450349) (xy 9.931881 -404.491886) (xy 9.889013 -404.527561)
			(xy 9.841407 -404.556615) (xy 9.790078 -404.578427) (xy 9.736121 -404.592533) (xy 9.680684 -404.598633)
			(xy 9.62495 -404.596596) (xy 9.570107 -404.586466) (xy 9.517323 -404.568459) (xy 9.467723 -404.542958)
			(xy 9.422365 -404.510507) (xy 9.382216 -404.471798) (xy 9.34813 -404.427655) (xy 9.320834 -404.37902)
			(xy 9.300911 -404.326929) (xy 9.288785 -404.272492) (xy 9.284714 -404.21687) (xy 6.169406 -404.21687)
			(xy 6.66369 -404.711154) (xy 6.671086 -404.718007) (xy 6.689684 -404.725752) (xy 6.699758 -404.72614)
			(xy 9.371076 -404.72614) (xy 9.399653 -404.726685) (xy 9.456101 -404.735656) (xy 9.510449 -404.753348)
			(xy 9.561359 -404.779327) (xy 9.607578 -404.812951) (xy 9.628124 -404.83282) (xy 10.208006 -405.412702)
			(xy 10.227801 -405.433303) (xy 10.261369 -405.479529) (xy 10.2873 -405.530433) (xy 10.304959 -405.584763)
			(xy 10.31391 -405.641186) (xy 10.314432 -405.66975) (xy 10.314432 -405.929846) (xy 13.447268 -405.929846)
			(xy 13.447268 -396.932912) (xy 13.4479 -396.907929) (xy 13.457637 -396.858922) (xy 13.476738 -396.812752)
			(xy 13.504471 -396.771191) (xy 13.52169 -396.75308) (xy 16.480282 -393.794488) (xy 16.485616 -393.762484)
			(xy 16.478504 -393.748006) (xy 16.466518 -393.722022) (xy 16.449648 -393.667343) (xy 16.441145 -393.610756)
			(xy 16.440658 -393.582144) (xy 16.441144 -393.554893) (xy 16.4489 -393.500945) (xy 16.464255 -393.44865)
			(xy 16.486897 -393.399073) (xy 16.516363 -393.353223) (xy 16.552054 -393.312032) (xy 16.593245 -393.276341)
			(xy 16.639095 -393.246875) (xy 16.688672 -393.224233) (xy 16.740967 -393.208878) (xy 16.794915 -393.201122)
			(xy 16.849417 -393.201122) (xy 16.903365 -393.208878) (xy 16.95566 -393.224233) (xy 17.005237 -393.246875)
			(xy 17.051087 -393.276341) (xy 17.092278 -393.312032) (xy 17.127969 -393.353223) (xy 17.157435 -393.399073)
			(xy 17.180077 -393.44865) (xy 17.189889 -393.482068) (xy 23.315166 -393.482068) (xy 23.319237 -393.426446)
			(xy 23.331363 -393.372009) (xy 23.351286 -393.319918) (xy 23.378582 -393.271283) (xy 23.412668 -393.22714)
			(xy 23.452817 -393.188431) (xy 23.498175 -393.15598) (xy 23.547775 -393.130479) (xy 23.600559 -393.112472)
			(xy 23.655402 -393.102342) (xy 23.711136 -393.100305) (xy 23.766573 -393.106405) (xy 23.82053 -393.120511)
			(xy 23.871859 -393.142323) (xy 23.919465 -393.171377) (xy 23.962333 -393.207052) (xy 23.99955 -393.248589)
			(xy 24.030323 -393.295102) (xy 24.053995 -393.345599) (xy 24.070063 -393.399006) (xy 24.078183 -393.454182)
			(xy 24.078692 -393.482068) (xy 24.078183 -393.509954) (xy 24.070063 -393.56513) (xy 24.053995 -393.618537)
			(xy 24.030323 -393.669034) (xy 23.99955 -393.715547) (xy 23.962333 -393.757084) (xy 23.919465 -393.792759)
			(xy 23.871859 -393.821813) (xy 23.82053 -393.843625) (xy 23.766573 -393.857731) (xy 23.711136 -393.863831)
			(xy 23.655402 -393.861794) (xy 23.600559 -393.851664) (xy 23.547775 -393.833657) (xy 23.498175 -393.808156)
			(xy 23.452817 -393.775705) (xy 23.412668 -393.736996) (xy 23.378582 -393.692853) (xy 23.351286 -393.644218)
			(xy 23.331363 -393.592127) (xy 23.319237 -393.53769) (xy 23.315166 -393.482068) (xy 17.189889 -393.482068)
			(xy 17.195432 -393.500945) (xy 17.203188 -393.554893) (xy 17.203674 -393.582144) (xy 17.20323 -393.608522)
			(xy 17.195985 -393.660777) (xy 17.181613 -393.711536) (xy 17.160387 -393.759833) (xy 17.132712 -393.804745)
			(xy 17.099114 -393.845419) (xy 17.079976 -393.863576) (xy 17.075054 -393.868281) (xy 17.067712 -393.879742)
			(xy 17.065498 -393.886182) (xy 17.05905 -393.905965) (xy 17.040648 -393.943278) (xy 17.016414 -393.977096)
			(xy 17.001998 -393.9921) (xy 16.683646 -394.310452) (xy 22.100762 -394.310452) (xy 22.100762 -394.255948)
			(xy 22.108518 -394.201998) (xy 22.123874 -394.149702) (xy 22.146516 -394.100123) (xy 22.175983 -394.054271)
			(xy 22.211675 -394.013079) (xy 22.252866 -393.977386) (xy 22.298718 -393.947918) (xy 22.348296 -393.925276)
			(xy 22.400593 -393.90992) (xy 22.454542 -393.902162) (xy 22.481794 -393.901676) (xy 22.510712 -393.90217)
			(xy 22.567886 -393.9109) (xy 22.623086 -393.928161) (xy 22.675049 -393.953557) (xy 22.722582 -393.986506)
			(xy 22.764596 -394.026253) (xy 22.782784 -394.048742) (xy 22.79035 -394.057499) (xy 22.811106 -394.067683)
			(xy 22.822662 -394.0683) (xy 22.902926 -394.0683) (xy 22.914488 -394.067687) (xy 22.93526 -394.057523)
			(xy 22.942804 -394.048742) (xy 22.961003 -394.026265) (xy 23.00302 -393.986528) (xy 23.050553 -393.953587)
			(xy 23.102513 -393.928197) (xy 23.157709 -393.91094) (xy 23.214878 -393.902211) (xy 23.243794 -393.901676)
			(xy 23.271046 -393.902171) (xy 23.324995 -393.909927) (xy 23.377292 -393.925282) (xy 23.42687 -393.947923)
			(xy 23.472722 -393.97739) (xy 23.513914 -394.013082) (xy 23.549607 -394.054273) (xy 23.579074 -394.100124)
			(xy 23.601716 -394.149703) (xy 23.617072 -394.201999) (xy 23.624829 -394.255948) (xy 23.624829 -394.310452)
			(xy 23.617072 -394.364401) (xy 23.601716 -394.416697) (xy 23.579074 -394.466276) (xy 23.549607 -394.512127)
			(xy 23.513914 -394.553318) (xy 23.472722 -394.58901) (xy 23.42687 -394.618477) (xy 23.377292 -394.641118)
			(xy 23.324995 -394.656473) (xy 23.271046 -394.664229) (xy 23.243794 -394.664692) (xy 23.214877 -394.664181)
			(xy 23.157705 -394.655451) (xy 23.102506 -394.638191) (xy 23.050544 -394.612799) (xy 23.003011 -394.579854)
			(xy 22.960994 -394.540112) (xy 22.942804 -394.517626) (xy 22.935249 -394.508858) (xy 22.914484 -394.498681)
			(xy 22.902926 -394.498068) (xy 22.822662 -394.498068) (xy 22.811095 -394.49865) (xy 22.790322 -394.508834)
			(xy 22.782784 -394.517626) (xy 22.764609 -394.540123) (xy 22.722585 -394.579856) (xy 22.675046 -394.612792)
			(xy 22.623082 -394.638178) (xy 22.567882 -394.655432) (xy 22.510711 -394.664158) (xy 22.481794 -394.664692)
			(xy 22.454542 -394.664238) (xy 22.400593 -394.65648) (xy 22.348296 -394.641124) (xy 22.298718 -394.618482)
			(xy 22.252866 -394.589014) (xy 22.211675 -394.553321) (xy 22.175983 -394.512129) (xy 22.146516 -394.466277)
			(xy 22.123874 -394.416698) (xy 22.108518 -394.364402) (xy 22.100762 -394.310452) (xy 16.683646 -394.310452)
			(xy 15.029434 -395.964664) (xy 19.52498 -395.964664) (xy 19.525465 -395.937331) (xy 19.533271 -395.883225)
			(xy 19.548717 -395.830786) (xy 19.571488 -395.781088) (xy 19.601118 -395.735148) (xy 19.618706 -395.71422)
			(xy 19.61896 -395.713966) (xy 19.619214 -395.713712) (xy 19.624803 -395.706627) (xy 19.631048 -395.689709)
			(xy 19.631406 -395.680692) (xy 19.631406 -395.613636) (xy 19.631031 -395.604621) (xy 19.624796 -395.587704)
			(xy 19.619214 -395.580616) (xy 19.61896 -395.580362) (xy 19.618706 -395.580108) (xy 19.601105 -395.559189)
			(xy 19.571468 -395.51325) (xy 19.548693 -395.463551) (xy 19.533247 -395.411109) (xy 19.525447 -395.356999)
			(xy 19.52498 -395.329664) (xy 19.525466 -395.302413) (xy 19.533222 -395.248465) (xy 19.548577 -395.19617)
			(xy 19.571219 -395.146593) (xy 19.600685 -395.100743) (xy 19.636376 -395.059552) (xy 19.677567 -395.023861)
			(xy 19.723417 -394.994395) (xy 19.772994 -394.971753) (xy 19.825289 -394.956398) (xy 19.879237 -394.948642)
			(xy 19.933739 -394.948642) (xy 19.987687 -394.956398) (xy 20.039982 -394.971753) (xy 20.089559 -394.994395)
			(xy 20.135409 -395.023861) (xy 20.1766 -395.059552) (xy 20.212291 -395.100743) (xy 20.241757 -395.146593)
			(xy 20.264399 -395.19617) (xy 20.279754 -395.248465) (xy 20.28751 -395.302413) (xy 20.287996 -395.329664)
			(xy 20.287533 -395.356998) (xy 20.279723 -395.411105) (xy 20.264272 -395.463544) (xy 20.241495 -395.513242)
			(xy 20.21186 -395.559181) (xy 20.19427 -395.580108) (xy 20.194016 -395.580362) (xy 20.193762 -395.580616)
			(xy 20.188158 -395.587691) (xy 20.181923 -395.604617) (xy 20.18157 -395.613636) (xy 20.18157 -395.680692)
			(xy 20.181937 -395.689708) (xy 20.188179 -395.706624) (xy 20.193762 -395.713712) (xy 20.194016 -395.713966)
			(xy 20.19427 -395.71422) (xy 20.211881 -395.735131) (xy 20.241517 -395.781072) (xy 20.264291 -395.830773)
			(xy 20.279734 -395.883217) (xy 20.287531 -395.937329) (xy 20.287996 -395.964664) (xy 20.28751 -395.991915)
			(xy 20.279754 -396.045863) (xy 20.264399 -396.098158) (xy 20.241757 -396.147735) (xy 20.212291 -396.193585)
			(xy 20.1766 -396.234776) (xy 20.135409 -396.270467) (xy 20.089559 -396.299933) (xy 20.039982 -396.322575)
			(xy 19.987687 -396.33793) (xy 19.933739 -396.345686) (xy 19.879237 -396.345686) (xy 19.825289 -396.33793)
			(xy 19.772994 -396.322575) (xy 19.723417 -396.299933) (xy 19.677567 -396.270467) (xy 19.636376 -396.234776)
			(xy 19.600685 -396.193585) (xy 19.571219 -396.147735) (xy 19.548577 -396.098158) (xy 19.533222 -396.045863)
			(xy 19.525466 -395.991915) (xy 19.52498 -395.964664) (xy 15.029434 -395.964664) (xy 13.970762 -397.023336)
			(xy 13.963908 -397.030725) (xy 13.956198 -397.049333) (xy 13.955776 -397.059404) (xy 13.955776 -398.878552)
			(xy 19.56308 -398.878552) (xy 19.563558 -398.851219) (xy 19.571365 -398.797112) (xy 19.586813 -398.744673)
			(xy 19.609586 -398.694976) (xy 19.639218 -398.649036) (xy 19.656806 -398.628108) (xy 19.65706 -398.627854)
			(xy 19.657314 -398.6276) (xy 19.662908 -398.620519) (xy 19.66915 -398.603598) (xy 19.669506 -398.59458)
			(xy 19.669506 -398.527524) (xy 19.669136 -398.518508) (xy 19.662897 -398.501591) (xy 19.657314 -398.494504)
			(xy 19.65706 -398.49425) (xy 19.656806 -398.493996) (xy 19.639199 -398.473082) (xy 19.609563 -398.427142)
			(xy 19.586789 -398.377441) (xy 19.571345 -398.324998) (xy 19.563546 -398.270887) (xy 19.56308 -398.243552)
			(xy 19.563499 -398.217882) (xy 19.570385 -398.167007) (xy 19.584026 -398.117513) (xy 19.604176 -398.070293)
			(xy 19.630472 -398.026199) (xy 19.662439 -397.986026) (xy 19.680682 -397.967962) (xy 19.687823 -397.960475)
			(xy 19.695948 -397.941467) (xy 19.69643 -397.931132) (xy 19.69643 -397.858234) (xy 19.695996 -397.84789)
			(xy 19.68785 -397.828876) (xy 19.680682 -397.821404) (xy 19.662461 -397.803318) (xy 19.630484 -397.763154)
			(xy 19.604181 -397.719066) (xy 19.584026 -397.67185) (xy 19.570383 -397.622358) (xy 19.563498 -397.571483)
			(xy 19.56308 -397.545814) (xy 19.563536 -397.51848) (xy 19.571348 -397.464372) (xy 19.586802 -397.411933)
			(xy 19.60958 -397.362236) (xy 19.639215 -397.316297) (xy 19.656806 -397.29537) (xy 19.65706 -397.295116)
			(xy 19.657314 -397.294862) (xy 19.662882 -397.287763) (xy 19.66914 -397.270856) (xy 19.669506 -397.261842)
			(xy 19.669506 -397.194786) (xy 19.669154 -397.185769) (xy 19.662903 -397.168852) (xy 19.657314 -397.161766)
			(xy 19.65706 -397.161512) (xy 19.656806 -397.161258) (xy 19.639228 -397.14032) (xy 19.609587 -397.094387)
			(xy 19.586808 -397.044692) (xy 19.571357 -396.992254) (xy 19.56355 -396.938147) (xy 19.56308 -396.910814)
			(xy 19.563566 -396.883563) (xy 19.571322 -396.829615) (xy 19.586677 -396.77732) (xy 19.609319 -396.727743)
			(xy 19.638785 -396.681893) (xy 19.674476 -396.640702) (xy 19.715667 -396.605011) (xy 19.761517 -396.575545)
			(xy 19.811094 -396.552903) (xy 19.863389 -396.537548) (xy 19.917337 -396.529792) (xy 19.971839 -396.529792)
			(xy 20.025787 -396.537548) (xy 20.078082 -396.552903) (xy 20.127659 -396.575545) (xy 20.173509 -396.605011)
			(xy 20.2147 -396.640702) (xy 20.250391 -396.681893) (xy 20.279857 -396.727743) (xy 20.302499 -396.77732)
			(xy 20.317854 -396.829615) (xy 20.32561 -396.883563) (xy 20.326096 -396.910814) (xy 20.325604 -396.938147)
			(xy 20.317801 -396.992253) (xy 20.302356 -397.044692) (xy 20.279587 -397.09439) (xy 20.249957 -397.14033)
			(xy 20.23237 -397.161258) (xy 20.232116 -397.161512) (xy 20.231862 -397.161766) (xy 20.226279 -397.168855)
			(xy 20.220031 -397.18577) (xy 20.21967 -397.194786) (xy 20.21967 -397.261842) (xy 20.220061 -397.270855)
			(xy 20.226286 -397.287772) (xy 20.231862 -397.294862) (xy 20.232116 -397.295116) (xy 20.23237 -397.29537)
			(xy 20.249957 -397.3163) (xy 20.279597 -397.362235) (xy 20.302375 -397.411932) (xy 20.317824 -397.464372)
			(xy 20.325628 -397.51848) (xy 20.326096 -397.545814) (xy 20.325662 -397.571483) (xy 20.31878 -397.622359)
			(xy 20.305143 -397.671853) (xy 20.284995 -397.719073) (xy 20.258702 -397.763167) (xy 20.226736 -397.80334)
			(xy 20.208494 -397.821404) (xy 20.201365 -397.8289) (xy 20.193234 -397.847901) (xy 20.192746 -397.858234)
			(xy 20.192746 -397.931132) (xy 20.193205 -397.941473) (xy 20.201335 -397.960486) (xy 20.208494 -397.967962)
			(xy 20.226761 -397.986003) (xy 20.258731 -398.026178) (xy 20.285026 -398.070276) (xy 20.305172 -398.117501)
			(xy 20.318807 -398.167) (xy 20.325682 -398.217881) (xy 20.326096 -398.243552) (xy 20.325527 -398.273028)
			(xy 20.316465 -398.33128) (xy 20.29855 -398.387445) (xy 20.272207 -398.440185) (xy 20.238064 -398.488244)
			(xy 20.217892 -398.509744) (xy 20.212769 -398.515325) (xy 20.205782 -398.528757) (xy 20.204176 -398.53616)
			(xy 20.203414 -398.545304) (xy 20.203414 -398.5768) (xy 20.204176 -398.585944) (xy 20.205853 -398.593325)
			(xy 20.212807 -398.606756) (xy 20.217892 -398.61236) (xy 20.231354 -398.627092) (xy 20.238974 -398.635728)
			(xy 20.259802 -398.644872) (xy 20.362164 -398.641316) (xy 20.38223 -398.630902) (xy 20.389088 -398.621758)
			(xy 20.407229 -398.598733) (xy 20.449382 -398.558002) (xy 20.497271 -398.524202) (xy 20.549769 -398.498128)
			(xy 20.605639 -398.480395) (xy 20.663564 -398.471421) (xy 20.692872 -398.470882) (xy 20.721896 -398.471416)
			(xy 20.779271 -398.480225) (xy 20.834649 -398.497628) (xy 20.886749 -398.523222) (xy 20.934368 -398.556417)
			(xy 20.955762 -398.576038) (xy 20.956016 -398.576292) (xy 20.95627 -398.576546) (xy 20.963567 -398.582815)
			(xy 20.981456 -398.589855) (xy 20.991068 -398.590262) (xy 21.061426 -398.590262) (xy 21.071045 -398.589901)
			(xy 21.088936 -398.582835) (xy 21.096224 -398.576546) (xy 21.096478 -398.576292) (xy 21.096732 -398.576038)
			(xy 21.118126 -398.556417) (xy 21.165742 -398.523217) (xy 21.217842 -398.497622) (xy 21.273221 -398.480224)
			(xy 21.330598 -398.471424) (xy 21.359622 -398.470882) (xy 21.386871 -398.47139) (xy 21.440815 -398.479149)
			(xy 21.493106 -398.494505) (xy 21.542679 -398.517147) (xy 21.588525 -398.546613) (xy 21.629712 -398.582304)
			(xy 21.6654 -398.623492) (xy 21.694864 -398.66934) (xy 21.717502 -398.718915) (xy 21.732856 -398.771206)
			(xy 21.740612 -398.825151) (xy 21.740612 -398.879649) (xy 21.732856 -398.933594) (xy 21.717502 -398.985885)
			(xy 21.694864 -399.03546) (xy 21.6654 -399.081308) (xy 21.629712 -399.122496) (xy 21.588526 -399.158187)
			(xy 21.542679 -399.187653) (xy 21.493106 -399.210295) (xy 21.440815 -399.225651) (xy 21.386871 -399.23341)
			(xy 21.359622 -399.233898) (xy 21.330599 -399.233345) (xy 21.273226 -399.224538) (xy 21.217849 -399.207138)
			(xy 21.165749 -399.181549) (xy 21.118128 -399.148359) (xy 21.096732 -399.128742) (xy 21.096478 -399.128488)
			(xy 21.096224 -399.128234) (xy 21.088931 -399.12196) (xy 21.071039 -399.114923) (xy 21.061426 -399.114518)
			(xy 20.991068 -399.114518) (xy 20.981449 -399.114882) (xy 20.963559 -399.121946) (xy 20.95627 -399.128234)
			(xy 20.956016 -399.128488) (xy 20.955762 -399.128742) (xy 20.934367 -399.148362) (xy 20.886752 -399.181563)
			(xy 20.834652 -399.207159) (xy 20.779273 -399.224557) (xy 20.721896 -399.233356) (xy 20.692872 -399.233898)
			(xy 20.665813 -399.233375) (xy 20.61224 -399.22572) (xy 20.560286 -399.210568) (xy 20.510997 -399.188224)
			(xy 20.465361 -399.159136) (xy 20.424296 -399.123888) (xy 20.406106 -399.10385) (xy 20.398232 -399.09496)
			(xy 20.377658 -399.08607) (xy 20.275296 -399.089626) (xy 20.25523 -399.10004) (xy 20.248372 -399.109184)
			(xy 20.230239 -399.132216) (xy 20.188086 -399.172949) (xy 20.140196 -399.20675) (xy 20.087696 -399.232823)
			(xy 20.031824 -399.250554) (xy 19.973897 -399.259524) (xy 19.944588 -399.26006) (xy 19.917333 -399.259656)
			(xy 19.863377 -399.251896) (xy 19.811075 -399.236536) (xy 19.761492 -399.213889) (xy 19.715636 -399.184415)
			(xy 19.674442 -399.148715) (xy 19.638749 -399.107516) (xy 19.609282 -399.061656) (xy 19.586643 -399.012069)
			(xy 19.571291 -398.959764) (xy 19.56354 -398.905807) (xy 19.56308 -398.878552) (xy 13.955776 -398.878552)
			(xy 13.955776 -401.426243) (xy 19.533319 -401.426243) (xy 19.533319 -401.371737) (xy 19.541076 -401.317787)
			(xy 19.556432 -401.265489) (xy 19.579075 -401.21591) (xy 19.608543 -401.170057) (xy 19.644236 -401.128865)
			(xy 19.685428 -401.093171) (xy 19.731281 -401.063704) (xy 19.780861 -401.041062) (xy 19.833159 -401.025706)
			(xy 19.887109 -401.017949) (xy 19.914362 -401.017486) (xy 19.944485 -401.018071) (xy 20.003981 -401.027547)
			(xy 20.061249 -401.046254) (xy 20.114867 -401.073727) (xy 20.163501 -401.109284) (xy 20.185126 -401.130262)
			(xy 20.192238 -401.137628) (xy 20.211034 -401.145248) (xy 20.30349 -401.145248) (xy 20.322286 -401.137628)
			(xy 20.329398 -401.130262) (xy 20.351011 -401.109268) (xy 20.399642 -401.073699) (xy 20.453261 -401.046221)
			(xy 20.510534 -401.027516) (xy 20.570037 -401.018051) (xy 20.600162 -401.017486) (xy 20.627531 -401.017978)
			(xy 20.681709 -401.02579) (xy 20.734212 -401.041273) (xy 20.783959 -401.064109) (xy 20.829927 -401.093828)
			(xy 20.85086 -401.111466) (xy 20.857972 -401.117562) (xy 20.87499 -401.123912) (xy 20.960334 -401.123912)
			(xy 20.977352 -401.117562) (xy 20.984464 -401.111466) (xy 21.005394 -401.093825) (xy 21.051368 -401.064115)
			(xy 21.101116 -401.04128) (xy 21.153617 -401.025789) (xy 21.207793 -401.01796) (xy 21.235162 -401.017486)
			(xy 21.262416 -401.017959) (xy 21.31637 -401.025711) (xy 21.368672 -401.041064) (xy 21.418256 -401.063704)
			(xy 21.464113 -401.09317) (xy 21.50531 -401.128863) (xy 21.541007 -401.170056) (xy 21.570478 -401.215911)
			(xy 21.593123 -401.265492) (xy 21.608481 -401.317792) (xy 21.616239 -401.371746) (xy 21.616239 -401.426254)
			(xy 21.608481 -401.480208) (xy 21.593123 -401.532508) (xy 21.570478 -401.582089) (xy 21.541007 -401.627944)
			(xy 21.50531 -401.669137) (xy 21.464113 -401.70483) (xy 21.418256 -401.734296) (xy 21.368672 -401.756936)
			(xy 21.31637 -401.772289) (xy 21.262416 -401.780041) (xy 21.235162 -401.780502) (xy 21.207793 -401.779999)
			(xy 21.153616 -401.77219) (xy 21.101113 -401.75671) (xy 21.051365 -401.733876) (xy 21.005397 -401.704159)
			(xy 20.984464 -401.686522) (xy 20.977352 -401.680426) (xy 20.960334 -401.674076) (xy 20.87499 -401.674076)
			(xy 20.857972 -401.680426) (xy 20.85086 -401.686522) (xy 20.829919 -401.70415) (xy 20.783948 -401.733863)
			(xy 20.734203 -401.7567) (xy 20.681704 -401.772194) (xy 20.62753 -401.780026) (xy 20.600162 -401.780502)
			(xy 20.570039 -401.779906) (xy 20.510544 -401.770433) (xy 20.453275 -401.751729) (xy 20.399658 -401.724258)
			(xy 20.351023 -401.688703) (xy 20.329398 -401.667726) (xy 20.322286 -401.66036) (xy 20.30349 -401.65274)
			(xy 20.211034 -401.65274) (xy 20.192238 -401.66036) (xy 20.185126 -401.667726) (xy 20.1635 -401.688706)
			(xy 20.114873 -401.724277) (xy 20.061257 -401.751758) (xy 20.003986 -401.770466) (xy 19.944486 -401.779935)
			(xy 19.914362 -401.780502) (xy 19.887109 -401.780031) (xy 19.833159 -401.772274) (xy 19.780861 -401.756918)
			(xy 19.731281 -401.734276) (xy 19.685428 -401.704809) (xy 19.644236 -401.669115) (xy 19.608543 -401.627923)
			(xy 19.579075 -401.58207) (xy 19.556432 -401.532491) (xy 19.541076 -401.480193) (xy 19.533319 -401.426243)
			(xy 13.955776 -401.426243) (xy 13.955776 -403.220174) (xy 14.510764 -403.220174) (xy 14.514835 -403.164552)
			(xy 14.526961 -403.110115) (xy 14.546884 -403.058024) (xy 14.57418 -403.009389) (xy 14.608266 -402.965246)
			(xy 14.648415 -402.926537) (xy 14.693773 -402.894086) (xy 14.743373 -402.868585) (xy 14.796157 -402.850578)
			(xy 14.851 -402.840448) (xy 14.906734 -402.838411) (xy 14.962171 -402.844511) (xy 15.016128 -402.858617)
			(xy 15.067457 -402.880429) (xy 15.115063 -402.909483) (xy 15.157931 -402.945158) (xy 15.195148 -402.986695)
			(xy 15.225921 -403.033208) (xy 15.249593 -403.083705) (xy 15.265661 -403.137112) (xy 15.273781 -403.192288)
			(xy 15.27429 -403.220174) (xy 15.780764 -403.220174) (xy 15.784835 -403.164552) (xy 15.796961 -403.110115)
			(xy 15.816884 -403.058024) (xy 15.84418 -403.009389) (xy 15.878266 -402.965246) (xy 15.918415 -402.926537)
			(xy 15.963773 -402.894086) (xy 16.013373 -402.868585) (xy 16.066157 -402.850578) (xy 16.121 -402.840448)
			(xy 16.176734 -402.838411) (xy 16.232171 -402.844511) (xy 16.286128 -402.858617) (xy 16.337457 -402.880429)
			(xy 16.385063 -402.909483) (xy 16.427931 -402.945158) (xy 16.465148 -402.986695) (xy 16.495921 -403.033208)
			(xy 16.519593 -403.083705) (xy 16.535661 -403.137112) (xy 16.543781 -403.192288) (xy 16.54429 -403.220174)
			(xy 16.543781 -403.24806) (xy 16.535661 -403.303236) (xy 16.528937 -403.325584) (xy 16.923764 -403.325584)
			(xy 16.927835 -403.269962) (xy 16.939961 -403.215525) (xy 16.959884 -403.163434) (xy 16.98718 -403.114799)
			(xy 17.021266 -403.070656) (xy 17.061415 -403.031947) (xy 17.106773 -402.999496) (xy 17.156373 -402.973995)
			(xy 17.209157 -402.955988) (xy 17.264 -402.945858) (xy 17.319734 -402.943821) (xy 17.375171 -402.949921)
			(xy 17.429128 -402.964027) (xy 17.480457 -402.985839) (xy 17.528063 -403.014893) (xy 17.570931 -403.050568)
			(xy 17.608148 -403.092105) (xy 17.638921 -403.138618) (xy 17.662593 -403.189115) (xy 17.663073 -403.19071)
			(xy 18.073622 -403.19071) (xy 18.077693 -403.135088) (xy 18.089819 -403.080651) (xy 18.109742 -403.02856)
			(xy 18.137038 -402.979925) (xy 18.171124 -402.935782) (xy 18.211273 -402.897073) (xy 18.256631 -402.864622)
			(xy 18.306231 -402.839121) (xy 18.359015 -402.821114) (xy 18.413858 -402.810984) (xy 18.469592 -402.808947)
			(xy 18.525029 -402.815047) (xy 18.578986 -402.829153) (xy 18.630315 -402.850965) (xy 18.677921 -402.880019)
			(xy 18.720789 -402.915694) (xy 18.758006 -402.957231) (xy 18.788779 -403.003744) (xy 18.812451 -403.054241)
			(xy 18.828519 -403.107648) (xy 18.836639 -403.162824) (xy 18.837148 -403.19071) (xy 18.836639 -403.218596)
			(xy 18.828519 -403.273772) (xy 18.812451 -403.327179) (xy 18.788779 -403.377676) (xy 18.758006 -403.424189)
			(xy 18.720789 -403.465726) (xy 18.677921 -403.501401) (xy 18.630315 -403.530455) (xy 18.578986 -403.552267)
			(xy 18.525029 -403.566373) (xy 18.469592 -403.572473) (xy 18.413858 -403.570436) (xy 18.359015 -403.560306)
			(xy 18.306231 -403.542299) (xy 18.256631 -403.516798) (xy 18.211273 -403.484347) (xy 18.171124 -403.445638)
			(xy 18.137038 -403.401495) (xy 18.109742 -403.35286) (xy 18.089819 -403.300769) (xy 18.077693 -403.246332)
			(xy 18.073622 -403.19071) (xy 17.663073 -403.19071) (xy 17.678661 -403.242522) (xy 17.686781 -403.297698)
			(xy 17.68729 -403.325584) (xy 17.686781 -403.35347) (xy 17.678661 -403.408646) (xy 17.662593 -403.462053)
			(xy 17.638921 -403.51255) (xy 17.608148 -403.559063) (xy 17.570931 -403.6006) (xy 17.528063 -403.636275)
			(xy 17.480457 -403.665329) (xy 17.429128 -403.687141) (xy 17.375171 -403.701247) (xy 17.319734 -403.707347)
			(xy 17.264 -403.70531) (xy 17.209157 -403.69518) (xy 17.156373 -403.677173) (xy 17.106773 -403.651672)
			(xy 17.061415 -403.619221) (xy 17.021266 -403.580512) (xy 16.98718 -403.536369) (xy 16.959884 -403.487734)
			(xy 16.939961 -403.435643) (xy 16.927835 -403.381206) (xy 16.923764 -403.325584) (xy 16.528937 -403.325584)
			(xy 16.519593 -403.356643) (xy 16.495921 -403.40714) (xy 16.465148 -403.453653) (xy 16.427931 -403.49519)
			(xy 16.385063 -403.530865) (xy 16.337457 -403.559919) (xy 16.286128 -403.581731) (xy 16.232171 -403.595837)
			(xy 16.176734 -403.601937) (xy 16.121 -403.5999) (xy 16.066157 -403.58977) (xy 16.013373 -403.571763)
			(xy 15.963773 -403.546262) (xy 15.918415 -403.513811) (xy 15.878266 -403.475102) (xy 15.84418 -403.430959)
			(xy 15.816884 -403.382324) (xy 15.796961 -403.330233) (xy 15.784835 -403.275796) (xy 15.780764 -403.220174)
			(xy 15.27429 -403.220174) (xy 15.273781 -403.24806) (xy 15.265661 -403.303236) (xy 15.249593 -403.356643)
			(xy 15.225921 -403.40714) (xy 15.195148 -403.453653) (xy 15.157931 -403.49519) (xy 15.115063 -403.530865)
			(xy 15.067457 -403.559919) (xy 15.016128 -403.581731) (xy 14.962171 -403.595837) (xy 14.906734 -403.601937)
			(xy 14.851 -403.5999) (xy 14.796157 -403.58977) (xy 14.743373 -403.571763) (xy 14.693773 -403.546262)
			(xy 14.648415 -403.513811) (xy 14.608266 -403.475102) (xy 14.57418 -403.430959) (xy 14.546884 -403.382324)
			(xy 14.526961 -403.330233) (xy 14.514835 -403.275796) (xy 14.510764 -403.220174) (xy 13.955776 -403.220174)
			(xy 13.955776 -405.803354) (xy 13.956206 -405.813423) (xy 13.963921 -405.832022) (xy 13.970762 -405.839422)
			(xy 14.023848 -405.892508) (xy 14.129512 -405.997918) (xy 14.137024 -406.004779) (xy 14.155832 -406.012481)
			(xy 14.176153 -406.01224) (xy 14.185646 -406.008586) (xy 14.286738 -405.96439) (xy 14.303248 -405.938228)
			(xy 14.30274 -405.92248) (xy 14.302486 -405.907494) (xy 14.30297 -405.880669) (xy 14.310481 -405.827547)
			(xy 14.325356 -405.776) (xy 14.347301 -405.727043) (xy 14.375884 -405.681641) (xy 14.410542 -405.640687)
			(xy 14.450592 -405.604988) (xy 14.472666 -405.58974) (xy 14.475933 -405.587478) (xy 14.481803 -405.582123)
			(xy 14.48435 -405.579072) (xy 14.504162 -405.556974) (xy 15.043658 -405.017478) (xy 15.061777 -405.000266)
			(xy 15.103333 -404.972522) (xy 15.1495 -404.953411) (xy 15.198507 -404.943668) (xy 15.22349 -404.943056)
			(xy 16.24965 -404.943056) (xy 16.274634 -404.943654) (xy 16.323643 -404.953401) (xy 16.369813 -404.972512)
			(xy 16.411373 -405.000255) (xy 16.429482 -405.017478) (xy 16.568674 -405.15667) (xy 16.576023 -405.16336)
			(xy 16.594314 -405.171078) (xy 16.604234 -405.171656) (xy 16.604742 -405.171656) (xy 20.280376 -405.171656)
			(xy 20.290257 -405.170688) (xy 20.308239 -405.162332) (xy 20.321692 -405.147765) (xy 20.325588 -405.138636)
			(xy 20.326096 -405.137366) (xy 20.357338 -405.046434) (xy 20.360311 -405.036294) (xy 20.358616 -405.015256)
			(xy 20.348582 -404.996686) (xy 20.340574 -404.989792) (xy 20.318153 -404.971622) (xy 20.278554 -404.929642)
			(xy 20.245732 -404.882175) (xy 20.220436 -404.830305) (xy 20.203243 -404.775215) (xy 20.194547 -404.718165)
			(xy 20.194016 -404.68931) (xy 20.194465 -404.662056) (xy 20.202221 -404.608104) (xy 20.217577 -404.555804)
			(xy 20.24022 -404.506222) (xy 20.269689 -404.460368) (xy 20.305385 -404.419175) (xy 20.346579 -404.383481)
			(xy 20.392435 -404.354013) (xy 20.442017 -404.331372) (xy 20.494317 -404.316018) (xy 20.54827 -404.308264)
			(xy 20.575524 -404.307802) (xy 20.602259 -404.308253) (xy 20.655205 -404.315711) (xy 20.706591 -404.33049)
			(xy 20.755409 -404.352303) (xy 20.800702 -404.380719) (xy 20.841582 -404.415184) (xy 20.85975 -404.434802)
			(xy 20.870164 -404.446486) (xy 20.900644 -404.453852) (xy 21.004022 -404.414482) (xy 21.01346 -404.410398)
			(xy 21.028273 -404.396161) (xy 21.036321 -404.377257) (xy 21.036788 -404.366984) (xy 21.036788 -404.28418)
			(xy 21.037393 -404.259182) (xy 21.047204 -404.210157) (xy 21.066386 -404.163986) (xy 21.094204 -404.122442)
			(xy 21.111464 -404.104348) (xy 22.59457 -402.621242) (xy 22.601253 -402.613887) (xy 22.608975 -402.595601)
			(xy 22.609556 -402.585682) (xy 22.609556 -402.585174) (xy 22.609556 -396.443454) (xy 22.610156 -396.41847)
			(xy 22.619903 -396.369461) (xy 22.639013 -396.323292) (xy 22.666755 -396.281732) (xy 22.683978 -396.263622)
			(xy 25.365964 -393.581636) (xy 25.384044 -393.564363) (xy 25.425594 -393.536554) (xy 25.47177 -393.517385)
			(xy 25.520798 -393.507593) (xy 25.545796 -393.50696) (xy 25.614884 -393.50696) (xy 25.63368 -393.49934)
			(xy 25.640792 -393.491974) (xy 25.662406 -393.471138) (xy 25.710936 -393.435803) (xy 25.764404 -393.408508)
			(xy 25.821488 -393.389928) (xy 25.880778 -393.380521) (xy 25.910794 -393.37996) (xy 25.938045 -393.380487)
			(xy 25.991992 -393.388242) (xy 26.044286 -393.403597) (xy 26.093863 -393.426237) (xy 26.139713 -393.455702)
			(xy 26.180903 -393.491393) (xy 26.216594 -393.532582) (xy 26.24606 -393.578432) (xy 26.268701 -393.628008)
			(xy 26.284056 -393.680302) (xy 26.291813 -393.734249) (xy 26.291813 -393.788751) (xy 26.284056 -393.842698)
			(xy 26.268701 -393.894992) (xy 26.24606 -393.944568) (xy 26.216594 -393.990418) (xy 26.180903 -394.031607)
			(xy 26.139713 -394.067298) (xy 26.093863 -394.096763) (xy 26.044286 -394.119403) (xy 25.991992 -394.134758)
			(xy 25.938045 -394.142513) (xy 25.910794 -394.142976) (xy 25.88498 -394.142547) (xy 25.833826 -394.135576)
			(xy 25.784081 -394.121763) (xy 25.736657 -394.10136) (xy 25.692421 -394.074741) (xy 25.672034 -394.058902)
			(xy 25.664478 -394.053414) (xy 25.646721 -394.047698) (xy 25.628095 -394.048735) (xy 25.611082 -394.056385)
			(xy 25.604216 -394.062712) (xy 23.889208 -395.77772) (xy 28.172664 -395.77772) (xy 28.173126 -395.750349)
			(xy 28.180943 -395.69617) (xy 28.196432 -395.643666) (xy 28.219275 -395.593919) (xy 28.249001 -395.547953)
			(xy 28.266644 -395.527022) (xy 28.27274 -395.51991) (xy 28.27909 -395.502892) (xy 28.27909 -395.417548)
			(xy 28.27274 -395.40053) (xy 28.266644 -395.393418) (xy 28.249007 -395.372484) (xy 28.219293 -395.326513)
			(xy 28.196456 -395.276766) (xy 28.180965 -395.224265) (xy 28.173137 -395.170089) (xy 28.172664 -395.14272)
			(xy 28.17315 -395.115469) (xy 28.180906 -395.061521) (xy 28.196261 -395.009226) (xy 28.218903 -394.959649)
			(xy 28.248369 -394.913799) (xy 28.28406 -394.872608) (xy 28.325251 -394.836917) (xy 28.371101 -394.807451)
			(xy 28.420678 -394.784809) (xy 28.472973 -394.769454) (xy 28.526921 -394.761698) (xy 28.581423 -394.761698)
			(xy 28.635371 -394.769454) (xy 28.687666 -394.784809) (xy 28.737243 -394.807451) (xy 28.783093 -394.836917)
			(xy 28.824284 -394.872608) (xy 28.859975 -394.913799) (xy 28.889441 -394.959649) (xy 28.912083 -395.009226)
			(xy 28.927438 -395.061521) (xy 28.935194 -395.115469) (xy 28.93568 -395.14272) (xy 28.935231 -395.170091)
			(xy 28.927409 -395.224271) (xy 28.911917 -395.276774) (xy 28.889071 -395.326521) (xy 28.859343 -395.372487)
			(xy 28.8417 -395.393418) (xy 28.835604 -395.40053) (xy 28.829254 -395.417548) (xy 28.829254 -395.502892)
			(xy 28.835604 -395.51991) (xy 28.8417 -395.527022) (xy 28.859316 -395.547973) (xy 28.889031 -395.59394)
			(xy 28.911872 -395.643683) (xy 28.927368 -395.69618) (xy 28.935203 -395.750352) (xy 28.93568 -395.77772)
			(xy 28.935194 -395.804971) (xy 28.927438 -395.858919) (xy 28.912083 -395.911214) (xy 28.889441 -395.960791)
			(xy 28.859975 -396.006641) (xy 28.824284 -396.047832) (xy 28.783093 -396.083523) (xy 28.737243 -396.112989)
			(xy 28.687666 -396.135631) (xy 28.635371 -396.150986) (xy 28.581423 -396.158742) (xy 28.526921 -396.158742)
			(xy 28.472973 -396.150986) (xy 28.420678 -396.135631) (xy 28.371101 -396.112989) (xy 28.325251 -396.083523)
			(xy 28.28406 -396.047832) (xy 28.248369 -396.006641) (xy 28.218903 -395.960791) (xy 28.196261 -395.911214)
			(xy 28.180906 -395.858919) (xy 28.17315 -395.804971) (xy 28.172664 -395.77772) (xy 23.889208 -395.77772)
			(xy 23.13305 -396.533878) (xy 23.126361 -396.541228) (xy 23.118641 -396.559518) (xy 23.118064 -396.569438)
			(xy 23.118064 -396.569946) (xy 23.118064 -397.51381) (xy 28.152598 -397.51381) (xy 28.15307 -397.48644)
			(xy 28.160887 -397.432261) (xy 28.176374 -397.379758) (xy 28.199215 -397.330011) (xy 28.228938 -397.284044)
			(xy 28.246578 -397.263112) (xy 28.252674 -397.256) (xy 28.259024 -397.238982) (xy 28.259024 -397.153638)
			(xy 28.252674 -397.13662) (xy 28.246578 -397.129508) (xy 28.228926 -397.108587) (xy 28.199217 -397.06261)
			(xy 28.176384 -397.01286) (xy 28.160896 -396.960357) (xy 28.15307 -396.90618) (xy 28.152598 -396.87881)
			(xy 28.153084 -396.851559) (xy 28.16084 -396.797611) (xy 28.176195 -396.745316) (xy 28.198837 -396.695739)
			(xy 28.228303 -396.649889) (xy 28.263994 -396.608698) (xy 28.305185 -396.573007) (xy 28.351035 -396.543541)
			(xy 28.400612 -396.520899) (xy 28.452907 -396.505544) (xy 28.506855 -396.497788) (xy 28.561357 -396.497788)
			(xy 28.615305 -396.505544) (xy 28.6676 -396.520899) (xy 28.717177 -396.543541) (xy 28.763027 -396.573007)
			(xy 28.804218 -396.608698) (xy 28.839909 -396.649889) (xy 28.869375 -396.695739) (xy 28.892017 -396.745316)
			(xy 28.907372 -396.797611) (xy 28.915128 -396.851559) (xy 28.915614 -396.87881) (xy 28.91515 -396.90618)
			(xy 28.907331 -396.960359) (xy 28.891842 -397.012862) (xy 28.868999 -397.062609) (xy 28.839275 -397.108576)
			(xy 28.821634 -397.129508) (xy 28.815538 -397.13662) (xy 28.809188 -397.153638) (xy 28.809188 -397.238982)
			(xy 28.815538 -397.256) (xy 28.821634 -397.263112) (xy 28.839251 -397.284062) (xy 28.868965 -397.33003)
			(xy 28.891804 -397.379773) (xy 28.907301 -397.43227) (xy 28.915136 -397.486442) (xy 28.915614 -397.51381)
			(xy 28.915128 -397.541061) (xy 28.907372 -397.595009) (xy 28.892017 -397.647304) (xy 28.869375 -397.696881)
			(xy 28.839909 -397.742731) (xy 28.804218 -397.783922) (xy 28.763027 -397.819613) (xy 28.717177 -397.849079)
			(xy 28.6676 -397.871721) (xy 28.615305 -397.887076) (xy 28.561357 -397.894832) (xy 28.506855 -397.894832)
			(xy 28.452907 -397.887076) (xy 28.400612 -397.871721) (xy 28.351035 -397.849079) (xy 28.305185 -397.819613)
			(xy 28.263994 -397.783922) (xy 28.228303 -397.742731) (xy 28.198837 -397.696881) (xy 28.176195 -397.647304)
			(xy 28.16084 -397.595009) (xy 28.153084 -397.541061) (xy 28.152598 -397.51381) (xy 23.118064 -397.51381)
			(xy 23.118064 -400.48307) (xy 23.694136 -400.48307) (xy 23.694576 -400.455699) (xy 23.702399 -400.401518)
			(xy 23.717893 -400.349014) (xy 23.740741 -400.299268) (xy 23.770472 -400.253303) (xy 23.788116 -400.232372)
			(xy 23.794212 -400.22526) (xy 23.800562 -400.208242) (xy 23.800562 -400.122898) (xy 23.794212 -400.10588)
			(xy 23.788116 -400.098768) (xy 23.770498 -400.077819) (xy 23.740782 -400.031851) (xy 23.717942 -399.982108)
			(xy 23.702446 -399.929611) (xy 23.694613 -399.875438) (xy 23.694136 -399.84807) (xy 23.694527 -399.820814)
			(xy 23.702289 -399.766859) (xy 23.717651 -399.714557) (xy 23.740301 -399.664973) (xy 23.769776 -399.619118)
			(xy 23.805477 -399.577925) (xy 23.846678 -399.542231) (xy 23.892538 -399.512765) (xy 23.942126 -399.490125)
			(xy 23.994431 -399.474774) (xy 24.048388 -399.467022) (xy 24.075644 -399.466562) (xy 24.105766 -399.467165)
			(xy 24.165261 -399.476638) (xy 24.222529 -399.495341) (xy 24.276146 -399.52281) (xy 24.324782 -399.558362)
			(xy 24.346408 -399.579338) (xy 24.35352 -399.586704) (xy 24.372316 -399.594324) (xy 24.464772 -399.594324)
			(xy 24.483568 -399.586704) (xy 24.49068 -399.579338) (xy 24.512297 -399.558349) (xy 24.560927 -399.52278)
			(xy 24.614545 -399.495301) (xy 24.671818 -399.476595) (xy 24.731319 -399.467128) (xy 24.761444 -399.466562)
			(xy 24.788814 -399.467046) (xy 24.842993 -399.474857) (xy 24.895496 -399.490341) (xy 24.945243 -399.513179)
			(xy 24.99121 -399.542902) (xy 25.012142 -399.560542) (xy 25.019254 -399.566638) (xy 25.036272 -399.572988)
			(xy 25.121616 -399.572988) (xy 25.138634 -399.566638) (xy 25.145746 -399.560542) (xy 25.166693 -399.542921)
			(xy 25.212661 -399.513205) (xy 25.262405 -399.490365) (xy 25.314902 -399.47487) (xy 25.369076 -399.467038)
			(xy 25.396444 -399.466562) (xy 25.423695 -399.467037) (xy 25.477642 -399.474799) (xy 25.529935 -399.490158)
			(xy 25.57951 -399.512802) (xy 25.625359 -399.54227) (xy 25.666548 -399.577962) (xy 25.702239 -399.619152)
			(xy 25.731705 -399.665002) (xy 25.754347 -399.714579) (xy 25.769704 -399.766872) (xy 25.777464 -399.820819)
			(xy 25.777952 -399.84807) (xy 25.77748 -399.87544) (xy 25.769665 -399.929619) (xy 25.754178 -399.982123)
			(xy 25.731338 -400.03187) (xy 25.701613 -400.077837) (xy 25.683972 -400.098768) (xy 25.677876 -400.10588)
			(xy 25.671526 -400.122898) (xy 25.671526 -400.208242) (xy 25.677876 -400.22526) (xy 25.683972 -400.232372)
			(xy 25.701607 -400.253307) (xy 25.73132 -400.299279) (xy 25.754158 -400.349025) (xy 25.76965 -400.401526)
			(xy 25.777478 -400.455701) (xy 25.777952 -400.48307) (xy 25.777394 -400.510318) (xy 25.769643 -400.564261)
			(xy 25.754294 -400.616552) (xy 25.731659 -400.666126) (xy 25.725734 -400.675348) (xy 27.191462 -400.675348)
			(xy 27.191889 -400.64897) (xy 27.199135 -400.596713) (xy 27.21351 -400.545953) (xy 27.234739 -400.497656)
			(xy 27.262418 -400.452744) (xy 27.29602 -400.412072) (xy 27.31516 -400.393916) (xy 27.322678 -400.386475)
			(xy 27.33123 -400.367147) (xy 27.33167 -400.356578) (xy 27.33167 -400.281648) (xy 27.331059 -400.271115)
			(xy 27.322551 -400.251837) (xy 27.31516 -400.24431) (xy 27.295999 -400.226174) (xy 27.262389 -400.185504)
			(xy 27.234707 -400.140589) (xy 27.213481 -400.092288) (xy 27.199116 -400.041521) (xy 27.191887 -399.989258)
			(xy 27.191462 -399.962878) (xy 27.191948 -399.935627) (xy 27.199704 -399.881679) (xy 27.215059 -399.829384)
			(xy 27.237701 -399.779807) (xy 27.267167 -399.733957) (xy 27.302858 -399.692766) (xy 27.344049 -399.657075)
			(xy 27.389899 -399.627609) (xy 27.439476 -399.604967) (xy 27.491771 -399.589612) (xy 27.545719 -399.581856)
			(xy 27.600221 -399.581856) (xy 27.654169 -399.589612) (xy 27.706464 -399.604967) (xy 27.756041 -399.627609)
			(xy 27.801891 -399.657075) (xy 27.843082 -399.692766) (xy 27.878773 -399.733957) (xy 27.908239 -399.779807)
			(xy 27.930881 -399.829384) (xy 27.946236 -399.881679) (xy 27.953992 -399.935627) (xy 27.954478 -399.962878)
			(xy 27.954055 -399.989256) (xy 27.946806 -400.041512) (xy 27.93243 -400.092272) (xy 27.9112 -400.140569)
			(xy 27.883521 -400.185481) (xy 27.84992 -400.226153) (xy 27.83078 -400.24431) (xy 27.82331 -400.251783)
			(xy 27.814786 -400.271093) (xy 27.81427 -400.281648) (xy 27.81427 -400.356578) (xy 27.814855 -400.367114)
			(xy 27.82338 -400.386393) (xy 27.83078 -400.393916) (xy 27.849913 -400.412081) (xy 27.883524 -400.452745)
			(xy 27.911209 -400.497654) (xy 27.932439 -400.54595) (xy 27.946811 -400.596712) (xy 27.954048 -400.648969)
			(xy 27.954478 -400.675348) (xy 27.953992 -400.702599) (xy 27.946236 -400.756547) (xy 27.930881 -400.808842)
			(xy 27.908239 -400.858419) (xy 27.878773 -400.904269) (xy 27.843082 -400.94546) (xy 27.801891 -400.981151)
			(xy 27.756041 -401.010617) (xy 27.706464 -401.033259) (xy 27.654169 -401.048614) (xy 27.600221 -401.05637)
			(xy 27.545719 -401.05637) (xy 27.491771 -401.048614) (xy 27.439476 -401.033259) (xy 27.389899 -401.010617)
			(xy 27.344049 -400.981151) (xy 27.302858 -400.94546) (xy 27.267167 -400.904269) (xy 27.237701 -400.858419)
			(xy 27.215059 -400.808842) (xy 27.199704 -400.756547) (xy 27.191948 -400.702599) (xy 27.191462 -400.675348)
			(xy 25.725734 -400.675348) (xy 25.7022 -400.711974) (xy 25.666516 -400.753164) (xy 25.625334 -400.788856)
			(xy 25.579491 -400.818324) (xy 25.529921 -400.840968) (xy 25.477634 -400.856327) (xy 25.423692 -400.864089)
			(xy 25.396444 -400.864578) (xy 25.369074 -400.864092) (xy 25.314896 -400.856279) (xy 25.262393 -400.840795)
			(xy 25.212646 -400.817958) (xy 25.166678 -400.788237) (xy 25.145746 -400.770598) (xy 25.138634 -400.764502)
			(xy 25.121616 -400.758152) (xy 25.036272 -400.758152) (xy 25.019254 -400.764502) (xy 25.012142 -400.770598)
			(xy 24.991205 -400.788231) (xy 24.945233 -400.817943) (xy 24.895487 -400.840781) (xy 24.842988 -400.856273)
			(xy 24.788813 -400.864103) (xy 24.761444 -400.864578) (xy 24.731322 -400.863971) (xy 24.671828 -400.854498)
			(xy 24.614561 -400.835795) (xy 24.560943 -400.808327) (xy 24.512306 -400.772777) (xy 24.49068 -400.751802)
			(xy 24.483568 -400.744436) (xy 24.464772 -400.736816) (xy 24.372316 -400.736816) (xy 24.35352 -400.744436)
			(xy 24.346408 -400.751802) (xy 24.324803 -400.772804) (xy 24.276169 -400.808369) (xy 24.222547 -400.835845)
			(xy 24.165273 -400.854548) (xy 24.10577 -400.864013) (xy 24.075644 -400.864578) (xy 24.048391 -400.864104)
			(xy 23.994439 -400.856352) (xy 23.942139 -400.841) (xy 23.892557 -400.81836) (xy 23.846703 -400.788894)
			(xy 23.805509 -400.753201) (xy 23.769814 -400.712009) (xy 23.740346 -400.666155) (xy 23.717705 -400.616574)
			(xy 23.702351 -400.564275) (xy 23.694597 -400.510323) (xy 23.694136 -400.48307) (xy 23.118064 -400.48307)
			(xy 23.118064 -402.711666) (xy 23.11747 -402.73665) (xy 23.107721 -402.785659) (xy 23.088608 -402.831828)
			(xy 23.060865 -402.873388) (xy 23.043642 -402.891498) (xy 21.56079 -404.37435) (xy 21.553978 -404.381772)
			(xy 21.546242 -404.400355) (xy 21.545804 -404.410418) (xy 21.545804 -404.905972) (xy 21.545172 -404.930968)
			(xy 21.535369 -404.979992) (xy 21.516195 -405.026163) (xy 21.488385 -405.067709) (xy 21.471128 -405.085804)
			(xy 20.95119 -405.605742) (xy 20.933096 -405.622982) (xy 20.891531 -405.65072) (xy 20.845356 -405.669823)
			(xy 20.796343 -405.679557) (xy 20.771358 -405.680164) (xy 16.47825 -405.680164) (xy 16.453266 -405.679561)
			(xy 16.404258 -405.669814) (xy 16.358089 -405.650704) (xy 16.316528 -405.622964) (xy 16.298418 -405.605742)
			(xy 16.159226 -405.46655) (xy 16.151874 -405.459863) (xy 16.133586 -405.452142) (xy 16.123666 -405.451564)
			(xy 16.123158 -405.451564) (xy 15.825724 -405.451564) (xy 15.81524 -405.452016) (xy 15.795988 -405.460308)
			(xy 15.781685 -405.475631) (xy 15.777718 -405.485346) (xy 15.745714 -405.57577) (xy 15.742669 -405.585752)
			(xy 15.744014 -405.606558) (xy 15.753494 -405.625129) (xy 15.761208 -405.632158) (xy 15.761716 -405.632412)
			(xy 15.76197 -405.632412) (xy 15.78369 -405.650613) (xy 15.821993 -405.692376) (xy 15.853688 -405.73935)
			(xy 15.878077 -405.790501) (xy 15.894621 -405.844699) (xy 15.902957 -405.90075) (xy 15.903448 -405.929084)
			(xy 15.90299 -405.954763) (xy 15.896087 -406.005655) (xy 15.891911 -406.020778) (xy 22.643338 -406.020778)
			(xy 22.64375 -405.995078) (xy 22.65065 -405.944142) (xy 22.664322 -405.894593) (xy 22.684518 -405.847326)
			(xy 22.710874 -405.803197) (xy 22.742913 -405.763003) (xy 22.761194 -405.744934) (xy 22.768814 -405.737822)
			(xy 22.776688 -405.71928) (xy 22.777704 -405.625554) (xy 22.770084 -405.607012) (xy 22.762464 -405.599646)
			(xy 22.741488 -405.578031) (xy 22.705977 -405.529382) (xy 22.678555 -405.475756) (xy 22.659903 -405.418487)
			(xy 22.650485 -405.358998) (xy 22.649942 -405.328882) (xy 22.650387 -405.301511) (xy 22.658209 -405.247331)
			(xy 22.673702 -405.194827) (xy 22.696549 -405.14508) (xy 22.726278 -405.099115) (xy 22.743922 -405.078184)
			(xy 22.750018 -405.071072) (xy 22.756368 -405.054054) (xy 22.756368 -404.96871) (xy 22.750018 -404.951692)
			(xy 22.743922 -404.94458) (xy 22.726264 -404.923661) (xy 22.69654 -404.877691) (xy 22.673696 -404.827942)
			(xy 22.658202 -404.775438) (xy 22.650375 -404.721258) (xy 22.650377 -404.666515) (xy 22.658207 -404.612335)
			(xy 22.673706 -404.559832) (xy 22.696553 -404.510085) (xy 22.72628 -404.464117) (xy 22.743922 -404.443184)
			(xy 22.750018 -404.436072) (xy 22.756368 -404.419054) (xy 22.756368 -404.33371) (xy 22.750018 -404.316692)
			(xy 22.743922 -404.30958) (xy 22.72631 -404.288626) (xy 22.696594 -404.242659) (xy 22.673752 -404.192918)
			(xy 22.658255 -404.140422) (xy 22.65042 -404.08625) (xy 22.649942 -404.058882) (xy 22.650428 -404.031631)
			(xy 22.658184 -403.977683) (xy 22.673539 -403.925388) (xy 22.696181 -403.875811) (xy 22.725647 -403.829961)
			(xy 22.761338 -403.78877) (xy 22.802529 -403.753079) (xy 22.848379 -403.723613) (xy 22.897956 -403.700971)
			(xy 22.950251 -403.685616) (xy 23.004199 -403.67786) (xy 23.058701 -403.67786) (xy 23.112649 -403.685616)
			(xy 23.164944 -403.700971) (xy 23.214521 -403.723613) (xy 23.260371 -403.753079) (xy 23.301562 -403.78877)
			(xy 23.337253 -403.829961) (xy 23.366719 -403.875811) (xy 23.389361 -403.925388) (xy 23.404716 -403.977683)
			(xy 23.412472 -404.031631) (xy 23.412958 -404.058882) (xy 23.412492 -404.086252) (xy 23.404675 -404.140432)
			(xy 23.389187 -404.192935) (xy 23.366345 -404.242682) (xy 23.33662 -404.288649) (xy 23.318978 -404.30958)
			(xy 23.312882 -404.316692) (xy 23.306532 -404.33371) (xy 23.306532 -404.419054) (xy 23.312882 -404.436072)
			(xy 23.318978 -404.443184) (xy 23.323804 -404.448772) (xy 23.330662 -404.4569) (xy 23.34895 -404.466298)
			(xy 23.443692 -404.472394) (xy 23.462996 -404.465282) (xy 23.470616 -404.45817) (xy 23.491895 -404.439221)
			(xy 23.539032 -404.407212) (xy 23.590401 -404.382562) (xy 23.644862 -404.365818) (xy 23.701207 -404.357351)
			(xy 23.729696 -404.356824) (xy 23.759819 -404.357405) (xy 23.819314 -404.366885) (xy 23.876582 -404.385593)
			(xy 23.930199 -404.413067) (xy 23.978834 -404.448623) (xy 24.00046 -404.4696) (xy 24.007572 -404.476966)
			(xy 24.026368 -404.484586) (xy 24.118824 -404.484586) (xy 24.13762 -404.476966) (xy 24.144732 -404.4696)
			(xy 24.166364 -404.448627) (xy 24.214991 -404.413058) (xy 24.268605 -404.385577) (xy 24.325874 -404.366867)
			(xy 24.385372 -404.357393) (xy 24.415496 -404.356824) (xy 24.441793 -404.357286) (xy 24.493889 -404.364503)
			(xy 24.544499 -404.378814) (xy 24.59266 -404.399948) (xy 24.637458 -404.427503) (xy 24.678041 -404.460956)
			(xy 24.696166 -404.480014) (xy 24.703278 -404.487634) (xy 24.721566 -404.496016) (xy 24.814022 -404.499318)
			(xy 24.833072 -404.49246) (xy 24.840438 -404.485348) (xy 24.861768 -404.466081) (xy 24.909129 -404.433514)
			(xy 24.96084 -404.40842) (xy 25.01573 -404.391369) (xy 25.072557 -404.382745) (xy 25.101296 -404.382224)
			(xy 25.131419 -404.382805) (xy 25.190914 -404.392285) (xy 25.248182 -404.410993) (xy 25.301799 -404.438467)
			(xy 25.350434 -404.474023) (xy 25.37206 -404.495) (xy 25.379172 -404.502366) (xy 25.397968 -404.509986)
			(xy 25.490424 -404.509986) (xy 25.50922 -404.502366) (xy 25.516332 -404.495) (xy 25.537964 -404.474027)
			(xy 25.586591 -404.438458) (xy 25.640205 -404.410977) (xy 25.697474 -404.392267) (xy 25.756972 -404.382793)
			(xy 25.787096 -404.382224) (xy 25.81435 -404.382659) (xy 25.868304 -404.390416) (xy 25.920604 -404.405774)
			(xy 25.970186 -404.428418) (xy 26.016041 -404.457888) (xy 26.057235 -404.493585) (xy 26.092928 -404.534781)
			(xy 26.122396 -404.580638) (xy 26.145036 -404.630222) (xy 26.16039 -404.682524) (xy 26.168143 -404.736478)
			(xy 26.168604 -404.763732) (xy 26.168156 -404.791103) (xy 26.160333 -404.845283) (xy 26.14484 -404.897786)
			(xy 26.121995 -404.947532) (xy 26.092267 -404.993499) (xy 26.074624 -405.01443) (xy 26.068528 -405.021542)
			(xy 26.062178 -405.03856) (xy 26.062178 -405.123904) (xy 26.068528 -405.140922) (xy 26.074624 -405.148034)
			(xy 26.092249 -405.168977) (xy 26.121962 -405.214947) (xy 26.144801 -405.264692) (xy 26.160295 -405.31719)
			(xy 26.168127 -405.371364) (xy 26.168604 -405.398732) (xy 26.168145 -405.425093) (xy 26.160898 -405.477315)
			(xy 26.146532 -405.528043) (xy 26.125321 -405.57631) (xy 26.097669 -405.621199) (xy 26.081228 -405.64181)
			(xy 26.075132 -405.649176) (xy 26.06929 -405.666702) (xy 26.0731 -405.754078) (xy 26.080466 -405.771096)
			(xy 26.087324 -405.777954) (xy 26.107808 -405.799505) (xy 26.142506 -405.847786) (xy 26.169292 -405.900866)
			(xy 26.187517 -405.95746) (xy 26.196739 -406.016196) (xy 26.197306 -406.045924) (xy 26.196845 -406.073176)
			(xy 26.189085 -406.127125) (xy 26.173726 -406.17942) (xy 26.151082 -406.228997) (xy 26.121613 -406.274848)
			(xy 26.085919 -406.316038) (xy 26.044727 -406.351729) (xy 25.998875 -406.381195) (xy 25.949296 -406.403836)
			(xy 25.896999 -406.41919) (xy 25.84305 -406.426946) (xy 25.815798 -406.427432) (xy 25.785674 -406.426868)
			(xy 25.726177 -406.417386) (xy 25.668909 -406.398674) (xy 25.615292 -406.371196) (xy 25.566658 -406.335636)
			(xy 25.545034 -406.314656) (xy 25.537922 -406.30729) (xy 25.519126 -406.29967) (xy 25.42667 -406.29967)
			(xy 25.407874 -406.30729) (xy 25.400762 -406.314656) (xy 25.379126 -406.335624) (xy 25.330501 -406.371196)
			(xy 25.276887 -406.398679) (xy 25.219619 -406.41739) (xy 25.160122 -406.426863) (xy 25.129998 -406.427432)
			(xy 25.1037 -406.426988) (xy 25.051602 -406.419769) (xy 25.000992 -406.405455) (xy 24.952831 -406.384318)
			(xy 24.908034 -406.356759) (xy 24.867451 -406.323303) (xy 24.849328 -406.304242) (xy 24.842216 -406.296622)
			(xy 24.823928 -406.28824) (xy 24.731472 -406.284938) (xy 24.712422 -406.291796) (xy 24.705056 -406.298908)
			(xy 24.683722 -406.31817) (xy 24.636363 -406.35074) (xy 24.584653 -406.375835) (xy 24.529763 -406.392887)
			(xy 24.472937 -406.401511) (xy 24.444198 -406.402032) (xy 24.414074 -406.401468) (xy 24.354577 -406.391986)
			(xy 24.297309 -406.373274) (xy 24.243692 -406.345796) (xy 24.195058 -406.310236) (xy 24.173434 -406.289256)
			(xy 24.166322 -406.28189) (xy 24.147526 -406.27427) (xy 24.05507 -406.27427) (xy 24.036274 -406.28189)
			(xy 24.029162 -406.289256) (xy 24.007526 -406.310224) (xy 23.958901 -406.345796) (xy 23.905287 -406.373279)
			(xy 23.848019 -406.39199) (xy 23.788522 -406.401463) (xy 23.758398 -406.402032) (xy 23.730987 -406.401592)
			(xy 23.676728 -406.393743) (xy 23.624152 -406.378209) (xy 23.574342 -406.355307) (xy 23.528323 -406.325511)
			(xy 23.487043 -406.289434) (xy 23.468838 -406.268936) (xy 23.461472 -406.260554) (xy 23.441406 -406.251156)
			(xy 23.342092 -406.251156) (xy 23.321772 -406.260554) (xy 23.31466 -406.268936) (xy 23.296441 -406.28946)
			(xy 23.255134 -406.325592) (xy 23.209079 -406.355436) (xy 23.159225 -406.378377) (xy 23.106598 -406.393941)
			(xy 23.052286 -406.401807) (xy 23.024846 -406.402286) (xy 22.997593 -406.401802) (xy 22.943642 -406.394051)
			(xy 22.891343 -406.378699) (xy 22.841762 -406.35606) (xy 22.795907 -406.326595) (xy 22.754714 -406.290903)
			(xy 22.719019 -406.249712) (xy 22.689551 -406.203859) (xy 22.666909 -406.154279) (xy 22.651555 -406.101982)
			(xy 22.6438 -406.048031) (xy 22.643338 -406.020778) (xy 15.891911 -406.020778) (xy 15.882417 -406.055161)
			(xy 15.862228 -406.102384) (xy 15.835884 -406.146471) (xy 15.803863 -406.186625) (xy 15.785592 -406.204674)
			(xy 15.77848 -406.21331) (xy 15.775838 -406.217403) (xy 15.771997 -406.226353) (xy 15.77086 -406.23109)
			(xy 15.768093 -406.243337) (xy 15.76046 -406.267257) (xy 15.75562 -406.278842) (xy 15.745553 -406.300822)
			(xy 15.718455 -406.340848) (xy 15.701772 -406.358344) (xy 15.247112 -406.813004) (xy 15.235435 -406.824317)
			(xy 15.209702 -406.84419) (xy 15.195804 -406.852628) (xy 15.176176 -406.8636) (xy 15.134015 -406.879227)
			(xy 15.089761 -406.88718) (xy 15.06728 -406.88768) (xy 14.404848 -406.88768) (xy 14.38237 -406.887144)
			(xy 14.338124 -406.879177) (xy 14.295957 -406.863586) (xy 14.276324 -406.852628) (xy 14.26242 -406.844199)
			(xy 14.236691 -406.82432) (xy 14.225016 -406.813004) (xy 13.52169 -406.109678) (xy 13.50445 -406.091584)
			(xy 13.47671 -406.05002) (xy 13.457607 -406.003845) (xy 13.447874 -405.954831) (xy 13.447268 -405.929846)
			(xy 10.314432 -405.929846) (xy 10.314432 -406.627584) (xy 11.716764 -406.627584) (xy 11.720835 -406.571962)
			(xy 11.732961 -406.517525) (xy 11.752884 -406.465434) (xy 11.78018 -406.416799) (xy 11.814266 -406.372656)
			(xy 11.854415 -406.333947) (xy 11.899773 -406.301496) (xy 11.949373 -406.275995) (xy 12.002157 -406.257988)
			(xy 12.057 -406.247858) (xy 12.112734 -406.245821) (xy 12.168171 -406.251921) (xy 12.222128 -406.266027)
			(xy 12.273457 -406.287839) (xy 12.321063 -406.316893) (xy 12.363931 -406.352568) (xy 12.401148 -406.394105)
			(xy 12.431921 -406.440618) (xy 12.455593 -406.491115) (xy 12.471661 -406.544522) (xy 12.479781 -406.599698)
			(xy 12.48029 -406.627584) (xy 12.479781 -406.65547) (xy 12.471661 -406.710646) (xy 12.455593 -406.764053)
			(xy 12.431921 -406.81455) (xy 12.401148 -406.861063) (xy 12.363931 -406.9026) (xy 12.321063 -406.938275)
			(xy 12.273457 -406.967329) (xy 12.222128 -406.989141) (xy 12.168171 -407.003247) (xy 12.112734 -407.009347)
			(xy 12.057 -407.00731) (xy 12.002157 -406.99718) (xy 11.949373 -406.979173) (xy 11.899773 -406.953672)
			(xy 11.854415 -406.921221) (xy 11.814266 -406.882512) (xy 11.78018 -406.838369) (xy 11.752884 -406.789734)
			(xy 11.732961 -406.737643) (xy 11.720835 -406.683206) (xy 11.716764 -406.627584) (xy 10.314432 -406.627584)
			(xy 10.314432 -407.50871) (xy 18.001232 -407.50871) (xy 18.005303 -407.453088) (xy 18.017429 -407.398651)
			(xy 18.037352 -407.34656) (xy 18.064648 -407.297925) (xy 18.098734 -407.253782) (xy 18.138883 -407.215073)
			(xy 18.184241 -407.182622) (xy 18.233841 -407.157121) (xy 18.286625 -407.139114) (xy 18.341468 -407.128984)
			(xy 18.397202 -407.126947) (xy 18.452639 -407.133047) (xy 18.506596 -407.147153) (xy 18.557925 -407.168965)
			(xy 18.605531 -407.198019) (xy 18.648399 -407.233694) (xy 18.685616 -407.275231) (xy 18.716389 -407.321744)
			(xy 18.740061 -407.372241) (xy 18.756129 -407.425648) (xy 18.764249 -407.480824) (xy 18.764758 -407.50871)
			(xy 18.764249 -407.536596) (xy 18.756129 -407.591772) (xy 18.740061 -407.645179) (xy 18.716389 -407.695676)
			(xy 18.685616 -407.742189) (xy 18.648399 -407.783726) (xy 18.605531 -407.819401) (xy 18.557925 -407.848455)
			(xy 18.506596 -407.870267) (xy 18.452639 -407.884373) (xy 18.397202 -407.890473) (xy 18.341468 -407.888436)
			(xy 18.286625 -407.878306) (xy 18.233841 -407.860299) (xy 18.184241 -407.834798) (xy 18.138883 -407.802347)
			(xy 18.098734 -407.763638) (xy 18.064648 -407.719495) (xy 18.037352 -407.67086) (xy 18.017429 -407.618769)
			(xy 18.005303 -407.564332) (xy 18.001232 -407.50871) (xy 10.314432 -407.50871) (xy 10.314432 -407.74366)
			(xy 10.313875 -407.772224) (xy 10.304945 -407.828649) (xy 10.2873 -407.882982) (xy 10.261373 -407.933887)
			(xy 10.227802 -407.98011) (xy 10.208006 -408.000708) (xy 10.05713 -408.151584) (xy 10.700764 -408.151584)
			(xy 10.704835 -408.095962) (xy 10.716961 -408.041525) (xy 10.736884 -407.989434) (xy 10.76418 -407.940799)
			(xy 10.798266 -407.896656) (xy 10.838415 -407.857947) (xy 10.883773 -407.825496) (xy 10.933373 -407.799995)
			(xy 10.986157 -407.781988) (xy 11.041 -407.771858) (xy 11.096734 -407.769821) (xy 11.152171 -407.775921)
			(xy 11.206128 -407.790027) (xy 11.257457 -407.811839) (xy 11.305063 -407.840893) (xy 11.347931 -407.876568)
			(xy 11.385148 -407.918105) (xy 11.415921 -407.964618) (xy 11.439593 -408.015115) (xy 11.455661 -408.068522)
			(xy 11.463781 -408.123698) (xy 11.46429 -408.151584) (xy 11.463781 -408.17947) (xy 11.455661 -408.234646)
			(xy 11.439593 -408.288053) (xy 11.415921 -408.33855) (xy 11.385148 -408.385063) (xy 11.347931 -408.4266)
			(xy 11.305063 -408.462275) (xy 11.257457 -408.491329) (xy 11.206128 -408.513141) (xy 11.188108 -408.517852)
			(xy 32.401762 -408.517852) (xy 32.405833 -408.46223) (xy 32.417959 -408.407793) (xy 32.437882 -408.355702)
			(xy 32.465178 -408.307067) (xy 32.499264 -408.262924) (xy 32.539413 -408.224215) (xy 32.584771 -408.191764)
			(xy 32.634371 -408.166263) (xy 32.687155 -408.148256) (xy 32.741998 -408.138126) (xy 32.797732 -408.136089)
			(xy 32.853169 -408.142189) (xy 32.907126 -408.156295) (xy 32.958455 -408.178107) (xy 33.006061 -408.207161)
			(xy 33.048929 -408.242836) (xy 33.086146 -408.284373) (xy 33.116919 -408.330886) (xy 33.140591 -408.381383)
			(xy 33.156659 -408.43479) (xy 33.164779 -408.489966) (xy 33.165288 -408.517852) (xy 33.164779 -408.545738)
			(xy 33.156659 -408.600914) (xy 33.140591 -408.654321) (xy 33.116919 -408.704818) (xy 33.086146 -408.751331)
			(xy 33.048929 -408.792868) (xy 33.006061 -408.828543) (xy 32.958455 -408.857597) (xy 32.907126 -408.879409)
			(xy 32.853169 -408.893515) (xy 32.797732 -408.899615) (xy 32.741998 -408.897578) (xy 32.687155 -408.887448)
			(xy 32.634371 -408.869441) (xy 32.584771 -408.84394) (xy 32.539413 -408.811489) (xy 32.499264 -408.77278)
			(xy 32.465178 -408.728637) (xy 32.437882 -408.680002) (xy 32.417959 -408.627911) (xy 32.405833 -408.573474)
			(xy 32.401762 -408.517852) (xy 11.188108 -408.517852) (xy 11.152171 -408.527247) (xy 11.096734 -408.533347)
			(xy 11.041 -408.53131) (xy 10.986157 -408.52118) (xy 10.933373 -408.503173) (xy 10.883773 -408.477672)
			(xy 10.838415 -408.445221) (xy 10.798266 -408.406512) (xy 10.76418 -408.362369) (xy 10.736884 -408.313734)
			(xy 10.716961 -408.261643) (xy 10.704835 -408.207206) (xy 10.700764 -408.151584) (xy 10.05713 -408.151584)
			(xy 10.024618 -408.184096) (xy 10.017769 -408.191494) (xy 10.01003 -408.210092) (xy 10.009632 -408.220164)
			(xy 10.009632 -409.167584) (xy 18.447764 -409.167584) (xy 18.451835 -409.111962) (xy 18.463961 -409.057525)
			(xy 18.483884 -409.005434) (xy 18.51118 -408.956799) (xy 18.545266 -408.912656) (xy 18.585415 -408.873947)
			(xy 18.630773 -408.841496) (xy 18.680373 -408.815995) (xy 18.733157 -408.797988) (xy 18.788 -408.787858)
			(xy 18.843734 -408.785821) (xy 18.899171 -408.791921) (xy 18.953128 -408.806027) (xy 19.004457 -408.827839)
			(xy 19.052063 -408.856893) (xy 19.094931 -408.892568) (xy 19.132148 -408.934105) (xy 19.162921 -408.980618)
			(xy 19.186593 -409.031115) (xy 19.202661 -409.084522) (xy 19.210781 -409.139698) (xy 19.21129 -409.167584)
			(xy 19.210781 -409.19547) (xy 19.202661 -409.250646) (xy 19.186593 -409.304053) (xy 19.162921 -409.35455)
			(xy 19.132148 -409.401063) (xy 19.113761 -409.421584) (xy 21.165564 -409.421584) (xy 21.169635 -409.365962)
			(xy 21.181761 -409.311525) (xy 21.201684 -409.259434) (xy 21.22898 -409.210799) (xy 21.263066 -409.166656)
			(xy 21.303215 -409.127947) (xy 21.348573 -409.095496) (xy 21.398173 -409.069995) (xy 21.450957 -409.051988)
			(xy 21.5058 -409.041858) (xy 21.561534 -409.039821) (xy 21.616971 -409.045921) (xy 21.670928 -409.060027)
			(xy 21.722257 -409.081839) (xy 21.769863 -409.110893) (xy 21.812731 -409.146568) (xy 21.849948 -409.188105)
			(xy 21.880721 -409.234618) (xy 21.904393 -409.285115) (xy 21.920461 -409.338522) (xy 21.928581 -409.393698)
			(xy 21.92909 -409.421584) (xy 21.928581 -409.44947) (xy 21.920461 -409.504646) (xy 21.904393 -409.558053)
			(xy 21.880721 -409.60855) (xy 21.849948 -409.655063) (xy 21.812731 -409.6966) (xy 21.769863 -409.732275)
			(xy 21.722257 -409.761329) (xy 21.670928 -409.783141) (xy 21.616971 -409.797247) (xy 21.561534 -409.803347)
			(xy 21.5058 -409.80131) (xy 21.450957 -409.79118) (xy 21.398173 -409.773173) (xy 21.348573 -409.747672)
			(xy 21.303215 -409.715221) (xy 21.263066 -409.676512) (xy 21.22898 -409.632369) (xy 21.201684 -409.583734)
			(xy 21.181761 -409.531643) (xy 21.169635 -409.477206) (xy 21.165564 -409.421584) (xy 19.113761 -409.421584)
			(xy 19.094931 -409.4426) (xy 19.052063 -409.478275) (xy 19.004457 -409.507329) (xy 18.953128 -409.529141)
			(xy 18.899171 -409.543247) (xy 18.843734 -409.549347) (xy 18.788 -409.54731) (xy 18.733157 -409.53718)
			(xy 18.680373 -409.519173) (xy 18.630773 -409.493672) (xy 18.585415 -409.461221) (xy 18.545266 -409.422512)
			(xy 18.51118 -409.378369) (xy 18.483884 -409.329734) (xy 18.463961 -409.277643) (xy 18.451835 -409.223206)
			(xy 18.447764 -409.167584) (xy 10.009632 -409.167584) (xy 10.009632 -409.937023) (xy 10.777937 -409.937023)
			(xy 10.777937 -409.882517) (xy 10.785694 -409.828566) (xy 10.80105 -409.776269) (xy 10.823693 -409.726689)
			(xy 10.853161 -409.680836) (xy 10.888855 -409.639643) (xy 10.930047 -409.60395) (xy 10.9759 -409.574482)
			(xy 11.025481 -409.55184) (xy 11.077778 -409.536484) (xy 11.131729 -409.528727) (xy 11.158982 -409.528264)
			(xy 11.186427 -409.528721) (xy 11.24075 -409.536598) (xy 11.293379 -409.552193) (xy 11.343224 -409.575181)
			(xy 11.3665 -409.589732) (xy 11.37867 -409.597011) (xy 11.40576 -409.605338) (xy 11.434095 -409.605891)
			(xy 11.461489 -409.598628) (xy 11.485829 -409.584109) (xy 11.505235 -409.563455) (xy 11.51821 -409.538259)
			(xy 11.52144 -409.524454) (xy 11.527693 -409.496008) (xy 11.54769 -409.441309) (xy 11.575765 -409.390283)
			(xy 11.611268 -409.344116) (xy 11.653373 -409.303879) (xy 11.701103 -409.270507) (xy 11.753349 -409.244774)
			(xy 11.808899 -409.227279) (xy 11.866462 -409.218427) (xy 11.895582 -409.217876) (xy 11.922835 -409.21837)
			(xy 11.976785 -409.226125) (xy 12.029083 -409.241478) (xy 12.078663 -409.264119) (xy 12.124517 -409.293585)
			(xy 12.16571 -409.329277) (xy 12.201404 -409.370469) (xy 12.230872 -409.416321) (xy 12.253515 -409.4659)
			(xy 12.268872 -409.518197) (xy 12.276629 -409.572147) (xy 12.276629 -409.626653) (xy 12.268872 -409.680603)
			(xy 12.253515 -409.7329) (xy 12.230872 -409.782479) (xy 12.201404 -409.828331) (xy 12.16571 -409.869523)
			(xy 12.124517 -409.905215) (xy 12.078663 -409.934681) (xy 12.029083 -409.957322) (xy 11.976785 -409.972675)
			(xy 11.922835 -409.98043) (xy 11.895582 -409.980892) (xy 11.868137 -409.980412) (xy 11.813815 -409.972542)
			(xy 11.761186 -409.956955) (xy 11.71134 -409.933973) (xy 11.688064 -409.919424) (xy 11.675937 -409.912065)
			(xy 11.648831 -409.903736) (xy 11.62048 -409.903187) (xy 11.593073 -409.910461) (xy 11.568725 -409.924997)
			(xy 11.549317 -409.945671) (xy 11.536348 -409.970887) (xy 11.533124 -409.984702) (xy 11.526851 -410.013142)
			(xy 11.506851 -410.067836) (xy 11.478775 -410.118858) (xy 11.443273 -410.165022) (xy 11.401171 -410.205257)
			(xy 11.353445 -410.23863) (xy 11.301204 -410.264365) (xy 11.245659 -410.281865) (xy 11.1881 -410.290725)
			(xy 11.158982 -410.29128) (xy 11.131729 -410.290813) (xy 11.077778 -410.283056) (xy 11.025481 -410.2677)
			(xy 10.9759 -410.245058) (xy 10.930047 -410.21559) (xy 10.888855 -410.179897) (xy 10.853161 -410.138704)
			(xy 10.823693 -410.092851) (xy 10.80105 -410.043271) (xy 10.785694 -409.990974) (xy 10.777937 -409.937023)
			(xy 10.009632 -409.937023) (xy 10.009632 -410.64942) (xy 17.970752 -410.64942) (xy 17.974823 -410.593798)
			(xy 17.986949 -410.539361) (xy 18.006872 -410.48727) (xy 18.034168 -410.438635) (xy 18.068254 -410.394492)
			(xy 18.108403 -410.355783) (xy 18.153761 -410.323332) (xy 18.203361 -410.297831) (xy 18.256145 -410.279824)
			(xy 18.310988 -410.269694) (xy 18.366722 -410.267657) (xy 18.422159 -410.273757) (xy 18.476116 -410.287863)
			(xy 18.527445 -410.309675) (xy 18.575051 -410.338729) (xy 18.617919 -410.374404) (xy 18.655136 -410.415941)
			(xy 18.685909 -410.462454) (xy 18.709581 -410.512951) (xy 18.725649 -410.566358) (xy 18.733769 -410.621534)
			(xy 18.734278 -410.64942) (xy 18.733769 -410.677306) (xy 18.725649 -410.732482) (xy 18.709581 -410.785889)
			(xy 18.685909 -410.836386) (xy 18.655136 -410.882899) (xy 18.617919 -410.924436) (xy 18.575051 -410.960111)
			(xy 18.527445 -410.989165) (xy 18.476116 -411.010977) (xy 18.422159 -411.025083) (xy 18.366722 -411.031183)
			(xy 18.310988 -411.029146) (xy 18.256145 -411.019016) (xy 18.203361 -411.001009) (xy 18.153761 -410.975508)
			(xy 18.108403 -410.943057) (xy 18.068254 -410.904348) (xy 18.034168 -410.860205) (xy 18.006872 -410.81157)
			(xy 17.986949 -410.759479) (xy 17.974823 -410.705042) (xy 17.970752 -410.64942) (xy 10.009632 -410.64942)
			(xy 10.009632 -411.126178) (xy 10.009632 -411.14218) (xy 10.027412 -411.168088) (xy 10.04189 -411.173676)
			(xy 10.042398 -411.173676) (xy 10.130028 -411.20822) (xy 10.139679 -411.211509) (xy 10.160045 -411.211001)
			(xy 10.178633 -411.202663) (xy 10.185908 -411.19552) (xy 10.194798 -411.185868) (xy 10.216435 -411.164733)
			(xy 10.26515 -411.128889) (xy 10.318909 -411.101178) (xy 10.376367 -411.082294) (xy 10.436084 -411.07271)
			(xy 10.466324 -411.072076) (xy 10.466832 -411.072076) (xy 10.494083 -411.072562) (xy 10.54803 -411.080319)
			(xy 10.600324 -411.095674) (xy 10.6499 -411.118315) (xy 10.69575 -411.147781) (xy 10.736939 -411.183472)
			(xy 10.77263 -411.224662) (xy 10.802096 -411.270512) (xy 10.824737 -411.320088) (xy 10.840092 -411.372382)
			(xy 10.847848 -411.426329) (xy 10.847848 -411.480831) (xy 10.840092 -411.534778) (xy 10.824737 -411.587072)
			(xy 10.802096 -411.636648) (xy 10.77263 -411.682498) (xy 10.736939 -411.723688) (xy 10.69575 -411.759379)
			(xy 10.6499 -411.788845) (xy 10.600324 -411.811486) (xy 10.54803 -411.826841) (xy 10.49418 -411.834584)
			(xy 18.448018 -411.834584) (xy 18.452089 -411.778962) (xy 18.464215 -411.724525) (xy 18.484138 -411.672434)
			(xy 18.511434 -411.623799) (xy 18.54552 -411.579656) (xy 18.585669 -411.540947) (xy 18.631027 -411.508496)
			(xy 18.680627 -411.482995) (xy 18.733411 -411.464988) (xy 18.788254 -411.454858) (xy 18.843988 -411.452821)
			(xy 18.899425 -411.458921) (xy 18.953382 -411.473027) (xy 19.004711 -411.494839) (xy 19.052317 -411.523893)
			(xy 19.095185 -411.559568) (xy 19.132402 -411.601105) (xy 19.163175 -411.647618) (xy 19.186847 -411.698115)
			(xy 19.202915 -411.751522) (xy 19.211035 -411.806698) (xy 19.211544 -411.834584) (xy 19.211035 -411.86247)
			(xy 19.202915 -411.917646) (xy 19.186847 -411.971053) (xy 19.163175 -412.02155) (xy 19.132402 -412.068063)
			(xy 19.095185 -412.1096) (xy 19.052317 -412.145275) (xy 19.004711 -412.174329) (xy 18.953382 -412.196141)
			(xy 18.899425 -412.210247) (xy 18.843988 -412.216347) (xy 18.788254 -412.21431) (xy 18.733411 -412.20418)
			(xy 18.680627 -412.186173) (xy 18.631027 -412.160672) (xy 18.585669 -412.128221) (xy 18.54552 -412.089512)
			(xy 18.511434 -412.045369) (xy 18.484138 -411.996734) (xy 18.464215 -411.944643) (xy 18.452089 -411.890206)
			(xy 18.448018 -411.834584) (xy 10.49418 -411.834584) (xy 10.494083 -411.834598) (xy 10.466832 -411.835092)
			(xy 10.466324 -411.835092) (xy 10.440047 -411.83464) (xy 10.387994 -411.827396) (xy 10.33743 -411.813071)
			(xy 10.289314 -411.791935) (xy 10.244556 -411.764389) (xy 10.204008 -411.730956) (xy 10.185908 -411.711902)
			(xy 10.17524 -411.700218) (xy 10.144506 -411.693106) (xy 10.04189 -411.733746) (xy 10.032586 -411.737883)
			(xy 10.018016 -411.752082) (xy 10.01009 -411.770819) (xy 10.009632 -411.78099) (xy 10.009632 -412.706566)
			(xy 10.009886 -412.714212) (xy 10.014402 -412.728822) (xy 10.018522 -412.735268) (xy 10.021316 -412.739332)
			(xy 10.185146 -412.903162) (xy 17.542 -412.903162) (xy 17.546071 -412.84754) (xy 17.558197 -412.793103)
			(xy 17.57812 -412.741012) (xy 17.605416 -412.692377) (xy 17.639502 -412.648234) (xy 17.679651 -412.609525)
			(xy 17.725009 -412.577074) (xy 17.774609 -412.551573) (xy 17.827393 -412.533566) (xy 17.882236 -412.523436)
			(xy 17.93797 -412.521399) (xy 17.993407 -412.527499) (xy 18.047364 -412.541605) (xy 18.098693 -412.563417)
			(xy 18.146299 -412.592471) (xy 18.189167 -412.628146) (xy 18.226384 -412.669683) (xy 18.257157 -412.716196)
			(xy 18.280829 -412.766693) (xy 18.296897 -412.8201) (xy 18.305017 -412.875276) (xy 18.305526 -412.903162)
			(xy 18.305017 -412.931048) (xy 18.296897 -412.986224) (xy 18.280829 -413.039631) (xy 18.257157 -413.090128)
			(xy 18.226384 -413.136641) (xy 18.189167 -413.178178) (xy 18.146299 -413.213853) (xy 18.098693 -413.242907)
			(xy 18.047364 -413.264719) (xy 17.993407 -413.278825) (xy 17.93797 -413.284925) (xy 17.882236 -413.282888)
			(xy 17.827393 -413.272758) (xy 17.774609 -413.254751) (xy 17.725009 -413.22925) (xy 17.679651 -413.196799)
			(xy 17.639502 -413.15809) (xy 17.605416 -413.113947) (xy 17.57812 -413.065312) (xy 17.558197 -413.013221)
			(xy 17.546071 -412.958784) (xy 17.542 -412.903162) (xy 10.185146 -412.903162) (xy 10.767568 -413.485584)
			(xy 15.907764 -413.485584) (xy 15.911835 -413.429962) (xy 15.923961 -413.375525) (xy 15.943884 -413.323434)
			(xy 15.97118 -413.274799) (xy 16.005266 -413.230656) (xy 16.045415 -413.191947) (xy 16.090773 -413.159496)
			(xy 16.140373 -413.133995) (xy 16.193157 -413.115988) (xy 16.248 -413.105858) (xy 16.303734 -413.103821)
			(xy 16.359171 -413.109921) (xy 16.413128 -413.124027) (xy 16.464457 -413.145839) (xy 16.512063 -413.174893)
			(xy 16.554931 -413.210568) (xy 16.592148 -413.252105) (xy 16.622921 -413.298618) (xy 16.646593 -413.349115)
			(xy 16.662661 -413.402522) (xy 16.664643 -413.415988) (xy 18.764502 -413.415988) (xy 18.768573 -413.360366)
			(xy 18.780699 -413.305929) (xy 18.800622 -413.253838) (xy 18.827918 -413.205203) (xy 18.862004 -413.16106)
			(xy 18.902153 -413.122351) (xy 18.947511 -413.0899) (xy 18.997111 -413.064399) (xy 19.049895 -413.046392)
			(xy 19.104738 -413.036262) (xy 19.160472 -413.034225) (xy 19.215909 -413.040325) (xy 19.269866 -413.054431)
			(xy 19.321195 -413.076243) (xy 19.368801 -413.105297) (xy 19.411669 -413.140972) (xy 19.448886 -413.182509)
			(xy 19.479659 -413.229022) (xy 19.503331 -413.279519) (xy 19.519399 -413.332926) (xy 19.527519 -413.388102)
			(xy 19.528028 -413.415988) (xy 19.527519 -413.443874) (xy 19.519399 -413.49905) (xy 19.503331 -413.552457)
			(xy 19.479659 -413.602954) (xy 19.448886 -413.649467) (xy 19.411669 -413.691004) (xy 19.368801 -413.726679)
			(xy 19.321195 -413.755733) (xy 19.269866 -413.777545) (xy 19.215909 -413.791651) (xy 19.160472 -413.797751)
			(xy 19.104738 -413.795714) (xy 19.049895 -413.785584) (xy 18.997111 -413.767577) (xy 18.947511 -413.742076)
			(xy 18.902153 -413.709625) (xy 18.862004 -413.670916) (xy 18.827918 -413.626773) (xy 18.800622 -413.578138)
			(xy 18.780699 -413.526047) (xy 18.768573 -413.47161) (xy 18.764502 -413.415988) (xy 16.664643 -413.415988)
			(xy 16.670781 -413.457698) (xy 16.67129 -413.485584) (xy 16.670781 -413.51347) (xy 16.662661 -413.568646)
			(xy 16.646593 -413.622053) (xy 16.622921 -413.67255) (xy 16.592148 -413.719063) (xy 16.554931 -413.7606)
			(xy 16.512063 -413.796275) (xy 16.464457 -413.825329) (xy 16.413128 -413.847141) (xy 16.359171 -413.861247)
			(xy 16.303734 -413.867347) (xy 16.248 -413.86531) (xy 16.193157 -413.85518) (xy 16.140373 -413.837173)
			(xy 16.090773 -413.811672) (xy 16.045415 -413.779221) (xy 16.005266 -413.740512) (xy 15.97118 -413.696369)
			(xy 15.943884 -413.647734) (xy 15.923961 -413.595643) (xy 15.911835 -413.541206) (xy 15.907764 -413.485584)
			(xy 10.767568 -413.485584) (xy 11.275568 -413.993584) (xy 13.240764 -413.993584) (xy 13.244835 -413.937962)
			(xy 13.256961 -413.883525) (xy 13.276884 -413.831434) (xy 13.30418 -413.782799) (xy 13.338266 -413.738656)
			(xy 13.378415 -413.699947) (xy 13.423773 -413.667496) (xy 13.473373 -413.641995) (xy 13.526157 -413.623988)
			(xy 13.581 -413.613858) (xy 13.636734 -413.611821) (xy 13.692171 -413.617921) (xy 13.746128 -413.632027)
			(xy 13.797457 -413.653839) (xy 13.845063 -413.682893) (xy 13.887931 -413.718568) (xy 13.925148 -413.760105)
			(xy 13.955921 -413.806618) (xy 13.979593 -413.857115) (xy 13.995661 -413.910522) (xy 14.003781 -413.965698)
			(xy 14.00429 -413.993584) (xy 14.510764 -413.993584) (xy 14.514835 -413.937962) (xy 14.526961 -413.883525)
			(xy 14.546884 -413.831434) (xy 14.57418 -413.782799) (xy 14.608266 -413.738656) (xy 14.648415 -413.699947)
			(xy 14.693773 -413.667496) (xy 14.743373 -413.641995) (xy 14.796157 -413.623988) (xy 14.851 -413.613858)
			(xy 14.906734 -413.611821) (xy 14.962171 -413.617921) (xy 15.016128 -413.632027) (xy 15.067457 -413.653839)
			(xy 15.115063 -413.682893) (xy 15.157931 -413.718568) (xy 15.195148 -413.760105) (xy 15.225921 -413.806618)
			(xy 15.249593 -413.857115) (xy 15.265661 -413.910522) (xy 15.273781 -413.965698) (xy 15.27429 -413.993584)
			(xy 15.273781 -414.02147) (xy 15.265661 -414.076646) (xy 15.249593 -414.130053) (xy 15.225921 -414.18055)
			(xy 15.195148 -414.227063) (xy 15.157931 -414.2686) (xy 15.115063 -414.304275) (xy 15.067457 -414.333329)
			(xy 15.016128 -414.355141) (xy 14.962171 -414.369247) (xy 14.906734 -414.375347) (xy 14.851 -414.37331)
			(xy 14.796157 -414.36318) (xy 14.743373 -414.345173) (xy 14.693773 -414.319672) (xy 14.648415 -414.287221)
			(xy 14.608266 -414.248512) (xy 14.57418 -414.204369) (xy 14.546884 -414.155734) (xy 14.526961 -414.103643)
			(xy 14.514835 -414.049206) (xy 14.510764 -413.993584) (xy 14.00429 -413.993584) (xy 14.003781 -414.02147)
			(xy 13.995661 -414.076646) (xy 13.979593 -414.130053) (xy 13.955921 -414.18055) (xy 13.925148 -414.227063)
			(xy 13.887931 -414.2686) (xy 13.845063 -414.304275) (xy 13.797457 -414.333329) (xy 13.746128 -414.355141)
			(xy 13.692171 -414.369247) (xy 13.636734 -414.375347) (xy 13.581 -414.37331) (xy 13.526157 -414.36318)
			(xy 13.473373 -414.345173) (xy 13.423773 -414.319672) (xy 13.378415 -414.287221) (xy 13.338266 -414.248512)
			(xy 13.30418 -414.204369) (xy 13.276884 -414.155734) (xy 13.256961 -414.103643) (xy 13.244835 -414.049206)
			(xy 13.240764 -413.993584) (xy 11.275568 -413.993584) (xy 12.252706 -414.970722) (xy 12.260101 -414.977576)
			(xy 12.2787 -414.98532) (xy 12.288774 -414.985708)
		)
		(stroke
			(width 0)
			(type solid)
		)
		(fill yes)
		(layer "In4.Cu")
		(net "GND")
	)
	(gr_poly
		(pts
			(xy 423.810684 -369.97132) (xy 423.820695 -369.970835) (xy 423.839196 -369.963179) (xy 423.853359 -369.949026)
			(xy 423.861028 -369.930531) (xy 423.861484 -369.92052) (xy 423.861484 -366.992408) (xy 423.858436 -366.984026)
			(xy 423.847929 -366.952806) (xy 423.836566 -366.887927) (xy 423.83583 -366.854994) (xy 423.836316 -366.827743)
			(xy 423.844072 -366.773795) (xy 423.859427 -366.7215) (xy 423.882069 -366.671923) (xy 423.911535 -366.626073)
			(xy 423.947226 -366.584882) (xy 423.988417 -366.549191) (xy 424.034267 -366.519725) (xy 424.083844 -366.497083)
			(xy 424.136139 -366.481728) (xy 424.190087 -366.473972) (xy 424.244589 -366.473972) (xy 424.298537 -366.481728)
			(xy 424.350832 -366.497083) (xy 424.400409 -366.519725) (xy 424.446259 -366.549191) (xy 424.48745 -366.584882)
			(xy 424.523141 -366.626073) (xy 424.552607 -366.671923) (xy 424.575249 -366.7215) (xy 424.590604 -366.773795)
			(xy 424.59836 -366.827743) (xy 424.598846 -366.854994) (xy 424.598131 -366.887928) (xy 424.586761 -366.952809)
			(xy 424.57624 -366.984026) (xy 424.573192 -366.992408) (xy 424.573192 -369.92052) (xy 424.573684 -369.930526)
			(xy 424.581346 -369.949012) (xy 424.595498 -369.96316) (xy 424.613986 -369.970819) (xy 424.623992 -369.97132)
			(xy 424.861228 -369.97132) (xy 424.871233 -369.970828) (xy 424.889719 -369.963164) (xy 424.903868 -369.949012)
			(xy 424.911529 -369.930526) (xy 424.912028 -369.92052) (xy 424.912028 -366.780318) (xy 424.911604 -366.771462)
			(xy 424.905499 -366.754831) (xy 424.90009 -366.747806) (xy 423.469816 -365.317532) (xy 423.456068 -365.303081)
			(xy 423.43392 -365.269917) (xy 423.418657 -365.233073) (xy 423.410865 -365.193962) (xy 423.41038 -365.174022)
			(xy 423.41038 -362.691172) (xy 423.410895 -362.671237) (xy 423.418705 -362.632137) (xy 423.433965 -362.5953)
			(xy 423.456092 -362.562131) (xy 423.469816 -362.547662) (xy 424.396408 -361.621324) (xy 424.400438 -361.617119)
			(xy 424.406595 -361.607235) (xy 424.4086 -361.601766) (xy 424.412156 -361.591606) (xy 424.410886 -361.579414)
			(xy 424.409676 -361.568278) (xy 424.408402 -361.545911) (xy 424.408346 -361.53471) (xy 424.408808 -361.507453)
			(xy 424.416565 -361.453494) (xy 424.431923 -361.401188) (xy 424.454568 -361.3516) (xy 424.48404 -361.305739)
			(xy 424.519739 -361.26454) (xy 424.560938 -361.228841) (xy 424.606798 -361.199369) (xy 424.656386 -361.176723)
			(xy 424.708692 -361.161366) (xy 424.762652 -361.153608) (xy 424.817166 -361.15361) (xy 424.871125 -361.161369)
			(xy 424.92343 -361.176729) (xy 424.973017 -361.199377) (xy 425.018876 -361.228851) (xy 425.060073 -361.264552)
			(xy 425.09577 -361.305753) (xy 425.12524 -361.351615) (xy 425.147883 -361.401204) (xy 425.163238 -361.453511)
			(xy 425.170993 -361.50747) (xy 425.170989 -361.561984) (xy 425.163227 -361.615943) (xy 425.147864 -361.668247)
			(xy 425.125214 -361.717833) (xy 425.095737 -361.763691) (xy 425.060034 -361.804886) (xy 425.018832 -361.840581)
			(xy 424.972969 -361.870049) (xy 424.972695 -361.870174) (xy 431.124356 -361.870174) (xy 431.124356 -361.785478)
			(xy 431.132407 -361.701164) (xy 431.148436 -361.617998) (xy 431.172297 -361.536731) (xy 431.203776 -361.458101)
			(xy 431.242587 -361.38282) (xy 431.288377 -361.311568) (xy 431.340733 -361.244992) (xy 431.399181 -361.183694)
			(xy 431.463191 -361.128229) (xy 431.532183 -361.0791) (xy 431.605533 -361.036751) (xy 431.682576 -361.001567)
			(xy 431.762615 -360.973865) (xy 431.844924 -360.953897) (xy 431.928759 -360.941844) (xy 432.01336 -360.937814)
			(xy 432.097961 -360.941844) (xy 432.181796 -360.953897) (xy 432.264105 -360.973865) (xy 432.344144 -361.001567)
			(xy 432.421187 -361.036751) (xy 432.494537 -361.0791) (xy 432.563529 -361.128229) (xy 432.627539 -361.183694)
			(xy 432.685987 -361.244992) (xy 432.738343 -361.311568) (xy 432.784133 -361.38282) (xy 432.822944 -361.458101)
			(xy 432.854423 -361.536731) (xy 432.878284 -361.617998) (xy 432.894313 -361.701164) (xy 432.902364 -361.785478)
			(xy 432.902868 -361.827826) (xy 432.902364 -361.870174) (xy 432.894313 -361.954488) (xy 432.878284 -362.037654)
			(xy 432.854423 -362.118921) (xy 432.822944 -362.197551) (xy 432.784133 -362.272832) (xy 432.738343 -362.344084)
			(xy 432.685987 -362.41066) (xy 432.627539 -362.471958) (xy 432.563529 -362.527423) (xy 432.494537 -362.576552)
			(xy 432.421187 -362.618901) (xy 432.344144 -362.654085) (xy 432.264105 -362.681787) (xy 432.181796 -362.701755)
			(xy 432.097961 -362.713808) (xy 432.01336 -362.717839) (xy 431.928759 -362.713808) (xy 431.844924 -362.701755)
			(xy 431.762615 -362.681787) (xy 431.682576 -362.654085) (xy 431.605533 -362.618901) (xy 431.532183 -362.576552)
			(xy 431.463191 -362.527423) (xy 431.399181 -362.471958) (xy 431.340733 -362.41066) (xy 431.288377 -362.344084)
			(xy 431.242587 -362.272832) (xy 431.203776 -362.197551) (xy 431.172297 -362.118921) (xy 431.148436 -362.037654)
			(xy 431.132407 -361.954488) (xy 431.124356 -361.870174) (xy 424.972695 -361.870174) (xy 424.923379 -361.89269)
			(xy 424.871071 -361.908042) (xy 424.817111 -361.915794) (xy 424.789854 -361.916218) (xy 424.789092 -361.916218)
			(xy 424.77075 -361.915974) (xy 424.734238 -361.912409) (xy 424.716194 -361.909106) (xy 424.71594 -361.909106)
			(xy 424.70972 -361.908061) (xy 424.697128 -361.9087) (xy 424.691048 -361.910376) (xy 424.679618 -361.913932)
			(xy 423.830242 -362.763308) (xy 423.827847 -362.766029) (xy 423.823766 -362.77202) (xy 423.822114 -362.775246)
			(xy 423.819854 -362.780421) (xy 423.81742 -362.791445) (xy 423.817288 -362.79709) (xy 423.817288 -362.930948)
			(xy 439.741056 -362.930948) (xy 439.741537 -362.903578) (xy 439.749349 -362.849399) (xy 439.764834 -362.796896)
			(xy 439.787673 -362.747148) (xy 439.817395 -362.701182) (xy 439.835036 -362.68025) (xy 439.841132 -362.673138)
			(xy 439.847482 -362.65612) (xy 439.847482 -362.570776) (xy 439.841132 -362.553758) (xy 439.835036 -362.546646)
			(xy 439.817411 -362.525703) (xy 439.787695 -362.479734) (xy 439.764856 -362.429989) (xy 439.749362 -362.377491)
			(xy 439.741531 -362.323317) (xy 439.741056 -362.295948) (xy 439.7416 -362.268698) (xy 439.749349 -362.214752)
			(xy 439.764697 -362.162458) (xy 439.787332 -362.11288) (xy 439.816791 -362.067028) (xy 439.852477 -362.025836)
			(xy 439.893661 -361.990142) (xy 439.939506 -361.960672) (xy 439.989079 -361.938027) (xy 440.04137 -361.922667)
			(xy 440.095314 -361.914906) (xy 440.122564 -361.91444) (xy 440.149934 -361.914917) (xy 440.204113 -361.922731)
			(xy 440.256616 -361.938217) (xy 440.306363 -361.961056) (xy 440.35233 -361.990779) (xy 440.373262 -362.00842)
			(xy 440.380374 -362.014516) (xy 440.397392 -362.020866) (xy 440.482736 -362.020866) (xy 440.499754 -362.014516)
			(xy 440.506866 -362.00842) (xy 440.527799 -361.990779) (xy 440.573767 -361.961055) (xy 440.623513 -361.938209)
			(xy 440.676015 -361.922713) (xy 440.730193 -361.914884) (xy 440.784935 -361.914884) (xy 440.839113 -361.922713)
			(xy 440.891615 -361.938209) (xy 440.941361 -361.961055) (xy 440.987329 -361.990779) (xy 441.008262 -362.00842)
			(xy 441.015374 -362.014516) (xy 441.032392 -362.020866) (xy 441.117736 -362.020866) (xy 441.134754 -362.014516)
			(xy 441.141866 -362.00842) (xy 441.162799 -361.990779) (xy 441.208767 -361.961055) (xy 441.258513 -361.938209)
			(xy 441.311015 -361.922713) (xy 441.365193 -361.914884) (xy 441.419935 -361.914884) (xy 441.474113 -361.922713)
			(xy 441.526615 -361.938209) (xy 441.576361 -361.961055) (xy 441.622329 -361.990779) (xy 441.643262 -362.00842)
			(xy 441.650374 -362.014516) (xy 441.667392 -362.020866) (xy 441.752736 -362.020866) (xy 441.769754 -362.014516)
			(xy 441.776866 -362.00842) (xy 441.780676 -362.005118) (xy 441.788794 -361.997516) (xy 441.798146 -361.977364)
			(xy 441.79871 -361.966256) (xy 441.79871 -361.88904) (xy 441.798164 -361.877927) (xy 441.788813 -361.857766)
			(xy 441.780676 -361.850178) (xy 441.759946 -361.831987) (xy 441.723478 -361.790614) (xy 441.693349 -361.744419)
			(xy 441.670187 -361.694367) (xy 441.654474 -361.641501) (xy 441.646539 -361.586924) (xy 441.646056 -361.559348)
			(xy 441.646537 -361.531978) (xy 441.654349 -361.477799) (xy 441.669834 -361.425296) (xy 441.692673 -361.375548)
			(xy 441.722395 -361.329582) (xy 441.740036 -361.30865) (xy 441.746132 -361.301538) (xy 441.752482 -361.28452)
			(xy 441.752482 -361.199176) (xy 441.746132 -361.182158) (xy 441.740036 -361.175046) (xy 441.722442 -361.154075)
			(xy 441.692715 -361.108114) (xy 441.669866 -361.058374) (xy 441.654365 -361.005878) (xy 441.646532 -360.951705)
			(xy 441.646527 -360.896968) (xy 441.65435 -360.842793) (xy 441.66984 -360.790293) (xy 441.69268 -360.740549)
			(xy 441.722398 -360.694582) (xy 441.740036 -360.67365) (xy 441.746132 -360.666538) (xy 441.752482 -360.64952)
			(xy 441.752482 -360.564176) (xy 441.746132 -360.547158) (xy 441.740036 -360.540046) (xy 441.722442 -360.519075)
			(xy 441.692715 -360.473114) (xy 441.669866 -360.423374) (xy 441.654365 -360.370878) (xy 441.646532 -360.316705)
			(xy 441.646527 -360.261968) (xy 441.65435 -360.207793) (xy 441.66984 -360.155293) (xy 441.69268 -360.105549)
			(xy 441.722398 -360.059582) (xy 441.740036 -360.03865) (xy 441.746132 -360.031538) (xy 441.752482 -360.01452)
			(xy 441.752482 -359.929176) (xy 441.746132 -359.912158) (xy 441.740036 -359.905046) (xy 441.722411 -359.884103)
			(xy 441.692695 -359.838134) (xy 441.669856 -359.788389) (xy 441.654362 -359.735891) (xy 441.646531 -359.681717)
			(xy 441.646056 -359.654348) (xy 441.646535 -359.626774) (xy 441.654482 -359.572201) (xy 441.670203 -359.51934)
			(xy 441.693371 -359.469294) (xy 441.723502 -359.423104) (xy 441.759969 -359.381733) (xy 441.780676 -359.363518)
			(xy 441.788794 -359.355916) (xy 441.798146 -359.335764) (xy 441.79871 -359.324656) (xy 441.79871 -359.24744)
			(xy 441.798164 -359.236327) (xy 441.788813 -359.216166) (xy 441.780676 -359.208578) (xy 441.776866 -359.205276)
			(xy 441.769754 -359.19918) (xy 441.752736 -359.19283) (xy 441.667392 -359.19283) (xy 441.650374 -359.19918)
			(xy 441.643262 -359.205276) (xy 441.622329 -359.222917) (xy 441.576361 -359.252641) (xy 441.526615 -359.275487)
			(xy 441.474113 -359.290983) (xy 441.419935 -359.298812) (xy 441.365193 -359.298812) (xy 441.311015 -359.290983)
			(xy 441.258513 -359.275487) (xy 441.208767 -359.252641) (xy 441.162799 -359.222917) (xy 441.141866 -359.205276)
			(xy 441.134754 -359.19918) (xy 441.117736 -359.19283) (xy 441.032392 -359.19283) (xy 441.015374 -359.19918)
			(xy 441.008262 -359.205276) (xy 440.987329 -359.222917) (xy 440.941361 -359.252641) (xy 440.891615 -359.275487)
			(xy 440.839113 -359.290983) (xy 440.784935 -359.298812) (xy 440.730193 -359.298812) (xy 440.676015 -359.290983)
			(xy 440.623513 -359.275487) (xy 440.573767 -359.252641) (xy 440.527799 -359.222917) (xy 440.506866 -359.205276)
			(xy 440.499754 -359.19918) (xy 440.482736 -359.19283) (xy 440.397392 -359.19283) (xy 440.380374 -359.19918)
			(xy 440.373262 -359.205276) (xy 440.352314 -359.222896) (xy 440.306346 -359.252611) (xy 440.256603 -359.275451)
			(xy 440.204105 -359.290947) (xy 440.149932 -359.29878) (xy 440.122564 -359.299256) (xy 440.095314 -359.298756)
			(xy 440.041369 -359.290996) (xy 439.989078 -359.275638) (xy 439.939504 -359.252997) (xy 439.893656 -359.223531)
			(xy 439.852467 -359.187841) (xy 439.816776 -359.146654) (xy 439.787309 -359.100807) (xy 439.764666 -359.051233)
			(xy 439.749307 -358.998942) (xy 439.741545 -358.944998) (xy 439.741056 -358.917748) (xy 439.741537 -358.890378)
			(xy 439.749349 -358.836199) (xy 439.764834 -358.783696) (xy 439.787673 -358.733948) (xy 439.817395 -358.687982)
			(xy 439.835036 -358.66705) (xy 439.841132 -358.659938) (xy 439.847482 -358.64292) (xy 439.847482 -358.557576)
			(xy 439.841132 -358.540558) (xy 439.835036 -358.533446) (xy 439.817411 -358.512503) (xy 439.787695 -358.466534)
			(xy 439.764856 -358.416789) (xy 439.749362 -358.364291) (xy 439.741531 -358.310117) (xy 439.741056 -358.282748)
			(xy 439.7416 -358.255498) (xy 439.749349 -358.201552) (xy 439.764697 -358.149258) (xy 439.787332 -358.09968)
			(xy 439.816791 -358.053828) (xy 439.852477 -358.012636) (xy 439.893661 -357.976942) (xy 439.939506 -357.947472)
			(xy 439.989079 -357.924827) (xy 440.04137 -357.909467) (xy 440.095314 -357.901706) (xy 440.122564 -357.90124)
			(xy 440.149934 -357.901717) (xy 440.204113 -357.909531) (xy 440.256616 -357.925017) (xy 440.306363 -357.947856)
			(xy 440.35233 -357.977579) (xy 440.373262 -357.99522) (xy 440.380374 -358.001316) (xy 440.397392 -358.007666)
			(xy 440.482736 -358.007666) (xy 440.499754 -358.001316) (xy 440.506866 -357.99522) (xy 440.527799 -357.977579)
			(xy 440.573767 -357.947855) (xy 440.623513 -357.925009) (xy 440.676015 -357.909513) (xy 440.730193 -357.901684)
			(xy 440.784935 -357.901684) (xy 440.839113 -357.909513) (xy 440.891615 -357.925009) (xy 440.941361 -357.947855)
			(xy 440.987329 -357.977579) (xy 441.008262 -357.99522) (xy 441.015374 -358.001316) (xy 441.032392 -358.007666)
			(xy 441.117736 -358.007666) (xy 441.134754 -358.001316) (xy 441.141866 -357.99522) (xy 441.162799 -357.977579)
			(xy 441.208767 -357.947855) (xy 441.258513 -357.925009) (xy 441.311015 -357.909513) (xy 441.365193 -357.901684)
			(xy 441.419935 -357.901684) (xy 441.474113 -357.909513) (xy 441.526615 -357.925009) (xy 441.576361 -357.947855)
			(xy 441.622329 -357.977579) (xy 441.643262 -357.99522) (xy 441.650374 -358.001316) (xy 441.667392 -358.007666)
			(xy 441.752736 -358.007666) (xy 441.769754 -358.001316) (xy 441.776866 -357.99522) (xy 441.797799 -357.977579)
			(xy 441.843767 -357.947855) (xy 441.893513 -357.925009) (xy 441.946015 -357.909513) (xy 442.000193 -357.901684)
			(xy 442.054935 -357.901684) (xy 442.109113 -357.909513) (xy 442.161615 -357.925009) (xy 442.211361 -357.947855)
			(xy 442.257329 -357.977579) (xy 442.278262 -357.99522) (xy 442.285374 -358.001316) (xy 442.302392 -358.007666)
			(xy 442.387736 -358.007666) (xy 442.404754 -358.001316) (xy 442.411866 -357.99522) (xy 442.432803 -357.977586)
			(xy 442.478774 -357.947873) (xy 442.52852 -357.925036) (xy 442.58102 -357.909543) (xy 442.635195 -357.901714)
			(xy 442.662564 -357.90124) (xy 442.689818 -357.901689) (xy 442.743772 -357.909442) (xy 442.796073 -357.924796)
			(xy 442.845656 -357.947438) (xy 442.891512 -357.976907) (xy 442.932706 -358.012602) (xy 442.968401 -358.053798)
			(xy 442.997868 -358.099654) (xy 443.020508 -358.149238) (xy 443.03586 -358.20154) (xy 443.043612 -358.255494)
			(xy 443.044072 -358.282748) (xy 443.043582 -358.310117) (xy 443.035771 -358.364296) (xy 443.020288 -358.416799)
			(xy 442.997451 -358.466546) (xy 442.967731 -358.512514) (xy 442.950092 -358.533446) (xy 442.943996 -358.540558)
			(xy 442.937646 -358.557576) (xy 442.937646 -358.64292) (xy 442.943996 -358.659938) (xy 442.950092 -358.66705)
			(xy 442.96772 -358.687991) (xy 442.997434 -358.733961) (xy 443.020272 -358.783707) (xy 443.035766 -358.836205)
			(xy 443.043597 -358.890379) (xy 443.044072 -358.917748) (xy 443.04358 -358.945322) (xy 443.035634 -358.999894)
			(xy 443.019915 -359.052754) (xy 442.99675 -359.1028) (xy 442.966622 -359.14899) (xy 442.930158 -359.190362)
			(xy 442.909452 -359.208578) (xy 442.90134 -359.216186) (xy 442.891984 -359.236334) (xy 442.891418 -359.24744)
			(xy 442.891418 -359.324656) (xy 442.891989 -359.335766) (xy 442.901325 -359.355925) (xy 442.909452 -359.363518)
			(xy 442.930165 -359.381727) (xy 442.966638 -359.423095) (xy 442.996771 -359.469285) (xy 443.019936 -359.519334)
			(xy 443.035652 -359.572197) (xy 443.043589 -359.626773) (xy 443.044072 -359.654348) (xy 443.043582 -359.681717)
			(xy 443.035771 -359.735896) (xy 443.020288 -359.788399) (xy 442.997451 -359.838146) (xy 442.967731 -359.884114)
			(xy 442.950092 -359.905046) (xy 442.943996 -359.912158) (xy 442.937646 -359.929176) (xy 442.937646 -360.01452)
			(xy 442.943996 -360.031538) (xy 442.950092 -360.03865) (xy 442.967779 -360.059545) (xy 442.9975 -360.10552)
			(xy 443.020342 -360.155272) (xy 443.035833 -360.20778) (xy 443.043657 -360.261963) (xy 443.043652 -360.316709)
			(xy 443.035818 -360.370891) (xy 443.020316 -360.423395) (xy 442.997465 -360.473144) (xy 442.967735 -360.519113)
			(xy 442.950092 -360.540046) (xy 442.943996 -360.547158) (xy 442.937646 -360.564176) (xy 442.937646 -360.64952)
			(xy 442.943996 -360.666538) (xy 442.950092 -360.67365) (xy 442.967779 -360.694545) (xy 442.9975 -360.74052)
			(xy 443.020342 -360.790272) (xy 443.035833 -360.84278) (xy 443.043657 -360.896963) (xy 443.043652 -360.951709)
			(xy 443.035818 -361.005891) (xy 443.020316 -361.058395) (xy 442.997465 -361.108144) (xy 442.967735 -361.154113)
			(xy 442.950092 -361.175046) (xy 442.943996 -361.182158) (xy 442.937646 -361.199176) (xy 442.937646 -361.28452)
			(xy 442.943996 -361.301538) (xy 442.950092 -361.30865) (xy 442.96772 -361.329591) (xy 442.997434 -361.375561)
			(xy 443.020272 -361.425307) (xy 443.035766 -361.477805) (xy 443.043597 -361.531979) (xy 443.044072 -361.559348)
			(xy 443.043667 -361.586602) (xy 443.035903 -361.640555) (xy 443.02054 -361.692853) (xy 442.99789 -361.742433)
			(xy 442.968416 -361.788285) (xy 442.932716 -361.829475) (xy 442.891517 -361.865166) (xy 442.845659 -361.894631)
			(xy 442.796074 -361.917269) (xy 442.743772 -361.932621) (xy 442.689818 -361.940373) (xy 442.662564 -361.940856)
			(xy 442.635192 -361.940422) (xy 442.581012 -361.932598) (xy 442.528508 -361.917102) (xy 442.478761 -361.894253)
			(xy 442.432796 -361.864521) (xy 442.411866 -361.846876) (xy 442.404754 -361.84078) (xy 442.387736 -361.83443)
			(xy 442.302392 -361.83443) (xy 442.285374 -361.84078) (xy 442.278262 -361.846876) (xy 442.274452 -361.850178)
			(xy 442.26634 -361.857786) (xy 442.256984 -361.877934) (xy 442.256418 -361.88904) (xy 442.256418 -361.966256)
			(xy 442.256989 -361.977366) (xy 442.266325 -361.997525) (xy 442.274452 -362.005118) (xy 442.295165 -362.023327)
			(xy 442.331638 -362.064695) (xy 442.361771 -362.110885) (xy 442.384936 -362.160934) (xy 442.400652 -362.213797)
			(xy 442.408589 -362.268373) (xy 442.409072 -362.295948) (xy 442.408667 -362.323202) (xy 442.400903 -362.377155)
			(xy 442.38554 -362.429453) (xy 442.36289 -362.479033) (xy 442.333416 -362.524885) (xy 442.297716 -362.566075)
			(xy 442.256517 -362.601766) (xy 442.210659 -362.631231) (xy 442.161074 -362.653869) (xy 442.108772 -362.669221)
			(xy 442.054818 -362.676973) (xy 442.027564 -362.677456) (xy 441.998087 -362.676888) (xy 441.939835 -362.667827)
			(xy 441.88367 -362.649912) (xy 441.83093 -362.623569) (xy 441.782872 -362.589424) (xy 441.761372 -362.569252)
			(xy 441.754047 -362.562706) (xy 441.735879 -362.555269) (xy 441.726066 -362.554774) (xy 441.672726 -362.554774)
			(xy 441.665868 -362.56214) (xy 441.659319 -362.569463) (xy 441.651883 -362.587632) (xy 441.65139 -362.597446)
			(xy 441.65139 -362.62945) (xy 441.651862 -362.639266) (xy 441.659317 -362.65743) (xy 441.665868 -362.664756)
			(xy 441.686023 -362.686272) (xy 441.72017 -362.734327) (xy 441.746519 -362.787062) (xy 441.764445 -362.843223)
			(xy 441.77352 -362.901472) (xy 441.774072 -362.930948) (xy 441.773667 -362.958202) (xy 441.765903 -363.012155)
			(xy 441.75054 -363.064453) (xy 441.72789 -363.114033) (xy 441.698416 -363.159885) (xy 441.662716 -363.201075)
			(xy 441.621517 -363.236766) (xy 441.575659 -363.266231) (xy 441.526074 -363.288869) (xy 441.473772 -363.304221)
			(xy 441.419818 -363.311973) (xy 441.392564 -363.312456) (xy 441.365192 -363.312022) (xy 441.311012 -363.304198)
			(xy 441.258508 -363.288702) (xy 441.208761 -363.265853) (xy 441.162796 -363.236121) (xy 441.141866 -363.218476)
			(xy 441.134754 -363.21238) (xy 441.117736 -363.20603) (xy 441.032392 -363.20603) (xy 441.015374 -363.21238)
			(xy 441.008262 -363.218476) (xy 440.987329 -363.236117) (xy 440.941361 -363.265841) (xy 440.891615 -363.288687)
			(xy 440.839113 -363.304183) (xy 440.784935 -363.312012) (xy 440.730193 -363.312012) (xy 440.676015 -363.304183)
			(xy 440.623513 -363.288687) (xy 440.573767 -363.265841) (xy 440.527799 -363.236117) (xy 440.506866 -363.218476)
			(xy 440.499754 -363.21238) (xy 440.482736 -363.20603) (xy 440.397392 -363.20603) (xy 440.380374 -363.21238)
			(xy 440.373262 -363.218476) (xy 440.352314 -363.236096) (xy 440.306346 -363.265811) (xy 440.256603 -363.288651)
			(xy 440.204105 -363.304147) (xy 440.149932 -363.31198) (xy 440.122564 -363.312456) (xy 440.095314 -363.311956)
			(xy 440.041369 -363.304196) (xy 439.989078 -363.288838) (xy 439.939504 -363.266197) (xy 439.893656 -363.236731)
			(xy 439.852467 -363.201041) (xy 439.816776 -363.159854) (xy 439.787309 -363.114007) (xy 439.764666 -363.064433)
			(xy 439.749307 -363.012142) (xy 439.741545 -362.958198) (xy 439.741056 -362.930948) (xy 423.817288 -362.930948)
			(xy 423.817288 -363.954314) (xy 425.230796 -363.954314) (xy 425.234867 -363.898692) (xy 425.246993 -363.844255)
			(xy 425.266916 -363.792164) (xy 425.294212 -363.743529) (xy 425.328298 -363.699386) (xy 425.368447 -363.660677)
			(xy 425.413805 -363.628226) (xy 425.463405 -363.602725) (xy 425.516189 -363.584718) (xy 425.571032 -363.574588)
			(xy 425.626766 -363.572551) (xy 425.682203 -363.578651) (xy 425.73616 -363.592757) (xy 425.787489 -363.614569)
			(xy 425.835095 -363.643623) (xy 425.877963 -363.679298) (xy 425.91518 -363.720835) (xy 425.945953 -363.767348)
			(xy 425.969625 -363.817845) (xy 425.985693 -363.871252) (xy 425.993813 -363.926428) (xy 425.994322 -363.954314)
			(xy 425.993813 -363.9822) (xy 425.985693 -364.037376) (xy 425.969625 -364.090783) (xy 425.945953 -364.14128)
			(xy 425.91518 -364.187793) (xy 425.877963 -364.22933) (xy 425.835095 -364.265005) (xy 425.787489 -364.294059)
			(xy 425.73616 -364.315871) (xy 425.682203 -364.329977) (xy 425.626766 -364.336077) (xy 425.571032 -364.33404)
			(xy 425.516189 -364.32391) (xy 425.463405 -364.305903) (xy 425.413805 -364.280402) (xy 425.368447 -364.247951)
			(xy 425.328298 -364.209242) (xy 425.294212 -364.165099) (xy 425.266916 -364.116464) (xy 425.246993 -364.064373)
			(xy 425.234867 -364.009936) (xy 425.230796 -363.954314) (xy 423.817288 -363.954314) (xy 423.817288 -364.507526)
			(xy 424.072048 -364.507526) (xy 424.076119 -364.451904) (xy 424.088245 -364.397467) (xy 424.108168 -364.345376)
			(xy 424.135464 -364.296741) (xy 424.16955 -364.252598) (xy 424.209699 -364.213889) (xy 424.255057 -364.181438)
			(xy 424.304657 -364.155937) (xy 424.357441 -364.13793) (xy 424.412284 -364.1278) (xy 424.468018 -364.125763)
			(xy 424.523455 -364.131863) (xy 424.577412 -364.145969) (xy 424.628741 -364.167781) (xy 424.676347 -364.196835)
			(xy 424.719215 -364.23251) (xy 424.756432 -364.274047) (xy 424.787205 -364.32056) (xy 424.81052 -364.370296)
			(xy 431.124356 -364.370296) (xy 431.124356 -364.2856) (xy 431.132407 -364.201286) (xy 431.148436 -364.11812)
			(xy 431.172297 -364.036853) (xy 431.203776 -363.958223) (xy 431.242587 -363.882942) (xy 431.288377 -363.81169)
			(xy 431.340733 -363.745114) (xy 431.399181 -363.683816) (xy 431.463191 -363.628351) (xy 431.532183 -363.579222)
			(xy 431.605533 -363.536873) (xy 431.682576 -363.501689) (xy 431.762615 -363.473987) (xy 431.844924 -363.454019)
			(xy 431.928759 -363.441966) (xy 432.01336 -363.437936) (xy 432.097961 -363.441966) (xy 432.181796 -363.454019)
			(xy 432.264105 -363.473987) (xy 432.344144 -363.501689) (xy 432.421187 -363.536873) (xy 432.494537 -363.579222)
			(xy 432.563529 -363.628351) (xy 432.627539 -363.683816) (xy 432.685987 -363.745114) (xy 432.738343 -363.81169)
			(xy 432.784133 -363.882942) (xy 432.822944 -363.958223) (xy 432.854423 -364.036853) (xy 432.878284 -364.11812)
			(xy 432.894313 -364.201286) (xy 432.902364 -364.2856) (xy 432.902868 -364.327948) (xy 432.902364 -364.370296)
			(xy 432.894313 -364.45461) (xy 432.878284 -364.537776) (xy 432.854423 -364.619043) (xy 432.822944 -364.697673)
			(xy 432.784133 -364.772954) (xy 432.738343 -364.844206) (xy 432.685987 -364.910782) (xy 432.627539 -364.97208)
			(xy 432.563529 -365.027545) (xy 432.494537 -365.076674) (xy 432.421187 -365.119023) (xy 432.344144 -365.154207)
			(xy 432.264105 -365.181909) (xy 432.181796 -365.201877) (xy 432.097961 -365.21393) (xy 432.01336 -365.217961)
			(xy 431.928759 -365.21393) (xy 431.844924 -365.201877) (xy 431.762615 -365.181909) (xy 431.682576 -365.154207)
			(xy 431.605533 -365.119023) (xy 431.532183 -365.076674) (xy 431.463191 -365.027545) (xy 431.399181 -364.97208)
			(xy 431.340733 -364.910782) (xy 431.288377 -364.844206) (xy 431.242587 -364.772954) (xy 431.203776 -364.697673)
			(xy 431.172297 -364.619043) (xy 431.148436 -364.537776) (xy 431.132407 -364.45461) (xy 431.124356 -364.370296)
			(xy 424.81052 -364.370296) (xy 424.810877 -364.371057) (xy 424.826945 -364.424464) (xy 424.835065 -364.47964)
			(xy 424.835574 -364.507526) (xy 424.835065 -364.535412) (xy 424.826945 -364.590588) (xy 424.810877 -364.643995)
			(xy 424.787205 -364.694492) (xy 424.756432 -364.741005) (xy 424.719215 -364.782542) (xy 424.676347 -364.818217)
			(xy 424.628741 -364.847271) (xy 424.577412 -364.869083) (xy 424.523455 -364.883189) (xy 424.468018 -364.889289)
			(xy 424.412284 -364.887252) (xy 424.357441 -364.877122) (xy 424.304657 -364.859115) (xy 424.255057 -364.833614)
			(xy 424.209699 -364.801163) (xy 424.16955 -364.762454) (xy 424.135464 -364.718311) (xy 424.108168 -364.669676)
			(xy 424.088245 -364.617585) (xy 424.076119 -364.563148) (xy 424.072048 -364.507526) (xy 423.817288 -364.507526)
			(xy 423.817288 -365.068104) (xy 423.817288 -365.068358) (xy 423.817672 -365.076714) (xy 423.82312 -365.092519)
			(xy 423.827956 -365.099346) (xy 423.832274 -365.104172) (xy 425.259754 -366.531398) (xy 425.268936 -366.54105)
			(xy 427.288196 -366.54105) (xy 427.292267 -366.485428) (xy 427.304393 -366.430991) (xy 427.324316 -366.3789)
			(xy 427.351612 -366.330265) (xy 427.385698 -366.286122) (xy 427.425847 -366.247413) (xy 427.471205 -366.214962)
			(xy 427.520805 -366.189461) (xy 427.573589 -366.171454) (xy 427.628432 -366.161324) (xy 427.684166 -366.159287)
			(xy 427.739603 -366.165387) (xy 427.79356 -366.179493) (xy 427.844889 -366.201305) (xy 427.892495 -366.230359)
			(xy 427.935363 -366.266034) (xy 427.97258 -366.307571) (xy 428.003353 -366.354084) (xy 428.027025 -366.404581)
			(xy 428.043093 -366.457988) (xy 428.051213 -366.513164) (xy 428.051722 -366.54105) (xy 428.051213 -366.568936)
			(xy 428.043093 -366.624112) (xy 428.027025 -366.677519) (xy 428.003353 -366.728016) (xy 427.97258 -366.774529)
			(xy 427.935363 -366.816066) (xy 427.892495 -366.851741) (xy 427.844889 -366.880795) (xy 427.79356 -366.902607)
			(xy 427.739603 -366.916713) (xy 427.684166 -366.922813) (xy 427.628432 -366.920776) (xy 427.573589 -366.910646)
			(xy 427.520805 -366.892639) (xy 427.471205 -366.867138) (xy 427.425847 -366.834687) (xy 427.385698 -366.795978)
			(xy 427.351612 -366.751835) (xy 427.324316 -366.7032) (xy 427.304393 -366.651109) (xy 427.292267 -366.596672)
			(xy 427.288196 -366.54105) (xy 425.268936 -366.54105) (xy 425.27355 -366.5459) (xy 425.295775 -366.579182)
			(xy 425.311087 -366.616156) (xy 425.318902 -366.655406) (xy 425.319444 -366.675416) (xy 425.319444 -368.249454)
			(xy 431.997356 -368.249454) (xy 432.001427 -368.193832) (xy 432.013553 -368.139395) (xy 432.033476 -368.087304)
			(xy 432.060772 -368.038669) (xy 432.094858 -367.994526) (xy 432.135007 -367.955817) (xy 432.180365 -367.923366)
			(xy 432.229965 -367.897865) (xy 432.282749 -367.879858) (xy 432.337592 -367.869728) (xy 432.393326 -367.867691)
			(xy 432.448763 -367.873791) (xy 432.50272 -367.887897) (xy 432.554049 -367.909709) (xy 432.601655 -367.938763)
			(xy 432.644523 -367.974438) (xy 432.68174 -368.015975) (xy 432.712513 -368.062488) (xy 432.736185 -368.112985)
			(xy 432.752253 -368.166392) (xy 432.760373 -368.221568) (xy 432.760882 -368.249454) (xy 432.760373 -368.27734)
			(xy 432.752253 -368.332516) (xy 432.736185 -368.385923) (xy 432.712513 -368.43642) (xy 432.68174 -368.482933)
			(xy 432.644523 -368.52447) (xy 432.601655 -368.560145) (xy 432.554049 -368.589199) (xy 432.50272 -368.611011)
			(xy 432.448763 -368.625117) (xy 432.393326 -368.631217) (xy 432.337592 -368.62918) (xy 432.282749 -368.61905)
			(xy 432.229965 -368.601043) (xy 432.180365 -368.575542) (xy 432.135007 -368.543091) (xy 432.094858 -368.504382)
			(xy 432.060772 -368.460239) (xy 432.033476 -368.411604) (xy 432.013553 -368.359513) (xy 432.001427 -368.305076)
			(xy 431.997356 -368.249454) (xy 425.319444 -368.249454) (xy 425.319444 -368.686588) (xy 426.728634 -368.686588)
			(xy 426.732705 -368.630966) (xy 426.744831 -368.576529) (xy 426.764754 -368.524438) (xy 426.79205 -368.475803)
			(xy 426.826136 -368.43166) (xy 426.866285 -368.392951) (xy 426.911643 -368.3605) (xy 426.961243 -368.334999)
			(xy 427.014027 -368.316992) (xy 427.06887 -368.306862) (xy 427.124604 -368.304825) (xy 427.180041 -368.310925)
			(xy 427.233998 -368.325031) (xy 427.285327 -368.346843) (xy 427.332933 -368.375897) (xy 427.375801 -368.411572)
			(xy 427.413018 -368.453109) (xy 427.443791 -368.499622) (xy 427.467463 -368.550119) (xy 427.483531 -368.603526)
			(xy 427.491651 -368.658702) (xy 427.492039 -368.679984) (xy 428.63973 -368.679984) (xy 428.643801 -368.624362)
			(xy 428.655927 -368.569925) (xy 428.67585 -368.517834) (xy 428.703146 -368.469199) (xy 428.737232 -368.425056)
			(xy 428.777381 -368.386347) (xy 428.822739 -368.353896) (xy 428.872339 -368.328395) (xy 428.925123 -368.310388)
			(xy 428.979966 -368.300258) (xy 429.0357 -368.298221) (xy 429.091137 -368.304321) (xy 429.145094 -368.318427)
			(xy 429.196423 -368.340239) (xy 429.244029 -368.369293) (xy 429.286897 -368.404968) (xy 429.324114 -368.446505)
			(xy 429.354887 -368.493018) (xy 429.378559 -368.543515) (xy 429.394627 -368.596922) (xy 429.402747 -368.652098)
			(xy 429.403256 -368.679984) (xy 429.402747 -368.70787) (xy 429.396459 -368.750596) (xy 432.715414 -368.750596)
			(xy 432.719485 -368.694974) (xy 432.731611 -368.640537) (xy 432.751534 -368.588446) (xy 432.77883 -368.539811)
			(xy 432.812916 -368.495668) (xy 432.853065 -368.456959) (xy 432.898423 -368.424508) (xy 432.948023 -368.399007)
			(xy 433.000807 -368.381) (xy 433.05565 -368.37087) (xy 433.111384 -368.368833) (xy 433.166821 -368.374933)
			(xy 433.220778 -368.389039) (xy 433.272107 -368.410851) (xy 433.319713 -368.439905) (xy 433.362581 -368.47558)
			(xy 433.399798 -368.517117) (xy 433.430571 -368.56363) (xy 433.454243 -368.614127) (xy 433.470311 -368.667534)
			(xy 433.478431 -368.72271) (xy 433.47894 -368.750596) (xy 433.478431 -368.778482) (xy 433.470311 -368.833658)
			(xy 433.454243 -368.887065) (xy 433.430571 -368.937562) (xy 433.399798 -368.984075) (xy 433.362581 -369.025612)
			(xy 433.319713 -369.061287) (xy 433.272107 -369.090341) (xy 433.220778 -369.112153) (xy 433.166821 -369.126259)
			(xy 433.111384 -369.132359) (xy 433.05565 -369.130322) (xy 433.000807 -369.120192) (xy 432.948023 -369.102185)
			(xy 432.898423 -369.076684) (xy 432.853065 -369.044233) (xy 432.812916 -369.005524) (xy 432.77883 -368.961381)
			(xy 432.751534 -368.912746) (xy 432.731611 -368.860655) (xy 432.719485 -368.806218) (xy 432.715414 -368.750596)
			(xy 429.396459 -368.750596) (xy 429.394627 -368.763046) (xy 429.378559 -368.816453) (xy 429.354887 -368.86695)
			(xy 429.324114 -368.913463) (xy 429.286897 -368.955) (xy 429.244029 -368.990675) (xy 429.196423 -369.019729)
			(xy 429.145094 -369.041541) (xy 429.091137 -369.055647) (xy 429.0357 -369.061747) (xy 428.979966 -369.05971)
			(xy 428.925123 -369.04958) (xy 428.872339 -369.031573) (xy 428.822739 -369.006072) (xy 428.777381 -368.973621)
			(xy 428.737232 -368.934912) (xy 428.703146 -368.890769) (xy 428.67585 -368.842134) (xy 428.655927 -368.790043)
			(xy 428.643801 -368.735606) (xy 428.63973 -368.679984) (xy 427.492039 -368.679984) (xy 427.49216 -368.686588)
			(xy 427.491651 -368.714474) (xy 427.483531 -368.76965) (xy 427.467463 -368.823057) (xy 427.443791 -368.873554)
			(xy 427.413018 -368.920067) (xy 427.375801 -368.961604) (xy 427.332933 -368.997279) (xy 427.285327 -369.026333)
			(xy 427.233998 -369.048145) (xy 427.180041 -369.062251) (xy 427.124604 -369.068351) (xy 427.06887 -369.066314)
			(xy 427.014027 -369.056184) (xy 426.961243 -369.038177) (xy 426.911643 -369.012676) (xy 426.866285 -368.980225)
			(xy 426.826136 -368.941516) (xy 426.79205 -368.897373) (xy 426.764754 -368.848738) (xy 426.744831 -368.796647)
			(xy 426.732705 -368.74221) (xy 426.728634 -368.686588) (xy 425.319444 -368.686588) (xy 425.319444 -369.92052)
			(xy 425.319868 -369.930535) (xy 425.327543 -369.949038) (xy 425.341716 -369.963193) (xy 425.360228 -369.970845)
			(xy 425.370244 -369.97132) (xy 441.895992 -369.97132) (xy 441.905864 -369.970847) (xy 441.924145 -369.963387)
			(xy 441.931552 -369.956842) (xy 441.931806 -369.956588) (xy 445.379094 -366.5093) (xy 445.379602 -366.508792)
			(xy 445.386197 -366.501416) (xy 445.393671 -366.483116) (xy 445.39408 -366.473232) (xy 445.39408 -329.179682)
			(xy 445.393916 -329.173672) (xy 445.391098 -329.161986) (xy 445.388492 -329.156568) (xy 445.386651 -329.153095)
			(xy 445.382056 -329.146717) (xy 445.379348 -329.143868) (xy 443.826392 -327.590912) (xy 443.82354 -327.588207)
			(xy 443.81716 -327.583617) (xy 443.813692 -327.581768) (xy 443.808266 -327.579183) (xy 443.796586 -327.576353)
			(xy 443.790578 -327.57618) (xy 413.763206 -327.57618) (xy 413.757364 -327.576434) (xy 413.748763 -327.577792)
			(xy 413.733146 -327.585467) (xy 413.720984 -327.597911) (xy 413.716978 -327.605644) (xy 413.71393 -327.61301)
			(xy 413.710374 -327.6219) (xy 413.713168 -327.636632) (xy 413.714905 -327.643972) (xy 413.721998 -327.657275)
			(xy 413.727138 -327.662794) (xy 414.489646 -328.425302) (xy 414.917128 -328.85253) (xy 414.934382 -328.870626)
			(xy 414.962187 -328.912172) (xy 414.981355 -328.958344) (xy 414.991151 -329.007367) (xy 414.991804 -329.032362)
			(xy 414.991804 -332.27137) (xy 414.991165 -332.296366) (xy 414.981364 -332.345389) (xy 414.96219 -332.391559)
			(xy 414.934381 -332.433104) (xy 414.917128 -332.451202) (xy 414.36163 -333.0067) (xy 414.34352 -333.02392)
			(xy 414.301959 -333.051656) (xy 414.255789 -333.07076) (xy 414.206781 -333.080499) (xy 414.181798 -333.081122)
			(xy 413.873696 -333.081122) (xy 413.873696 -333.080868) (xy 413.505142 -333.080868) (xy 413.496864 -333.081194)
			(xy 413.481186 -333.086517) (xy 413.474408 -333.091282) (xy 413.467804 -333.096108) (xy 413.45866 -333.109824)
			(xy 413.456374 -333.118206) (xy 413.448583 -333.144704) (xy 413.426418 -333.19529) (xy 413.397188 -333.242152)
			(xy 413.361506 -333.284307) (xy 413.320117 -333.320876) (xy 413.273887 -333.351093) (xy 413.223781 -333.374327)
			(xy 413.170849 -333.390091) (xy 413.116197 -333.398057) (xy 413.060967 -333.398057) (xy 413.006315 -333.390091)
			(xy 412.953383 -333.374327) (xy 412.903277 -333.351093) (xy 412.857047 -333.320876) (xy 412.815658 -333.284307)
			(xy 412.779976 -333.242152) (xy 412.750746 -333.19529) (xy 412.728581 -333.144704) (xy 412.72079 -333.118206)
			(xy 412.718297 -333.110217) (xy 412.708974 -333.096332) (xy 412.702502 -333.091028) (xy 412.695898 -333.086202)
			(xy 412.680404 -333.080868) (xy 412.581598 -333.080868) (xy 412.58109 -333.080868) (xy 412.572876 -333.081225)
			(xy 412.557331 -333.086546) (xy 412.55061 -333.091282) (xy 412.54553 -333.095854) (xy 412.356046 -333.285338)
			(xy 412.351474 -333.290418) (xy 412.34675 -333.297144) (xy 412.341435 -333.312688) (xy 412.34106 -333.320898)
			(xy 412.34106 -335.314799) (xy 418.990283 -335.314799) (xy 418.994013 -335.261548) (xy 419.005129 -335.209336)
			(xy 419.023415 -335.159184) (xy 419.048513 -335.11207) (xy 419.079934 -335.068915) (xy 419.117063 -335.030562)
			(xy 419.137846 -335.013808) (xy 419.146607 -335.006246) (xy 419.156789 -334.985487) (xy 419.157404 -334.97393)
			(xy 419.157404 -334.893666) (xy 419.156794 -334.882103) (xy 419.146627 -334.861332) (xy 419.137846 -334.853788)
			(xy 419.117062 -334.837037) (xy 419.079932 -334.798683) (xy 419.048512 -334.755527) (xy 419.023414 -334.708414)
			(xy 419.005128 -334.658262) (xy 418.994012 -334.60605) (xy 418.990283 -334.552799) (xy 418.994013 -334.499548)
			(xy 419.005129 -334.447336) (xy 419.023415 -334.397184) (xy 419.048513 -334.35007) (xy 419.079934 -334.306915)
			(xy 419.117063 -334.268562) (xy 419.137846 -334.251808) (xy 419.146607 -334.244246) (xy 419.156789 -334.223487)
			(xy 419.157404 -334.21193) (xy 419.157404 -334.131666) (xy 419.156794 -334.120103) (xy 419.146627 -334.099332)
			(xy 419.137846 -334.091788) (xy 419.115346 -334.073617) (xy 419.075614 -334.031592) (xy 419.042678 -333.984052)
			(xy 419.017293 -333.932087) (xy 419.00004 -333.876887) (xy 418.991314 -333.819715) (xy 418.99078 -333.790798)
			(xy 418.991266 -333.763547) (xy 418.999022 -333.709599) (xy 419.014377 -333.657304) (xy 419.037019 -333.607727)
			(xy 419.066485 -333.561877) (xy 419.102176 -333.520686) (xy 419.143367 -333.484995) (xy 419.189217 -333.455529)
			(xy 419.238794 -333.432887) (xy 419.291089 -333.417532) (xy 419.345037 -333.409776) (xy 419.399539 -333.409776)
			(xy 419.453487 -333.417532) (xy 419.505782 -333.432887) (xy 419.555359 -333.455529) (xy 419.601209 -333.484995)
			(xy 419.6424 -333.520686) (xy 419.678091 -333.561877) (xy 419.707557 -333.607727) (xy 419.730199 -333.657304)
			(xy 419.745554 -333.709599) (xy 419.75331 -333.763547) (xy 419.753796 -333.790798) (xy 419.753278 -333.819715)
			(xy 419.744549 -333.876886) (xy 419.727291 -333.932085) (xy 419.701899 -333.984047) (xy 419.668956 -334.031581)
			(xy 419.629215 -334.073598) (xy 419.60673 -334.091788) (xy 419.597966 -334.099347) (xy 419.587787 -334.120109)
			(xy 419.587172 -334.131666) (xy 419.587172 -334.21193) (xy 419.587757 -334.223497) (xy 419.597939 -334.24427)
			(xy 419.60673 -334.251808) (xy 419.627512 -334.268563) (xy 419.664643 -334.306916) (xy 419.696065 -334.35007)
			(xy 419.721165 -334.397183) (xy 419.739452 -334.447335) (xy 419.750569 -334.499547) (xy 419.754299 -334.552799)
			(xy 419.750569 -334.60605) (xy 419.739453 -334.658262) (xy 419.721166 -334.708414) (xy 419.696067 -334.755528)
			(xy 419.664645 -334.798682) (xy 419.627513 -334.837035) (xy 419.60673 -334.853788) (xy 419.597966 -334.861347)
			(xy 419.587787 -334.882109) (xy 419.587172 -334.893666) (xy 419.587172 -334.97393) (xy 419.587757 -334.985497)
			(xy 419.597939 -335.00627) (xy 419.60673 -335.013808) (xy 419.627512 -335.030563) (xy 419.664643 -335.068916)
			(xy 419.696065 -335.11207) (xy 419.721165 -335.159183) (xy 419.739452 -335.209335) (xy 419.745683 -335.238599)
			(xy 421.403283 -335.238599) (xy 421.407013 -335.185348) (xy 421.418129 -335.133136) (xy 421.436415 -335.082984)
			(xy 421.461513 -335.03587) (xy 421.492934 -334.992715) (xy 421.530063 -334.954362) (xy 421.550846 -334.937608)
			(xy 421.559607 -334.930046) (xy 421.569789 -334.909287) (xy 421.570404 -334.89773) (xy 421.570404 -334.817466)
			(xy 421.569794 -334.805903) (xy 421.559627 -334.785132) (xy 421.550846 -334.777588) (xy 421.530062 -334.760837)
			(xy 421.492932 -334.722483) (xy 421.461512 -334.679327) (xy 421.436414 -334.632214) (xy 421.418128 -334.582062)
			(xy 421.407012 -334.52985) (xy 421.403283 -334.476599) (xy 421.407013 -334.423348) (xy 421.418129 -334.371136)
			(xy 421.436415 -334.320984) (xy 421.461513 -334.27387) (xy 421.492934 -334.230715) (xy 421.530063 -334.192362)
			(xy 421.550846 -334.175608) (xy 421.559607 -334.168046) (xy 421.569789 -334.147287) (xy 421.570404 -334.13573)
			(xy 421.570404 -334.055466) (xy 421.569794 -334.043903) (xy 421.559627 -334.023132) (xy 421.550846 -334.015588)
			(xy 421.528346 -333.997417) (xy 421.488614 -333.955392) (xy 421.455678 -333.907852) (xy 421.430293 -333.855887)
			(xy 421.41304 -333.800687) (xy 421.404314 -333.743515) (xy 421.40378 -333.714598) (xy 421.404266 -333.687347)
			(xy 421.412022 -333.633399) (xy 421.427377 -333.581104) (xy 421.450019 -333.531527) (xy 421.479485 -333.485677)
			(xy 421.515176 -333.444486) (xy 421.556367 -333.408795) (xy 421.602217 -333.379329) (xy 421.651794 -333.356687)
			(xy 421.704089 -333.341332) (xy 421.758037 -333.333576) (xy 421.812539 -333.333576) (xy 421.866487 -333.341332)
			(xy 421.918782 -333.356687) (xy 421.968359 -333.379329) (xy 422.014209 -333.408795) (xy 422.0554 -333.444486)
			(xy 422.091091 -333.485677) (xy 422.120557 -333.531527) (xy 422.143199 -333.581104) (xy 422.158554 -333.633399)
			(xy 422.16631 -333.687347) (xy 422.166796 -333.714598) (xy 422.166278 -333.743515) (xy 422.157549 -333.800686)
			(xy 422.140291 -333.855885) (xy 422.114899 -333.907847) (xy 422.081956 -333.955381) (xy 422.042215 -333.997398)
			(xy 422.01973 -334.015588) (xy 422.010966 -334.023147) (xy 422.000787 -334.043909) (xy 422.000172 -334.055466)
			(xy 422.000172 -334.13573) (xy 422.000757 -334.147297) (xy 422.010939 -334.16807) (xy 422.01973 -334.175608)
			(xy 422.040512 -334.192363) (xy 422.077643 -334.230716) (xy 422.109065 -334.27387) (xy 422.134165 -334.320983)
			(xy 422.152452 -334.371135) (xy 422.163569 -334.423347) (xy 422.167299 -334.476599) (xy 422.163569 -334.52985)
			(xy 422.152453 -334.582062) (xy 422.134166 -334.632214) (xy 422.109067 -334.679328) (xy 422.077645 -334.722482)
			(xy 422.040513 -334.760835) (xy 422.01973 -334.777588) (xy 422.010966 -334.785147) (xy 422.000787 -334.805909)
			(xy 422.000172 -334.817466) (xy 422.000172 -334.89773) (xy 422.000757 -334.909297) (xy 422.010939 -334.93007)
			(xy 422.01973 -334.937608) (xy 422.040512 -334.954363) (xy 422.077643 -334.992716) (xy 422.109065 -335.03587)
			(xy 422.134165 -335.082983) (xy 422.152452 -335.133135) (xy 422.163569 -335.185347) (xy 422.167299 -335.238599)
			(xy 425.060883 -335.238599) (xy 425.064613 -335.185348) (xy 425.075729 -335.133136) (xy 425.094015 -335.082984)
			(xy 425.119113 -335.03587) (xy 425.150534 -334.992715) (xy 425.187663 -334.954362) (xy 425.208446 -334.937608)
			(xy 425.217207 -334.930046) (xy 425.227389 -334.909287) (xy 425.228004 -334.89773) (xy 425.228004 -334.817466)
			(xy 425.227394 -334.805903) (xy 425.217227 -334.785132) (xy 425.208446 -334.777588) (xy 425.187662 -334.760837)
			(xy 425.150532 -334.722483) (xy 425.119112 -334.679327) (xy 425.094014 -334.632214) (xy 425.075728 -334.582062)
			(xy 425.064612 -334.52985) (xy 425.060883 -334.476599) (xy 425.064613 -334.423348) (xy 425.075729 -334.371136)
			(xy 425.094015 -334.320984) (xy 425.119113 -334.27387) (xy 425.150534 -334.230715) (xy 425.187663 -334.192362)
			(xy 425.208446 -334.175608) (xy 425.217207 -334.168046) (xy 425.227389 -334.147287) (xy 425.228004 -334.13573)
			(xy 425.228004 -334.055466) (xy 425.227394 -334.043903) (xy 425.217227 -334.023132) (xy 425.208446 -334.015588)
			(xy 425.185946 -333.997417) (xy 425.146214 -333.955392) (xy 425.113278 -333.907852) (xy 425.087893 -333.855887)
			(xy 425.07064 -333.800687) (xy 425.061914 -333.743515) (xy 425.06138 -333.714598) (xy 425.061866 -333.687347)
			(xy 425.069622 -333.633399) (xy 425.084977 -333.581104) (xy 425.107619 -333.531527) (xy 425.137085 -333.485677)
			(xy 425.172776 -333.444486) (xy 425.213967 -333.408795) (xy 425.259817 -333.379329) (xy 425.309394 -333.356687)
			(xy 425.361689 -333.341332) (xy 425.415637 -333.333576) (xy 425.470139 -333.333576) (xy 425.524087 -333.341332)
			(xy 425.576382 -333.356687) (xy 425.625959 -333.379329) (xy 425.671809 -333.408795) (xy 425.713 -333.444486)
			(xy 425.748691 -333.485677) (xy 425.778157 -333.531527) (xy 425.800799 -333.581104) (xy 425.816154 -333.633399)
			(xy 425.82391 -333.687347) (xy 425.824396 -333.714598) (xy 425.823878 -333.743515) (xy 425.815149 -333.800686)
			(xy 425.797891 -333.855885) (xy 425.772499 -333.907847) (xy 425.739556 -333.955381) (xy 425.699815 -333.997398)
			(xy 425.67733 -334.015588) (xy 425.668566 -334.023147) (xy 425.658387 -334.043909) (xy 425.657772 -334.055466)
			(xy 425.657772 -334.13573) (xy 425.658357 -334.147297) (xy 425.668539 -334.16807) (xy 425.67733 -334.175608)
			(xy 425.698112 -334.192363) (xy 425.735243 -334.230716) (xy 425.766665 -334.27387) (xy 425.791765 -334.320983)
			(xy 425.810052 -334.371135) (xy 425.821169 -334.423347) (xy 425.824899 -334.476599) (xy 425.821169 -334.52985)
			(xy 425.810053 -334.582062) (xy 425.791766 -334.632214) (xy 425.766667 -334.679328) (xy 425.735245 -334.722482)
			(xy 425.698113 -334.760835) (xy 425.67733 -334.777588) (xy 425.668566 -334.785147) (xy 425.658387 -334.805909)
			(xy 425.657772 -334.817466) (xy 425.657772 -334.89773) (xy 425.658357 -334.909297) (xy 425.668539 -334.93007)
			(xy 425.67733 -334.937608) (xy 425.698112 -334.954363) (xy 425.735243 -334.992716) (xy 425.766665 -335.03587)
			(xy 425.791765 -335.082983) (xy 425.810052 -335.133135) (xy 425.821169 -335.185347) (xy 425.824899 -335.238599)
			(xy 427.524683 -335.238599) (xy 427.528413 -335.185348) (xy 427.539529 -335.133136) (xy 427.557815 -335.082984)
			(xy 427.582913 -335.03587) (xy 427.614334 -334.992715) (xy 427.651463 -334.954362) (xy 427.672246 -334.937608)
			(xy 427.681007 -334.930046) (xy 427.691189 -334.909287) (xy 427.691804 -334.89773) (xy 427.691804 -334.817466)
			(xy 427.691194 -334.805903) (xy 427.681027 -334.785132) (xy 427.672246 -334.777588) (xy 427.651462 -334.760837)
			(xy 427.614332 -334.722483) (xy 427.582912 -334.679327) (xy 427.557814 -334.632214) (xy 427.539528 -334.582062)
			(xy 427.528412 -334.52985) (xy 427.524683 -334.476599) (xy 427.528413 -334.423348) (xy 427.539529 -334.371136)
			(xy 427.557815 -334.320984) (xy 427.582913 -334.27387) (xy 427.614334 -334.230715) (xy 427.651463 -334.192362)
			(xy 427.672246 -334.175608) (xy 427.681007 -334.168046) (xy 427.691189 -334.147287) (xy 427.691804 -334.13573)
			(xy 427.691804 -334.055466) (xy 427.691194 -334.043903) (xy 427.681027 -334.023132) (xy 427.672246 -334.015588)
			(xy 427.649746 -333.997417) (xy 427.610014 -333.955392) (xy 427.577078 -333.907852) (xy 427.551693 -333.855887)
			(xy 427.53444 -333.800687) (xy 427.525714 -333.743515) (xy 427.52518 -333.714598) (xy 427.525666 -333.687347)
			(xy 427.533422 -333.633399) (xy 427.548777 -333.581104) (xy 427.571419 -333.531527) (xy 427.600885 -333.485677)
			(xy 427.636576 -333.444486) (xy 427.677767 -333.408795) (xy 427.723617 -333.379329) (xy 427.773194 -333.356687)
			(xy 427.825489 -333.341332) (xy 427.879437 -333.333576) (xy 427.933939 -333.333576) (xy 427.987887 -333.341332)
			(xy 428.040182 -333.356687) (xy 428.089759 -333.379329) (xy 428.135609 -333.408795) (xy 428.1768 -333.444486)
			(xy 428.212491 -333.485677) (xy 428.241957 -333.531527) (xy 428.264599 -333.581104) (xy 428.279954 -333.633399)
			(xy 428.28771 -333.687347) (xy 428.288196 -333.714598) (xy 428.287678 -333.743515) (xy 428.278949 -333.800686)
			(xy 428.261691 -333.855885) (xy 428.236299 -333.907847) (xy 428.203356 -333.955381) (xy 428.163615 -333.997398)
			(xy 428.14113 -334.015588) (xy 428.132366 -334.023147) (xy 428.122187 -334.043909) (xy 428.121572 -334.055466)
			(xy 428.121572 -334.13573) (xy 428.122157 -334.147297) (xy 428.132339 -334.16807) (xy 428.14113 -334.175608)
			(xy 428.161912 -334.192363) (xy 428.199043 -334.230716) (xy 428.230465 -334.27387) (xy 428.255565 -334.320983)
			(xy 428.273852 -334.371135) (xy 428.284969 -334.423347) (xy 428.288699 -334.476599) (xy 428.284969 -334.52985)
			(xy 428.273853 -334.582062) (xy 428.255566 -334.632214) (xy 428.230467 -334.679328) (xy 428.199045 -334.722482)
			(xy 428.161913 -334.760835) (xy 428.14113 -334.777588) (xy 428.132366 -334.785147) (xy 428.122187 -334.805909)
			(xy 428.121572 -334.817466) (xy 428.121572 -334.89773) (xy 428.122157 -334.909297) (xy 428.132339 -334.93007)
			(xy 428.14113 -334.937608) (xy 428.161912 -334.954363) (xy 428.199043 -334.992716) (xy 428.230465 -335.03587)
			(xy 428.255565 -335.082983) (xy 428.273852 -335.133135) (xy 428.284969 -335.185347) (xy 428.28692 -335.213199)
			(xy 431.182283 -335.213199) (xy 431.186013 -335.159948) (xy 431.197129 -335.107736) (xy 431.215415 -335.057584)
			(xy 431.240513 -335.01047) (xy 431.271934 -334.967315) (xy 431.309063 -334.928962) (xy 431.329846 -334.912208)
			(xy 431.338607 -334.904646) (xy 431.348789 -334.883887) (xy 431.349404 -334.87233) (xy 431.349404 -334.792066)
			(xy 431.348794 -334.780503) (xy 431.338627 -334.759732) (xy 431.329846 -334.752188) (xy 431.309062 -334.735437)
			(xy 431.271932 -334.697083) (xy 431.240512 -334.653927) (xy 431.215414 -334.606814) (xy 431.197128 -334.556662)
			(xy 431.186012 -334.50445) (xy 431.182283 -334.451199) (xy 431.186013 -334.397948) (xy 431.197129 -334.345736)
			(xy 431.215415 -334.295584) (xy 431.240513 -334.24847) (xy 431.271934 -334.205315) (xy 431.309063 -334.166962)
			(xy 431.329846 -334.150208) (xy 431.338607 -334.142646) (xy 431.348789 -334.121887) (xy 431.349404 -334.11033)
			(xy 431.349404 -334.030066) (xy 431.348794 -334.018503) (xy 431.338627 -333.997732) (xy 431.329846 -333.990188)
			(xy 431.307346 -333.972017) (xy 431.267614 -333.929992) (xy 431.234678 -333.882452) (xy 431.209293 -333.830487)
			(xy 431.19204 -333.775287) (xy 431.183314 -333.718115) (xy 431.18278 -333.689198) (xy 431.183266 -333.661947)
			(xy 431.191022 -333.607999) (xy 431.206377 -333.555704) (xy 431.229019 -333.506127) (xy 431.258485 -333.460277)
			(xy 431.294176 -333.419086) (xy 431.335367 -333.383395) (xy 431.381217 -333.353929) (xy 431.430794 -333.331287)
			(xy 431.483089 -333.315932) (xy 431.537037 -333.308176) (xy 431.591539 -333.308176) (xy 431.645487 -333.315932)
			(xy 431.697782 -333.331287) (xy 431.747359 -333.353929) (xy 431.793209 -333.383395) (xy 431.8344 -333.419086)
			(xy 431.870091 -333.460277) (xy 431.899557 -333.506127) (xy 431.922199 -333.555704) (xy 431.937554 -333.607999)
			(xy 431.94531 -333.661947) (xy 431.945796 -333.689198) (xy 431.945278 -333.718115) (xy 431.936549 -333.775286)
			(xy 431.919291 -333.830485) (xy 431.893899 -333.882447) (xy 431.860956 -333.929981) (xy 431.821215 -333.971998)
			(xy 431.79873 -333.990188) (xy 431.789966 -333.997747) (xy 431.779787 -334.018509) (xy 431.779172 -334.030066)
			(xy 431.779172 -334.11033) (xy 431.779757 -334.121897) (xy 431.789939 -334.14267) (xy 431.79873 -334.150208)
			(xy 431.819512 -334.166963) (xy 431.856643 -334.205316) (xy 431.888065 -334.24847) (xy 431.913165 -334.295583)
			(xy 431.931452 -334.345735) (xy 431.942569 -334.397947) (xy 431.946299 -334.451199) (xy 431.942569 -334.50445)
			(xy 431.931453 -334.556662) (xy 431.913166 -334.606814) (xy 431.888067 -334.653928) (xy 431.856645 -334.697082)
			(xy 431.819513 -334.735435) (xy 431.79873 -334.752188) (xy 431.789966 -334.759747) (xy 431.779787 -334.780509)
			(xy 431.779172 -334.792066) (xy 431.779172 -334.87233) (xy 431.779757 -334.883897) (xy 431.789939 -334.90467)
			(xy 431.79873 -334.912208) (xy 431.819512 -334.928963) (xy 431.856643 -334.967316) (xy 431.888065 -335.01047)
			(xy 431.913165 -335.057583) (xy 431.931452 -335.107735) (xy 431.942569 -335.159947) (xy 431.946299 -335.213199)
			(xy 433.620683 -335.213199) (xy 433.624413 -335.159948) (xy 433.635529 -335.107736) (xy 433.653815 -335.057584)
			(xy 433.678913 -335.01047) (xy 433.710334 -334.967315) (xy 433.747463 -334.928962) (xy 433.768246 -334.912208)
			(xy 433.777007 -334.904646) (xy 433.787189 -334.883887) (xy 433.787804 -334.87233) (xy 433.787804 -334.792066)
			(xy 433.787194 -334.780503) (xy 433.777027 -334.759732) (xy 433.768246 -334.752188) (xy 433.747462 -334.735437)
			(xy 433.710332 -334.697083) (xy 433.678912 -334.653927) (xy 433.653814 -334.606814) (xy 433.635528 -334.556662)
			(xy 433.624412 -334.50445) (xy 433.620683 -334.451199) (xy 433.624413 -334.397948) (xy 433.635529 -334.345736)
			(xy 433.653815 -334.295584) (xy 433.678913 -334.24847) (xy 433.710334 -334.205315) (xy 433.747463 -334.166962)
			(xy 433.768246 -334.150208) (xy 433.777007 -334.142646) (xy 433.787189 -334.121887) (xy 433.787804 -334.11033)
			(xy 433.787804 -334.030066) (xy 433.787194 -334.018503) (xy 433.777027 -333.997732) (xy 433.768246 -333.990188)
			(xy 433.745746 -333.972017) (xy 433.706014 -333.929992) (xy 433.673078 -333.882452) (xy 433.647693 -333.830487)
			(xy 433.63044 -333.775287) (xy 433.621714 -333.718115) (xy 433.62118 -333.689198) (xy 433.621666 -333.661947)
			(xy 433.629422 -333.607999) (xy 433.644777 -333.555704) (xy 433.667419 -333.506127) (xy 433.696885 -333.460277)
			(xy 433.732576 -333.419086) (xy 433.773767 -333.383395) (xy 433.819617 -333.353929) (xy 433.869194 -333.331287)
			(xy 433.921489 -333.315932) (xy 433.975437 -333.308176) (xy 434.029939 -333.308176) (xy 434.083887 -333.315932)
			(xy 434.136182 -333.331287) (xy 434.185759 -333.353929) (xy 434.231609 -333.383395) (xy 434.2728 -333.419086)
			(xy 434.308491 -333.460277) (xy 434.337957 -333.506127) (xy 434.360599 -333.555704) (xy 434.375954 -333.607999)
			(xy 434.38371 -333.661947) (xy 434.384196 -333.689198) (xy 434.383678 -333.718115) (xy 434.374949 -333.775286)
			(xy 434.357691 -333.830485) (xy 434.332299 -333.882447) (xy 434.299356 -333.929981) (xy 434.259615 -333.971998)
			(xy 434.23713 -333.990188) (xy 434.228366 -333.997747) (xy 434.218187 -334.018509) (xy 434.217572 -334.030066)
			(xy 434.217572 -334.11033) (xy 434.218157 -334.121897) (xy 434.228339 -334.14267) (xy 434.23713 -334.150208)
			(xy 434.257912 -334.166963) (xy 434.295043 -334.205316) (xy 434.326465 -334.24847) (xy 434.351565 -334.295583)
			(xy 434.369852 -334.345735) (xy 434.380969 -334.397947) (xy 434.384699 -334.451199) (xy 434.380969 -334.50445)
			(xy 434.369853 -334.556662) (xy 434.351566 -334.606814) (xy 434.326467 -334.653928) (xy 434.295045 -334.697082)
			(xy 434.257913 -334.735435) (xy 434.23713 -334.752188) (xy 434.228366 -334.759747) (xy 434.218187 -334.780509)
			(xy 434.217572 -334.792066) (xy 434.217572 -334.87233) (xy 434.218157 -334.883897) (xy 434.228339 -334.90467)
			(xy 434.23713 -334.912208) (xy 434.257912 -334.928963) (xy 434.295043 -334.967316) (xy 434.326465 -335.01047)
			(xy 434.351565 -335.057583) (xy 434.361999 -335.086199) (xy 437.176683 -335.086199) (xy 437.180413 -335.032948)
			(xy 437.191529 -334.980736) (xy 437.209815 -334.930584) (xy 437.234913 -334.88347) (xy 437.266334 -334.840315)
			(xy 437.303463 -334.801962) (xy 437.324246 -334.785208) (xy 437.333007 -334.777646) (xy 437.343189 -334.756887)
			(xy 437.343804 -334.74533) (xy 437.343804 -334.665066) (xy 437.343194 -334.653503) (xy 437.333027 -334.632732)
			(xy 437.324246 -334.625188) (xy 437.303462 -334.608437) (xy 437.266332 -334.570083) (xy 437.234912 -334.526927)
			(xy 437.209814 -334.479814) (xy 437.191528 -334.429662) (xy 437.180412 -334.37745) (xy 437.176683 -334.324199)
			(xy 437.180413 -334.270948) (xy 437.191529 -334.218736) (xy 437.209815 -334.168584) (xy 437.234913 -334.12147)
			(xy 437.266334 -334.078315) (xy 437.303463 -334.039962) (xy 437.324246 -334.023208) (xy 437.333007 -334.015646)
			(xy 437.343189 -333.994887) (xy 437.343804 -333.98333) (xy 437.343804 -333.903066) (xy 437.343194 -333.891503)
			(xy 437.333027 -333.870732) (xy 437.324246 -333.863188) (xy 437.301746 -333.845017) (xy 437.262014 -333.802992)
			(xy 437.229078 -333.755452) (xy 437.203693 -333.703487) (xy 437.18644 -333.648287) (xy 437.177714 -333.591115)
			(xy 437.17718 -333.562198) (xy 437.177666 -333.534947) (xy 437.185422 -333.480999) (xy 437.200777 -333.428704)
			(xy 437.223419 -333.379127) (xy 437.252885 -333.333277) (xy 437.288576 -333.292086) (xy 437.329767 -333.256395)
			(xy 437.375617 -333.226929) (xy 437.425194 -333.204287) (xy 437.477489 -333.188932) (xy 437.531437 -333.181176)
			(xy 437.585939 -333.181176) (xy 437.639887 -333.188932) (xy 437.692182 -333.204287) (xy 437.741759 -333.226929)
			(xy 437.787609 -333.256395) (xy 437.8288 -333.292086) (xy 437.864491 -333.333277) (xy 437.893957 -333.379127)
			(xy 437.916599 -333.428704) (xy 437.931954 -333.480999) (xy 437.93971 -333.534947) (xy 437.940196 -333.562198)
			(xy 437.939678 -333.591115) (xy 437.930949 -333.648286) (xy 437.913691 -333.703485) (xy 437.888299 -333.755447)
			(xy 437.855356 -333.802981) (xy 437.815615 -333.844998) (xy 437.79313 -333.863188) (xy 437.784366 -333.870747)
			(xy 437.774187 -333.891509) (xy 437.773572 -333.903066) (xy 437.773572 -333.98333) (xy 437.774157 -333.994897)
			(xy 437.784339 -334.01567) (xy 437.79313 -334.023208) (xy 437.813912 -334.039963) (xy 437.851043 -334.078316)
			(xy 437.882465 -334.12147) (xy 437.907565 -334.168583) (xy 437.925852 -334.218735) (xy 437.936969 -334.270947)
			(xy 437.940699 -334.324199) (xy 437.936969 -334.37745) (xy 437.925853 -334.429662) (xy 437.907566 -334.479814)
			(xy 437.882467 -334.526928) (xy 437.851045 -334.570082) (xy 437.813913 -334.608435) (xy 437.79313 -334.625188)
			(xy 437.784366 -334.632747) (xy 437.774187 -334.653509) (xy 437.773572 -334.665066) (xy 437.773572 -334.74533)
			(xy 437.774157 -334.756897) (xy 437.784339 -334.77767) (xy 437.79313 -334.785208) (xy 437.813912 -334.801963)
			(xy 437.851043 -334.840316) (xy 437.882465 -334.88347) (xy 437.907565 -334.930583) (xy 437.925852 -334.980735)
			(xy 437.93587 -335.027786) (xy 439.724279 -335.027786) (xy 439.728011 -334.974532) (xy 439.739131 -334.922319)
			(xy 439.75742 -334.872165) (xy 439.782522 -334.82505) (xy 439.813947 -334.781895) (xy 439.851081 -334.743541)
			(xy 439.871866 -334.726788) (xy 439.88064 -334.719238) (xy 439.890814 -334.69847) (xy 439.891424 -334.68691)
			(xy 439.891424 -334.606646) (xy 439.890853 -334.595077) (xy 439.880662 -334.574305) (xy 439.871866 -334.566768)
			(xy 439.851061 -334.550041) (xy 439.81393 -334.511685) (xy 439.782508 -334.468527) (xy 439.757409 -334.421411)
			(xy 439.739123 -334.371255) (xy 439.728008 -334.319041) (xy 439.724279 -334.265786) (xy 439.728011 -334.212532)
			(xy 439.739131 -334.160319) (xy 439.75742 -334.110165) (xy 439.782522 -334.06305) (xy 439.813947 -334.019895)
			(xy 439.851081 -333.981541) (xy 439.871866 -333.964788) (xy 439.88064 -333.957238) (xy 439.890814 -333.93647)
			(xy 439.891424 -333.92491) (xy 439.891424 -333.844646) (xy 439.890853 -333.833077) (xy 439.880662 -333.812305)
			(xy 439.871866 -333.804768) (xy 439.84936 -333.786604) (xy 439.809628 -333.744577) (xy 439.776692 -333.697037)
			(xy 439.751308 -333.64507) (xy 439.734057 -333.589868) (xy 439.725332 -333.532695) (xy 439.7248 -333.503778)
			(xy 439.725286 -333.476527) (xy 439.733042 -333.422579) (xy 439.748397 -333.370284) (xy 439.771039 -333.320707)
			(xy 439.800505 -333.274857) (xy 439.836196 -333.233666) (xy 439.877387 -333.197975) (xy 439.923237 -333.168509)
			(xy 439.972814 -333.145867) (xy 440.025109 -333.130512) (xy 440.079057 -333.122756) (xy 440.133559 -333.122756)
			(xy 440.187507 -333.130512) (xy 440.239802 -333.145867) (xy 440.289379 -333.168509) (xy 440.335229 -333.197975)
			(xy 440.37642 -333.233666) (xy 440.412111 -333.274857) (xy 440.441577 -333.320707) (xy 440.464219 -333.370284)
			(xy 440.479574 -333.422579) (xy 440.48733 -333.476527) (xy 440.487816 -333.503778) (xy 440.487314 -333.532696)
			(xy 440.478586 -333.589869) (xy 440.461327 -333.64507) (xy 440.435932 -333.697032) (xy 440.402984 -333.744565)
			(xy 440.363238 -333.78658) (xy 440.34075 -333.804768) (xy 440.331998 -333.812339) (xy 440.321811 -333.833091)
			(xy 440.321192 -333.844646) (xy 440.321192 -333.92491) (xy 440.32176 -333.936478) (xy 440.331957 -333.957249)
			(xy 440.34075 -333.964788) (xy 440.361511 -333.981567) (xy 440.39864 -334.019918) (xy 440.430061 -334.06307)
			(xy 440.45516 -334.11018) (xy 440.473447 -334.160329) (xy 440.484564 -334.212538) (xy 440.488296 -334.265786)
			(xy 440.484568 -334.319035) (xy 440.473454 -334.371245) (xy 440.455171 -334.421395) (xy 440.430075 -334.468507)
			(xy 440.398658 -334.511661) (xy 440.361531 -334.550014) (xy 440.34075 -334.566768) (xy 440.331998 -334.574339)
			(xy 440.321811 -334.595091) (xy 440.321192 -334.606646) (xy 440.321192 -334.68691) (xy 440.32176 -334.698478)
			(xy 440.331957 -334.719249) (xy 440.34075 -334.726788) (xy 440.361511 -334.743567) (xy 440.39864 -334.781918)
			(xy 440.430061 -334.82507) (xy 440.45516 -334.87218) (xy 440.473447 -334.922329) (xy 440.484564 -334.974538)
			(xy 440.488296 -335.027786) (xy 440.484568 -335.081035) (xy 440.473454 -335.133245) (xy 440.455171 -335.183395)
			(xy 440.430075 -335.230507) (xy 440.398658 -335.273661) (xy 440.361531 -335.312014) (xy 440.34075 -335.328768)
			(xy 440.331998 -335.336339) (xy 440.321811 -335.357091) (xy 440.321192 -335.368646) (xy 440.321192 -335.44891)
			(xy 440.32176 -335.460478) (xy 440.331957 -335.481249) (xy 440.34075 -335.488788) (xy 440.363238 -335.506973)
			(xy 440.402971 -335.548996) (xy 440.435908 -335.596532) (xy 440.461295 -335.648494) (xy 440.478551 -335.703692)
			(xy 440.48728 -335.760862) (xy 440.487816 -335.789778) (xy 440.48733 -335.817029) (xy 440.479574 -335.870977)
			(xy 440.464219 -335.923272) (xy 440.441577 -335.972849) (xy 440.412111 -336.018699) (xy 440.37642 -336.05989)
			(xy 440.335229 -336.095581) (xy 440.289379 -336.125047) (xy 440.239802 -336.147689) (xy 440.187507 -336.163044)
			(xy 440.133559 -336.1708) (xy 440.079057 -336.1708) (xy 440.025109 -336.163044) (xy 439.972814 -336.147689)
			(xy 439.923237 -336.125047) (xy 439.877387 -336.095581) (xy 439.836196 -336.05989) (xy 439.800505 -336.018699)
			(xy 439.771039 -335.972849) (xy 439.748397 -335.923272) (xy 439.733042 -335.870977) (xy 439.725286 -335.817029)
			(xy 439.7248 -335.789778) (xy 439.725374 -335.760863) (xy 439.734092 -335.703695) (xy 439.751338 -335.648497)
			(xy 439.77672 -335.596535) (xy 439.809653 -335.548999) (xy 439.849385 -335.50698) (xy 439.871866 -335.488788)
			(xy 439.88064 -335.481238) (xy 439.890814 -335.46047) (xy 439.891424 -335.44891) (xy 439.891424 -335.368646)
			(xy 439.890853 -335.357077) (xy 439.880662 -335.336305) (xy 439.871866 -335.328768) (xy 439.851061 -335.312041)
			(xy 439.81393 -335.273685) (xy 439.782508 -335.230527) (xy 439.757409 -335.183411) (xy 439.739123 -335.133255)
			(xy 439.728008 -335.081041) (xy 439.724279 -335.027786) (xy 437.93587 -335.027786) (xy 437.936969 -335.032947)
			(xy 437.940699 -335.086199) (xy 437.936969 -335.13945) (xy 437.925853 -335.191662) (xy 437.907566 -335.241814)
			(xy 437.882467 -335.288928) (xy 437.851045 -335.332082) (xy 437.813913 -335.370435) (xy 437.79313 -335.387188)
			(xy 437.784366 -335.394747) (xy 437.774187 -335.415509) (xy 437.773572 -335.427066) (xy 437.773572 -335.50733)
			(xy 437.774157 -335.518897) (xy 437.784339 -335.53967) (xy 437.79313 -335.547208) (xy 437.815624 -335.565387)
			(xy 437.855357 -335.60741) (xy 437.888294 -335.654948) (xy 437.91368 -335.706911) (xy 437.930934 -335.762111)
			(xy 437.939662 -335.819281) (xy 437.940196 -335.848198) (xy 437.93971 -335.875449) (xy 437.931954 -335.929397)
			(xy 437.916599 -335.981692) (xy 437.893957 -336.031269) (xy 437.864491 -336.077119) (xy 437.8288 -336.11831)
			(xy 437.787609 -336.154001) (xy 437.741759 -336.183467) (xy 437.692182 -336.206109) (xy 437.639887 -336.221464)
			(xy 437.585939 -336.22922) (xy 437.531437 -336.22922) (xy 437.477489 -336.221464) (xy 437.425194 -336.206109)
			(xy 437.375617 -336.183467) (xy 437.329767 -336.154001) (xy 437.288576 -336.11831) (xy 437.252885 -336.077119)
			(xy 437.223419 -336.031269) (xy 437.200777 -335.981692) (xy 437.185422 -335.929397) (xy 437.177666 -335.875449)
			(xy 437.17718 -335.848198) (xy 437.177667 -335.81928) (xy 437.186398 -335.762105) (xy 437.20366 -335.706905)
			(xy 437.229058 -335.654942) (xy 437.262008 -335.60741) (xy 437.301757 -335.565396) (xy 437.324246 -335.547208)
			(xy 437.333007 -335.539646) (xy 437.343189 -335.518887) (xy 437.343804 -335.50733) (xy 437.343804 -335.427066)
			(xy 437.343194 -335.415503) (xy 437.333027 -335.394732) (xy 437.324246 -335.387188) (xy 437.303462 -335.370437)
			(xy 437.266332 -335.332083) (xy 437.234912 -335.288927) (xy 437.209814 -335.241814) (xy 437.191528 -335.191662)
			(xy 437.180412 -335.13945) (xy 437.176683 -335.086199) (xy 434.361999 -335.086199) (xy 434.369852 -335.107735)
			(xy 434.380969 -335.159947) (xy 434.384699 -335.213199) (xy 434.380969 -335.26645) (xy 434.369853 -335.318662)
			(xy 434.351566 -335.368814) (xy 434.326467 -335.415928) (xy 434.295045 -335.459082) (xy 434.257913 -335.497435)
			(xy 434.23713 -335.514188) (xy 434.228366 -335.521747) (xy 434.218187 -335.542509) (xy 434.217572 -335.554066)
			(xy 434.217572 -335.63433) (xy 434.218157 -335.645897) (xy 434.228339 -335.66667) (xy 434.23713 -335.674208)
			(xy 434.259624 -335.692387) (xy 434.299357 -335.73441) (xy 434.332294 -335.781948) (xy 434.35768 -335.833911)
			(xy 434.374934 -335.889111) (xy 434.383662 -335.946281) (xy 434.384196 -335.975198) (xy 434.38371 -336.002449)
			(xy 434.375954 -336.056397) (xy 434.360599 -336.108692) (xy 434.337957 -336.158269) (xy 434.308491 -336.204119)
			(xy 434.2728 -336.24531) (xy 434.231609 -336.281001) (xy 434.185759 -336.310467) (xy 434.136182 -336.333109)
			(xy 434.083887 -336.348464) (xy 434.029939 -336.35622) (xy 433.975437 -336.35622) (xy 433.921489 -336.348464)
			(xy 433.869194 -336.333109) (xy 433.819617 -336.310467) (xy 433.773767 -336.281001) (xy 433.732576 -336.24531)
			(xy 433.696885 -336.204119) (xy 433.667419 -336.158269) (xy 433.644777 -336.108692) (xy 433.629422 -336.056397)
			(xy 433.621666 -336.002449) (xy 433.62118 -335.975198) (xy 433.621667 -335.94628) (xy 433.630398 -335.889105)
			(xy 433.64766 -335.833905) (xy 433.673058 -335.781942) (xy 433.706008 -335.73441) (xy 433.745757 -335.692396)
			(xy 433.768246 -335.674208) (xy 433.777007 -335.666646) (xy 433.787189 -335.645887) (xy 433.787804 -335.63433)
			(xy 433.787804 -335.554066) (xy 433.787194 -335.542503) (xy 433.777027 -335.521732) (xy 433.768246 -335.514188)
			(xy 433.747462 -335.497437) (xy 433.710332 -335.459083) (xy 433.678912 -335.415927) (xy 433.653814 -335.368814)
			(xy 433.635528 -335.318662) (xy 433.624412 -335.26645) (xy 433.620683 -335.213199) (xy 431.946299 -335.213199)
			(xy 431.942569 -335.26645) (xy 431.931453 -335.318662) (xy 431.913166 -335.368814) (xy 431.888067 -335.415928)
			(xy 431.856645 -335.459082) (xy 431.819513 -335.497435) (xy 431.79873 -335.514188) (xy 431.789966 -335.521747)
			(xy 431.779787 -335.542509) (xy 431.779172 -335.554066) (xy 431.779172 -335.63433) (xy 431.779757 -335.645897)
			(xy 431.789939 -335.66667) (xy 431.79873 -335.674208) (xy 431.821224 -335.692387) (xy 431.860957 -335.73441)
			(xy 431.893894 -335.781948) (xy 431.91928 -335.833911) (xy 431.936534 -335.889111) (xy 431.945262 -335.946281)
			(xy 431.945796 -335.975198) (xy 431.94531 -336.002449) (xy 431.937554 -336.056397) (xy 431.922199 -336.108692)
			(xy 431.899557 -336.158269) (xy 431.870091 -336.204119) (xy 431.8344 -336.24531) (xy 431.793209 -336.281001)
			(xy 431.747359 -336.310467) (xy 431.697782 -336.333109) (xy 431.645487 -336.348464) (xy 431.591539 -336.35622)
			(xy 431.537037 -336.35622) (xy 431.483089 -336.348464) (xy 431.430794 -336.333109) (xy 431.381217 -336.310467)
			(xy 431.335367 -336.281001) (xy 431.294176 -336.24531) (xy 431.258485 -336.204119) (xy 431.229019 -336.158269)
			(xy 431.206377 -336.108692) (xy 431.191022 -336.056397) (xy 431.183266 -336.002449) (xy 431.18278 -335.975198)
			(xy 431.183267 -335.94628) (xy 431.191998 -335.889105) (xy 431.20926 -335.833905) (xy 431.234658 -335.781942)
			(xy 431.267608 -335.73441) (xy 431.307357 -335.692396) (xy 431.329846 -335.674208) (xy 431.338607 -335.666646)
			(xy 431.348789 -335.645887) (xy 431.349404 -335.63433) (xy 431.349404 -335.554066) (xy 431.348794 -335.542503)
			(xy 431.338627 -335.521732) (xy 431.329846 -335.514188) (xy 431.309062 -335.497437) (xy 431.271932 -335.459083)
			(xy 431.240512 -335.415927) (xy 431.215414 -335.368814) (xy 431.197128 -335.318662) (xy 431.186012 -335.26645)
			(xy 431.182283 -335.213199) (xy 428.28692 -335.213199) (xy 428.288699 -335.238599) (xy 428.284969 -335.29185)
			(xy 428.273853 -335.344062) (xy 428.255566 -335.394214) (xy 428.230467 -335.441328) (xy 428.199045 -335.484482)
			(xy 428.161913 -335.522835) (xy 428.14113 -335.539588) (xy 428.132366 -335.547147) (xy 428.122187 -335.567909)
			(xy 428.121572 -335.579466) (xy 428.121572 -335.65973) (xy 428.122157 -335.671297) (xy 428.132339 -335.69207)
			(xy 428.14113 -335.699608) (xy 428.163624 -335.717787) (xy 428.203357 -335.75981) (xy 428.236294 -335.807348)
			(xy 428.26168 -335.859311) (xy 428.278934 -335.914511) (xy 428.287662 -335.971681) (xy 428.288196 -336.000598)
			(xy 428.28771 -336.027849) (xy 428.279954 -336.081797) (xy 428.264599 -336.134092) (xy 428.241957 -336.183669)
			(xy 428.212491 -336.229519) (xy 428.1768 -336.27071) (xy 428.135609 -336.306401) (xy 428.089759 -336.335867)
			(xy 428.040182 -336.358509) (xy 427.987887 -336.373864) (xy 427.933939 -336.38162) (xy 427.879437 -336.38162)
			(xy 427.825489 -336.373864) (xy 427.773194 -336.358509) (xy 427.723617 -336.335867) (xy 427.677767 -336.306401)
			(xy 427.636576 -336.27071) (xy 427.600885 -336.229519) (xy 427.571419 -336.183669) (xy 427.548777 -336.134092)
			(xy 427.533422 -336.081797) (xy 427.525666 -336.027849) (xy 427.52518 -336.000598) (xy 427.525667 -335.97168)
			(xy 427.534398 -335.914505) (xy 427.55166 -335.859305) (xy 427.577058 -335.807342) (xy 427.610008 -335.75981)
			(xy 427.649757 -335.717796) (xy 427.672246 -335.699608) (xy 427.681007 -335.692046) (xy 427.691189 -335.671287)
			(xy 427.691804 -335.65973) (xy 427.691804 -335.579466) (xy 427.691194 -335.567903) (xy 427.681027 -335.547132)
			(xy 427.672246 -335.539588) (xy 427.651462 -335.522837) (xy 427.614332 -335.484483) (xy 427.582912 -335.441327)
			(xy 427.557814 -335.394214) (xy 427.539528 -335.344062) (xy 427.528412 -335.29185) (xy 427.524683 -335.238599)
			(xy 425.824899 -335.238599) (xy 425.821169 -335.29185) (xy 425.810053 -335.344062) (xy 425.791766 -335.394214)
			(xy 425.766667 -335.441328) (xy 425.735245 -335.484482) (xy 425.698113 -335.522835) (xy 425.67733 -335.539588)
			(xy 425.668566 -335.547147) (xy 425.658387 -335.567909) (xy 425.657772 -335.579466) (xy 425.657772 -335.65973)
			(xy 425.658357 -335.671297) (xy 425.668539 -335.69207) (xy 425.67733 -335.699608) (xy 425.699824 -335.717787)
			(xy 425.739557 -335.75981) (xy 425.772494 -335.807348) (xy 425.79788 -335.859311) (xy 425.815134 -335.914511)
			(xy 425.823862 -335.971681) (xy 425.824396 -336.000598) (xy 425.82391 -336.027849) (xy 425.816154 -336.081797)
			(xy 425.800799 -336.134092) (xy 425.778157 -336.183669) (xy 425.748691 -336.229519) (xy 425.713 -336.27071)
			(xy 425.671809 -336.306401) (xy 425.625959 -336.335867) (xy 425.576382 -336.358509) (xy 425.524087 -336.373864)
			(xy 425.470139 -336.38162) (xy 425.415637 -336.38162) (xy 425.361689 -336.373864) (xy 425.309394 -336.358509)
			(xy 425.259817 -336.335867) (xy 425.213967 -336.306401) (xy 425.172776 -336.27071) (xy 425.137085 -336.229519)
			(xy 425.107619 -336.183669) (xy 425.084977 -336.134092) (xy 425.069622 -336.081797) (xy 425.061866 -336.027849)
			(xy 425.06138 -336.000598) (xy 425.061867 -335.97168) (xy 425.070598 -335.914505) (xy 425.08786 -335.859305)
			(xy 425.113258 -335.807342) (xy 425.146208 -335.75981) (xy 425.185957 -335.717796) (xy 425.208446 -335.699608)
			(xy 425.217207 -335.692046) (xy 425.227389 -335.671287) (xy 425.228004 -335.65973) (xy 425.228004 -335.579466)
			(xy 425.227394 -335.567903) (xy 425.217227 -335.547132) (xy 425.208446 -335.539588) (xy 425.187662 -335.522837)
			(xy 425.150532 -335.484483) (xy 425.119112 -335.441327) (xy 425.094014 -335.394214) (xy 425.075728 -335.344062)
			(xy 425.064612 -335.29185) (xy 425.060883 -335.238599) (xy 422.167299 -335.238599) (xy 422.163569 -335.29185)
			(xy 422.152453 -335.344062) (xy 422.134166 -335.394214) (xy 422.109067 -335.441328) (xy 422.077645 -335.484482)
			(xy 422.040513 -335.522835) (xy 422.01973 -335.539588) (xy 422.010966 -335.547147) (xy 422.000787 -335.567909)
			(xy 422.000172 -335.579466) (xy 422.000172 -335.65973) (xy 422.000757 -335.671297) (xy 422.010939 -335.69207)
			(xy 422.01973 -335.699608) (xy 422.042224 -335.717787) (xy 422.081957 -335.75981) (xy 422.114894 -335.807348)
			(xy 422.14028 -335.859311) (xy 422.157534 -335.914511) (xy 422.166262 -335.971681) (xy 422.166796 -336.000598)
			(xy 422.16631 -336.027849) (xy 422.158554 -336.081797) (xy 422.143199 -336.134092) (xy 422.120557 -336.183669)
			(xy 422.091091 -336.229519) (xy 422.0554 -336.27071) (xy 422.014209 -336.306401) (xy 421.968359 -336.335867)
			(xy 421.918782 -336.358509) (xy 421.866487 -336.373864) (xy 421.812539 -336.38162) (xy 421.758037 -336.38162)
			(xy 421.704089 -336.373864) (xy 421.651794 -336.358509) (xy 421.602217 -336.335867) (xy 421.556367 -336.306401)
			(xy 421.515176 -336.27071) (xy 421.479485 -336.229519) (xy 421.450019 -336.183669) (xy 421.427377 -336.134092)
			(xy 421.412022 -336.081797) (xy 421.404266 -336.027849) (xy 421.40378 -336.000598) (xy 421.404267 -335.97168)
			(xy 421.412998 -335.914505) (xy 421.43026 -335.859305) (xy 421.455658 -335.807342) (xy 421.488608 -335.75981)
			(xy 421.528357 -335.717796) (xy 421.550846 -335.699608) (xy 421.559607 -335.692046) (xy 421.569789 -335.671287)
			(xy 421.570404 -335.65973) (xy 421.570404 -335.579466) (xy 421.569794 -335.567903) (xy 421.559627 -335.547132)
			(xy 421.550846 -335.539588) (xy 421.530062 -335.522837) (xy 421.492932 -335.484483) (xy 421.461512 -335.441327)
			(xy 421.436414 -335.394214) (xy 421.418128 -335.344062) (xy 421.407012 -335.29185) (xy 421.403283 -335.238599)
			(xy 419.745683 -335.238599) (xy 419.750569 -335.261547) (xy 419.754299 -335.314799) (xy 419.750569 -335.36805)
			(xy 419.739453 -335.420262) (xy 419.721166 -335.470414) (xy 419.696067 -335.517528) (xy 419.664645 -335.560682)
			(xy 419.627513 -335.599035) (xy 419.60673 -335.615788) (xy 419.597966 -335.623347) (xy 419.587787 -335.644109)
			(xy 419.587172 -335.655666) (xy 419.587172 -335.73593) (xy 419.587757 -335.747497) (xy 419.597939 -335.76827)
			(xy 419.60673 -335.775808) (xy 419.629224 -335.793987) (xy 419.668957 -335.83601) (xy 419.701894 -335.883548)
			(xy 419.72728 -335.935511) (xy 419.744534 -335.990711) (xy 419.753262 -336.047881) (xy 419.753796 -336.076798)
			(xy 419.75331 -336.104049) (xy 419.745554 -336.157997) (xy 419.730199 -336.210292) (xy 419.707557 -336.259869)
			(xy 419.678091 -336.305719) (xy 419.6424 -336.34691) (xy 419.601209 -336.382601) (xy 419.555359 -336.412067)
			(xy 419.505782 -336.434709) (xy 419.453487 -336.450064) (xy 419.399539 -336.45782) (xy 419.345037 -336.45782)
			(xy 419.291089 -336.450064) (xy 419.238794 -336.434709) (xy 419.189217 -336.412067) (xy 419.143367 -336.382601)
			(xy 419.102176 -336.34691) (xy 419.066485 -336.305719) (xy 419.037019 -336.259869) (xy 419.014377 -336.210292)
			(xy 418.999022 -336.157997) (xy 418.991266 -336.104049) (xy 418.99078 -336.076798) (xy 418.991267 -336.04788)
			(xy 418.999998 -335.990705) (xy 419.01726 -335.935505) (xy 419.042658 -335.883542) (xy 419.075608 -335.83601)
			(xy 419.115357 -335.793996) (xy 419.137846 -335.775808) (xy 419.146607 -335.768246) (xy 419.156789 -335.747487)
			(xy 419.157404 -335.73593) (xy 419.157404 -335.655666) (xy 419.156794 -335.644103) (xy 419.146627 -335.623332)
			(xy 419.137846 -335.615788) (xy 419.117062 -335.599037) (xy 419.079932 -335.560683) (xy 419.048512 -335.517527)
			(xy 419.023414 -335.470414) (xy 419.005128 -335.420262) (xy 418.994012 -335.36805) (xy 418.990283 -335.314799)
			(xy 412.34106 -335.314799) (xy 412.34106 -340.097364) (xy 420.754302 -340.097364) (xy 420.754746 -340.069993)
			(xy 420.762569 -340.015813) (xy 420.778064 -339.96331) (xy 420.80091 -339.913563) (xy 420.830639 -339.867597)
			(xy 420.848282 -339.846666) (xy 420.854378 -339.839554) (xy 420.860728 -339.822536) (xy 420.860728 -339.737192)
			(xy 420.854378 -339.720174) (xy 420.848282 -339.713062) (xy 420.830608 -339.692157) (xy 420.800888 -339.646183)
			(xy 420.778048 -339.596432) (xy 420.762556 -339.543926) (xy 420.754732 -339.489745) (xy 420.754736 -339.435001)
			(xy 420.762568 -339.380821) (xy 420.778067 -339.328317) (xy 420.800914 -339.278569) (xy 420.830641 -339.2326)
			(xy 420.848282 -339.211666) (xy 420.854378 -339.204554) (xy 420.860728 -339.187536) (xy 420.860728 -339.102192)
			(xy 420.854378 -339.085174) (xy 420.848282 -339.078062) (xy 420.830608 -339.057157) (xy 420.800888 -339.011183)
			(xy 420.778048 -338.961432) (xy 420.762556 -338.908926) (xy 420.754732 -338.854745) (xy 420.754736 -338.800001)
			(xy 420.762568 -338.745821) (xy 420.778067 -338.693317) (xy 420.800914 -338.643569) (xy 420.830641 -338.5976)
			(xy 420.848282 -338.576666) (xy 420.854378 -338.569554) (xy 420.860728 -338.552536) (xy 420.860728 -338.467192)
			(xy 420.854378 -338.450174) (xy 420.848282 -338.443062) (xy 420.830608 -338.422157) (xy 420.800888 -338.376183)
			(xy 420.778048 -338.326432) (xy 420.762556 -338.273926) (xy 420.754732 -338.219745) (xy 420.754736 -338.165001)
			(xy 420.762568 -338.110821) (xy 420.778067 -338.058317) (xy 420.800914 -338.008569) (xy 420.830641 -337.9626)
			(xy 420.848282 -337.941666) (xy 420.854378 -337.934554) (xy 420.860728 -337.917536) (xy 420.860728 -337.832192)
			(xy 420.854378 -337.815174) (xy 420.848282 -337.808062) (xy 420.830656 -337.78712) (xy 420.800943 -337.741149)
			(xy 420.778104 -337.691404) (xy 420.76261 -337.638906) (xy 420.754778 -337.584732) (xy 420.754302 -337.557364)
			(xy 420.754851 -337.528447) (xy 420.763578 -337.471276) (xy 420.780841 -337.41608) (xy 420.806244 -337.364124)
			(xy 420.839205 -337.316603) (xy 420.858696 -337.295236) (xy 420.865046 -337.288378) (xy 420.872158 -337.271614)
			(xy 420.875714 -337.186016) (xy 420.869872 -337.168998) (xy 420.86403 -337.161632) (xy 420.848161 -337.141195)
			(xy 420.821462 -337.096874) (xy 420.800995 -337.049352) (xy 420.787135 -336.999501) (xy 420.780137 -336.948235)
			(xy 420.779702 -336.922364) (xy 420.780144 -336.895111) (xy 420.787906 -336.841162) (xy 420.803266 -336.788865)
			(xy 420.825912 -336.739287) (xy 420.855383 -336.693437) (xy 420.891079 -336.652247) (xy 420.932274 -336.616556)
			(xy 420.978128 -336.58709) (xy 421.027709 -336.56445) (xy 421.080007 -336.549096) (xy 421.133957 -336.541341)
			(xy 421.16121 -336.540856) (xy 421.188847 -336.54137) (xy 421.243542 -336.549358) (xy 421.296512 -336.565151)
			(xy 421.346651 -336.588419) (xy 421.39291 -336.618675) (xy 421.41394 -336.636614) (xy 421.421052 -336.64271)
			(xy 421.438324 -336.649314) (xy 421.524176 -336.649314) (xy 421.541448 -336.64271) (xy 421.54856 -336.636614)
			(xy 421.56957 -336.618647) (xy 421.615825 -336.588375) (xy 421.665968 -336.565101) (xy 421.718946 -336.549313)
			(xy 421.773649 -336.541341) (xy 421.80129 -336.540856) (xy 421.828311 -336.541308) (xy 421.881813 -336.548922)
			(xy 421.933705 -336.564012) (xy 421.982947 -336.586278) (xy 422.028552 -336.615272) (xy 422.069607 -336.650414)
			(xy 422.087802 -336.670396) (xy 422.094914 -336.678778) (xy 422.113964 -336.687414) (xy 422.210738 -336.689446)
			(xy 422.230042 -336.681572) (xy 422.237408 -336.673698) (xy 422.255473 -336.655456) (xy 422.295643 -336.623484)
			(xy 422.339736 -336.597186) (xy 422.386956 -336.577035) (xy 422.436451 -336.563395) (xy 422.487328 -336.556513)
			(xy 422.512998 -336.556096) (xy 422.540251 -336.556557) (xy 422.594202 -336.564314) (xy 422.6465 -336.57967)
			(xy 422.696081 -336.602313) (xy 422.741934 -336.631781) (xy 422.783127 -336.667475) (xy 422.81882 -336.708668)
			(xy 422.848288 -336.754521) (xy 422.870931 -336.804102) (xy 422.886286 -336.8564) (xy 422.894043 -336.910351)
			(xy 422.894506 -336.937604) (xy 422.894051 -336.964863) (xy 422.886283 -337.018824) (xy 422.870918 -337.071132)
			(xy 422.84827 -337.120723) (xy 422.818798 -337.166588) (xy 422.783103 -337.207795) (xy 422.74191 -337.243507)
			(xy 422.719246 -337.25866) (xy 422.71228 -337.263513) (xy 422.701759 -337.276822) (xy 422.696195 -337.292849)
			(xy 422.695878 -337.301332) (xy 422.695878 -337.386676) (xy 422.696243 -337.395151) (xy 422.701814 -337.411163)
			(xy 422.712292 -337.424491) (xy 422.719246 -337.429348) (xy 422.741892 -337.444527) (xy 422.78309 -337.480228)
			(xy 422.818788 -337.521429) (xy 422.84826 -337.567291) (xy 422.870905 -337.61688) (xy 422.886263 -337.669187)
			(xy 422.89402 -337.723147) (xy 422.894506 -337.750404) (xy 422.894041 -337.777774) (xy 422.886223 -337.831953)
			(xy 422.870733 -337.884456) (xy 422.847891 -337.934203) (xy 422.818167 -337.98017) (xy 422.800526 -338.001102)
			(xy 422.79443 -338.008214) (xy 422.78808 -338.025232) (xy 422.78808 -338.110576) (xy 422.79443 -338.127594)
			(xy 422.800526 -338.134706) (xy 422.818173 -338.155635) (xy 422.847901 -338.201602) (xy 422.870749 -338.251349)
			(xy 422.886247 -338.303852) (xy 422.894076 -338.358032) (xy 422.894076 -338.412774) (xy 422.886245 -338.466954)
			(xy 422.870747 -338.519457) (xy 422.847898 -338.569203) (xy 422.818169 -338.61517) (xy 422.800526 -338.636102)
			(xy 422.79443 -338.643214) (xy 422.78808 -338.660232) (xy 422.78808 -338.745576) (xy 422.79443 -338.762594)
			(xy 422.800526 -338.769706) (xy 422.818185 -338.790622) (xy 422.847893 -338.836599) (xy 422.870725 -338.886351)
			(xy 422.886211 -338.938855) (xy 422.894035 -338.993034) (xy 422.894287 -339.007704) (xy 424.464734 -339.007704)
			(xy 424.465194 -338.980333) (xy 424.473012 -338.926154) (xy 424.488502 -338.87365) (xy 424.511345 -338.823903)
			(xy 424.541072 -338.777937) (xy 424.558714 -338.757006) (xy 424.56481 -338.749894) (xy 424.57116 -338.732876)
			(xy 424.57116 -338.647532) (xy 424.56481 -338.630514) (xy 424.558714 -338.623402) (xy 424.541078 -338.602466)
			(xy 424.511354 -338.556498) (xy 424.488509 -338.506753) (xy 424.473013 -338.454251) (xy 424.465184 -338.400073)
			(xy 424.465184 -338.345333) (xy 424.473012 -338.291155) (xy 424.488507 -338.238653) (xy 424.511351 -338.188907)
			(xy 424.541074 -338.142939) (xy 424.558714 -338.122006) (xy 424.56481 -338.114894) (xy 424.57116 -338.097876)
			(xy 424.57116 -338.012532) (xy 424.56481 -337.995514) (xy 424.558714 -337.988402) (xy 424.541065 -337.967478)
			(xy 424.511354 -337.921503) (xy 424.48852 -337.871754) (xy 424.473031 -337.819251) (xy 424.465206 -337.765074)
			(xy 424.464734 -337.737704) (xy 424.465222 -337.710447) (xy 424.472988 -337.656488) (xy 424.488349 -337.604182)
			(xy 424.510993 -337.554593) (xy 424.540458 -337.508727) (xy 424.576147 -337.467518) (xy 424.617333 -337.431803)
			(xy 424.639994 -337.416648) (xy 424.64699 -337.411832) (xy 424.65751 -337.398509) (xy 424.663058 -337.382465)
			(xy 424.663362 -337.373976) (xy 424.663362 -337.288632) (xy 424.662974 -337.280159) (xy 424.65741 -337.26415)
			(xy 424.646942 -337.250821) (xy 424.639994 -337.24596) (xy 424.617338 -337.230795) (xy 424.576143 -337.19509)
			(xy 424.540447 -337.153885) (xy 424.510978 -337.108021) (xy 424.488335 -337.058431) (xy 424.472978 -337.006123)
			(xy 424.46522 -336.952162) (xy 424.464734 -336.924904) (xy 424.465159 -336.897649) (xy 424.472917 -336.843695)
			(xy 424.488274 -336.791394) (xy 424.510919 -336.741811) (xy 424.540391 -336.695956) (xy 424.576089 -336.654762)
			(xy 424.617286 -336.619068) (xy 424.663144 -336.589601) (xy 424.712729 -336.566961) (xy 424.765032 -336.551609)
			(xy 424.818987 -336.543856) (xy 424.846242 -336.543396) (xy 424.875756 -336.543918) (xy 424.934079 -336.553016)
			(xy 424.990305 -336.570987) (xy 425.043092 -336.597403) (xy 425.091181 -336.631634) (xy 425.112688 -336.651854)
			(xy 425.119546 -336.658712) (xy 425.13758 -336.666078) (xy 425.226734 -336.667602) (xy 425.245022 -336.660744)
			(xy 425.252134 -336.65414) (xy 425.273317 -336.635437) (xy 425.320209 -336.603906) (xy 425.37124 -336.579635)
			(xy 425.425291 -336.563155) (xy 425.481182 -336.554826) (xy 425.509436 -336.554318) (xy 425.537075 -336.554801)
			(xy 425.591771 -336.562795) (xy 425.644742 -336.578594) (xy 425.694881 -336.601869) (xy 425.741138 -336.632133)
			(xy 425.762166 -336.650076) (xy 425.769278 -336.656172) (xy 425.78655 -336.662776) (xy 425.872402 -336.662776)
			(xy 425.889674 -336.656172) (xy 425.896786 -336.650076) (xy 425.917819 -336.632138) (xy 425.964069 -336.601863)
			(xy 426.014206 -336.578584) (xy 426.067179 -336.562789) (xy 426.121877 -336.554809) (xy 426.149516 -336.554318)
			(xy 426.17677 -336.55474) (xy 426.230724 -336.5625) (xy 426.283025 -336.577859) (xy 426.332607 -336.600506)
			(xy 426.378461 -336.629978) (xy 426.419654 -336.665676) (xy 426.455348 -336.706873) (xy 426.484815 -336.75273)
			(xy 426.507455 -336.802315) (xy 426.522809 -336.854617) (xy 426.530563 -336.908571) (xy 426.531024 -336.935826)
			(xy 426.530592 -336.963198) (xy 426.522769 -337.017379) (xy 426.507273 -337.069883) (xy 426.484423 -337.11963)
			(xy 426.45469 -337.165594) (xy 426.437044 -337.186524) (xy 426.430948 -337.193636) (xy 426.424598 -337.210654)
			(xy 426.424598 -337.295998) (xy 426.430948 -337.313016) (xy 426.437044 -337.320128) (xy 426.454711 -337.34104)
			(xy 426.484437 -337.38701) (xy 426.507283 -337.43676) (xy 426.522778 -337.489265) (xy 426.530605 -337.543447)
			(xy 426.530602 -337.598192) (xy 426.52277 -337.652373) (xy 426.507269 -337.704877) (xy 426.484418 -337.754624)
			(xy 426.454688 -337.800592) (xy 426.437044 -337.821524) (xy 426.430948 -337.828636) (xy 426.424598 -337.845654)
			(xy 426.424598 -337.930998) (xy 426.430948 -337.948016) (xy 426.437044 -337.955128) (xy 426.454711 -337.97604)
			(xy 426.484437 -338.02201) (xy 426.507283 -338.07176) (xy 426.522778 -338.124265) (xy 426.530605 -338.178447)
			(xy 426.530602 -338.233192) (xy 426.52277 -338.287373) (xy 426.507269 -338.339877) (xy 426.484418 -338.389624)
			(xy 426.454688 -338.435592) (xy 426.437044 -338.456524) (xy 426.430948 -338.463636) (xy 426.424598 -338.480654)
			(xy 426.424598 -338.565998) (xy 426.430948 -338.583016) (xy 426.437044 -338.590128) (xy 426.454711 -338.61104)
			(xy 426.484437 -338.65701) (xy 426.507283 -338.70676) (xy 426.522778 -338.759265) (xy 426.530605 -338.813447)
			(xy 426.530602 -338.868192) (xy 426.52277 -338.922373) (xy 426.507269 -338.974877) (xy 426.484418 -339.024624)
			(xy 426.454688 -339.070592) (xy 426.437044 -339.091524) (xy 426.430948 -339.098636) (xy 426.424598 -339.115654)
			(xy 426.424598 -339.200998) (xy 426.430948 -339.218016) (xy 426.437044 -339.225128) (xy 426.454711 -339.24604)
			(xy 426.484437 -339.29201) (xy 426.507283 -339.34176) (xy 426.522778 -339.394265) (xy 426.530605 -339.448447)
			(xy 426.530602 -339.503192) (xy 426.52277 -339.557373) (xy 426.507269 -339.609877) (xy 426.484418 -339.659624)
			(xy 426.454688 -339.705592) (xy 426.437044 -339.726524) (xy 426.430948 -339.733636) (xy 426.424598 -339.750654)
			(xy 426.424598 -339.835998) (xy 426.430948 -339.853016) (xy 426.437044 -339.860128) (xy 426.45467 -339.88107)
			(xy 426.484382 -339.927041) (xy 426.50722 -339.976786) (xy 426.522715 -340.029284) (xy 426.530548 -340.083458)
			(xy 426.531024 -340.110826) (xy 426.530795 -340.122764) (xy 429.05553 -340.122764) (xy 429.055968 -340.095393)
			(xy 429.063791 -340.041212) (xy 429.079287 -339.988708) (xy 429.102135 -339.938962) (xy 429.131866 -339.892997)
			(xy 429.14951 -339.872066) (xy 429.155606 -339.864954) (xy 429.161956 -339.847936) (xy 429.161956 -339.762592)
			(xy 429.155606 -339.745574) (xy 429.14951 -339.738462) (xy 429.131835 -339.717557) (xy 429.102113 -339.671584)
			(xy 429.07927 -339.621833) (xy 429.063778 -339.569327) (xy 429.055953 -339.515145) (xy 429.055957 -339.460401)
			(xy 429.063789 -339.40622) (xy 429.07929 -339.353716) (xy 429.102139 -339.303968) (xy 429.131867 -339.257999)
			(xy 429.14951 -339.237066) (xy 429.155606 -339.229954) (xy 429.161956 -339.212936) (xy 429.161956 -339.127592)
			(xy 429.155606 -339.110574) (xy 429.14951 -339.103462) (xy 429.131835 -339.082557) (xy 429.102113 -339.036584)
			(xy 429.07927 -338.986833) (xy 429.063778 -338.934327) (xy 429.055953 -338.880145) (xy 429.055957 -338.825401)
			(xy 429.063789 -338.77122) (xy 429.07929 -338.718716) (xy 429.102139 -338.668968) (xy 429.131867 -338.622999)
			(xy 429.14951 -338.602066) (xy 429.155606 -338.594954) (xy 429.161956 -338.577936) (xy 429.161956 -338.492592)
			(xy 429.155606 -338.475574) (xy 429.14951 -338.468462) (xy 429.131835 -338.447557) (xy 429.102113 -338.401584)
			(xy 429.07927 -338.351833) (xy 429.063778 -338.299327) (xy 429.055953 -338.245145) (xy 429.055957 -338.190401)
			(xy 429.063789 -338.13622) (xy 429.07929 -338.083716) (xy 429.102139 -338.033968) (xy 429.131867 -337.987999)
			(xy 429.14951 -337.967066) (xy 429.155606 -337.959954) (xy 429.161956 -337.942936) (xy 429.161956 -337.857592)
			(xy 429.155606 -337.840574) (xy 429.14951 -337.833462) (xy 429.131835 -337.812557) (xy 429.102113 -337.766584)
			(xy 429.07927 -337.716833) (xy 429.063778 -337.664327) (xy 429.055953 -337.610145) (xy 429.055957 -337.555401)
			(xy 429.063789 -337.50122) (xy 429.07929 -337.448716) (xy 429.102139 -337.398968) (xy 429.131867 -337.352999)
			(xy 429.14951 -337.332066) (xy 429.155606 -337.324954) (xy 429.161956 -337.307936) (xy 429.161956 -337.222592)
			(xy 429.155606 -337.205574) (xy 429.14951 -337.198462) (xy 429.131888 -337.177516) (xy 429.102173 -337.131547)
			(xy 429.079334 -337.081803) (xy 429.063839 -337.029306) (xy 429.056006 -336.975132) (xy 429.05553 -336.947764)
			(xy 429.055922 -336.920508) (xy 429.063684 -336.866553) (xy 429.079047 -336.814251) (xy 429.101696 -336.764669)
			(xy 429.131172 -336.718814) (xy 429.166873 -336.67762) (xy 429.208073 -336.641927) (xy 429.253934 -336.612461)
			(xy 429.303521 -336.589821) (xy 429.355825 -336.574469) (xy 429.409782 -336.566716) (xy 429.437038 -336.566256)
			(xy 429.464676 -336.566754) (xy 429.519371 -336.574746) (xy 429.572342 -336.590543) (xy 429.62248 -336.613814)
			(xy 429.668738 -336.644074) (xy 429.689768 -336.662014) (xy 429.69688 -336.66811) (xy 429.714152 -336.674714)
			(xy 429.800004 -336.674714) (xy 429.817276 -336.66811) (xy 429.824388 -336.662014) (xy 429.845425 -336.644081)
			(xy 429.891673 -336.613804) (xy 429.941809 -336.590523) (xy 429.994781 -336.574727) (xy 430.049479 -336.566747)
			(xy 430.077118 -336.566256) (xy 430.103911 -336.56672) (xy 430.15697 -336.574227) (xy 430.208459 -336.589076)
			(xy 430.257366 -336.610977) (xy 430.302732 -336.639499) (xy 430.343666 -336.674082) (xy 430.361852 -336.693764)
			(xy 430.369218 -336.702146) (xy 430.388522 -336.710782) (xy 430.486058 -336.711036) (xy 430.505616 -336.7024)
			(xy 430.512982 -336.694272) (xy 430.531135 -336.674865) (xy 430.571932 -336.640812) (xy 430.617058 -336.612745)
			(xy 430.665639 -336.591208) (xy 430.716738 -336.576616) (xy 430.769367 -336.569252) (xy 430.795938 -336.568796)
			(xy 430.82319 -336.569242) (xy 430.87714 -336.577004) (xy 430.929435 -336.592364) (xy 430.979013 -336.61501)
			(xy 431.024863 -336.644481) (xy 431.066053 -336.680176) (xy 431.101744 -336.72137) (xy 431.13121 -336.767224)
			(xy 431.15385 -336.816804) (xy 431.169205 -336.869101) (xy 431.176961 -336.923052) (xy 431.177446 -336.950304)
			(xy 431.177009 -336.97628) (xy 431.169965 -337.027751) (xy 431.155996 -337.077789) (xy 431.135359 -337.125465)
			(xy 431.108438 -337.169896) (xy 431.075731 -337.210259) (xy 431.037845 -337.245806) (xy 431.016918 -337.2612)
			(xy 431.007401 -337.268805) (xy 430.996271 -337.290438) (xy 430.995582 -337.302602) (xy 430.995582 -337.385406)
			(xy 430.996285 -337.397567) (xy 431.007414 -337.41919) (xy 431.016918 -337.426808) (xy 431.037848 -337.442196)
			(xy 431.075726 -337.47775) (xy 431.108427 -337.518117) (xy 431.135345 -337.562549) (xy 431.155982 -337.610224)
			(xy 431.169955 -337.66026) (xy 431.177007 -337.711729) (xy 431.177446 -337.737704) (xy 431.176995 -337.765075)
			(xy 431.169176 -337.819255) (xy 431.153684 -337.871759) (xy 431.130838 -337.921506) (xy 431.10111 -337.967471)
			(xy 431.083466 -337.988402) (xy 431.07737 -337.995514) (xy 431.07102 -338.012532) (xy 431.07102 -338.097876)
			(xy 431.07737 -338.114894) (xy 431.083466 -338.122006) (xy 431.101111 -338.142935) (xy 431.130836 -338.188904)
			(xy 431.153682 -338.23865) (xy 431.169178 -338.291153) (xy 431.177006 -338.345332) (xy 431.177006 -338.400074)
			(xy 431.169177 -338.454253) (xy 431.15368 -338.506755) (xy 431.130833 -338.556502) (xy 431.101107 -338.602469)
			(xy 431.083466 -338.623402) (xy 431.07737 -338.630514) (xy 431.07102 -338.647532) (xy 431.07102 -338.732876)
			(xy 431.07737 -338.749894) (xy 431.083466 -338.757006) (xy 431.101116 -338.777929) (xy 431.130827 -338.823904)
			(xy 431.153662 -338.873654) (xy 431.16915 -338.926156) (xy 431.176974 -338.980334) (xy 431.177446 -339.007704)
			(xy 432.785774 -339.007704) (xy 432.786224 -338.980333) (xy 432.794043 -338.926153) (xy 432.809535 -338.873649)
			(xy 432.832381 -338.823902) (xy 432.86211 -338.777936) (xy 432.879754 -338.757006) (xy 432.88585 -338.749894)
			(xy 432.8922 -338.732876) (xy 432.8922 -338.647532) (xy 432.88585 -338.630514) (xy 432.879754 -338.623402)
			(xy 432.862116 -338.602467) (xy 432.832389 -338.5565) (xy 432.809542 -338.506754) (xy 432.794044 -338.454252)
			(xy 432.786215 -338.400074) (xy 432.786214 -338.345332) (xy 432.794043 -338.291153) (xy 432.80954 -338.238651)
			(xy 432.832386 -338.188905) (xy 432.862112 -338.142938) (xy 432.879754 -338.122006) (xy 432.88585 -338.114894)
			(xy 432.8922 -338.097876) (xy 432.8922 -338.012532) (xy 432.88585 -337.995514) (xy 432.879754 -337.988402)
			(xy 432.862111 -337.967473) (xy 432.832398 -337.9215) (xy 432.809562 -337.871752) (xy 432.794072 -337.81925)
			(xy 432.786246 -337.765074) (xy 432.785774 -337.737704) (xy 432.786209 -337.711728) (xy 432.793252 -337.660256)
			(xy 432.807221 -337.610218) (xy 432.827858 -337.562542) (xy 432.85478 -337.51811) (xy 432.887487 -337.477747)
			(xy 432.925374 -337.442202) (xy 432.946302 -337.426808) (xy 432.955801 -337.419184) (xy 432.966944 -337.397566)
			(xy 432.967638 -337.385406) (xy 432.967638 -337.302602) (xy 432.966982 -337.290435) (xy 432.955818 -337.268813)
			(xy 432.946302 -337.2612) (xy 432.925358 -337.24583) (xy 432.887484 -337.210271) (xy 432.854787 -337.1699)
			(xy 432.827872 -337.125464) (xy 432.807238 -337.077787) (xy 432.793265 -337.02775) (xy 432.786213 -336.97628)
			(xy 432.785774 -336.950304) (xy 432.786281 -336.923054) (xy 432.794037 -336.869108) (xy 432.809391 -336.816814)
			(xy 432.83203 -336.767238) (xy 432.861494 -336.721389) (xy 432.897183 -336.680199) (xy 432.938371 -336.644507)
			(xy 432.984219 -336.615041) (xy 433.033794 -336.592398) (xy 433.086086 -336.577042) (xy 433.140032 -336.569283)
			(xy 433.167282 -336.568796) (xy 433.197081 -336.569368) (xy 433.255951 -336.578646) (xy 433.312664 -336.596962)
			(xy 433.36584 -336.623873) (xy 433.414186 -336.658722) (xy 433.43576 -336.679286) (xy 433.442872 -336.686398)
			(xy 433.460652 -336.693764) (xy 433.551076 -336.695288) (xy 433.56911 -336.68843) (xy 433.576476 -336.681572)
			(xy 433.597798 -336.662565) (xy 433.64499 -336.630391) (xy 433.69645 -336.605608) (xy 433.751028 -336.588771)
			(xy 433.807506 -336.580254) (xy 433.836064 -336.579718) (xy 433.863703 -336.580185) (xy 433.9184 -336.588182)
			(xy 433.971372 -336.603985) (xy 434.02151 -336.627264) (xy 434.067766 -336.657532) (xy 434.088794 -336.675476)
			(xy 434.095906 -336.681572) (xy 434.113178 -336.688176) (xy 434.19903 -336.688176) (xy 434.216302 -336.681572)
			(xy 434.223414 -336.675476) (xy 434.244436 -336.657525) (xy 434.290689 -336.627252) (xy 434.340829 -336.603975)
			(xy 434.393804 -336.588183) (xy 434.448504 -336.580207) (xy 434.476144 -336.579718) (xy 434.503398 -336.580137)
			(xy 434.557349 -336.5879) (xy 434.609647 -336.603262) (xy 434.659226 -336.62591) (xy 434.705077 -336.655384)
			(xy 434.746268 -336.691082) (xy 434.781958 -336.732279) (xy 434.811423 -336.778136) (xy 434.834062 -336.827719)
			(xy 434.849415 -336.88002) (xy 434.857168 -336.933972) (xy 434.857652 -336.961226) (xy 434.857213 -336.988597)
			(xy 434.84939 -337.042778) (xy 434.833896 -337.095282) (xy 434.811048 -337.145028) (xy 434.781317 -337.190994)
			(xy 434.763672 -337.211924) (xy 434.757576 -337.219036) (xy 434.751226 -337.236054) (xy 434.751226 -337.321398)
			(xy 434.757576 -337.338416) (xy 434.763672 -337.345528) (xy 434.781338 -337.36644) (xy 434.811062 -337.412411)
			(xy 434.833906 -337.462161) (xy 434.8494 -337.514666) (xy 434.857226 -337.568848) (xy 434.857224 -337.623591)
			(xy 434.849392 -337.677772) (xy 434.833892 -337.730276) (xy 434.811043 -337.780023) (xy 434.781315 -337.825991)
			(xy 434.763672 -337.846924) (xy 434.757576 -337.854036) (xy 434.751226 -337.871054) (xy 434.751226 -337.956398)
			(xy 434.757576 -337.973416) (xy 434.763672 -337.980528) (xy 434.781338 -338.00144) (xy 434.811062 -338.047411)
			(xy 434.833906 -338.097161) (xy 434.8494 -338.149666) (xy 434.857226 -338.203848) (xy 434.857224 -338.258591)
			(xy 434.849392 -338.312772) (xy 434.833892 -338.365276) (xy 434.811043 -338.415023) (xy 434.781315 -338.460991)
			(xy 434.763672 -338.481924) (xy 434.757576 -338.489036) (xy 434.751226 -338.506054) (xy 434.751226 -338.591398)
			(xy 434.757576 -338.608416) (xy 434.763672 -338.615528) (xy 434.781338 -338.63644) (xy 434.811062 -338.682411)
			(xy 434.833906 -338.732161) (xy 434.8494 -338.784666) (xy 434.857226 -338.838848) (xy 434.857224 -338.893591)
			(xy 434.849392 -338.947772) (xy 434.833892 -339.000276) (xy 434.811043 -339.050023) (xy 434.781315 -339.095991)
			(xy 434.763672 -339.116924) (xy 434.757576 -339.124036) (xy 434.751226 -339.141054) (xy 434.751226 -339.226398)
			(xy 434.757576 -339.243416) (xy 434.763672 -339.250528) (xy 434.781338 -339.27144) (xy 434.811062 -339.317411)
			(xy 434.833906 -339.367161) (xy 434.8494 -339.419666) (xy 434.857226 -339.473848) (xy 434.857224 -339.528591)
			(xy 434.849392 -339.582772) (xy 434.833892 -339.635276) (xy 434.811043 -339.685023) (xy 434.781315 -339.730991)
			(xy 434.763672 -339.751924) (xy 434.757576 -339.759036) (xy 434.751226 -339.776054) (xy 434.751226 -339.861398)
			(xy 434.757576 -339.878416) (xy 434.763672 -339.885528) (xy 434.781286 -339.90648) (xy 434.811003 -339.952447)
			(xy 434.833844 -340.002189) (xy 434.849341 -340.054686) (xy 434.857175 -340.108858) (xy 434.857386 -340.120986)
			(xy 435.837076 -340.120986) (xy 435.837515 -340.093615) (xy 435.845337 -340.039434) (xy 435.860831 -339.98693)
			(xy 435.883679 -339.937183) (xy 435.913411 -339.891218) (xy 435.931056 -339.870288) (xy 435.937152 -339.863176)
			(xy 435.943502 -339.846158) (xy 435.943502 -339.760814) (xy 435.937152 -339.743796) (xy 435.931056 -339.736684)
			(xy 435.9134 -339.715763) (xy 435.883674 -339.669794) (xy 435.860828 -339.620046) (xy 435.845331 -339.567542)
			(xy 435.837503 -339.513361) (xy 435.837505 -339.458618) (xy 435.845336 -339.404438) (xy 435.860835 -339.351934)
			(xy 435.883684 -339.302188) (xy 435.913413 -339.25622) (xy 435.931056 -339.235288) (xy 435.937152 -339.228176)
			(xy 435.943502 -339.211158) (xy 435.943502 -339.125814) (xy 435.937152 -339.108796) (xy 435.931056 -339.101684)
			(xy 435.9134 -339.080763) (xy 435.883674 -339.034794) (xy 435.860828 -338.985046) (xy 435.845331 -338.932542)
			(xy 435.837503 -338.878361) (xy 435.837505 -338.823618) (xy 435.845336 -338.769438) (xy 435.860835 -338.716934)
			(xy 435.883684 -338.667188) (xy 435.913413 -338.62122) (xy 435.931056 -338.600288) (xy 435.937152 -338.593176)
			(xy 435.943502 -338.576158) (xy 435.943502 -338.490814) (xy 435.937152 -338.473796) (xy 435.931056 -338.466684)
			(xy 435.9134 -338.445763) (xy 435.883674 -338.399794) (xy 435.860828 -338.350046) (xy 435.845331 -338.297542)
			(xy 435.837503 -338.243361) (xy 435.837505 -338.188618) (xy 435.845336 -338.134438) (xy 435.860835 -338.081934)
			(xy 435.883684 -338.032188) (xy 435.913413 -337.98622) (xy 435.931056 -337.965288) (xy 435.937152 -337.958176)
			(xy 435.943502 -337.941158) (xy 435.943502 -337.855814) (xy 435.937152 -337.838796) (xy 435.931056 -337.831684)
			(xy 435.9134 -337.810763) (xy 435.883674 -337.764794) (xy 435.860828 -337.715046) (xy 435.845331 -337.662542)
			(xy 435.837503 -337.608361) (xy 435.837505 -337.553618) (xy 435.845336 -337.499438) (xy 435.860835 -337.446934)
			(xy 435.883684 -337.397188) (xy 435.913413 -337.35122) (xy 435.931056 -337.330288) (xy 435.937152 -337.323176)
			(xy 435.943502 -337.306158) (xy 435.943502 -337.220814) (xy 435.937152 -337.203796) (xy 435.931056 -337.196684)
			(xy 435.913436 -337.175737) (xy 435.883722 -337.129768) (xy 435.860883 -337.080024) (xy 435.845388 -337.027527)
			(xy 435.837553 -336.973354) (xy 435.837076 -336.945986) (xy 435.837565 -336.918735) (xy 435.845323 -336.864788)
			(xy 435.860679 -336.812495) (xy 435.88332 -336.762918) (xy 435.912787 -336.717069) (xy 435.948478 -336.675879)
			(xy 435.989667 -336.640188) (xy 436.035517 -336.610721) (xy 436.085093 -336.58808) (xy 436.137386 -336.572723)
			(xy 436.191333 -336.564965) (xy 436.218584 -336.564478) (xy 436.246221 -336.565002) (xy 436.300915 -336.572987)
			(xy 436.353886 -336.588777) (xy 436.404025 -336.612043) (xy 436.450284 -336.642298) (xy 436.471314 -336.660236)
			(xy 436.478426 -336.666332) (xy 436.495698 -336.672936) (xy 436.58155 -336.672936) (xy 436.598822 -336.666332)
			(xy 436.605934 -336.660236) (xy 436.626943 -336.642269) (xy 436.6732 -336.612) (xy 436.723343 -336.588727)
			(xy 436.776321 -336.572938) (xy 436.831024 -336.564965) (xy 436.858664 -336.564478) (xy 436.885915 -336.564989)
			(xy 436.939864 -336.57274) (xy 436.99216 -336.588091) (xy 437.041739 -336.610729) (xy 437.087592 -336.640191)
			(xy 437.128784 -336.67588) (xy 437.164479 -336.717068) (xy 437.193947 -336.762917) (xy 437.216591 -336.812493)
			(xy 437.231949 -336.864787) (xy 437.239708 -336.918735) (xy 437.240172 -336.945986) (xy 437.239705 -336.973356)
			(xy 437.231888 -337.027536) (xy 437.2164 -337.080039) (xy 437.193558 -337.129786) (xy 437.163833 -337.175752)
			(xy 437.146192 -337.196684) (xy 437.140096 -337.203796) (xy 437.133746 -337.220814) (xy 437.133746 -337.306158)
			(xy 437.140096 -337.323176) (xy 437.146192 -337.330288) (xy 437.163818 -337.351232) (xy 437.193542 -337.397198)
			(xy 437.216387 -337.446943) (xy 437.231884 -337.499443) (xy 437.239713 -337.55362) (xy 437.239715 -337.608359)
			(xy 437.231888 -337.662536) (xy 437.216395 -337.715037) (xy 437.193552 -337.764783) (xy 437.163831 -337.810751)
			(xy 437.146192 -337.831684) (xy 437.140096 -337.838796) (xy 437.133746 -337.855814) (xy 437.133746 -337.941158)
			(xy 437.140096 -337.958176) (xy 437.146192 -337.965288) (xy 437.163818 -337.986232) (xy 437.193542 -338.032198)
			(xy 437.216387 -338.081943) (xy 437.231884 -338.134443) (xy 437.239713 -338.18862) (xy 437.239715 -338.243359)
			(xy 437.231888 -338.297536) (xy 437.216395 -338.350037) (xy 437.193552 -338.399783) (xy 437.163831 -338.445751)
			(xy 437.146192 -338.466684) (xy 437.140096 -338.473796) (xy 437.133746 -338.490814) (xy 437.133746 -338.576158)
			(xy 437.140096 -338.593176) (xy 437.146192 -338.600288) (xy 437.163818 -338.621232) (xy 437.193542 -338.667198)
			(xy 437.216387 -338.716943) (xy 437.231884 -338.769443) (xy 437.239713 -338.82362) (xy 437.239715 -338.878359)
			(xy 437.231888 -338.932536) (xy 437.216395 -338.985037) (xy 437.193552 -339.034783) (xy 437.163831 -339.080751)
			(xy 437.146192 -339.101684) (xy 437.140096 -339.108796) (xy 437.133746 -339.125814) (xy 437.133746 -339.211158)
			(xy 437.140096 -339.228176) (xy 437.146192 -339.235288) (xy 437.163818 -339.256232) (xy 437.193542 -339.302198)
			(xy 437.216387 -339.351943) (xy 437.231884 -339.404443) (xy 437.239713 -339.45862) (xy 437.239715 -339.513359)
			(xy 437.231888 -339.567536) (xy 437.216395 -339.620037) (xy 437.193552 -339.669783) (xy 437.163831 -339.715751)
			(xy 437.146192 -339.736684) (xy 437.140096 -339.743796) (xy 437.133746 -339.760814) (xy 437.133746 -339.846158)
			(xy 437.140096 -339.863176) (xy 437.146192 -339.870288) (xy 437.163838 -339.891215) (xy 437.193549 -339.937189)
			(xy 437.216384 -339.986938) (xy 437.231873 -340.03944) (xy 437.239699 -340.093616) (xy 437.240172 -340.120986)
			(xy 437.239659 -340.148188) (xy 437.231907 -340.202038) (xy 437.216586 -340.254242) (xy 437.194007 -340.30374)
			(xy 437.164628 -340.349531) (xy 437.129044 -340.390686) (xy 437.087977 -340.42637) (xy 437.042258 -340.455861)
			(xy 436.992814 -340.47856) (xy 436.966868 -340.486746) (xy 436.9562 -340.490048) (xy 436.939944 -340.503764)
			(xy 436.898288 -340.592664) (xy 436.89778 -340.614) (xy 436.902352 -340.62416) (xy 436.91203 -340.647897)
			(xy 436.925611 -340.697328) (xy 436.932439 -340.748134) (xy 436.932832 -340.773766) (xy 436.932363 -340.801136)
			(xy 436.924548 -340.855316) (xy 436.909061 -340.90782) (xy 436.886219 -340.957567) (xy 436.856494 -341.003533)
			(xy 436.838852 -341.024464) (xy 436.832756 -341.031576) (xy 436.826406 -341.048594) (xy 436.826406 -341.133938)
			(xy 436.832756 -341.150956) (xy 436.838852 -341.158068) (xy 436.856482 -341.179007) (xy 436.886197 -341.224977)
			(xy 436.909035 -341.274723) (xy 436.924528 -341.327222) (xy 436.932358 -341.381397) (xy 436.932832 -341.408766)
			(xy 436.932346 -341.436017) (xy 436.92459 -341.489965) (xy 436.909235 -341.54226) (xy 436.886593 -341.591837)
			(xy 436.857127 -341.637687) (xy 436.821436 -341.678878) (xy 436.780245 -341.714569) (xy 436.734395 -341.744035)
			(xy 436.684818 -341.766677) (xy 436.632523 -341.782032) (xy 436.578575 -341.789788) (xy 436.524073 -341.789788)
			(xy 436.470125 -341.782032) (xy 436.41783 -341.766677) (xy 436.368253 -341.744035) (xy 436.322403 -341.714569)
			(xy 436.281212 -341.678878) (xy 436.245521 -341.637687) (xy 436.216055 -341.591837) (xy 436.193413 -341.54226)
			(xy 436.178058 -341.489965) (xy 436.170302 -341.436017) (xy 436.169816 -341.408766) (xy 436.170258 -341.381395)
			(xy 436.178081 -341.327215) (xy 436.193576 -341.274711) (xy 436.216423 -341.224965) (xy 436.246152 -341.178999)
			(xy 436.263796 -341.158068) (xy 436.269892 -341.150956) (xy 436.276242 -341.133938) (xy 436.276242 -341.048594)
			(xy 436.269892 -341.031576) (xy 436.263796 -341.024464) (xy 436.246173 -341.003519) (xy 436.216459 -340.95755)
			(xy 436.19362 -340.907806) (xy 436.178125 -340.855308) (xy 436.170292 -340.801134) (xy 436.169816 -340.773766)
			(xy 436.170198 -340.74901) (xy 436.176577 -340.69991) (xy 436.189251 -340.652046) (xy 436.198264 -340.628986)
			(xy 436.202582 -340.618572) (xy 436.201566 -340.596474) (xy 436.156608 -340.508082) (xy 436.139082 -340.494366)
			(xy 436.128414 -340.491572) (xy 436.1011 -340.484369) (xy 436.04878 -340.463081) (xy 436.000172 -340.434309)
			(xy 435.956338 -340.398684) (xy 435.918238 -340.356983) (xy 435.886704 -340.31012) (xy 435.862426 -340.259118)
			(xy 435.845936 -340.205094) (xy 435.837593 -340.149228) (xy 435.837076 -340.120986) (xy 434.857386 -340.120986)
			(xy 434.857652 -340.136226) (xy 434.857149 -340.164182) (xy 434.848973 -340.219492) (xy 434.832815 -340.273018)
			(xy 434.80902 -340.323614) (xy 434.778097 -340.370196) (xy 434.740709 -340.411768) (xy 434.697655 -340.44744)
			(xy 434.67401 -340.462362) (xy 434.66385 -340.468458) (xy 434.65115 -340.488016) (xy 434.638958 -340.590632)
			(xy 434.646324 -340.61273) (xy 434.654706 -340.621112) (xy 434.675432 -340.642729) (xy 434.710608 -340.691193)
			(xy 434.737775 -340.744559) (xy 434.756266 -340.801517) (xy 434.765626 -340.860664) (xy 434.766212 -340.890606)
			(xy 434.765747 -340.917976) (xy 434.757928 -340.972155) (xy 434.742439 -341.024658) (xy 434.719597 -341.074405)
			(xy 434.689873 -341.120372) (xy 434.672232 -341.141304) (xy 434.666136 -341.148416) (xy 434.659786 -341.165434)
			(xy 434.659786 -341.250778) (xy 434.666136 -341.267796) (xy 434.672232 -341.274908) (xy 434.689893 -341.295822)
			(xy 434.719601 -341.3418) (xy 434.742432 -341.391552) (xy 434.757918 -341.444057) (xy 434.765741 -341.498236)
			(xy 434.766212 -341.525606) (xy 434.765726 -341.552857) (xy 434.75797 -341.606805) (xy 434.742615 -341.6591)
			(xy 434.719973 -341.708677) (xy 434.690507 -341.754527) (xy 434.654816 -341.795718) (xy 434.613625 -341.831409)
			(xy 434.567775 -341.860875) (xy 434.518198 -341.883517) (xy 434.465903 -341.898872) (xy 434.411955 -341.906628)
			(xy 434.357453 -341.906628) (xy 434.303505 -341.898872) (xy 434.25121 -341.883517) (xy 434.201633 -341.860875)
			(xy 434.155783 -341.831409) (xy 434.114592 -341.795718) (xy 434.078901 -341.754527) (xy 434.049435 -341.708677)
			(xy 434.026793 -341.6591) (xy 434.011438 -341.606805) (xy 434.003682 -341.552857) (xy 434.003196 -341.525606)
			(xy 434.003667 -341.498236) (xy 434.011483 -341.444057) (xy 434.026972 -341.391554) (xy 434.049812 -341.341807)
			(xy 434.079535 -341.29584) (xy 434.097176 -341.274908) (xy 434.103272 -341.267796) (xy 434.109622 -341.250778)
			(xy 434.109622 -341.165434) (xy 434.103272 -341.148416) (xy 434.097176 -341.141304) (xy 434.079522 -341.120384)
			(xy 434.049813 -341.074408) (xy 434.02698 -341.024657) (xy 434.011493 -340.972154) (xy 434.003668 -340.917976)
			(xy 434.003196 -340.890606) (xy 434.0037 -340.863827) (xy 434.011197 -340.810795) (xy 434.026031 -340.759332)
			(xy 434.04791 -340.710446) (xy 434.076406 -340.665097) (xy 434.11096 -340.624175) (xy 434.150892 -340.588483)
			(xy 434.195421 -340.558721) (xy 434.21935 -340.54669) (xy 434.226894 -340.542743) (xy 434.238981 -340.530762)
			(xy 434.246458 -340.515475) (xy 434.247798 -340.507066) (xy 434.255164 -340.447122) (xy 434.234336 -340.431374)
			(xy 434.226716 -340.425024) (xy 434.208174 -340.419182) (xy 434.118512 -340.42604) (xy 434.100986 -340.434676)
			(xy 434.094382 -340.442042) (xy 434.076221 -340.461583) (xy 434.035386 -340.495913) (xy 433.990166 -340.524215)
			(xy 433.941442 -340.545939) (xy 433.890165 -340.56066) (xy 433.837338 -340.568091) (xy 433.810664 -340.568534)
			(xy 433.783413 -340.568056) (xy 433.729466 -340.560295) (xy 433.677173 -340.544937) (xy 433.627597 -340.522293)
			(xy 433.581749 -340.492826) (xy 433.540559 -340.457134) (xy 433.504868 -340.415943) (xy 433.475402 -340.370094)
			(xy 433.45276 -340.320517) (xy 433.437403 -340.268224) (xy 433.429644 -340.214277) (xy 433.429156 -340.187026)
			(xy 433.429624 -340.159656) (xy 433.437439 -340.105476) (xy 433.452927 -340.052972) (xy 433.475769 -340.003226)
			(xy 433.505494 -339.957259) (xy 433.523136 -339.936328) (xy 433.529232 -339.929216) (xy 433.535582 -339.912198)
			(xy 433.535582 -339.826854) (xy 433.529232 -339.809836) (xy 433.523136 -339.802724) (xy 433.5055 -339.781789)
			(xy 433.475787 -339.735818) (xy 433.45295 -339.686071) (xy 433.437458 -339.633571) (xy 433.42963 -339.579395)
			(xy 433.429156 -339.552026) (xy 433.429345 -339.533816) (xy 433.432778 -339.497558) (xy 433.436014 -339.479636)
			(xy 433.438808 -339.46592) (xy 433.429664 -339.440266) (xy 433.340764 -339.364828) (xy 433.31384 -339.360256)
			(xy 433.300886 -339.365082) (xy 433.268631 -339.376312) (xy 433.201427 -339.388452) (xy 433.167282 -339.389212)
			(xy 433.14003 -339.388739) (xy 433.086083 -339.38098) (xy 433.033788 -339.365623) (xy 432.984211 -339.34298)
			(xy 432.938361 -339.313512) (xy 432.897171 -339.277819) (xy 432.861479 -339.236628) (xy 432.832013 -339.190777)
			(xy 432.809372 -339.141199) (xy 432.794017 -339.088904) (xy 432.78626 -339.034956) (xy 432.785774 -339.007704)
			(xy 431.177446 -339.007704) (xy 431.176926 -339.034954) (xy 431.16917 -339.088898) (xy 431.153816 -339.14119)
			(xy 431.131177 -339.190765) (xy 431.101714 -339.236613) (xy 431.066026 -339.277802) (xy 431.02484 -339.313494)
			(xy 430.978995 -339.342961) (xy 430.929422 -339.365604) (xy 430.877131 -339.380963) (xy 430.823188 -339.388724)
			(xy 430.795938 -339.389212) (xy 430.769797 -339.388796) (xy 430.718005 -339.381658) (xy 430.667673 -339.367512)
			(xy 430.643538 -339.357462) (xy 430.63033 -339.35162) (xy 430.602898 -339.35543) (xy 430.510188 -339.428836)
			(xy 430.500536 -339.454998) (xy 430.503076 -339.468968) (xy 430.506064 -339.486211) (xy 430.509241 -339.521065)
			(xy 430.509426 -339.538564) (xy 430.508957 -339.565934) (xy 430.501143 -339.620114) (xy 430.485655 -339.672618)
			(xy 430.462814 -339.722365) (xy 430.433088 -339.768331) (xy 430.415446 -339.789262) (xy 430.40935 -339.796374)
			(xy 430.403 -339.813392) (xy 430.403 -339.898736) (xy 430.40935 -339.915754) (xy 430.415446 -339.922866)
			(xy 430.433074 -339.943807) (xy 430.46279 -339.989777) (xy 430.485628 -340.039522) (xy 430.501122 -340.092021)
			(xy 430.508952 -340.146195) (xy 430.509426 -340.173564) (xy 430.508911 -340.200815) (xy 430.50116 -340.254763)
			(xy 430.485809 -340.307059) (xy 430.463172 -340.356638) (xy 430.43371 -340.40249) (xy 430.398021 -340.443683)
			(xy 430.356834 -340.479377) (xy 430.310985 -340.508846) (xy 430.26141 -340.53149) (xy 430.209116 -340.546848)
			(xy 430.155169 -340.554607) (xy 430.127918 -340.555072) (xy 430.100148 -340.554573) (xy 430.045195 -340.546522)
			(xy 429.99199 -340.530587) (xy 429.941659 -340.507104) (xy 429.895264 -340.476571) (xy 429.853788 -340.439633)
			(xy 429.835564 -340.418674) (xy 429.82896 -340.410546) (xy 429.810926 -340.401402) (xy 429.7172 -340.394544)
			(xy 429.69815 -340.401148) (xy 429.690276 -340.408006) (xy 429.669251 -340.426064) (xy 429.622928 -340.45649)
			(xy 429.572688 -340.479887) (xy 429.519588 -340.495762) (xy 429.464749 -340.503779) (xy 429.437038 -340.504272)
			(xy 429.409784 -340.503809) (xy 429.355832 -340.496057) (xy 429.303532 -340.480703) (xy 429.253949 -340.458063)
			(xy 429.208094 -340.428595) (xy 429.1669 -340.392901) (xy 429.131206 -340.351707) (xy 429.101738 -340.305853)
			(xy 429.079097 -340.25627) (xy 429.063744 -340.20397) (xy 429.055991 -340.150018) (xy 429.05553 -340.122764)
			(xy 426.530795 -340.122764) (xy 426.530452 -340.140666) (xy 426.521195 -340.199624) (xy 426.50285 -340.256414)
			(xy 426.489876 -340.283292) (xy 426.484542 -340.293706) (xy 426.484034 -340.317074) (xy 426.52823 -340.411054)
			(xy 426.546264 -340.425532) (xy 426.557948 -340.428326) (xy 426.585683 -340.43513) (xy 426.638853 -340.45597)
			(xy 426.688319 -340.484506) (xy 426.732978 -340.520099) (xy 426.771829 -340.561954) (xy 426.804004 -340.609135)
			(xy 426.828784 -340.660586) (xy 426.845614 -340.715157) (xy 426.854118 -340.771628) (xy 426.85462 -340.800182)
			(xy 426.854163 -340.827553) (xy 426.846346 -340.881733) (xy 426.830856 -340.934237) (xy 426.808012 -340.983984)
			(xy 426.778283 -341.029949) (xy 426.76064 -341.05088) (xy 426.754544 -341.057992) (xy 426.748194 -341.07501)
			(xy 426.748194 -341.160354) (xy 426.754544 -341.177372) (xy 426.76064 -341.184484) (xy 426.778292 -341.205406)
			(xy 426.808 -341.251382) (xy 426.830833 -341.301132) (xy 426.846322 -341.353635) (xy 426.850763 -341.384382)
			(xy 428.175928 -341.384382) (xy 428.176377 -341.357011) (xy 428.184198 -341.302831) (xy 428.19969 -341.250327)
			(xy 428.222536 -341.200581) (xy 428.252265 -341.154615) (xy 428.269908 -341.133684) (xy 428.276004 -341.126572)
			(xy 428.282354 -341.109554) (xy 428.282354 -341.02421) (xy 428.276004 -341.007192) (xy 428.269908 -341.00008)
			(xy 428.252294 -340.979128) (xy 428.222578 -340.93316) (xy 428.199737 -340.883418) (xy 428.18424 -340.830922)
			(xy 428.176406 -340.77675) (xy 428.175928 -340.749382) (xy 428.176414 -340.722131) (xy 428.18417 -340.668183)
			(xy 428.199525 -340.615888) (xy 428.222167 -340.566311) (xy 428.251633 -340.520461) (xy 428.287324 -340.47927)
			(xy 428.328515 -340.443579) (xy 428.374365 -340.414113) (xy 428.423942 -340.391471) (xy 428.476237 -340.376116)
			(xy 428.530185 -340.36836) (xy 428.584687 -340.36836) (xy 428.638635 -340.376116) (xy 428.69093 -340.391471)
			(xy 428.740507 -340.414113) (xy 428.786357 -340.443579) (xy 428.827548 -340.47927) (xy 428.863239 -340.520461)
			(xy 428.892705 -340.566311) (xy 428.915347 -340.615888) (xy 428.930702 -340.668183) (xy 428.938458 -340.722131)
			(xy 428.938944 -340.749382) (xy 428.938481 -340.776752) (xy 428.930665 -340.830932) (xy 428.915176 -340.883436)
			(xy 428.892333 -340.933183) (xy 428.862606 -340.979149) (xy 428.844964 -341.00008) (xy 428.838868 -341.007192)
			(xy 428.832518 -341.02421) (xy 428.832518 -341.109554) (xy 428.838868 -341.126572) (xy 428.844964 -341.133684)
			(xy 428.862603 -341.154616) (xy 428.892316 -341.200588) (xy 428.915153 -341.250336) (xy 428.930644 -341.302837)
			(xy 428.938471 -341.357013) (xy 428.938944 -341.384382) (xy 428.938458 -341.411633) (xy 428.930702 -341.465581)
			(xy 428.915347 -341.517876) (xy 428.892705 -341.567453) (xy 428.863239 -341.613303) (xy 428.827548 -341.654494)
			(xy 428.786357 -341.690185) (xy 428.740507 -341.719651) (xy 428.69093 -341.742293) (xy 428.638635 -341.757648)
			(xy 428.584687 -341.765404) (xy 428.530185 -341.765404) (xy 428.476237 -341.757648) (xy 428.423942 -341.742293)
			(xy 428.374365 -341.719651) (xy 428.328515 -341.690185) (xy 428.287324 -341.654494) (xy 428.251633 -341.613303)
			(xy 428.222167 -341.567453) (xy 428.199525 -341.517876) (xy 428.18417 -341.465581) (xy 428.176414 -341.411633)
			(xy 428.175928 -341.384382) (xy 426.850763 -341.384382) (xy 426.854148 -341.407812) (xy 426.85462 -341.435182)
			(xy 426.854134 -341.462433) (xy 426.846378 -341.516381) (xy 426.831023 -341.568676) (xy 426.808381 -341.618253)
			(xy 426.778915 -341.664103) (xy 426.743224 -341.705294) (xy 426.702033 -341.740985) (xy 426.656183 -341.770451)
			(xy 426.606606 -341.793093) (xy 426.554311 -341.808448) (xy 426.500363 -341.816204) (xy 426.445861 -341.816204)
			(xy 426.391913 -341.808448) (xy 426.339618 -341.793093) (xy 426.290041 -341.770451) (xy 426.244191 -341.740985)
			(xy 426.203 -341.705294) (xy 426.167309 -341.664103) (xy 426.137843 -341.618253) (xy 426.115201 -341.568676)
			(xy 426.099846 -341.516381) (xy 426.09209 -341.462433) (xy 426.091604 -341.435182) (xy 426.092059 -341.407811)
			(xy 426.099879 -341.353632) (xy 426.115371 -341.301128) (xy 426.138215 -341.251382) (xy 426.167942 -341.205415)
			(xy 426.185584 -341.184484) (xy 426.19168 -341.177372) (xy 426.19803 -341.160354) (xy 426.19803 -341.07501)
			(xy 426.19168 -341.057992) (xy 426.185584 -341.05088) (xy 426.167966 -341.029931) (xy 426.138252 -340.983962)
			(xy 426.115412 -340.934219) (xy 426.099916 -340.881722) (xy 426.092082 -340.82755) (xy 426.091604 -340.800182)
			(xy 426.092176 -340.770342) (xy 426.101432 -340.711384) (xy 426.119778 -340.654594) (xy 426.132752 -340.627716)
			(xy 426.138086 -340.617302) (xy 426.138594 -340.593934) (xy 426.094398 -340.499954) (xy 426.076364 -340.485476)
			(xy 426.06468 -340.482682) (xy 426.036135 -340.475641) (xy 425.981486 -340.453963) (xy 425.930807 -340.424163)
			(xy 425.907708 -340.405974) (xy 425.900088 -340.399624) (xy 425.881546 -340.393782) (xy 425.791884 -340.40064)
			(xy 425.774358 -340.409276) (xy 425.767754 -340.416642) (xy 425.749607 -340.436197) (xy 425.708769 -340.470525)
			(xy 425.663546 -340.498826) (xy 425.614819 -340.520548) (xy 425.56354 -340.535266) (xy 425.510711 -340.542693)
			(xy 425.484036 -340.543134) (xy 425.456785 -340.542611) (xy 425.402838 -340.53486) (xy 425.350543 -340.51951)
			(xy 425.300964 -340.496873) (xy 425.255112 -340.467411) (xy 425.21392 -340.431724) (xy 425.178226 -340.390537)
			(xy 425.148756 -340.34469) (xy 425.126112 -340.295116) (xy 425.110753 -340.242823) (xy 425.102993 -340.188877)
			(xy 425.102528 -340.161626) (xy 425.103002 -340.134256) (xy 425.110817 -340.080077) (xy 425.126304 -340.027574)
			(xy 425.149144 -339.977827) (xy 425.178867 -339.93186) (xy 425.196508 -339.910928) (xy 425.202604 -339.903816)
			(xy 425.208954 -339.886798) (xy 425.208954 -339.801454) (xy 425.202604 -339.784436) (xy 425.196508 -339.777324)
			(xy 425.178868 -339.756393) (xy 425.149156 -339.71042) (xy 425.12632 -339.660672) (xy 425.110829 -339.608171)
			(xy 425.103002 -339.553995) (xy 425.102528 -339.526626) (xy 425.102647 -339.514206) (xy 425.1043 -339.489422)
			(xy 425.10583 -339.477096) (xy 425.107608 -339.463888) (xy 425.097702 -339.439504) (xy 425.010072 -339.36813)
			(xy 424.984164 -339.363558) (xy 424.971718 -339.36813) (xy 424.941292 -339.377996) (xy 424.878221 -339.388602)
			(xy 424.846242 -339.389212) (xy 424.81899 -339.388706) (xy 424.765041 -339.380954) (xy 424.712744 -339.365604)
			(xy 424.663165 -339.342967) (xy 424.617312 -339.313503) (xy 424.576118 -339.277814) (xy 424.540424 -339.236625)
			(xy 424.510955 -339.190776) (xy 424.488312 -339.141199) (xy 424.472955 -339.088904) (xy 424.465198 -339.034956)
			(xy 424.464734 -339.007704) (xy 422.894287 -339.007704) (xy 422.894506 -339.020404) (xy 422.894026 -339.047655)
			(xy 422.886269 -339.101603) (xy 422.870913 -339.153898) (xy 422.848271 -339.203476) (xy 422.818804 -339.249326)
			(xy 422.783112 -339.290517) (xy 422.741922 -339.326208) (xy 422.696071 -339.355674) (xy 422.646493 -339.378315)
			(xy 422.594198 -339.39367) (xy 422.540249 -339.401426) (xy 422.512998 -339.401912) (xy 422.486081 -339.4015)
			(xy 422.432782 -339.393939) (xy 422.381077 -339.378954) (xy 422.331995 -339.356843) (xy 422.286512 -339.328046)
			(xy 422.245533 -339.293135) (xy 422.209874 -339.252807) (xy 422.180244 -339.207861) (xy 422.16832 -339.183726)
			(xy 422.162646 -339.173243) (xy 422.143819 -339.15867) (xy 422.132252 -339.155786) (xy 422.074594 -339.144356)
			(xy 422.068084 -339.15171) (xy 422.060625 -339.169856) (xy 422.060116 -339.179662) (xy 422.060116 -339.211666)
			(xy 422.060573 -339.221484) (xy 422.068038 -339.239648) (xy 422.074594 -339.246972) (xy 422.094761 -339.268477)
			(xy 422.128905 -339.316536) (xy 422.155252 -339.369274) (xy 422.173175 -339.425437) (xy 422.182247 -339.483687)
			(xy 422.182798 -339.513164) (xy 422.182311 -339.540533) (xy 422.174499 -339.594712) (xy 422.159014 -339.647215)
			(xy 422.136177 -339.696962) (xy 422.106457 -339.74293) (xy 422.088818 -339.763862) (xy 422.082722 -339.770974)
			(xy 422.076372 -339.787992) (xy 422.076372 -339.873336) (xy 422.082722 -339.890354) (xy 422.088818 -339.897466)
			(xy 422.106457 -339.918398) (xy 422.136169 -339.964371) (xy 422.159004 -340.014119) (xy 422.174495 -340.066619)
			(xy 422.182324 -340.120795) (xy 422.182798 -340.148164) (xy 422.182311 -340.175416) (xy 422.174559 -340.229367)
			(xy 422.159207 -340.281665) (xy 422.136568 -340.331246) (xy 422.107103 -340.3771) (xy 422.071411 -340.418293)
			(xy 422.03022 -340.453987) (xy 421.984369 -340.483455) (xy 421.934789 -340.506098) (xy 421.882492 -340.521453)
			(xy 421.828542 -340.529209) (xy 421.80129 -340.529672) (xy 421.772613 -340.529168) (xy 421.715904 -340.520594)
			(xy 421.661119 -340.503624) (xy 421.609492 -340.478642) (xy 421.562188 -340.446211) (xy 421.520273 -340.407063)
			(xy 421.502078 -340.384892) (xy 421.495134 -340.377042) (xy 421.476655 -340.367203) (xy 421.466264 -340.365842)
			(xy 421.410892 -340.361524) (xy 421.404034 -340.368636) (xy 421.395906 -340.376764) (xy 421.388032 -340.397846)
			(xy 421.397176 -340.498938) (xy 421.408606 -340.518242) (xy 421.418004 -340.524846) (xy 421.439584 -340.540141)
			(xy 421.478668 -340.57578) (xy 421.512453 -340.616477) (xy 421.540292 -340.661452) (xy 421.56165 -340.709842)
			(xy 421.576118 -340.760718) (xy 421.583419 -340.813105) (xy 421.583866 -340.839552) (xy 421.583323 -340.868717)
			(xy 421.574438 -340.926367) (xy 421.556882 -340.981993) (xy 421.531064 -341.034299) (xy 421.514778 -341.0585)
			(xy 421.50919 -341.066628) (xy 421.504618 -341.085424) (xy 421.518334 -341.174578) (xy 421.52824 -341.191088)
			(xy 421.536114 -341.197184) (xy 421.558892 -341.215394) (xy 421.599226 -341.257505) (xy 421.632684 -341.305263)
			(xy 421.658486 -341.357555) (xy 421.67603 -341.413165) (xy 421.68491 -341.470796) (xy 421.685466 -341.499952)
			(xy 421.68498 -341.527203) (xy 421.677224 -341.581151) (xy 421.661869 -341.633446) (xy 421.639227 -341.683023)
			(xy 421.609761 -341.728873) (xy 421.57407 -341.770064) (xy 421.532879 -341.805755) (xy 421.487029 -341.835221)
			(xy 421.437452 -341.857863) (xy 421.385157 -341.873218) (xy 421.331209 -341.880974) (xy 421.276707 -341.880974)
			(xy 421.222759 -341.873218) (xy 421.170464 -341.857863) (xy 421.120887 -341.835221) (xy 421.075037 -341.805755)
			(xy 421.033846 -341.770064) (xy 420.998155 -341.728873) (xy 420.968689 -341.683023) (xy 420.946047 -341.633446)
			(xy 420.930692 -341.581151) (xy 420.922936 -341.527203) (xy 420.92245 -341.499952) (xy 420.922992 -341.470787)
			(xy 420.931877 -341.413137) (xy 420.949434 -341.357511) (xy 420.975252 -341.305205) (xy 420.991538 -341.281004)
			(xy 420.997126 -341.272876) (xy 421.001698 -341.25408) (xy 420.987982 -341.164926) (xy 420.978076 -341.148416)
			(xy 420.970202 -341.14232) (xy 420.947409 -341.12413) (xy 420.907079 -341.082012) (xy 420.873626 -341.034249)
			(xy 420.847827 -340.981953) (xy 420.830285 -340.926342) (xy 420.821406 -340.868708) (xy 420.82085 -340.839552)
			(xy 420.821456 -340.809358) (xy 420.830974 -340.749724) (xy 420.849765 -340.692334) (xy 420.87736 -340.638619)
			(xy 420.91307 -340.589921) (xy 420.934134 -340.56828) (xy 420.942262 -340.560152) (xy 420.950136 -340.53907)
			(xy 420.940992 -340.437978) (xy 420.929562 -340.418674) (xy 420.920164 -340.41207) (xy 420.898585 -340.396775)
			(xy 420.859502 -340.361135) (xy 420.825718 -340.320437) (xy 420.797879 -340.275462) (xy 420.776521 -340.227073)
			(xy 420.762052 -340.176197) (xy 420.75475 -340.123811) (xy 420.754302 -340.097364) (xy 412.34106 -340.097364)
			(xy 412.34106 -341.27186) (xy 412.341314 -341.27186) (xy 412.341314 -341.499952) (xy 416.60445 -341.499952)
			(xy 416.604987 -341.471036) (xy 416.613709 -341.413864) (xy 416.630962 -341.358665) (xy 416.65635 -341.306703)
			(xy 416.689292 -341.259169) (xy 416.729031 -341.217152) (xy 416.751516 -341.198962) (xy 416.760293 -341.191415)
			(xy 416.770468 -341.170645) (xy 416.771074 -341.159084) (xy 416.771074 -341.07882) (xy 416.770501 -341.067252)
			(xy 416.760309 -341.046481) (xy 416.751516 -341.038942) (xy 416.729056 -341.020723) (xy 416.689319 -340.97871)
			(xy 416.656376 -340.931181) (xy 416.630984 -340.879225) (xy 416.613723 -340.824032) (xy 416.604988 -340.766866)
			(xy 416.60445 -340.737952) (xy 416.604936 -340.710701) (xy 416.612692 -340.656753) (xy 416.628047 -340.604458)
			(xy 416.650689 -340.554881) (xy 416.680155 -340.509031) (xy 416.715846 -340.46784) (xy 416.757037 -340.432149)
			(xy 416.802887 -340.402683) (xy 416.852464 -340.380041) (xy 416.904759 -340.364686) (xy 416.958707 -340.35693)
			(xy 417.013209 -340.35693) (xy 417.067157 -340.364686) (xy 417.119452 -340.380041) (xy 417.169029 -340.402683)
			(xy 417.214879 -340.432149) (xy 417.25607 -340.46784) (xy 417.291761 -340.509031) (xy 417.321227 -340.554881)
			(xy 417.343869 -340.604458) (xy 417.359224 -340.656753) (xy 417.36698 -340.710701) (xy 417.367466 -340.737952)
			(xy 417.366926 -340.766868) (xy 417.358203 -340.824039) (xy 417.340951 -340.879238) (xy 417.315563 -340.9312)
			(xy 417.282623 -340.978734) (xy 417.242884 -341.020752) (xy 417.2204 -341.038942) (xy 417.211624 -341.04649)
			(xy 417.201448 -341.067259) (xy 417.200842 -341.07882) (xy 417.200842 -341.159084) (xy 417.201407 -341.170653)
			(xy 417.211604 -341.191425) (xy 417.2204 -341.198962) (xy 417.242865 -341.217174) (xy 417.282602 -341.25919)
			(xy 417.315543 -341.30672) (xy 417.340934 -341.358677) (xy 417.358195 -341.413871) (xy 417.366928 -341.471037)
			(xy 417.367466 -341.499952) (xy 418.76345 -341.499952) (xy 418.763987 -341.471036) (xy 418.772709 -341.413864)
			(xy 418.789962 -341.358665) (xy 418.81535 -341.306703) (xy 418.848292 -341.259169) (xy 418.888031 -341.217152)
			(xy 418.910516 -341.198962) (xy 418.919293 -341.191415) (xy 418.929468 -341.170645) (xy 418.930074 -341.159084)
			(xy 418.930074 -341.07882) (xy 418.929501 -341.067252) (xy 418.919309 -341.046481) (xy 418.910516 -341.038942)
			(xy 418.888056 -341.020723) (xy 418.848319 -340.97871) (xy 418.815376 -340.931181) (xy 418.789984 -340.879225)
			(xy 418.772723 -340.824032) (xy 418.763988 -340.766866) (xy 418.76345 -340.737952) (xy 418.763936 -340.710701)
			(xy 418.771692 -340.656753) (xy 418.787047 -340.604458) (xy 418.809689 -340.554881) (xy 418.839155 -340.509031)
			(xy 418.874846 -340.46784) (xy 418.916037 -340.432149) (xy 418.961887 -340.402683) (xy 419.011464 -340.380041)
			(xy 419.063759 -340.364686) (xy 419.117707 -340.35693) (xy 419.172209 -340.35693) (xy 419.226157 -340.364686)
			(xy 419.278452 -340.380041) (xy 419.328029 -340.402683) (xy 419.373879 -340.432149) (xy 419.41507 -340.46784)
			(xy 419.450761 -340.509031) (xy 419.480227 -340.554881) (xy 419.502869 -340.604458) (xy 419.518224 -340.656753)
			(xy 419.52598 -340.710701) (xy 419.526466 -340.737952) (xy 419.525926 -340.766868) (xy 419.517203 -340.824039)
			(xy 419.499951 -340.879238) (xy 419.474563 -340.9312) (xy 419.441623 -340.978734) (xy 419.401884 -341.020752)
			(xy 419.3794 -341.038942) (xy 419.370624 -341.04649) (xy 419.360448 -341.067259) (xy 419.359842 -341.07882)
			(xy 419.359842 -341.159084) (xy 419.360407 -341.170653) (xy 419.370604 -341.191425) (xy 419.3794 -341.198962)
			(xy 419.401865 -341.217174) (xy 419.441602 -341.25919) (xy 419.474543 -341.30672) (xy 419.499934 -341.358677)
			(xy 419.517195 -341.413871) (xy 419.525928 -341.471037) (xy 419.526466 -341.499952) (xy 419.52598 -341.527203)
			(xy 419.518224 -341.581151) (xy 419.502869 -341.633446) (xy 419.480227 -341.683023) (xy 419.450761 -341.728873)
			(xy 419.41507 -341.770064) (xy 419.373879 -341.805755) (xy 419.328029 -341.835221) (xy 419.278452 -341.857863)
			(xy 419.226157 -341.873218) (xy 419.172209 -341.880974) (xy 419.117707 -341.880974) (xy 419.063759 -341.873218)
			(xy 419.011464 -341.857863) (xy 418.961887 -341.835221) (xy 418.916037 -341.805755) (xy 418.874846 -341.770064)
			(xy 418.839155 -341.728873) (xy 418.809689 -341.683023) (xy 418.787047 -341.633446) (xy 418.771692 -341.581151)
			(xy 418.763936 -341.527203) (xy 418.76345 -341.499952) (xy 417.367466 -341.499952) (xy 417.36698 -341.527203)
			(xy 417.359224 -341.581151) (xy 417.343869 -341.633446) (xy 417.321227 -341.683023) (xy 417.291761 -341.728873)
			(xy 417.25607 -341.770064) (xy 417.214879 -341.805755) (xy 417.169029 -341.835221) (xy 417.119452 -341.857863)
			(xy 417.067157 -341.873218) (xy 417.013209 -341.880974) (xy 416.958707 -341.880974) (xy 416.904759 -341.873218)
			(xy 416.852464 -341.857863) (xy 416.802887 -341.835221) (xy 416.757037 -341.805755) (xy 416.715846 -341.770064)
			(xy 416.680155 -341.728873) (xy 416.650689 -341.683023) (xy 416.628047 -341.633446) (xy 416.612692 -341.581151)
			(xy 416.604936 -341.527203) (xy 416.60445 -341.499952) (xy 412.341314 -341.499952) (xy 412.341314 -347.621352)
			(xy 412.340707 -347.646337) (xy 412.330973 -347.695349) (xy 412.311868 -347.741523) (xy 412.284126 -347.783085)
			(xy 412.266892 -347.801184) (xy 411.224222 -348.8436) (xy 410.604208 -349.463868) (xy 410.598241 -349.471093)
			(xy 410.591458 -349.488545) (xy 410.591 -349.497904) (xy 410.591 -352.769678) (xy 419.579552 -352.769678)
			(xy 419.580041 -352.741767) (xy 419.588178 -352.686542) (xy 419.604275 -352.633091) (xy 419.627988 -352.582556)
			(xy 419.658812 -352.536016) (xy 419.677088 -352.514916) (xy 419.683438 -352.507804) (xy 419.690042 -352.490532)
			(xy 419.690042 -352.40341) (xy 419.683438 -352.386138) (xy 419.677088 -352.379026) (xy 419.658799 -352.357936)
			(xy 419.627973 -352.311395) (xy 419.604261 -352.260858) (xy 419.588167 -352.207404) (xy 419.580036 -352.152176)
			(xy 419.579552 -352.124264) (xy 419.580038 -352.097013) (xy 419.587794 -352.043065) (xy 419.603149 -351.99077)
			(xy 419.625791 -351.941193) (xy 419.655257 -351.895343) (xy 419.690948 -351.854152) (xy 419.732139 -351.818461)
			(xy 419.777989 -351.788995) (xy 419.827566 -351.766353) (xy 419.879861 -351.750998) (xy 419.933809 -351.743242)
			(xy 419.988311 -351.743242) (xy 420.042259 -351.750998) (xy 420.094554 -351.766353) (xy 420.144131 -351.788995)
			(xy 420.189981 -351.818461) (xy 420.231172 -351.854152) (xy 420.266863 -351.895343) (xy 420.296329 -351.941193)
			(xy 420.318971 -351.99077) (xy 420.334326 -352.043065) (xy 420.342082 -352.097013) (xy 420.342568 -352.124264)
			(xy 420.342099 -352.152176) (xy 420.333956 -352.207402) (xy 420.317855 -352.260852) (xy 420.294137 -352.311386)
			(xy 420.26331 -352.357926) (xy 420.245032 -352.379026) (xy 420.238682 -352.386138) (xy 420.232078 -352.40341)
			(xy 420.232078 -352.490532) (xy 420.238682 -352.507804) (xy 420.245032 -352.514916) (xy 420.263297 -352.536026)
			(xy 420.294125 -352.582562) (xy 420.317842 -352.633094) (xy 420.333942 -352.686543) (xy 420.34208 -352.741768)
			(xy 420.342568 -352.769678) (xy 420.342082 -352.796929) (xy 420.334326 -352.850877) (xy 420.318971 -352.903172)
			(xy 420.296329 -352.952749) (xy 420.266863 -352.998599) (xy 420.231172 -353.03979) (xy 420.189981 -353.075481)
			(xy 420.146849 -353.1032) (xy 423.961713 -353.1032) (xy 423.965882 -353.047576) (xy 423.978295 -352.993194)
			(xy 423.998676 -352.94127) (xy 424.026567 -352.892964) (xy 424.061348 -352.849355) (xy 424.10224 -352.811417)
			(xy 424.14833 -352.779998) (xy 424.198588 -352.755799) (xy 424.251892 -352.739362) (xy 424.30705 -352.731054)
			(xy 424.33494 -352.730562) (xy 424.361362 -352.731005) (xy 424.413678 -352.73846) (xy 424.464416 -352.753229)
			(xy 424.51256 -352.775016) (xy 424.557145 -352.803384) (xy 424.57751 -352.820224) (xy 424.584368 -352.82632)
			(xy 424.601386 -352.832416) (xy 424.685714 -352.832416) (xy 424.702732 -352.82632) (xy 424.70959 -352.820224)
			(xy 424.729956 -352.803385) (xy 424.774542 -352.77502) (xy 424.822686 -352.753233) (xy 424.873423 -352.738462)
			(xy 424.925738 -352.731002) (xy 424.978582 -352.731002) (xy 425.030897 -352.738462) (xy 425.081634 -352.753233)
			(xy 425.129778 -352.77502) (xy 425.174364 -352.803385) (xy 425.19473 -352.820224) (xy 425.201588 -352.82632)
			(xy 425.218606 -352.832416) (xy 425.302934 -352.832416) (xy 425.319952 -352.82632) (xy 425.32681 -352.820224)
			(xy 425.340704 -352.80864) (xy 425.370347 -352.787903) (xy 425.385992 -352.778822) (xy 425.396406 -352.77298)
			(xy 425.409614 -352.753676) (xy 425.424854 -352.65106) (xy 425.417996 -352.628962) (xy 425.409868 -352.620326)
			(xy 425.390283 -352.598948) (xy 425.357166 -352.55136) (xy 425.331637 -352.499306) (xy 425.314283 -352.443987)
			(xy 425.305506 -352.386678) (xy 425.304966 -352.35769) (xy 425.305471 -352.330117) (xy 425.313412 -352.275545)
			(xy 425.329128 -352.222684) (xy 425.352291 -352.172638) (xy 425.382418 -352.126448) (xy 425.418881 -352.085076)
			(xy 425.439586 -352.06686) (xy 425.447716 -352.059268) (xy 425.457064 -352.039109) (xy 425.45762 -352.027998)
			(xy 425.45762 -351.950782) (xy 425.457104 -351.939665) (xy 425.447731 -351.919505) (xy 425.439586 -351.91192)
			(xy 425.418879 -351.893705) (xy 425.382409 -351.852337) (xy 425.352276 -351.806147) (xy 425.32911 -351.7561)
			(xy 425.313393 -351.703239) (xy 425.305452 -351.648664) (xy 425.304966 -351.62109) (xy 425.305452 -351.593839)
			(xy 425.313208 -351.539891) (xy 425.328563 -351.487596) (xy 425.351205 -351.438019) (xy 425.380671 -351.392169)
			(xy 425.416362 -351.350978) (xy 425.457553 -351.315287) (xy 425.503403 -351.285821) (xy 425.55298 -351.263179)
			(xy 425.605275 -351.247824) (xy 425.659223 -351.240068) (xy 425.713725 -351.240068) (xy 425.767673 -351.247824)
			(xy 425.819968 -351.263179) (xy 425.869545 -351.285821) (xy 425.915395 -351.315287) (xy 425.956586 -351.350978)
			(xy 425.992277 -351.392169) (xy 426.021743 -351.438019) (xy 426.044385 -351.487596) (xy 426.05974 -351.539891)
			(xy 426.067496 -351.593839) (xy 426.067982 -351.62109) (xy 426.067516 -351.648665) (xy 426.059564 -351.703238)
			(xy 426.04384 -351.756098) (xy 426.02067 -351.806144) (xy 425.990537 -351.852333) (xy 425.954069 -351.893704)
			(xy 425.933362 -351.91192) (xy 425.925233 -351.919513) (xy 425.915886 -351.939672) (xy 425.915328 -351.950782)
			(xy 425.915328 -352.027998) (xy 425.915872 -352.039111) (xy 425.925227 -352.05927) (xy 425.933362 -352.06686)
			(xy 425.954049 -352.085097) (xy 425.990523 -352.126459) (xy 426.020659 -352.172644) (xy 426.043829 -352.222687)
			(xy 426.05955 -352.275545) (xy 426.067495 -352.330117) (xy 426.067982 -352.35769) (xy 426.06742 -352.386882)
			(xy 426.058512 -352.444583) (xy 426.040918 -352.500254) (xy 426.015049 -352.552595) (xy 425.981509 -352.600384)
			(xy 425.94108 -352.642507) (xy 425.894706 -352.677978) (xy 425.869354 -352.692462) (xy 425.85894 -352.698304)
			(xy 425.845478 -352.7171) (xy 425.832707 -352.795078) (xy 427.90618 -352.795078) (xy 427.906662 -352.767167)
			(xy 427.914799 -352.711941) (xy 427.930898 -352.65849) (xy 427.954613 -352.607955) (xy 427.985438 -352.561416)
			(xy 428.003716 -352.540316) (xy 428.010066 -352.533204) (xy 428.01667 -352.515932) (xy 428.01667 -352.42881)
			(xy 428.010066 -352.411538) (xy 428.003716 -352.404426) (xy 427.985431 -352.383332) (xy 427.954604 -352.336792)
			(xy 427.93089 -352.286256) (xy 427.914795 -352.232804) (xy 427.906664 -352.177576) (xy 427.90618 -352.149664)
			(xy 427.906666 -352.122413) (xy 427.914422 -352.068465) (xy 427.929777 -352.01617) (xy 427.952419 -351.966593)
			(xy 427.981885 -351.920743) (xy 428.017576 -351.879552) (xy 428.058767 -351.843861) (xy 428.104617 -351.814395)
			(xy 428.154194 -351.791753) (xy 428.206489 -351.776398) (xy 428.260437 -351.768642) (xy 428.314939 -351.768642)
			(xy 428.368887 -351.776398) (xy 428.421182 -351.791753) (xy 428.470759 -351.814395) (xy 428.516609 -351.843861)
			(xy 428.5578 -351.879552) (xy 428.593491 -351.920743) (xy 428.622957 -351.966593) (xy 428.645599 -352.01617)
			(xy 428.660954 -352.068465) (xy 428.66871 -352.122413) (xy 428.669196 -352.149664) (xy 428.66872 -352.177575)
			(xy 428.660578 -352.232801) (xy 428.644477 -352.286251) (xy 428.620762 -352.336785) (xy 428.589937 -352.383325)
			(xy 428.57166 -352.404426) (xy 428.56531 -352.411538) (xy 428.558706 -352.42881) (xy 428.558706 -352.515932)
			(xy 428.56531 -352.533204) (xy 428.57166 -352.540316) (xy 428.589929 -352.561423) (xy 428.620756 -352.60796)
			(xy 428.644472 -352.658493) (xy 428.660571 -352.711942) (xy 428.668708 -352.767167) (xy 428.669196 -352.795078)
			(xy 428.66871 -352.822329) (xy 428.660954 -352.876277) (xy 428.645599 -352.928572) (xy 428.622957 -352.978149)
			(xy 428.593491 -353.023999) (xy 428.5578 -353.06519) (xy 428.516609 -353.100881) (xy 428.473477 -353.1286)
			(xy 432.288439 -353.1286) (xy 432.292607 -353.072986) (xy 432.305016 -353.018615) (xy 432.32539 -352.9667)
			(xy 432.353273 -352.918401) (xy 432.388044 -352.874798) (xy 432.428924 -352.836863) (xy 432.475001 -352.805444)
			(xy 432.525246 -352.781244) (xy 432.578537 -352.764802) (xy 432.633683 -352.756485) (xy 432.661568 -352.755962)
			(xy 432.687991 -352.756389) (xy 432.740307 -352.763848) (xy 432.791046 -352.778621) (xy 432.83919 -352.800411)
			(xy 432.883773 -352.828782) (xy 432.904138 -352.845624) (xy 432.910996 -352.85172) (xy 432.928014 -352.857816)
			(xy 433.012342 -352.857816) (xy 433.02936 -352.85172) (xy 433.036218 -352.845624) (xy 433.056584 -352.828785)
			(xy 433.10117 -352.80042) (xy 433.149314 -352.778633) (xy 433.200051 -352.763862) (xy 433.252366 -352.756402)
			(xy 433.30521 -352.756402) (xy 433.357525 -352.763862) (xy 433.408262 -352.778633) (xy 433.456406 -352.80042)
			(xy 433.500992 -352.828785) (xy 433.521358 -352.845624) (xy 433.528216 -352.85172) (xy 433.545234 -352.857816)
			(xy 433.629562 -352.857816) (xy 433.64658 -352.85172) (xy 433.653438 -352.845624) (xy 433.66733 -352.834037)
			(xy 433.696974 -352.813302) (xy 433.71262 -352.804222) (xy 433.723034 -352.79838) (xy 433.736242 -352.779076)
			(xy 433.751482 -352.67646) (xy 433.744624 -352.654362) (xy 433.736496 -352.645726) (xy 433.716915 -352.624343)
			(xy 433.683797 -352.576757) (xy 433.658266 -352.524705) (xy 433.640912 -352.469387) (xy 433.632134 -352.412078)
			(xy 433.631594 -352.38309) (xy 433.632124 -352.355518) (xy 433.640063 -352.300948) (xy 433.655776 -352.248089)
			(xy 433.678934 -352.198043) (xy 433.709055 -352.151852) (xy 433.745512 -352.110478) (xy 433.766214 -352.09226)
			(xy 433.774348 -352.084672) (xy 433.783693 -352.064509) (xy 433.784248 -352.053398) (xy 433.784248 -351.976182)
			(xy 433.783723 -351.965067) (xy 433.774356 -351.944907) (xy 433.766214 -351.93732) (xy 433.745512 -351.919099)
			(xy 433.709041 -351.877732) (xy 433.678907 -351.831545) (xy 433.655739 -351.781499) (xy 433.640021 -351.728638)
			(xy 433.63208 -351.674064) (xy 433.631594 -351.64649) (xy 433.63208 -351.619239) (xy 433.639836 -351.565291)
			(xy 433.655191 -351.512996) (xy 433.677833 -351.463419) (xy 433.707299 -351.417569) (xy 433.74299 -351.376378)
			(xy 433.784181 -351.340687) (xy 433.830031 -351.311221) (xy 433.879608 -351.288579) (xy 433.931903 -351.273224)
			(xy 433.985851 -351.265468) (xy 434.040353 -351.265468) (xy 434.094301 -351.273224) (xy 434.146596 -351.288579)
			(xy 434.196173 -351.311221) (xy 434.242023 -351.340687) (xy 434.283214 -351.376378) (xy 434.318905 -351.417569)
			(xy 434.348371 -351.463419) (xy 434.371013 -351.512996) (xy 434.386368 -351.565291) (xy 434.394124 -351.619239)
			(xy 434.39461 -351.64649) (xy 434.394134 -351.674064) (xy 434.386183 -351.728636) (xy 434.37046 -351.781496)
			(xy 434.347292 -351.831542) (xy 434.317161 -351.877732) (xy 434.280696 -351.919104) (xy 434.25999 -351.93732)
			(xy 434.251865 -351.944917) (xy 434.242515 -351.965073) (xy 434.241956 -351.976182) (xy 434.241956 -352.053398)
			(xy 434.242491 -352.064512) (xy 434.251851 -352.084672) (xy 434.25999 -352.09226) (xy 434.280683 -352.110491)
			(xy 434.317155 -352.151855) (xy 434.34729 -352.198041) (xy 434.370459 -352.248085) (xy 434.386179 -352.300944)
			(xy 434.394123 -352.355516) (xy 434.39461 -352.38309) (xy 434.394033 -352.412282) (xy 434.385126 -352.469981)
			(xy 434.367534 -352.525651) (xy 434.341667 -352.577991) (xy 434.308129 -352.625781) (xy 434.267703 -352.667904)
			(xy 434.221332 -352.703377) (xy 434.195982 -352.717862) (xy 434.185568 -352.723704) (xy 434.172106 -352.7425)
			(xy 434.155342 -352.844862) (xy 434.161946 -352.867214) (xy 434.16982 -352.87585) (xy 434.18828 -352.896625)
			(xy 434.219491 -352.942607) (xy 434.243527 -352.992715) (xy 434.259854 -353.045836) (xy 434.268111 -353.100793)
			(xy 434.268626 -353.12858) (xy 434.268147 -353.155197) (xy 434.260574 -353.207889) (xy 434.245579 -353.258968)
			(xy 434.223467 -353.307392) (xy 434.194688 -353.352176) (xy 434.159829 -353.392409) (xy 434.119599 -353.427271)
			(xy 434.074817 -353.456053) (xy 434.026394 -353.478169) (xy 433.975317 -353.493168) (xy 433.922625 -353.500745)
			(xy 433.896008 -353.501198) (xy 433.869586 -353.500736) (xy 433.817271 -353.493287) (xy 433.766532 -353.478523)
			(xy 433.718388 -353.45674) (xy 433.673803 -353.428375) (xy 433.653438 -353.411536) (xy 433.64658 -353.40544)
			(xy 433.629562 -353.399344) (xy 433.545234 -353.399344) (xy 433.528216 -353.40544) (xy 433.521358 -353.411536)
			(xy 433.500992 -353.428375) (xy 433.456406 -353.45674) (xy 433.408262 -353.478527) (xy 433.357525 -353.493298)
			(xy 433.30521 -353.500758) (xy 433.252366 -353.500758) (xy 433.200051 -353.493298) (xy 433.149314 -353.478527)
			(xy 433.10117 -353.45674) (xy 433.056584 -353.428375) (xy 433.036218 -353.411536) (xy 433.02936 -353.40544)
			(xy 433.012342 -353.399344) (xy 432.928014 -353.399344) (xy 432.910996 -353.40544) (xy 432.904138 -353.411536)
			(xy 432.883751 -353.428346) (xy 432.839168 -353.456708) (xy 432.791029 -353.478494) (xy 432.740297 -353.493268)
			(xy 432.687988 -353.500734) (xy 432.661568 -353.501198) (xy 432.633683 -353.500715) (xy 432.578537 -353.492398)
			(xy 432.525246 -353.475956) (xy 432.475001 -353.451756) (xy 432.428924 -353.420337) (xy 432.388044 -353.382402)
			(xy 432.353273 -353.338799) (xy 432.32539 -353.2905) (xy 432.305016 -353.238585) (xy 432.292607 -353.184214)
			(xy 432.288439 -353.1286) (xy 428.473477 -353.1286) (xy 428.470759 -353.130347) (xy 428.421182 -353.152989)
			(xy 428.368887 -353.168344) (xy 428.314939 -353.1761) (xy 428.260437 -353.1761) (xy 428.206489 -353.168344)
			(xy 428.154194 -353.152989) (xy 428.104617 -353.130347) (xy 428.058767 -353.100881) (xy 428.017576 -353.06519)
			(xy 427.981885 -353.023999) (xy 427.952419 -352.978149) (xy 427.929777 -352.928572) (xy 427.914422 -352.876277)
			(xy 427.906666 -352.822329) (xy 427.90618 -352.795078) (xy 425.832707 -352.795078) (xy 425.828714 -352.819462)
			(xy 425.835318 -352.841814) (xy 425.843192 -352.85045) (xy 425.861647 -352.871229) (xy 425.89286 -352.91721)
			(xy 425.916897 -352.967316) (xy 425.933226 -353.020437) (xy 425.941483 -353.075393) (xy 425.941998 -353.10318)
			(xy 425.941547 -353.129798) (xy 425.933973 -353.182493) (xy 425.918976 -353.233574) (xy 425.896862 -353.282)
			(xy 425.868081 -353.326785) (xy 425.833219 -353.367019) (xy 425.792985 -353.401881) (xy 425.7482 -353.430662)
			(xy 425.699774 -353.452776) (xy 425.648693 -353.467773) (xy 425.595998 -353.475347) (xy 425.56938 -353.475798)
			(xy 425.542958 -353.475352) (xy 425.490642 -353.4679) (xy 425.439903 -353.453132) (xy 425.391759 -353.431345)
			(xy 425.347175 -353.402977) (xy 425.32681 -353.386136) (xy 425.319952 -353.38004) (xy 425.302934 -353.373944)
			(xy 425.218606 -353.373944) (xy 425.201588 -353.38004) (xy 425.19473 -353.386136) (xy 425.174364 -353.402975)
			(xy 425.129778 -353.43134) (xy 425.081634 -353.453127) (xy 425.030897 -353.467898) (xy 424.978582 -353.475358)
			(xy 424.925738 -353.475358) (xy 424.873423 -353.467898) (xy 424.822686 -353.453127) (xy 424.774542 -353.43134)
			(xy 424.729956 -353.402975) (xy 424.70959 -353.386136) (xy 424.702732 -353.38004) (xy 424.685714 -353.373944)
			(xy 424.601386 -353.373944) (xy 424.584368 -353.38004) (xy 424.57751 -353.386136) (xy 424.557133 -353.40296)
			(xy 424.512547 -353.431319) (xy 424.464405 -353.453102) (xy 424.413671 -353.467873) (xy 424.36136 -353.475336)
			(xy 424.33494 -353.475798) (xy 424.30705 -353.475346) (xy 424.251892 -353.467038) (xy 424.198588 -353.450601)
			(xy 424.14833 -353.426402) (xy 424.10224 -353.394983) (xy 424.061348 -353.357045) (xy 424.026567 -353.313436)
			(xy 423.998676 -353.26513) (xy 423.978295 -353.213206) (xy 423.965882 -353.158824) (xy 423.961713 -353.1032)
			(xy 420.146849 -353.1032) (xy 420.144131 -353.104947) (xy 420.094554 -353.127589) (xy 420.042259 -353.142944)
			(xy 419.988311 -353.1507) (xy 419.933809 -353.1507) (xy 419.879861 -353.142944) (xy 419.827566 -353.127589)
			(xy 419.777989 -353.104947) (xy 419.732139 -353.075481) (xy 419.690948 -353.03979) (xy 419.655257 -352.998599)
			(xy 419.625791 -352.952749) (xy 419.603149 -352.903172) (xy 419.587794 -352.850877) (xy 419.580038 -352.796929)
			(xy 419.579552 -352.769678) (xy 410.591 -352.769678) (xy 410.591 -353.857306) (xy 410.591427 -353.866162)
			(xy 410.59753 -353.882793) (xy 410.602938 -353.889818) (xy 410.714433 -354.001324) (xy 420.537384 -354.001324)
			(xy 420.541455 -353.945702) (xy 420.553581 -353.891265) (xy 420.573504 -353.839174) (xy 420.6008 -353.790539)
			(xy 420.634886 -353.746396) (xy 420.675035 -353.707687) (xy 420.720393 -353.675236) (xy 420.769993 -353.649735)
			(xy 420.822777 -353.631728) (xy 420.87762 -353.621598) (xy 420.933354 -353.619561) (xy 420.988791 -353.625661)
			(xy 421.042748 -353.639767) (xy 421.094077 -353.661579) (xy 421.141683 -353.690633) (xy 421.184551 -353.726308)
			(xy 421.221768 -353.767845) (xy 421.252541 -353.814358) (xy 421.276213 -353.864855) (xy 421.292281 -353.918262)
			(xy 421.300401 -353.973438) (xy 421.30091 -354.001324) (xy 421.300401 -354.02921) (xy 421.292281 -354.084386)
			(xy 421.276213 -354.137793) (xy 421.252541 -354.18829) (xy 421.221768 -354.234803) (xy 421.184551 -354.27634)
			(xy 421.141683 -354.312015) (xy 421.094077 -354.341069) (xy 421.042748 -354.362881) (xy 420.988791 -354.376987)
			(xy 420.933354 -354.383087) (xy 420.87762 -354.38105) (xy 420.822777 -354.37092) (xy 420.769993 -354.352913)
			(xy 420.720393 -354.327412) (xy 420.675035 -354.294961) (xy 420.634886 -354.256252) (xy 420.6008 -354.212109)
			(xy 420.573504 -354.163474) (xy 420.553581 -354.111383) (xy 420.541455 -354.056946) (xy 420.537384 -354.001324)
			(xy 410.714433 -354.001324) (xy 411.327018 -354.613972) (xy 416.45408 -354.613972) (xy 416.458151 -354.55835)
			(xy 416.470277 -354.503913) (xy 416.4902 -354.451822) (xy 416.517496 -354.403187) (xy 416.551582 -354.359044)
			(xy 416.591731 -354.320335) (xy 416.637089 -354.287884) (xy 416.686689 -354.262383) (xy 416.739473 -354.244376)
			(xy 416.794316 -354.234246) (xy 416.85005 -354.232209) (xy 416.905487 -354.238309) (xy 416.959444 -354.252415)
			(xy 417.010773 -354.274227) (xy 417.058379 -354.303281) (xy 417.101247 -354.338956) (xy 417.138464 -354.380493)
			(xy 417.169237 -354.427006) (xy 417.192909 -354.477503) (xy 417.208977 -354.53091) (xy 417.217097 -354.586086)
			(xy 417.217606 -354.613972) (xy 417.217097 -354.641858) (xy 417.208977 -354.697034) (xy 417.192909 -354.750441)
			(xy 417.182464 -354.772722) (xy 418.51402 -354.772722) (xy 418.518091 -354.7171) (xy 418.530217 -354.662663)
			(xy 418.55014 -354.610572) (xy 418.577436 -354.561937) (xy 418.611522 -354.517794) (xy 418.651671 -354.479085)
			(xy 418.697029 -354.446634) (xy 418.746629 -354.421133) (xy 418.799413 -354.403126) (xy 418.854256 -354.392996)
			(xy 418.90999 -354.390959) (xy 418.965427 -354.397059) (xy 419.019384 -354.411165) (xy 419.070713 -354.432977)
			(xy 419.118319 -354.462031) (xy 419.161187 -354.497706) (xy 419.198404 -354.539243) (xy 419.229177 -354.585756)
			(xy 419.252849 -354.636253) (xy 419.268917 -354.68966) (xy 419.277037 -354.744836) (xy 419.277546 -354.772722)
			(xy 419.277037 -354.800608) (xy 419.268917 -354.855784) (xy 419.256615 -354.896674) (xy 419.958264 -354.896674)
			(xy 419.962335 -354.841052) (xy 419.974461 -354.786615) (xy 419.994384 -354.734524) (xy 420.02168 -354.685889)
			(xy 420.055766 -354.641746) (xy 420.095915 -354.603037) (xy 420.141273 -354.570586) (xy 420.190873 -354.545085)
			(xy 420.243657 -354.527078) (xy 420.2985 -354.516948) (xy 420.354234 -354.514911) (xy 420.409671 -354.521011)
			(xy 420.463628 -354.535117) (xy 420.514957 -354.556929) (xy 420.562563 -354.585983) (xy 420.605431 -354.621658)
			(xy 420.642648 -354.663195) (xy 420.673421 -354.709708) (xy 420.697093 -354.760205) (xy 420.713161 -354.813612)
			(xy 420.721281 -354.868788) (xy 420.72179 -354.896674) (xy 420.721281 -354.92456) (xy 420.713161 -354.979736)
			(xy 420.697093 -355.033143) (xy 420.673421 -355.08364) (xy 420.642648 -355.130153) (xy 420.605431 -355.17169)
			(xy 420.562563 -355.207365) (xy 420.514957 -355.236419) (xy 420.463628 -355.258231) (xy 420.409671 -355.272337)
			(xy 420.354234 -355.278437) (xy 420.2985 -355.2764) (xy 420.243657 -355.26627) (xy 420.190873 -355.248263)
			(xy 420.141273 -355.222762) (xy 420.095915 -355.190311) (xy 420.055766 -355.151602) (xy 420.02168 -355.107459)
			(xy 419.994384 -355.058824) (xy 419.974461 -355.006733) (xy 419.962335 -354.952296) (xy 419.958264 -354.896674)
			(xy 419.256615 -354.896674) (xy 419.252849 -354.909191) (xy 419.229177 -354.959688) (xy 419.198404 -355.006201)
			(xy 419.161187 -355.047738) (xy 419.118319 -355.083413) (xy 419.070713 -355.112467) (xy 419.019384 -355.134279)
			(xy 418.965427 -355.148385) (xy 418.90999 -355.154485) (xy 418.854256 -355.152448) (xy 418.799413 -355.142318)
			(xy 418.746629 -355.124311) (xy 418.697029 -355.09881) (xy 418.651671 -355.066359) (xy 418.611522 -355.02765)
			(xy 418.577436 -354.983507) (xy 418.55014 -354.934872) (xy 418.530217 -354.882781) (xy 418.518091 -354.828344)
			(xy 418.51402 -354.772722) (xy 417.182464 -354.772722) (xy 417.169237 -354.800938) (xy 417.138464 -354.847451)
			(xy 417.101247 -354.888988) (xy 417.058379 -354.924663) (xy 417.010773 -354.953717) (xy 416.959444 -354.975529)
			(xy 416.905487 -354.989635) (xy 416.85005 -354.995735) (xy 416.794316 -354.993698) (xy 416.739473 -354.983568)
			(xy 416.686689 -354.965561) (xy 416.637089 -354.94006) (xy 416.591731 -354.907609) (xy 416.551582 -354.8689)
			(xy 416.517496 -354.824757) (xy 416.4902 -354.776122) (xy 416.470277 -354.724031) (xy 416.458151 -354.669594)
			(xy 416.45408 -354.613972) (xy 411.327018 -354.613972) (xy 413.096202 -356.383336) (xy 413.101028 -356.387654)
			(xy 413.104584 -356.38994) (xy 413.10964 -356.393038) (xy 413.120805 -356.397026) (xy 413.126682 -356.397814)
			(xy 413.13227 -356.398068) (xy 416.41395 -356.398068) (xy 416.422229 -356.397744) (xy 416.43791 -356.392426)
			(xy 416.444684 -356.387654) (xy 416.451288 -356.382828) (xy 416.460432 -356.369112) (xy 416.462718 -356.36073)
			(xy 416.470511 -356.33423) (xy 416.492678 -356.283638) (xy 416.521908 -356.23677) (xy 416.557589 -356.194606)
			(xy 416.598975 -356.158026) (xy 416.645203 -356.127794) (xy 416.695306 -356.104542) (xy 416.748238 -356.088757)
			(xy 416.802892 -356.080766) (xy 416.83051 -356.080314) (xy 416.857762 -356.080778) (xy 416.91171 -356.088536)
			(xy 416.964006 -356.103893) (xy 417.013583 -356.126537) (xy 417.059434 -356.156005) (xy 417.100623 -356.191699)
			(xy 417.136314 -356.232892) (xy 417.165779 -356.278745) (xy 417.188418 -356.328324) (xy 417.203771 -356.380621)
			(xy 417.211524 -356.43457) (xy 417.212018 -356.461822) (xy 417.211482 -356.490738) (xy 417.202753 -356.547908)
			(xy 417.185497 -356.603106) (xy 417.16011 -356.655068) (xy 417.127173 -356.702605) (xy 417.087441 -356.744627)
			(xy 417.064952 -356.762812) (xy 417.057563 -356.769093) (xy 417.047755 -356.785806) (xy 417.045902 -356.795324)
			(xy 417.045394 -356.802944) (xy 417.045394 -356.8827) (xy 417.046156 -356.89159) (xy 417.046976 -356.895709)
			(xy 417.049784 -356.903624) (xy 417.051744 -356.907338) (xy 417.073209 -356.922895) (xy 417.112078 -356.958945)
			(xy 417.145656 -356.999968) (xy 417.173312 -357.045195) (xy 417.194528 -357.093778) (xy 417.208906 -357.144804)
			(xy 417.216175 -357.197316) (xy 417.21659 -357.223822) (xy 417.215828 -357.24719) (xy 417.215616 -357.254407)
			(xy 417.218842 -357.268473) (xy 417.222178 -357.274876) (xy 417.224718 -357.279194) (xy 417.227512 -357.280718)
			(xy 417.316158 -357.33101) (xy 417.322262 -357.334275) (xy 417.335653 -357.337768) (xy 417.342574 -357.337868)
			(xy 417.34867 -357.337614) (xy 417.373603 -357.320145) (xy 417.427812 -357.292443) (xy 417.485693 -357.273583)
			(xy 417.545816 -357.264031) (xy 417.576254 -357.263446) (xy 417.603488 -357.263937) (xy 417.65741 -357.271637)
			(xy 417.709716 -357.286834) (xy 417.759369 -357.309227) (xy 417.805385 -357.338371) (xy 417.826444 -357.355648)
			(xy 417.830123 -357.356533) (xy 417.837649 -357.357303) (xy 417.84143 -357.357172) (xy 417.871148 -357.355902)
			(xy 417.878819 -357.355332) (xy 417.893295 -357.350155) (xy 417.899596 -357.345742) (xy 417.90493 -357.34117)
			(xy 418.084508 -357.161592) (xy 418.387022 -356.858824) (xy 418.405133 -356.841604) (xy 418.446695 -356.813868)
			(xy 418.492864 -356.794762) (xy 418.541871 -356.785018) (xy 418.566854 -356.784402) (xy 419.491922 -356.784402)
			(xy 419.491922 -356.784656) (xy 420.650162 -356.784656) (xy 420.65067 -356.784656) (xy 420.658886 -356.784306)
			(xy 420.67444 -356.778997) (xy 420.68115 -356.774242) (xy 420.68623 -356.76967) (xy 420.761414 -356.694486)
			(xy 420.765986 -356.689406) (xy 420.770716 -356.682682) (xy 420.776042 -356.667138) (xy 420.7764 -356.658926)
			(xy 420.7764 -355.983032) (xy 420.776146 -355.983032) (xy 420.776146 -355.443536) (xy 420.776754 -355.418551)
			(xy 420.786489 -355.369539) (xy 420.805593 -355.323365) (xy 420.833333 -355.281802) (xy 420.850568 -355.263704)
			(xy 421.326564 -354.787708) (xy 421.330374 -354.779072) (xy 421.342042 -354.754256) (xy 421.371438 -354.707964)
			(xy 421.407155 -354.666355) (xy 421.448459 -354.630285) (xy 421.494498 -354.600496) (xy 421.544326 -354.577601)
			(xy 421.596918 -354.562071) (xy 421.65119 -354.554226) (xy 421.678608 -354.553774) (xy 421.705859 -354.55426)
			(xy 421.759807 -354.562018) (xy 421.812102 -354.577373) (xy 421.861679 -354.600015) (xy 421.90753 -354.629481)
			(xy 421.948721 -354.665172) (xy 421.984413 -354.706362) (xy 422.013881 -354.752212) (xy 422.036523 -354.801789)
			(xy 422.05188 -354.854083) (xy 422.059639 -354.908031) (xy 422.060116 -354.935282) (xy 422.060116 -354.93579)
			(xy 422.059627 -354.963228) (xy 422.051741 -355.017535) (xy 422.03616 -355.070154) (xy 422.033674 -355.075553)
			(xy 422.301867 -355.075553) (xy 422.301867 -355.021047) (xy 422.309625 -354.967096) (xy 422.324981 -354.914797)
			(xy 422.347625 -354.865217) (xy 422.377094 -354.819364) (xy 422.412789 -354.778172) (xy 422.453984 -354.74248)
			(xy 422.499838 -354.713014) (xy 422.54942 -354.690373) (xy 422.601719 -354.67502) (xy 422.655671 -354.667266)
			(xy 422.682924 -354.666804) (xy 422.70816 -354.66719) (xy 422.758194 -354.673811) (xy 422.806914 -354.686987)
			(xy 422.853466 -354.706488) (xy 422.875456 -354.718874) (xy 422.885108 -354.724716) (xy 422.907206 -354.726748)
			(xy 423.001694 -354.69322) (xy 423.017696 -354.677726) (xy 423.02176 -354.667312) (xy 423.032479 -354.640545)
			(xy 423.060763 -354.590304) (xy 423.096289 -354.544893) (xy 423.138247 -354.50535) (xy 423.185681 -354.472575)
			(xy 423.23751 -354.447315) (xy 423.29255 -354.430147) (xy 423.349548 -354.421463) (xy 423.378376 -354.420932)
			(xy 423.40563 -354.421378) (xy 423.459584 -354.429133) (xy 423.511884 -354.444488) (xy 423.561467 -354.46713)
			(xy 423.607322 -354.496599) (xy 423.648516 -354.532295) (xy 423.68421 -354.573491) (xy 423.713678 -354.619347)
			(xy 423.736318 -354.668931) (xy 423.74904 -354.71227) (xy 425.889928 -354.71227) (xy 425.890432 -354.684697)
			(xy 425.898375 -354.630125) (xy 425.914092 -354.577266) (xy 425.937255 -354.527219) (xy 425.967381 -354.481029)
			(xy 426.003843 -354.439656) (xy 426.024548 -354.42144) (xy 426.032651 -354.413824) (xy 426.042012 -354.393683)
			(xy 426.042582 -354.382578) (xy 426.042582 -354.305362) (xy 426.042057 -354.294247) (xy 426.032689 -354.274088)
			(xy 426.024548 -354.2665) (xy 426.003843 -354.248282) (xy 425.96737 -354.206916) (xy 425.937236 -354.160728)
			(xy 425.914069 -354.110681) (xy 425.898352 -354.057819) (xy 425.890413 -354.003245) (xy 425.889928 -353.97567)
			(xy 425.890327 -353.948415) (xy 425.898089 -353.89446) (xy 425.913451 -353.842158) (xy 425.936099 -353.792576)
			(xy 425.965574 -353.746721) (xy 426.001274 -353.705528) (xy 426.042474 -353.669834) (xy 426.088334 -353.640368)
			(xy 426.13792 -353.617728) (xy 426.190224 -353.602375) (xy 426.244181 -353.594622) (xy 426.271436 -353.594162)
			(xy 426.305726 -353.595686) (xy 426.315886 -353.596702) (xy 426.33519 -353.590606) (xy 426.405802 -353.531424)
			(xy 426.4152 -353.51339) (xy 426.416216 -353.50323) (xy 426.419119 -353.475051) (xy 426.432297 -353.419956)
			(xy 426.453481 -353.367416) (xy 426.482204 -353.318589) (xy 426.517834 -353.274547) (xy 426.559587 -353.236261)
			(xy 426.606544 -353.204572) (xy 426.657673 -353.180179) (xy 426.711847 -353.163617) (xy 426.767875 -353.155252)
			(xy 426.7962 -353.154742) (xy 426.814219 -353.154968) (xy 426.850094 -353.158399) (xy 426.867828 -353.1616)
			(xy 426.877226 -353.163378) (xy 426.896276 -353.159568) (xy 426.97146 -353.111816) (xy 426.98289 -353.096068)
			(xy 426.985176 -353.08667) (xy 426.99262 -353.05964) (xy 427.014245 -353.007915) (xy 427.043203 -352.959911)
			(xy 427.078873 -352.91666) (xy 427.120486 -352.879092) (xy 427.167147 -352.848016) (xy 427.217853 -352.8241)
			(xy 427.271512 -352.80786) (xy 427.326969 -352.799644) (xy 427.355 -352.799142) (xy 427.382255 -352.799555)
			(xy 427.43621 -352.807314) (xy 427.488512 -352.822672) (xy 427.538096 -352.845318) (xy 427.583951 -352.874791)
			(xy 427.625145 -352.91049) (xy 427.660839 -352.951689) (xy 427.690306 -352.997548) (xy 427.712945 -353.047135)
			(xy 427.728297 -353.099438) (xy 427.736048 -353.153395) (xy 427.736508 -353.18065) (xy 427.736005 -353.208223)
			(xy 427.72806 -353.262794) (xy 427.712342 -353.315653) (xy 427.689179 -353.365699) (xy 427.659053 -353.41189)
			(xy 427.622592 -353.453263) (xy 427.601888 -353.47148) (xy 427.593781 -353.479093) (xy 427.584421 -353.499237)
			(xy 427.583854 -353.510342) (xy 427.583854 -353.587558) (xy 427.584412 -353.59867) (xy 427.593756 -353.618829)
			(xy 427.601888 -353.62642) (xy 427.622644 -353.644581) (xy 427.659109 -353.685959) (xy 427.689236 -353.732156)
			(xy 427.712397 -353.78221) (xy 427.728109 -353.835077) (xy 427.736046 -353.889656) (xy 427.736041 -353.944809)
			(xy 427.728095 -353.999386) (xy 427.719965 -354.026724) (xy 428.864012 -354.026724) (xy 428.868083 -353.971102)
			(xy 428.880209 -353.916665) (xy 428.900132 -353.864574) (xy 428.927428 -353.815939) (xy 428.961514 -353.771796)
			(xy 429.001663 -353.733087) (xy 429.047021 -353.700636) (xy 429.096621 -353.675135) (xy 429.149405 -353.657128)
			(xy 429.204248 -353.646998) (xy 429.259982 -353.644961) (xy 429.315419 -353.651061) (xy 429.369376 -353.665167)
			(xy 429.420705 -353.686979) (xy 429.468311 -353.716033) (xy 429.511179 -353.751708) (xy 429.548396 -353.793245)
			(xy 429.579169 -353.839758) (xy 429.602841 -353.890255) (xy 429.618909 -353.943662) (xy 429.627029 -353.998838)
			(xy 429.627538 -354.026724) (xy 429.627029 -354.05461) (xy 429.618909 -354.109786) (xy 429.602841 -354.163193)
			(xy 429.579169 -354.21369) (xy 429.548396 -354.260203) (xy 429.511179 -354.30174) (xy 429.468311 -354.337415)
			(xy 429.420705 -354.366469) (xy 429.369376 -354.388281) (xy 429.315419 -354.402387) (xy 429.259982 -354.408487)
			(xy 429.204248 -354.40645) (xy 429.149405 -354.39632) (xy 429.096621 -354.378313) (xy 429.047021 -354.352812)
			(xy 429.001663 -354.320361) (xy 428.961514 -354.281652) (xy 428.927428 -354.237509) (xy 428.900132 -354.188874)
			(xy 428.880209 -354.136783) (xy 428.868083 -354.082346) (xy 428.864012 -354.026724) (xy 427.719965 -354.026724)
			(xy 427.712374 -354.052251) (xy 427.689204 -354.102301) (xy 427.65907 -354.148493) (xy 427.622598 -354.189865)
			(xy 427.601888 -354.20808) (xy 427.593781 -354.215693) (xy 427.584421 -354.235837) (xy 427.583854 -354.246942)
			(xy 427.583854 -354.324158) (xy 427.584412 -354.33527) (xy 427.593756 -354.355429) (xy 427.601888 -354.36302)
			(xy 427.62261 -354.38122) (xy 427.65908 -354.422591) (xy 427.689211 -354.468783) (xy 427.712375 -354.518833)
			(xy 427.728089 -354.571698) (xy 427.736025 -354.626275) (xy 427.736508 -354.65385) (xy 427.735998 -354.681102)
			(xy 427.728248 -354.735051) (xy 427.712898 -354.787348) (xy 427.690262 -354.836928) (xy 427.660799 -354.882781)
			(xy 427.626756 -354.922074) (xy 428.284892 -354.922074) (xy 428.288963 -354.866452) (xy 428.301089 -354.812015)
			(xy 428.321012 -354.759924) (xy 428.348308 -354.711289) (xy 428.382394 -354.667146) (xy 428.422543 -354.628437)
			(xy 428.467901 -354.595986) (xy 428.517501 -354.570485) (xy 428.570285 -354.552478) (xy 428.625128 -354.542348)
			(xy 428.680862 -354.540311) (xy 428.736299 -354.546411) (xy 428.790256 -354.560517) (xy 428.841585 -354.582329)
			(xy 428.889191 -354.611383) (xy 428.932059 -354.647058) (xy 428.969276 -354.688595) (xy 429.000049 -354.735108)
			(xy 429.023721 -354.785605) (xy 429.039789 -354.839012) (xy 429.047909 -354.894188) (xy 429.048418 -354.922074)
			(xy 429.047909 -354.94996) (xy 429.039789 -355.005136) (xy 429.023721 -355.058543) (xy 429.000049 -355.10904)
			(xy 428.969276 -355.155553) (xy 428.932059 -355.19709) (xy 428.889191 -355.232765) (xy 428.841585 -355.261819)
			(xy 428.790256 -355.283631) (xy 428.736299 -355.297737) (xy 428.680862 -355.303837) (xy 428.625128 -355.3018)
			(xy 428.570285 -355.29167) (xy 428.517501 -355.273663) (xy 428.467901 -355.248162) (xy 428.422543 -355.215711)
			(xy 428.382394 -355.177002) (xy 428.348308 -355.132859) (xy 428.321012 -355.084224) (xy 428.301089 -355.032133)
			(xy 428.288963 -354.977696) (xy 428.284892 -354.922074) (xy 427.626756 -354.922074) (xy 427.62511 -354.923974)
			(xy 427.583921 -354.959669) (xy 427.538072 -354.989138) (xy 427.488495 -355.011781) (xy 427.4362 -355.027137)
			(xy 427.382252 -355.034895) (xy 427.355 -355.035358) (xy 427.327143 -355.034866) (xy 427.272025 -355.026741)
			(xy 427.218672 -355.010694) (xy 427.168218 -354.987064) (xy 427.121732 -354.956353) (xy 427.080203 -354.919213)
			(xy 427.044511 -354.876433) (xy 427.015414 -354.828921) (xy 426.99353 -354.777685) (xy 426.985938 -354.750878)
			(xy 426.983652 -354.741988) (xy 426.972984 -354.726748) (xy 426.901102 -354.678996) (xy 426.883068 -354.674932)
			(xy 426.873924 -354.676202) (xy 426.860907 -354.677867) (xy 426.834723 -354.67965) (xy 426.8216 -354.679758)
			(xy 426.807451 -354.679665) (xy 426.779228 -354.67763) (xy 426.765212 -354.675694) (xy 426.755052 -354.67417)
			(xy 426.735494 -354.678996) (xy 426.661072 -354.734876) (xy 426.650912 -354.752402) (xy 426.649642 -354.762562)
			(xy 426.645543 -354.789713) (xy 426.630569 -354.842542) (xy 426.608178 -354.892679) (xy 426.578831 -354.939088)
			(xy 426.543134 -354.980811) (xy 426.501826 -355.016988) (xy 426.455759 -355.046869) (xy 426.405885 -355.069839)
			(xy 426.353233 -355.085422) (xy 426.298891 -355.093298) (xy 426.271436 -355.093778) (xy 426.244183 -355.093311)
			(xy 426.19023 -355.085558) (xy 426.137931 -355.070205) (xy 426.088349 -355.047565) (xy 426.042494 -355.018098)
			(xy 426.0013 -354.982404) (xy 425.965606 -354.941211) (xy 425.936138 -354.895357) (xy 425.913497 -354.845775)
			(xy 425.898143 -354.793476) (xy 425.890389 -354.739523) (xy 425.889928 -354.71227) (xy 423.74904 -354.71227)
			(xy 423.751671 -354.721232) (xy 423.759423 -354.775186) (xy 423.759884 -354.80244) (xy 423.759227 -354.834003)
			(xy 423.748839 -354.896268) (xy 423.728352 -354.955977) (xy 423.71391 -354.98405) (xy 423.709084 -354.99294)
			(xy 423.707052 -355.012498) (xy 423.732706 -355.100636) (xy 423.745152 -355.11613) (xy 423.754042 -355.12121)
			(xy 423.779119 -355.135799) (xy 423.825003 -355.171294) (xy 423.864982 -355.21333) (xy 423.898131 -355.260936)
			(xy 423.923686 -355.313015) (xy 423.941057 -355.368365) (xy 423.949843 -355.425706) (xy 423.950384 -355.454712)
			(xy 423.949898 -355.481963) (xy 423.942142 -355.535911) (xy 423.926787 -355.588206) (xy 423.904145 -355.637783)
			(xy 423.874679 -355.683633) (xy 423.838988 -355.724824) (xy 423.797797 -355.760515) (xy 423.751947 -355.789981)
			(xy 423.70237 -355.812623) (xy 423.650075 -355.827978) (xy 423.596127 -355.835734) (xy 423.541625 -355.835734)
			(xy 423.487677 -355.827978) (xy 423.435382 -355.812623) (xy 423.385805 -355.789981) (xy 423.339955 -355.760515)
			(xy 423.298764 -355.724824) (xy 423.263073 -355.683633) (xy 423.233607 -355.637783) (xy 423.210965 -355.588206)
			(xy 423.19561 -355.535911) (xy 423.187854 -355.481963) (xy 423.187368 -355.454712) (xy 423.188012 -355.423149)
			(xy 423.198407 -355.360883) (xy 423.218898 -355.301174) (xy 423.233342 -355.273102) (xy 423.238168 -355.264212)
			(xy 423.2402 -355.244654) (xy 423.214546 -355.156516) (xy 423.2021 -355.141022) (xy 423.19321 -355.135942)
			(xy 423.185844 -355.131878) (xy 423.176192 -355.126036) (xy 423.154094 -355.124004) (xy 423.059606 -355.157532)
			(xy 423.043604 -355.173026) (xy 423.03954 -355.18344) (xy 423.028848 -355.210218) (xy 423.000558 -355.260458)
			(xy 422.965027 -355.305867) (xy 422.923064 -355.345408) (xy 422.875626 -355.378181) (xy 422.823795 -355.403439)
			(xy 422.768753 -355.420605) (xy 422.711753 -355.429289) (xy 422.682924 -355.42982) (xy 422.655671 -355.429334)
			(xy 422.601719 -355.42158) (xy 422.54942 -355.406227) (xy 422.499838 -355.383586) (xy 422.453984 -355.35412)
			(xy 422.412789 -355.318428) (xy 422.377094 -355.277236) (xy 422.347625 -355.231383) (xy 422.324981 -355.181803)
			(xy 422.309625 -355.129504) (xy 422.301867 -355.075553) (xy 422.033674 -355.075553) (xy 422.013205 -355.119998)
			(xy 421.983348 -355.166042) (xy 421.965628 -355.186996) (xy 421.959024 -355.194362) (xy 421.955976 -355.202236)
			(xy 421.95453 -355.206537) (xy 421.952998 -355.215479) (xy 421.952928 -355.220016) (xy 421.952928 -355.28758)
			(xy 421.952979 -355.292118) (xy 421.95452 -355.301061) (xy 421.955976 -355.30536) (xy 421.959024 -355.313234)
			(xy 421.965628 -355.3206) (xy 421.983359 -355.341608) (xy 422.013237 -355.387752) (xy 422.036197 -355.437699)
			(xy 422.051766 -355.49042) (xy 422.059624 -355.544828) (xy 422.060116 -355.572314) (xy 422.060116 -355.572568)
			(xy 422.059634 -355.600442) (xy 422.051517 -355.655597) (xy 422.035451 -355.708981) (xy 422.01178 -355.759455)
			(xy 421.981008 -355.805942) (xy 421.943792 -355.84745) (xy 421.922702 -355.865684) (xy 421.919852 -355.868743)
			(xy 421.915121 -355.875635) (xy 421.913304 -355.8794) (xy 421.903204 -355.902059) (xy 421.875582 -355.943257)
			(xy 421.85844 -355.961188) (xy 421.680894 -356.138734) (xy 421.676322 -356.143814) (xy 421.671594 -356.150539)
			(xy 421.666273 -356.166083) (xy 421.665908 -356.174294) (xy 421.665908 -356.612952) (xy 421.666162 -356.612952)
			(xy 421.666162 -356.96271) (xy 421.66555 -356.987693) (xy 421.655807 -357.036701) (xy 421.636698 -357.082869)
			(xy 421.608955 -357.124425) (xy 421.59174 -357.142542) (xy 421.134286 -357.599996) (xy 421.116177 -357.617221)
			(xy 421.074618 -357.644967) (xy 421.028449 -357.664081) (xy 420.979439 -357.67383) (xy 420.954454 -357.674418)
			(xy 420.040562 -357.674418) (xy 420.040562 -357.674164) (xy 418.896546 -357.674164) (xy 418.896038 -357.674164)
			(xy 418.891555 -357.674308) (xy 418.882743 -357.675975) (xy 418.878512 -357.677466) (xy 418.873498 -357.679523)
			(xy 418.864409 -357.685419) (xy 418.860478 -357.68915) (xy 418.78123 -357.768906) (xy 418.77386 -357.779001)
			(xy 418.769089 -357.803505) (xy 418.772086 -357.815642) (xy 418.774372 -357.820722) (xy 418.777481 -357.827472)
			(xy 418.786904 -357.838956) (xy 418.792914 -357.843328) (xy 418.798756 -357.847138) (xy 418.812726 -357.851456)
			(xy 419.076378 -357.851456) (xy 419.083934 -357.85173) (xy 419.098398 -357.856111) (xy 419.104826 -357.860092)
			(xy 419.165786 -357.901748) (xy 419.166294 -357.901748) (xy 419.231826 -357.94569) (xy 419.23335 -357.946706)
			(xy 419.233858 -357.94696) (xy 419.23462 -357.947722) (xy 419.235128 -357.94823) (xy 419.237922 -357.950008)
			(xy 419.24097 -357.953818) (xy 419.243764 -357.956866) (xy 419.24732 -357.961438) (xy 419.282372 -358.045258)
			(xy 419.28542 -358.053132) (xy 419.30193 -358.072944) (xy 419.307264 -358.079548) (xy 419.307772 -358.079802)
			(xy 419.3286 -358.091994) (xy 419.334188 -358.095042) (xy 419.336728 -358.096566) (xy 419.342449 -358.099275)
			(xy 419.354783 -358.102108) (xy 419.361112 -358.102154) (xy 419.368986 -358.101392) (xy 419.375336 -358.100376)
			(xy 419.387528 -358.098852) (xy 419.387782 -358.098852) (xy 419.389814 -358.098598) (xy 419.411912 -358.097836)
			(xy 419.41242 -358.097836) (xy 427.66742 -358.097836) (xy 427.667928 -358.097836) (xy 427.676147 -358.097492)
			(xy 427.691707 -358.092191) (xy 427.698408 -358.087422) (xy 427.703488 -358.08285) (xy 429.222154 -356.56393)
			(xy 429.228959 -356.556583) (xy 429.236673 -356.53812) (xy 429.23714 -356.528116) (xy 429.23714 -355.257608)
			(xy 429.237781 -355.232613) (xy 429.247587 -355.183594) (xy 429.266766 -355.137429) (xy 429.294581 -355.095891)
			(xy 429.311816 -355.077776) (xy 429.475138 -354.914708) (xy 429.608996 -354.78085) (xy 429.627689 -354.763015)
			(xy 429.670825 -354.734588) (xy 429.694594 -354.724462) (xy 429.698658 -354.722684) (xy 429.718216 -354.708968)
			(xy 429.72228 -354.70465) (xy 429.722534 -354.704396) (xy 429.740707 -354.685049) (xy 429.781477 -354.651062)
			(xy 429.826561 -354.623049) (xy 429.875091 -354.60155) (xy 429.926131 -354.586981) (xy 429.978697 -354.57962)
			(xy 430.005236 -354.579174) (xy 430.032486 -354.579662) (xy 430.086431 -354.587423) (xy 430.138722 -354.602781)
			(xy 430.188296 -354.625424) (xy 430.234143 -354.654891) (xy 430.275331 -354.690582) (xy 430.31102 -354.731771)
			(xy 430.340485 -354.77762) (xy 430.363125 -354.827195) (xy 430.378481 -354.879487) (xy 430.386239 -354.933432)
			(xy 430.386744 -354.960682) (xy 430.386744 -354.96119) (xy 430.386255 -354.988628) (xy 430.37837 -355.042936)
			(xy 430.36279 -355.095555) (xy 430.360306 -355.100948) (xy 430.62859 -355.100948) (xy 430.62859 -355.046452)
			(xy 430.636345 -354.99251) (xy 430.651697 -354.940221) (xy 430.674334 -354.890648) (xy 430.703795 -354.844802)
			(xy 430.73948 -354.803614) (xy 430.780663 -354.767924) (xy 430.826506 -354.738457) (xy 430.876076 -354.715814)
			(xy 430.928363 -354.700455) (xy 430.982304 -354.692694) (xy 431.009552 -354.692204) (xy 431.034788 -354.692578)
			(xy 431.084823 -354.699203) (xy 431.133543 -354.712382) (xy 431.180094 -354.731886) (xy 431.202084 -354.744274)
			(xy 431.211736 -354.750116) (xy 431.233834 -354.752148) (xy 431.328322 -354.71862) (xy 431.344324 -354.703126)
			(xy 431.348388 -354.692712) (xy 431.359084 -354.665935) (xy 431.38737 -354.615692) (xy 431.422899 -354.570282)
			(xy 431.464861 -354.530738) (xy 431.512299 -354.497964) (xy 431.56413 -354.472707) (xy 431.619174 -354.455542)
			(xy 431.676175 -354.446861) (xy 431.705004 -354.446332) (xy 431.732259 -354.446752) (xy 431.786213 -354.45451)
			(xy 431.838514 -354.469869) (xy 431.888097 -354.492515) (xy 431.933952 -354.521987) (xy 431.975146 -354.557685)
			(xy 432.01084 -354.598883) (xy 432.040306 -354.644741) (xy 432.062947 -354.694327) (xy 432.075669 -354.73767)
			(xy 434.216556 -354.73767) (xy 434.21705 -354.710096) (xy 434.224994 -354.655524) (xy 434.240712 -354.602664)
			(xy 434.263877 -354.552617) (xy 434.294005 -354.506427) (xy 434.33047 -354.465056) (xy 434.351176 -354.44684)
			(xy 434.359284 -354.439229) (xy 434.368641 -354.419083) (xy 434.36921 -354.407978) (xy 434.36921 -354.330762)
			(xy 434.368708 -354.319643) (xy 434.359326 -354.299484) (xy 434.351176 -354.2919) (xy 434.330457 -354.273698)
			(xy 434.293988 -354.232326) (xy 434.263858 -354.186135) (xy 434.240693 -354.136085) (xy 434.224979 -354.083221)
			(xy 434.217041 -354.028645) (xy 434.216556 -354.00107) (xy 434.21705 -353.97382) (xy 434.224809 -353.919874)
			(xy 434.240167 -353.867582) (xy 434.262809 -353.818007) (xy 434.292275 -353.772158) (xy 434.327965 -353.730969)
			(xy 434.369153 -353.695278) (xy 434.415001 -353.665811) (xy 434.464576 -353.643169) (xy 434.516868 -353.627811)
			(xy 434.570814 -353.62005) (xy 434.598064 -353.619562) (xy 434.632354 -353.621086) (xy 434.642514 -353.622102)
			(xy 434.661818 -353.616006) (xy 434.73243 -353.556824) (xy 434.741828 -353.53879) (xy 434.742844 -353.52863)
			(xy 434.745817 -353.50046) (xy 434.758992 -353.445371) (xy 434.780171 -353.392837) (xy 434.808887 -353.344013)
			(xy 434.844509 -353.299973) (xy 434.886254 -353.261687) (xy 434.933202 -353.229997) (xy 434.984321 -353.205599)
			(xy 435.038486 -353.189031) (xy 435.094507 -353.180657) (xy 435.122828 -353.180142) (xy 435.140847 -353.180364)
			(xy 435.176722 -353.183798) (xy 435.194456 -353.187) (xy 435.203854 -353.188778) (xy 435.222904 -353.184968)
			(xy 435.298088 -353.137216) (xy 435.309518 -353.121468) (xy 435.311804 -353.11207) (xy 435.319223 -353.085032)
			(xy 435.340849 -353.033306) (xy 435.369811 -352.985301) (xy 435.405483 -352.942049) (xy 435.4471 -352.904481)
			(xy 435.493765 -352.873406) (xy 435.544474 -352.849492) (xy 435.598136 -352.833254) (xy 435.653596 -352.825042)
			(xy 435.681628 -352.824542) (xy 435.708884 -352.824929) (xy 435.76284 -352.832691) (xy 435.815143 -352.848053)
			(xy 435.864726 -352.870703) (xy 435.910582 -352.900178) (xy 435.951775 -352.93588) (xy 435.987469 -352.977081)
			(xy 436.016935 -353.022942) (xy 436.039574 -353.072531) (xy 436.054926 -353.124836) (xy 436.062677 -353.178794)
			(xy 436.063136 -353.20605) (xy 436.062658 -353.233624) (xy 436.054711 -353.288198) (xy 436.03899 -353.341058)
			(xy 436.015823 -353.391105) (xy 435.985691 -353.437295) (xy 435.949223 -353.478665) (xy 435.928516 -353.49688)
			(xy 435.920414 -353.504497) (xy 435.91105 -353.524637) (xy 435.910482 -353.535742) (xy 435.910482 -353.612958)
			(xy 435.911031 -353.624071) (xy 435.92038 -353.644231) (xy 435.928516 -353.65182) (xy 435.949271 -353.669981)
			(xy 435.985733 -353.711361) (xy 436.015858 -353.757558) (xy 436.039017 -353.807612) (xy 436.054728 -353.860479)
			(xy 436.062664 -353.915056) (xy 436.062659 -353.970208) (xy 436.054714 -354.024785) (xy 436.038994 -354.077649)
			(xy 436.015826 -354.127698) (xy 435.985694 -354.173891) (xy 435.949225 -354.215264) (xy 435.928516 -354.23348)
			(xy 435.920414 -354.241097) (xy 435.91105 -354.261237) (xy 435.910482 -354.272342) (xy 435.910482 -354.349558)
			(xy 435.911031 -354.360671) (xy 435.92038 -354.380831) (xy 435.928516 -354.38842) (xy 435.949243 -354.406614)
			(xy 435.985712 -354.447986) (xy 436.015841 -354.49418) (xy 436.039004 -354.544232) (xy 436.054717 -354.597097)
			(xy 436.062653 -354.651674) (xy 436.063136 -354.67925) (xy 436.062598 -354.7065) (xy 436.054849 -354.760447)
			(xy 436.039501 -354.812742) (xy 436.016866 -354.86232) (xy 435.987406 -354.908172) (xy 435.95172 -354.949365)
			(xy 435.910535 -354.985059) (xy 435.864689 -355.014528) (xy 435.815115 -355.037173) (xy 435.762823 -355.052532)
			(xy 435.708878 -355.060293) (xy 435.681628 -355.060758) (xy 435.653772 -355.060241) (xy 435.598655 -355.05212)
			(xy 435.545303 -355.036076) (xy 435.494848 -355.01245) (xy 435.448363 -354.981742) (xy 435.406833 -354.944606)
			(xy 435.37114 -354.901828) (xy 435.342043 -354.854318) (xy 435.320158 -354.803084) (xy 435.312566 -354.776278)
			(xy 435.31028 -354.767388) (xy 435.299612 -354.752148) (xy 435.22773 -354.704396) (xy 435.209696 -354.700332)
			(xy 435.200552 -354.701602) (xy 435.187536 -354.703274) (xy 435.161351 -354.705052) (xy 435.148228 -354.705158)
			(xy 435.134079 -354.705062) (xy 435.105856 -354.703029) (xy 435.09184 -354.701094) (xy 435.08168 -354.69957)
			(xy 435.062122 -354.704396) (xy 434.9877 -354.760276) (xy 434.97754 -354.777802) (xy 434.97627 -354.787962)
			(xy 434.972144 -354.815109) (xy 434.957172 -354.867935) (xy 434.934782 -354.91807) (xy 434.905438 -354.964478)
			(xy 434.869745 -355.006201) (xy 434.82844 -355.042377) (xy 434.782376 -355.07226) (xy 434.732505 -355.095231)
			(xy 434.679857 -355.110817) (xy 434.625518 -355.118696) (xy 434.598064 -355.119178) (xy 434.57081 -355.118756)
			(xy 434.516859 -355.110993) (xy 434.464561 -355.095632) (xy 434.414982 -355.072985) (xy 434.36913 -355.043512)
			(xy 434.32794 -355.007814) (xy 434.292249 -354.966617) (xy 434.262784 -354.92076) (xy 434.240145 -354.871177)
			(xy 434.224793 -354.818876) (xy 434.21704 -354.764924) (xy 434.216556 -354.73767) (xy 432.075669 -354.73767)
			(xy 432.078299 -354.74663) (xy 432.086051 -354.800585) (xy 432.086512 -354.82784) (xy 432.085851 -354.859403)
			(xy 432.075464 -354.921668) (xy 432.054979 -354.981377) (xy 432.040538 -355.00945) (xy 432.035712 -355.01834)
			(xy 432.03368 -355.037898) (xy 432.059334 -355.126036) (xy 432.07178 -355.14153) (xy 432.08067 -355.14661)
			(xy 432.105753 -355.161188) (xy 432.151636 -355.196686) (xy 432.191613 -355.238724) (xy 432.224761 -355.286333)
			(xy 432.250315 -355.338413) (xy 432.267685 -355.393763) (xy 432.276471 -355.451106) (xy 432.277012 -355.480112)
			(xy 432.276526 -355.507363) (xy 432.26877 -355.561311) (xy 432.253415 -355.613606) (xy 432.230773 -355.663183)
			(xy 432.201307 -355.709033) (xy 432.165616 -355.750224) (xy 432.124425 -355.785915) (xy 432.078575 -355.815381)
			(xy 432.028998 -355.838023) (xy 431.976703 -355.853378) (xy 431.922755 -355.861134) (xy 431.868253 -355.861134)
			(xy 431.814305 -355.853378) (xy 431.76201 -355.838023) (xy 431.712433 -355.815381) (xy 431.666583 -355.785915)
			(xy 431.625392 -355.750224) (xy 431.589701 -355.709033) (xy 431.560235 -355.663183) (xy 431.537593 -355.613606)
			(xy 431.522238 -355.561311) (xy 431.514482 -355.507363) (xy 431.513996 -355.480112) (xy 431.514637 -355.448548)
			(xy 431.525032 -355.386283) (xy 431.545525 -355.326574) (xy 431.55997 -355.298502) (xy 431.564796 -355.289612)
			(xy 431.566828 -355.270054) (xy 431.541174 -355.181916) (xy 431.528728 -355.166422) (xy 431.519838 -355.161342)
			(xy 431.512472 -355.157278) (xy 431.50282 -355.151436) (xy 431.480722 -355.149404) (xy 431.386234 -355.182932)
			(xy 431.370232 -355.198426) (xy 431.366168 -355.20884) (xy 431.355453 -355.235608) (xy 431.327166 -355.285847)
			(xy 431.291637 -355.331255) (xy 431.249678 -355.370797) (xy 431.202244 -355.403571) (xy 431.150416 -355.428831)
			(xy 431.095377 -355.446) (xy 431.03838 -355.454687) (xy 431.009552 -355.45522) (xy 430.982304 -355.454706)
			(xy 430.928363 -355.446945) (xy 430.876076 -355.431586) (xy 430.826506 -355.408943) (xy 430.780663 -355.379476)
			(xy 430.73948 -355.343786) (xy 430.703795 -355.302598) (xy 430.674334 -355.256752) (xy 430.651697 -355.207179)
			(xy 430.636345 -355.15489) (xy 430.62859 -355.100948) (xy 430.360306 -355.100948) (xy 430.339836 -355.1454)
			(xy 430.309981 -355.191446) (xy 430.292256 -355.212396) (xy 430.285652 -355.219762) (xy 430.282604 -355.227636)
			(xy 430.281157 -355.231937) (xy 430.279624 -355.240879) (xy 430.279556 -355.245416) (xy 430.279556 -355.31298)
			(xy 430.279608 -355.317518) (xy 430.28115 -355.32646) (xy 430.282604 -355.33076) (xy 430.285652 -355.338634)
			(xy 430.292256 -355.346) (xy 430.309955 -355.366968) (xy 430.339788 -355.413019) (xy 430.36273 -355.462862)
			(xy 430.378312 -355.515473) (xy 430.386212 -355.569772) (xy 430.386744 -355.597206) (xy 430.386744 -355.597714)
			(xy 430.386179 -355.627765) (xy 430.376749 -355.687124) (xy 430.358124 -355.744268) (xy 430.330766 -355.797784)
			(xy 430.295352 -355.846345) (xy 430.274476 -355.86797) (xy 430.274222 -355.868224) (xy 430.263554 -355.894386)
			(xy 430.259744 -355.903784) (xy 430.259744 -356.680008) (xy 430.259111 -356.705006) (xy 430.249318 -356.754034)
			(xy 430.230149 -356.800209) (xy 430.20234 -356.841759) (xy 430.185068 -356.85984) (xy 428.131732 -358.913176)
			(xy 428.11362 -358.930392) (xy 428.072057 -358.958121) (xy 428.025887 -358.977219) (xy 427.976882 -358.986954)
			(xy 427.9519 -358.987598) (xy 425.403772 -358.987598) (xy 425.403772 -358.987344) (xy 422.213024 -358.987344)
			(xy 422.203003 -358.98776) (xy 422.184485 -358.995427) (xy 422.170316 -359.009602) (xy 422.162656 -359.028123)
			(xy 422.162224 -359.038144) (xy 422.162224 -359.047288) (xy 421.597328 -359.612184) (xy 421.591362 -359.619409)
			(xy 421.584582 -359.636862) (xy 421.58412 -359.64622) (xy 421.58412 -359.904792) (xy 421.71696 -359.904792)
			(xy 421.721031 -359.84917) (xy 421.733157 -359.794733) (xy 421.75308 -359.742642) (xy 421.780376 -359.694007)
			(xy 421.814462 -359.649864) (xy 421.854611 -359.611155) (xy 421.899969 -359.578704) (xy 421.949569 -359.553203)
			(xy 422.002353 -359.535196) (xy 422.057196 -359.525066) (xy 422.11293 -359.523029) (xy 422.168367 -359.529129)
			(xy 422.222324 -359.543235) (xy 422.273653 -359.565047) (xy 422.321259 -359.594101) (xy 422.364127 -359.629776)
			(xy 422.401344 -359.671313) (xy 422.432117 -359.717826) (xy 422.455789 -359.768323) (xy 422.471857 -359.82173)
			(xy 422.473988 -359.836212) (xy 424.433236 -359.836212) (xy 424.437307 -359.78059) (xy 424.449433 -359.726153)
			(xy 424.469356 -359.674062) (xy 424.496652 -359.625427) (xy 424.530738 -359.581284) (xy 424.570887 -359.542575)
			(xy 424.616245 -359.510124) (xy 424.665845 -359.484623) (xy 424.718629 -359.466616) (xy 424.773472 -359.456486)
			(xy 424.829206 -359.454449) (xy 424.884643 -359.460549) (xy 424.9386 -359.474655) (xy 424.989929 -359.496467)
			(xy 425.037535 -359.525521) (xy 425.080403 -359.561196) (xy 425.11762 -359.602733) (xy 425.148393 -359.649246)
			(xy 425.172065 -359.699743) (xy 425.188133 -359.75315) (xy 425.196253 -359.808326) (xy 425.196762 -359.836212)
			(xy 425.196253 -359.864098) (xy 425.188133 -359.919274) (xy 425.172065 -359.972681) (xy 425.148393 -360.023178)
			(xy 425.11762 -360.069691) (xy 425.080403 -360.111228) (xy 425.037535 -360.146903) (xy 424.989929 -360.175957)
			(xy 424.9386 -360.197769) (xy 424.884643 -360.211875) (xy 424.829206 -360.217975) (xy 424.773472 -360.215938)
			(xy 424.718629 -360.205808) (xy 424.665845 -360.187801) (xy 424.616245 -360.1623) (xy 424.570887 -360.129849)
			(xy 424.530738 -360.09114) (xy 424.496652 -360.046997) (xy 424.469356 -359.998362) (xy 424.449433 -359.946271)
			(xy 424.437307 -359.891834) (xy 424.433236 -359.836212) (xy 422.473988 -359.836212) (xy 422.479977 -359.876906)
			(xy 422.480486 -359.904792) (xy 422.479977 -359.932678) (xy 422.471857 -359.987854) (xy 422.455789 -360.041261)
			(xy 422.432117 -360.091758) (xy 422.401344 -360.138271) (xy 422.364127 -360.179808) (xy 422.321259 -360.215483)
			(xy 422.273653 -360.244537) (xy 422.222324 -360.266349) (xy 422.168367 -360.280455) (xy 422.11293 -360.286555)
			(xy 422.057196 -360.284518) (xy 422.002353 -360.274388) (xy 421.949569 -360.256381) (xy 421.899969 -360.23088)
			(xy 421.854611 -360.198429) (xy 421.814462 -360.15972) (xy 421.780376 -360.115577) (xy 421.75308 -360.066942)
			(xy 421.733157 -360.014851) (xy 421.721031 -359.960414) (xy 421.71696 -359.904792) (xy 421.58412 -359.904792)
			(xy 421.58412 -360.09326) (xy 421.584539 -360.102118) (xy 421.590634 -360.118758) (xy 421.596058 -360.125772)
			(xy 422.006776 -360.536744) (xy 422.013436 -360.544096) (xy 422.02104 -360.562397) (xy 422.021508 -360.572304)
			(xy 422.021508 -361.281472) (xy 422.021508 -361.282234) (xy 422.022019 -361.290806) (xy 422.027994 -361.306894)
			(xy 422.033192 -361.31373) (xy 422.04259 -361.32262) (xy 422.109138 -361.371134) (xy 422.114076 -361.374515)
			(xy 422.125107 -361.379145) (xy 422.130982 -361.380278) (xy 422.142666 -361.382056) (xy 422.15435 -361.378246)
			(xy 422.16832 -361.373928) (xy 422.175432 -361.371896) (xy 422.17594 -361.371896) (xy 422.17975 -361.37088)
			(xy 422.18102 -361.370626) (xy 422.192196 -361.367832) (xy 422.200578 -361.361228) (xy 422.204793 -361.357671)
			(xy 422.21171 -361.349083) (xy 422.214294 -361.34421) (xy 422.24325 -361.285282) (xy 422.248838 -361.274106)
			(xy 422.251196 -361.269014) (xy 422.253877 -361.25812) (xy 422.254172 -361.252516) (xy 422.254426 -361.241848)
			(xy 422.249854 -361.231434) (xy 422.249854 -361.230926) (xy 422.239746 -361.206759) (xy 422.225502 -361.156349)
			(xy 422.218293 -361.104464) (xy 422.21785 -361.078272) (xy 422.218336 -361.051021) (xy 422.226092 -360.997073)
			(xy 422.241447 -360.944778) (xy 422.264089 -360.895201) (xy 422.293555 -360.849351) (xy 422.329246 -360.80816)
			(xy 422.370437 -360.772469) (xy 422.416287 -360.743003) (xy 422.465864 -360.720361) (xy 422.518159 -360.705006)
			(xy 422.572107 -360.69725) (xy 422.626609 -360.69725) (xy 422.680557 -360.705006) (xy 422.732852 -360.720361)
			(xy 422.762937 -360.734101) (xy 435.087517 -360.734101) (xy 435.091247 -360.680849) (xy 435.102365 -360.628636)
			(xy 435.120653 -360.578484) (xy 435.145754 -360.53137) (xy 435.177178 -360.488216) (xy 435.214312 -360.449865)
			(xy 435.235096 -360.433112) (xy 435.243847 -360.42554) (xy 435.254037 -360.404789) (xy 435.254654 -360.393234)
			(xy 435.254654 -360.31297) (xy 435.254059 -360.301405) (xy 435.243883 -360.280633) (xy 435.235096 -360.273092)
			(xy 435.212608 -360.254907) (xy 435.172873 -360.212885) (xy 435.139935 -360.165349) (xy 435.114547 -360.113387)
			(xy 435.097292 -360.058189) (xy 435.088564 -360.001018) (xy 435.08803 -359.972102) (xy 435.088457 -359.944847)
			(xy 435.096215 -359.890893) (xy 435.111573 -359.838592) (xy 435.134218 -359.78901) (xy 435.163689 -359.743155)
			(xy 435.199387 -359.701961) (xy 435.240584 -359.666267) (xy 435.286441 -359.6368) (xy 435.336026 -359.61416)
			(xy 435.388329 -359.598807) (xy 435.442283 -359.591055) (xy 435.469538 -359.590594) (xy 435.498455 -359.591121)
			(xy 435.555627 -359.599844) (xy 435.610828 -359.617097) (xy 435.66279 -359.642487) (xy 435.710324 -359.675431)
			(xy 435.752339 -359.715174) (xy 435.770528 -359.73766) (xy 435.778072 -359.74644) (xy 435.798845 -359.756611)
			(xy 435.810406 -359.757218) (xy 435.89067 -359.757218) (xy 435.902235 -359.756624) (xy 435.923005 -359.746445)
			(xy 435.930548 -359.73766) (xy 435.948758 -359.715193) (xy 435.990775 -359.675459) (xy 436.038307 -359.642519)
			(xy 436.090264 -359.617128) (xy 436.145457 -359.599868) (xy 436.202623 -359.591133) (xy 436.231538 -359.590594)
			(xy 436.25879 -359.591042) (xy 436.312739 -359.598804) (xy 436.365035 -359.614164) (xy 436.414612 -359.63681)
			(xy 436.460463 -359.66628) (xy 436.501653 -359.701976) (xy 436.537344 -359.743169) (xy 436.566809 -359.789023)
			(xy 436.58945 -359.838603) (xy 436.604804 -359.8909) (xy 436.61256 -359.94485) (xy 436.613046 -359.972102)
			(xy 436.61255 -360.00102) (xy 436.603819 -360.058193) (xy 436.586558 -360.113393) (xy 436.561162 -360.165355)
			(xy 436.528214 -360.212888) (xy 436.488468 -360.254903) (xy 436.46598 -360.273092) (xy 436.457223 -360.280658)
			(xy 436.447037 -360.301414) (xy 436.446422 -360.31297) (xy 436.446422 -360.393234) (xy 436.447023 -360.404798)
			(xy 436.457195 -360.42557) (xy 436.46598 -360.433112) (xy 436.486763 -360.449864) (xy 436.52389 -360.488219)
			(xy 436.555308 -360.531375) (xy 436.580404 -360.578488) (xy 436.598689 -360.62864) (xy 436.609804 -360.680851)
			(xy 436.613533 -360.734101) (xy 436.609804 -360.787352) (xy 436.598688 -360.839562) (xy 436.580403 -360.889714)
			(xy 436.555307 -360.936827) (xy 436.523888 -360.979983) (xy 436.486761 -361.018338) (xy 436.46598 -361.035092)
			(xy 436.457223 -361.042658) (xy 436.447037 -361.063414) (xy 436.446422 -361.07497) (xy 436.446422 -361.155234)
			(xy 436.447023 -361.166798) (xy 436.457195 -361.18757) (xy 436.46598 -361.195112) (xy 436.488465 -361.213301)
			(xy 436.528201 -361.255321) (xy 436.56114 -361.302856) (xy 436.586529 -361.354818) (xy 436.603784 -361.410016)
			(xy 436.612512 -361.467186) (xy 436.613046 -361.496102) (xy 436.612524 -361.523352) (xy 436.604768 -361.577296)
			(xy 436.589415 -361.629588) (xy 436.566776 -361.679162) (xy 436.537313 -361.725011) (xy 436.501626 -361.7662)
			(xy 436.46044 -361.801892) (xy 436.414594 -361.831359) (xy 436.365022 -361.854002) (xy 436.312731 -361.869361)
			(xy 436.258788 -361.877122) (xy 436.231538 -361.87761) (xy 436.20262 -361.877098) (xy 436.145447 -361.868373)
			(xy 436.090247 -361.851116) (xy 436.038285 -361.825723) (xy 435.990751 -361.792776) (xy 435.948737 -361.753031)
			(xy 435.930548 -361.730544) (xy 435.922971 -361.721799) (xy 435.902223 -361.711608) (xy 435.89067 -361.710986)
			(xy 435.810406 -361.710986) (xy 435.798839 -361.711565) (xy 435.778069 -361.721754) (xy 435.770528 -361.730544)
			(xy 435.752332 -361.753023) (xy 435.710312 -361.792757) (xy 435.662778 -361.825695) (xy 435.610818 -361.851084)
			(xy 435.555622 -361.868341) (xy 435.498454 -361.877073) (xy 435.469538 -361.87761) (xy 435.442286 -361.877109)
			(xy 435.388337 -361.869358) (xy 435.33604 -361.854006) (xy 435.28646 -361.831369) (xy 435.240607 -361.801905)
			(xy 435.199414 -361.766215) (xy 435.163719 -361.725025) (xy 435.134251 -361.679175) (xy 435.111608 -361.629598)
			(xy 435.096251 -361.577302) (xy 435.088494 -361.523354) (xy 435.08803 -361.496102) (xy 435.088539 -361.467185)
			(xy 435.097268 -361.410012) (xy 435.114527 -361.354813) (xy 435.139921 -361.302851) (xy 435.172866 -361.255317)
			(xy 435.212609 -361.213301) (xy 435.235096 -361.195112) (xy 435.243847 -361.18754) (xy 435.254037 -361.166789)
			(xy 435.254654 -361.155234) (xy 435.254654 -361.07497) (xy 435.254059 -361.063405) (xy 435.243883 -361.042633)
			(xy 435.235096 -361.035092) (xy 435.214314 -361.018337) (xy 435.17718 -360.979986) (xy 435.145755 -360.936832)
			(xy 435.120654 -360.889719) (xy 435.102366 -360.839566) (xy 435.091248 -360.787354) (xy 435.087517 -360.734101)
			(xy 422.762937 -360.734101) (xy 422.782429 -360.743003) (xy 422.828279 -360.772469) (xy 422.86947 -360.80816)
			(xy 422.905161 -360.849351) (xy 422.934627 -360.895201) (xy 422.957269 -360.944778) (xy 422.972624 -360.997073)
			(xy 422.98038 -361.051021) (xy 422.980866 -361.078272) (xy 422.980353 -361.106479) (xy 422.972039 -361.162277)
			(xy 422.955601 -361.216242) (xy 422.931399 -361.267201) (xy 422.899959 -361.314042) (xy 422.861967 -361.355745)
			(xy 422.81825 -361.391401) (xy 422.769761 -361.420233) (xy 422.717556 -361.441614) (xy 422.69029 -361.448858)
			(xy 422.678606 -361.451906) (xy 422.670478 -361.458256) (xy 422.666236 -361.461862) (xy 422.659316 -361.47058)
			(xy 422.656762 -361.475528) (xy 422.622218 -361.545632) (xy 422.619892 -361.550668) (xy 422.61721 -361.56143)
			(xy 422.616884 -361.566968) (xy 422.61663 -361.577636) (xy 422.621202 -361.58805) (xy 422.621202 -361.588558)
			(xy 422.631306 -361.612726) (xy 422.645541 -361.663136) (xy 422.652739 -361.715021) (xy 422.653206 -361.741212)
			(xy 422.653118 -361.751457) (xy 422.651974 -361.771915) (xy 422.65092 -361.782106) (xy 422.649904 -361.792266)
			(xy 422.65346 -361.804204) (xy 422.656254 -361.812332) (xy 422.67759 -361.837986) (xy 422.70934 -361.876086)
			(xy 422.712695 -361.879923) (xy 422.720629 -361.886318) (xy 422.725088 -361.888786) (xy 422.734232 -361.893358)
			(xy 422.740328 -361.893866) (xy 422.744646 -361.89412) (xy 422.773084 -361.896755) (xy 422.828765 -361.909458)
			(xy 422.88193 -361.930319) (xy 422.931391 -361.958874) (xy 422.976041 -361.994484) (xy 423.014884 -362.036352)
			(xy 423.047051 -362.083543) (xy 423.071822 -362.135003) (xy 423.088645 -362.18958) (xy 423.097143 -362.246056)
			(xy 423.097706 -362.274612) (xy 423.097244 -362.301599) (xy 423.089646 -362.355034) (xy 423.074588 -362.406864)
			(xy 423.052372 -362.456053) (xy 423.023441 -362.501618) (xy 422.988374 -362.542647) (xy 422.947872 -362.578322)
			(xy 422.902744 -362.607929) (xy 422.878504 -362.619798) (xy 422.877234 -362.620306) (xy 422.865804 -362.62818)
			(xy 422.86174 -362.632244) (xy 422.854628 -362.643166) (xy 422.84015 -362.676694) (xy 422.826942 -362.707428)
			(xy 422.824656 -362.712254) (xy 422.823132 -362.716064) (xy 422.82237 -362.734606) (xy 422.825164 -362.743496)
			(xy 422.834058 -362.772406) (xy 422.843629 -362.832127) (xy 422.844214 -362.862368) (xy 422.843753 -362.889622)
			(xy 422.836 -362.943577) (xy 422.820646 -362.995879) (xy 422.798006 -363.045464) (xy 422.768539 -363.091321)
			(xy 422.732845 -363.132518) (xy 422.691652 -363.168216) (xy 422.645797 -363.197688) (xy 422.596215 -363.220333)
			(xy 422.543914 -363.235692) (xy 422.48996 -363.24345) (xy 422.462706 -363.243876) (xy 422.432979 -363.243307)
			(xy 422.374245 -363.234082) (xy 422.317654 -363.215854) (xy 422.264577 -363.189065) (xy 422.2163 -363.154364)
			(xy 422.194736 -363.133894) (xy 422.194482 -363.13364) (xy 422.188981 -363.128656) (xy 422.175814 -363.121818)
			(xy 422.168574 -363.120178) (xy 422.160954 -363.118654) (xy 422.146476 -363.120178) (xy 422.05275 -363.159294)
			(xy 422.044693 -363.162991) (xy 422.031632 -363.174959) (xy 422.023468 -363.190682) (xy 422.022016 -363.199426)
			(xy 422.021508 -363.206284) (xy 422.021508 -365.312198) (xy 422.020989 -365.322097) (xy 422.01341 -365.340393)
			(xy 422.006776 -365.347758) (xy 421.685466 -365.669068) (xy 421.681935 -365.672381) (xy 421.673878 -365.677746)
			(xy 421.669464 -365.679736) (xy 421.660066 -365.6838) (xy 420.983664 -365.6838) (xy 420.978568 -365.683683)
			(xy 420.968586 -365.681627) (xy 420.963852 -365.679736) (xy 420.954708 -365.675926) (xy 420.714932 -365.43615)
			(xy 420.708272 -365.428798) (xy 420.700669 -365.410497) (xy 420.7002 -365.40059) (xy 420.7002 -365.064548)
			(xy 420.700717 -365.039643) (xy 420.708865 -364.990503) (xy 420.724902 -364.943344) (xy 420.7484 -364.899425)
			(xy 420.763192 -364.879382) (xy 420.765732 -364.875826) (xy 420.772082 -364.861856) (xy 420.776146 -364.853474)
			(xy 420.776908 -364.844584) (xy 420.776908 -360.540046) (xy 420.776654 -360.534458) (xy 420.775831 -360.528589)
			(xy 420.771852 -360.517428) (xy 420.76878 -360.51236) (xy 420.766494 -360.508804) (xy 420.762176 -360.503978)
			(xy 420.63162 -360.373422) (xy 420.628942 -360.370814) (xy 420.622946 -360.366354) (xy 420.619682 -360.364532)
			(xy 420.613586 -360.36123) (xy 420.60622 -360.359706) (xy 420.583745 -360.354414) (xy 420.540601 -360.337973)
			(xy 420.500425 -360.31522) (xy 420.482014 -360.301286) (xy 420.475188 -360.296288) (xy 420.459226 -360.290707)
			(xy 420.450772 -360.290364) (xy 417.367974 -360.290364) (xy 417.34406 -360.289924) (xy 417.296821 -360.282448)
			(xy 417.251334 -360.267669) (xy 417.208722 -360.245951) (xy 417.170036 -360.217829) (xy 417.152836 -360.20121)
			(xy 416.953954 -360.002328) (xy 416.937378 -359.98509) (xy 416.909267 -359.946405) (xy 416.887547 -359.903802)
			(xy 416.872754 -359.858327) (xy 416.86525 -359.8111) (xy 416.8648 -359.78719) (xy 416.8648 -358.15651)
			(xy 416.864546 -358.15651) (xy 416.864546 -358.147874) (xy 416.865605 -358.12436) (xy 416.874072 -358.078061)
			(xy 416.889563 -358.033617) (xy 416.911709 -357.992086) (xy 416.939982 -357.954457) (xy 416.97371 -357.921628)
			(xy 417.012087 -357.894381) (xy 417.054201 -357.873364) (xy 417.099048 -357.859078) (xy 417.145558 -357.851864)
			(xy 417.169092 -357.851456) (xy 417.171378 -357.851456) (xy 417.180744 -357.851036) (xy 417.198226 -357.844305)
			(xy 417.212116 -357.831736) (xy 417.220554 -357.815012) (xy 417.221924 -357.805736) (xy 417.221924 -357.802942)
			(xy 417.211878 -357.778627) (xy 417.197728 -357.727956) (xy 417.190605 -357.675831) (xy 417.190174 -357.649526)
			(xy 417.190936 -357.626158) (xy 417.191093 -357.619007) (xy 417.187872 -357.605079) (xy 417.184586 -357.598726)
			(xy 417.1823 -357.594408) (xy 417.090606 -357.542338) (xy 417.0845 -357.53908) (xy 417.07111 -357.5356)
			(xy 417.06419 -357.53548) (xy 417.058094 -357.535734) (xy 417.033161 -357.553205) (xy 416.978953 -357.580913)
			(xy 416.921072 -357.59978) (xy 416.860949 -357.609341) (xy 416.83051 -357.609902) (xy 416.802255 -357.60941)
			(xy 416.746347 -357.601172) (xy 416.692239 -357.58487) (xy 416.641085 -357.560853) (xy 416.59398 -357.529635)
			(xy 416.55193 -357.491882) (xy 416.515834 -357.448401) (xy 416.486463 -357.400122) (xy 416.464446 -357.348077)
			(xy 416.456876 -357.32085) (xy 416.454405 -357.312698) (xy 416.444931 -357.298552) (xy 416.438334 -357.293164)
			(xy 416.430968 -357.287576) (xy 412.840424 -357.287576) (xy 412.81636 -357.286371) (xy 412.769304 -357.276043)
			(xy 412.725034 -357.25704) (xy 412.685134 -357.230043) (xy 412.667704 -357.213408) (xy 409.77566 -354.321364)
			(xy 409.758399 -354.30327) (xy 409.73058 -354.261726) (xy 409.711396 -354.215556) (xy 409.701583 -354.16653)
			(xy 409.700984 -354.141532) (xy 409.700984 -349.213424) (xy 409.701623 -349.188429) (xy 409.711429 -349.139409)
			(xy 409.730608 -349.093244) (xy 409.758425 -349.051707) (xy 409.77566 -349.033592) (xy 411.436566 -347.37294)
			(xy 411.441138 -347.36786) (xy 411.445858 -347.361133) (xy 411.451165 -347.345589) (xy 411.451552 -347.33738)
			(xy 411.451552 -339.386418) (xy 411.451298 -339.386418) (xy 411.451298 -333.036926) (xy 411.451906 -333.011941)
			(xy 411.461642 -332.962929) (xy 411.480745 -332.916754) (xy 411.508482 -332.875189) (xy 411.52572 -332.857094)
			(xy 412.117286 -332.265528) (xy 412.135399 -332.248313) (xy 412.176962 -332.220587) (xy 412.223131 -332.201492)
			(xy 412.272137 -332.191759) (xy 412.297118 -332.191106) (xy 412.471108 -332.191106) (xy 412.471108 -332.19136)
			(xy 412.672022 -332.19136) (xy 412.680303 -332.19104) (xy 412.695989 -332.185729) (xy 412.702756 -332.180946)
			(xy 412.70936 -332.17612) (xy 412.718504 -332.162404) (xy 412.72079 -332.154022) (xy 412.728581 -332.127524)
			(xy 412.750746 -332.076938) (xy 412.779976 -332.030076) (xy 412.815658 -331.987921) (xy 412.857047 -331.951352)
			(xy 412.903277 -331.921135) (xy 412.953383 -331.897901) (xy 413.006315 -331.882137) (xy 413.060967 -331.874171)
			(xy 413.116197 -331.874171) (xy 413.170849 -331.882137) (xy 413.223781 -331.897901) (xy 413.273887 -331.921135)
			(xy 413.320117 -331.951352) (xy 413.361506 -331.987921) (xy 413.397188 -332.030076) (xy 413.426418 -332.076938)
			(xy 413.448583 -332.127524) (xy 413.456374 -332.154022) (xy 413.458873 -332.162006) (xy 413.468209 -332.175875)
			(xy 413.474662 -332.1812) (xy 413.481266 -332.186026) (xy 413.49676 -332.19136) (xy 413.897318 -332.19136)
			(xy 413.897826 -332.19136) (xy 413.903137 -332.191169) (xy 413.913509 -332.188865) (xy 413.9184 -332.186788)
			(xy 413.922532 -332.184787) (xy 413.93007 -332.179549) (xy 413.933386 -332.176374) (xy 414.08858 -332.020926)
			(xy 414.094547 -332.013701) (xy 414.101329 -331.996249) (xy 414.101788 -331.98689) (xy 414.101788 -329.316588)
			(xy 414.10136 -329.307733) (xy 414.095254 -329.291104) (xy 414.08985 -329.284076) (xy 413.665924 -328.859896)
			(xy 412.396686 -327.590912) (xy 412.38933 -327.584264) (xy 412.371029 -327.576687) (xy 412.361126 -327.57618)
			(xy 411.056582 -327.57618) (xy 411.050571 -327.576343) (xy 411.038885 -327.57916) (xy 411.033468 -327.581768)
			(xy 411.029994 -327.583607) (xy 411.023614 -327.5882) (xy 411.020768 -327.590912) (xy 409.246324 -329.365356)
			(xy 409.239484 -329.372757) (xy 409.231766 -329.391355) (xy 409.231338 -329.401424) (xy 409.231338 -332.18755)
			(xy 409.230904 -332.197615) (xy 409.22317 -332.2162) (xy 409.216352 -332.223618) (xy 408.718766 -332.721204)
			(xy 408.711913 -332.728599) (xy 408.704169 -332.747198) (xy 408.70378 -332.757272) (xy 408.70378 -333.195422)
			(xy 408.703941 -333.201782) (xy 408.707019 -333.214122) (xy 408.709876 -333.219806) (xy 408.72664 -333.250286)
			(xy 408.726894 -333.25054) (xy 408.749326 -333.265732) (xy 408.790068 -333.301441) (xy 408.825352 -333.342552)
			(xy 408.854469 -333.388239) (xy 408.876834 -333.437583) (xy 408.891998 -333.489594) (xy 408.899655 -333.543226)
			(xy 408.899653 -333.597402) (xy 408.891992 -333.651034) (xy 408.876824 -333.703044) (xy 408.854455 -333.752386)
			(xy 408.825335 -333.798071) (xy 408.790048 -333.839179) (xy 408.749303 -333.874885) (xy 408.726894 -333.890112)
			(xy 408.72664 -333.890366) (xy 408.709876 -333.920846) (xy 408.707027 -333.926534) (xy 408.703938 -333.938871)
			(xy 408.70378 -333.94523) (xy 408.70378 -337.722464) (xy 408.704034 -337.726274) (xy 408.705595 -337.738206)
			(xy 408.718041 -337.758763) (xy 408.72791 -337.765644) (xy 408.752492 -337.780333) (xy 408.79735 -337.815926)
			(xy 408.836386 -337.857824) (xy 408.868721 -337.905085) (xy 408.89363 -337.956647) (xy 408.910553 -338.011353)
			(xy 408.919111 -338.067974) (xy 408.91968 -338.096606) (xy 408.91921 -338.123939) (xy 408.911404 -338.178046)
			(xy 408.895952 -338.230484) (xy 408.873172 -338.280178) (xy 408.843529 -338.32611) (xy 408.825954 -338.34705)
			(xy 408.8257 -338.347304) (xy 408.819604 -338.354416) (xy 408.816556 -338.362798) (xy 408.815034 -338.367086)
			(xy 408.813371 -338.37603) (xy 408.813254 -338.380578) (xy 408.813254 -338.447634) (xy 408.813375 -338.452182)
			(xy 408.815031 -338.461128) (xy 408.816556 -338.465414) (xy 408.819604 -338.473796) (xy 408.8257 -338.480908)
			(xy 408.825954 -338.481162) (xy 408.843541 -338.50209) (xy 408.873169 -338.54803) (xy 408.895937 -338.597729)
			(xy 408.91138 -338.650167) (xy 408.91918 -338.704273) (xy 408.91968 -338.731606) (xy 408.919166 -338.76024)
			(xy 408.910605 -338.816866) (xy 408.893675 -338.871575) (xy 408.868758 -338.923139) (xy 408.836412 -338.970399)
			(xy 408.797366 -339.012293) (xy 408.752496 -339.04788) (xy 408.72791 -339.062568) (xy 408.71804 -339.06945)
			(xy 408.705599 -339.090005) (xy 408.704034 -339.101938) (xy 408.70378 -339.105748) (xy 408.70378 -360.7943)
			(xy 412.920178 -360.7943) (xy 412.924249 -360.738678) (xy 412.936375 -360.684241) (xy 412.956298 -360.63215)
			(xy 412.983594 -360.583515) (xy 413.01768 -360.539372) (xy 413.057829 -360.500663) (xy 413.103187 -360.468212)
			(xy 413.152787 -360.442711) (xy 413.205571 -360.424704) (xy 413.260414 -360.414574) (xy 413.316148 -360.412537)
			(xy 413.371585 -360.418637) (xy 413.425542 -360.432743) (xy 413.476871 -360.454555) (xy 413.524477 -360.483609)
			(xy 413.567345 -360.519284) (xy 413.604562 -360.560821) (xy 413.635335 -360.607334) (xy 413.659007 -360.657831)
			(xy 413.675075 -360.711238) (xy 413.683195 -360.766414) (xy 413.683704 -360.7943) (xy 413.683195 -360.822186)
			(xy 413.675075 -360.877362) (xy 413.659007 -360.930769) (xy 413.635335 -360.981266) (xy 413.604562 -361.027779)
			(xy 413.567345 -361.069316) (xy 413.524477 -361.104991) (xy 413.476871 -361.134045) (xy 413.425542 -361.155857)
			(xy 413.371585 -361.169963) (xy 413.316148 -361.176063) (xy 413.260414 -361.174026) (xy 413.205571 -361.163896)
			(xy 413.152787 -361.145889) (xy 413.103187 -361.120388) (xy 413.057829 -361.087937) (xy 413.01768 -361.049228)
			(xy 412.983594 -361.005085) (xy 412.956298 -360.95645) (xy 412.936375 -360.904359) (xy 412.924249 -360.849922)
			(xy 412.920178 -360.7943) (xy 408.70378 -360.7943) (xy 408.70378 -361.3023) (xy 414.979356 -361.3023)
			(xy 414.983427 -361.246678) (xy 414.995553 -361.192241) (xy 415.015476 -361.14015) (xy 415.042772 -361.091515)
			(xy 415.076858 -361.047372) (xy 415.117007 -361.008663) (xy 415.162365 -360.976212) (xy 415.211965 -360.950711)
			(xy 415.264749 -360.932704) (xy 415.319592 -360.922574) (xy 415.375326 -360.920537) (xy 415.430763 -360.926637)
			(xy 415.48472 -360.940743) (xy 415.536049 -360.962555) (xy 415.583655 -360.991609) (xy 415.626523 -361.027284)
			(xy 415.66374 -361.068821) (xy 415.694513 -361.115334) (xy 415.718185 -361.165831) (xy 415.734253 -361.219238)
			(xy 415.742373 -361.274414) (xy 415.742882 -361.3023) (xy 415.742373 -361.330186) (xy 415.734253 -361.385362)
			(xy 415.718185 -361.438769) (xy 415.694513 -361.489266) (xy 415.66374 -361.535779) (xy 415.626523 -361.577316)
			(xy 415.583655 -361.612991) (xy 415.536049 -361.642045) (xy 415.48472 -361.663857) (xy 415.430763 -361.677963)
			(xy 415.375326 -361.684063) (xy 415.319592 -361.682026) (xy 415.264749 -361.671896) (xy 415.211965 -361.653889)
			(xy 415.162365 -361.628388) (xy 415.117007 -361.595937) (xy 415.076858 -361.557228) (xy 415.042772 -361.513085)
			(xy 415.015476 -361.46445) (xy 414.995553 -361.412359) (xy 414.983427 -361.357922) (xy 414.979356 -361.3023)
			(xy 408.70378 -361.3023) (xy 408.70378 -362.804964) (xy 412.9311 -362.804964) (xy 412.935171 -362.749342)
			(xy 412.947297 -362.694905) (xy 412.96722 -362.642814) (xy 412.994516 -362.594179) (xy 413.028602 -362.550036)
			(xy 413.068751 -362.511327) (xy 413.114109 -362.478876) (xy 413.163709 -362.453375) (xy 413.216493 -362.435368)
			(xy 413.271336 -362.425238) (xy 413.32707 -362.423201) (xy 413.382507 -362.429301) (xy 413.436464 -362.443407)
			(xy 413.487793 -362.465219) (xy 413.535399 -362.494273) (xy 413.578267 -362.529948) (xy 413.615484 -362.571485)
			(xy 413.646257 -362.617998) (xy 413.669929 -362.668495) (xy 413.685997 -362.721902) (xy 413.694117 -362.777078)
			(xy 413.694626 -362.804964) (xy 413.694117 -362.83285) (xy 413.685997 -362.888026) (xy 413.669929 -362.941433)
			(xy 413.646257 -362.99193) (xy 413.615484 -363.038443) (xy 413.578267 -363.07998) (xy 413.535399 -363.115655)
			(xy 413.487793 -363.144709) (xy 413.436464 -363.166521) (xy 413.382507 -363.180627) (xy 413.32707 -363.186727)
			(xy 413.271336 -363.18469) (xy 413.216493 -363.17456) (xy 413.163709 -363.156553) (xy 413.114109 -363.131052)
			(xy 413.068751 -363.098601) (xy 413.028602 -363.059892) (xy 412.994516 -363.015749) (xy 412.96722 -362.967114)
			(xy 412.947297 -362.915023) (xy 412.935171 -362.860586) (xy 412.9311 -362.804964) (xy 408.70378 -362.804964)
			(xy 408.70378 -363.244638) (xy 408.703946 -363.250648) (xy 408.706766 -363.262332) (xy 408.709368 -363.267752)
			(xy 408.711208 -363.271226) (xy 408.715803 -363.277603) (xy 408.718512 -363.280452) (xy 408.794204 -363.356144)
			(xy 415.065208 -363.356144) (xy 415.069279 -363.300522) (xy 415.081405 -363.246085) (xy 415.101328 -363.193994)
			(xy 415.128624 -363.145359) (xy 415.16271 -363.101216) (xy 415.202859 -363.062507) (xy 415.248217 -363.030056)
			(xy 415.297817 -363.004555) (xy 415.350601 -362.986548) (xy 415.405444 -362.976418) (xy 415.461178 -362.974381)
			(xy 415.516615 -362.980481) (xy 415.570572 -362.994587) (xy 415.621901 -363.016399) (xy 415.669507 -363.045453)
			(xy 415.712375 -363.081128) (xy 415.749592 -363.122665) (xy 415.780365 -363.169178) (xy 415.804037 -363.219675)
			(xy 415.820105 -363.273082) (xy 415.828225 -363.328258) (xy 415.828734 -363.356144) (xy 415.828225 -363.38403)
			(xy 415.820105 -363.439206) (xy 415.804037 -363.492613) (xy 415.780365 -363.54311) (xy 415.749592 -363.589623)
			(xy 415.712375 -363.63116) (xy 415.669507 -363.666835) (xy 415.621901 -363.695889) (xy 415.570572 -363.717701)
			(xy 415.516615 -363.731807) (xy 415.461178 -363.737907) (xy 415.405444 -363.73587) (xy 415.350601 -363.72574)
			(xy 415.297817 -363.707733) (xy 415.248217 -363.682232) (xy 415.202859 -363.649781) (xy 415.16271 -363.611072)
			(xy 415.128624 -363.566929) (xy 415.101328 -363.518294) (xy 415.081405 -363.466203) (xy 415.069279 -363.411766)
			(xy 415.065208 -363.356144) (xy 408.794204 -363.356144) (xy 409.517596 -364.079536) (xy 412.440372 -364.079536)
			(xy 412.444443 -364.023914) (xy 412.456569 -363.969477) (xy 412.476492 -363.917386) (xy 412.503788 -363.868751)
			(xy 412.537874 -363.824608) (xy 412.578023 -363.785899) (xy 412.623381 -363.753448) (xy 412.672981 -363.727947)
			(xy 412.725765 -363.70994) (xy 412.780608 -363.69981) (xy 412.836342 -363.697773) (xy 412.891779 -363.703873)
			(xy 412.945736 -363.717979) (xy 412.997065 -363.739791) (xy 413.044671 -363.768845) (xy 413.087539 -363.80452)
			(xy 413.124756 -363.846057) (xy 413.155529 -363.89257) (xy 413.179201 -363.943067) (xy 413.195269 -363.996474)
			(xy 413.203389 -364.05165) (xy 413.203898 -364.079536) (xy 413.203389 -364.107422) (xy 413.195269 -364.162598)
			(xy 413.179201 -364.216005) (xy 413.155529 -364.266502) (xy 413.124756 -364.313015) (xy 413.087539 -364.354552)
			(xy 413.084102 -364.357412) (xy 416.135818 -364.357412) (xy 416.139889 -364.30179) (xy 416.152015 -364.247353)
			(xy 416.171938 -364.195262) (xy 416.199234 -364.146627) (xy 416.23332 -364.102484) (xy 416.273469 -364.063775)
			(xy 416.318827 -364.031324) (xy 416.368427 -364.005823) (xy 416.421211 -363.987816) (xy 416.476054 -363.977686)
			(xy 416.531788 -363.975649) (xy 416.587225 -363.981749) (xy 416.641182 -363.995855) (xy 416.692511 -364.017667)
			(xy 416.740117 -364.046721) (xy 416.782985 -364.082396) (xy 416.820202 -364.123933) (xy 416.850975 -364.170446)
			(xy 416.874647 -364.220943) (xy 416.890715 -364.27435) (xy 416.898835 -364.329526) (xy 416.899344 -364.357412)
			(xy 416.898835 -364.385298) (xy 416.890715 -364.440474) (xy 416.874647 -364.493881) (xy 416.850975 -364.544378)
			(xy 416.820202 -364.590891) (xy 416.782985 -364.632428) (xy 416.740117 -364.668103) (xy 416.692511 -364.697157)
			(xy 416.641182 -364.718969) (xy 416.587225 -364.733075) (xy 416.531788 -364.739175) (xy 416.476054 -364.737138)
			(xy 416.421211 -364.727008) (xy 416.368427 -364.709001) (xy 416.318827 -364.6835) (xy 416.273469 -364.651049)
			(xy 416.23332 -364.61234) (xy 416.199234 -364.568197) (xy 416.171938 -364.519562) (xy 416.152015 -364.467471)
			(xy 416.139889 -364.413034) (xy 416.135818 -364.357412) (xy 413.084102 -364.357412) (xy 413.044671 -364.390227)
			(xy 412.997065 -364.419281) (xy 412.945736 -364.441093) (xy 412.891779 -364.455199) (xy 412.836342 -364.461299)
			(xy 412.780608 -364.459262) (xy 412.725765 -364.449132) (xy 412.672981 -364.431125) (xy 412.623381 -364.405624)
			(xy 412.578023 -364.373173) (xy 412.537874 -364.334464) (xy 412.503788 -364.290321) (xy 412.476492 -364.241686)
			(xy 412.456569 -364.189595) (xy 412.444443 -364.135158) (xy 412.440372 -364.079536) (xy 409.517596 -364.079536)
			(xy 410.316172 -364.878112) (xy 414.96564 -364.878112) (xy 414.969711 -364.82249) (xy 414.981837 -364.768053)
			(xy 415.00176 -364.715962) (xy 415.029056 -364.667327) (xy 415.063142 -364.623184) (xy 415.103291 -364.584475)
			(xy 415.148649 -364.552024) (xy 415.198249 -364.526523) (xy 415.251033 -364.508516) (xy 415.305876 -364.498386)
			(xy 415.36161 -364.496349) (xy 415.417047 -364.502449) (xy 415.471004 -364.516555) (xy 415.522333 -364.538367)
			(xy 415.569939 -364.567421) (xy 415.612807 -364.603096) (xy 415.650024 -364.644633) (xy 415.680797 -364.691146)
			(xy 415.704469 -364.741643) (xy 415.720537 -364.79505) (xy 415.728657 -364.850226) (xy 415.729166 -364.878112)
			(xy 415.728657 -364.905998) (xy 415.720537 -364.961174) (xy 415.704469 -365.014581) (xy 415.680797 -365.065078)
			(xy 415.650024 -365.111591) (xy 415.612807 -365.153128) (xy 415.569939 -365.188803) (xy 415.522333 -365.217857)
			(xy 415.471872 -365.2393) (xy 417.696648 -365.2393) (xy 417.700719 -365.183678) (xy 417.712845 -365.129241)
			(xy 417.732768 -365.07715) (xy 417.760064 -365.028515) (xy 417.79415 -364.984372) (xy 417.834299 -364.945663)
			(xy 417.879657 -364.913212) (xy 417.929257 -364.887711) (xy 417.982041 -364.869704) (xy 418.036884 -364.859574)
			(xy 418.092618 -364.857537) (xy 418.148055 -364.863637) (xy 418.202012 -364.877743) (xy 418.253341 -364.899555)
			(xy 418.300947 -364.928609) (xy 418.343815 -364.964284) (xy 418.381032 -365.005821) (xy 418.411805 -365.052334)
			(xy 418.435477 -365.102831) (xy 418.451545 -365.156238) (xy 418.458909 -365.20628) (xy 418.819582 -365.20628)
			(xy 418.823653 -365.150658) (xy 418.835779 -365.096221) (xy 418.855702 -365.04413) (xy 418.882998 -364.995495)
			(xy 418.917084 -364.951352) (xy 418.957233 -364.912643) (xy 419.002591 -364.880192) (xy 419.052191 -364.854691)
			(xy 419.104975 -364.836684) (xy 419.159818 -364.826554) (xy 419.215552 -364.824517) (xy 419.270989 -364.830617)
			(xy 419.324946 -364.844723) (xy 419.376275 -364.866535) (xy 419.423881 -364.895589) (xy 419.466749 -364.931264)
			(xy 419.503966 -364.972801) (xy 419.534739 -365.019314) (xy 419.558411 -365.069811) (xy 419.574479 -365.123218)
			(xy 419.582599 -365.178394) (xy 419.583108 -365.20628) (xy 419.582599 -365.234166) (xy 419.574479 -365.289342)
			(xy 419.558411 -365.342749) (xy 419.534739 -365.393246) (xy 419.503966 -365.439759) (xy 419.466749 -365.481296)
			(xy 419.423881 -365.516971) (xy 419.376275 -365.546025) (xy 419.324946 -365.567837) (xy 419.270989 -365.581943)
			(xy 419.215552 -365.588043) (xy 419.159818 -365.586006) (xy 419.104975 -365.575876) (xy 419.052191 -365.557869)
			(xy 419.002591 -365.532368) (xy 418.957233 -365.499917) (xy 418.917084 -365.461208) (xy 418.882998 -365.417065)
			(xy 418.855702 -365.36843) (xy 418.835779 -365.316339) (xy 418.823653 -365.261902) (xy 418.819582 -365.20628)
			(xy 418.458909 -365.20628) (xy 418.459665 -365.211414) (xy 418.460174 -365.2393) (xy 418.459665 -365.267186)
			(xy 418.451545 -365.322362) (xy 418.435477 -365.375769) (xy 418.411805 -365.426266) (xy 418.381032 -365.472779)
			(xy 418.343815 -365.514316) (xy 418.300947 -365.549991) (xy 418.253341 -365.579045) (xy 418.202012 -365.600857)
			(xy 418.148055 -365.614963) (xy 418.092618 -365.621063) (xy 418.036884 -365.619026) (xy 417.982041 -365.608896)
			(xy 417.929257 -365.590889) (xy 417.879657 -365.565388) (xy 417.834299 -365.532937) (xy 417.79415 -365.494228)
			(xy 417.760064 -365.450085) (xy 417.732768 -365.40145) (xy 417.712845 -365.349359) (xy 417.700719 -365.294922)
			(xy 417.696648 -365.2393) (xy 415.471872 -365.2393) (xy 415.471004 -365.239669) (xy 415.417047 -365.253775)
			(xy 415.36161 -365.259875) (xy 415.305876 -365.257838) (xy 415.251033 -365.247708) (xy 415.198249 -365.229701)
			(xy 415.148649 -365.2042) (xy 415.103291 -365.171749) (xy 415.063142 -365.13304) (xy 415.029056 -365.088897)
			(xy 415.00176 -365.040262) (xy 414.981837 -364.988171) (xy 414.969711 -364.933734) (xy 414.96564 -364.878112)
			(xy 410.316172 -364.878112) (xy 411.400498 -365.962438) (xy 411.78302 -365.962438) (xy 411.787091 -365.906816)
			(xy 411.799217 -365.852379) (xy 411.81914 -365.800288) (xy 411.846436 -365.751653) (xy 411.880522 -365.70751)
			(xy 411.920671 -365.668801) (xy 411.966029 -365.63635) (xy 412.015629 -365.610849) (xy 412.068413 -365.592842)
			(xy 412.123256 -365.582712) (xy 412.17899 -365.580675) (xy 412.234427 -365.586775) (xy 412.288384 -365.600881)
			(xy 412.339713 -365.622693) (xy 412.387319 -365.651747) (xy 412.417899 -365.677196) (xy 416.787582 -365.677196)
			(xy 416.791653 -365.621574) (xy 416.803779 -365.567137) (xy 416.823702 -365.515046) (xy 416.850998 -365.466411)
			(xy 416.885084 -365.422268) (xy 416.925233 -365.383559) (xy 416.970591 -365.351108) (xy 417.020191 -365.325607)
			(xy 417.072975 -365.3076) (xy 417.127818 -365.29747) (xy 417.183552 -365.295433) (xy 417.238989 -365.301533)
			(xy 417.292946 -365.315639) (xy 417.344275 -365.337451) (xy 417.391881 -365.366505) (xy 417.434749 -365.40218)
			(xy 417.471966 -365.443717) (xy 417.502739 -365.49023) (xy 417.526411 -365.540727) (xy 417.542479 -365.594134)
			(xy 417.550599 -365.64931) (xy 417.551108 -365.677196) (xy 417.550599 -365.705082) (xy 417.542479 -365.760258)
			(xy 417.526411 -365.813665) (xy 417.502739 -365.864162) (xy 417.471966 -365.910675) (xy 417.434749 -365.952212)
			(xy 417.391881 -365.987887) (xy 417.344275 -366.016941) (xy 417.292946 -366.038753) (xy 417.238989 -366.052859)
			(xy 417.183552 -366.058959) (xy 417.127818 -366.056922) (xy 417.072975 -366.046792) (xy 417.020191 -366.028785)
			(xy 416.970591 -366.003284) (xy 416.925233 -365.970833) (xy 416.885084 -365.932124) (xy 416.850998 -365.887981)
			(xy 416.823702 -365.839346) (xy 416.803779 -365.787255) (xy 416.791653 -365.732818) (xy 416.787582 -365.677196)
			(xy 412.417899 -365.677196) (xy 412.430187 -365.687422) (xy 412.467404 -365.728959) (xy 412.498177 -365.775472)
			(xy 412.521849 -365.825969) (xy 412.537917 -365.879376) (xy 412.546037 -365.934552) (xy 412.546546 -365.962438)
			(xy 412.546037 -365.990324) (xy 412.537917 -366.0455) (xy 412.521849 -366.098907) (xy 412.498177 -366.149404)
			(xy 412.467404 -366.195917) (xy 412.430187 -366.237454) (xy 412.387319 -366.273129) (xy 412.339713 -366.302183)
			(xy 412.288384 -366.323995) (xy 412.234427 -366.338101) (xy 412.17899 -366.344201) (xy 412.123256 -366.342164)
			(xy 412.068413 -366.332034) (xy 412.015629 -366.314027) (xy 411.966029 -366.288526) (xy 411.920671 -366.256075)
			(xy 411.880522 -366.217366) (xy 411.846436 -366.173223) (xy 411.81914 -366.124588) (xy 411.799217 -366.072497)
			(xy 411.787091 -366.01806) (xy 411.78302 -365.962438) (xy 411.400498 -365.962438) (xy 412.24073 -366.80267)
			(xy 412.249046 -366.810228) (xy 412.270144 -366.817885) (xy 412.28137 -366.817402) (xy 412.292038 -366.815116)
			(xy 412.293816 -366.814608) (xy 412.341822 -366.79759) (xy 412.380176 -366.783874) (xy 412.386904 -366.781264)
			(xy 412.398644 -366.772885) (xy 412.40329 -366.767364) (xy 412.407608 -366.761776) (xy 412.412942 -366.748568)
			(xy 412.413704 -366.741202) (xy 412.417053 -366.713369) (xy 412.430865 -366.659039) (xy 412.452478 -366.607314)
			(xy 412.481426 -366.559308) (xy 412.517086 -366.516053) (xy 412.558691 -366.478482) (xy 412.605345 -366.447402)
			(xy 412.656045 -366.423483) (xy 412.709698 -366.407239) (xy 412.765151 -366.399019) (xy 412.79318 -366.398556)
			(xy 412.820433 -366.39904) (xy 412.874385 -366.406794) (xy 412.926684 -366.422147) (xy 412.976266 -366.444787)
			(xy 413.022122 -366.474252) (xy 413.063317 -366.509943) (xy 413.099014 -366.551133) (xy 413.128486 -366.596985)
			(xy 413.151133 -366.646563) (xy 413.166494 -366.69886) (xy 413.174256 -366.752811) (xy 413.174688 -366.780064)
			(xy 413.174195 -366.808094) (xy 413.165994 -366.86355) (xy 413.149763 -366.917208) (xy 413.125853 -366.967912)
			(xy 413.094777 -367.01457) (xy 413.057206 -367.056177) (xy 413.01395 -367.091835) (xy 412.965939 -367.120777)
			(xy 412.914209 -367.142379) (xy 412.859874 -367.156175) (xy 412.832042 -367.15954) (xy 412.831788 -367.15954)
			(xy 412.824767 -367.160513) (xy 412.811617 -367.165792) (xy 412.80588 -367.169954) (xy 412.800038 -367.174526)
			(xy 412.791656 -367.185956) (xy 412.75762 -367.282984) (xy 412.75553 -367.291721) (xy 412.756949 -367.309617)
			(xy 412.76448 -367.325913) (xy 412.770574 -367.332514) (xy 412.911544 -367.473484) (xy 415.2044 -367.473484)
			(xy 415.208471 -367.417862) (xy 415.220597 -367.363425) (xy 415.24052 -367.311334) (xy 415.267816 -367.262699)
			(xy 415.301902 -367.218556) (xy 415.342051 -367.179847) (xy 415.387409 -367.147396) (xy 415.437009 -367.121895)
			(xy 415.489793 -367.103888) (xy 415.544636 -367.093758) (xy 415.60037 -367.091721) (xy 415.655807 -367.097821)
			(xy 415.709764 -367.111927) (xy 415.761093 -367.133739) (xy 415.808699 -367.162793) (xy 415.851567 -367.198468)
			(xy 415.888784 -367.240005) (xy 415.919557 -367.286518) (xy 415.943229 -367.337015) (xy 415.959297 -367.390422)
			(xy 415.967417 -367.445598) (xy 415.967926 -367.473484) (xy 416.4744 -367.473484) (xy 416.478471 -367.417862)
			(xy 416.490597 -367.363425) (xy 416.51052 -367.311334) (xy 416.537816 -367.262699) (xy 416.571902 -367.218556)
			(xy 416.612051 -367.179847) (xy 416.657409 -367.147396) (xy 416.707009 -367.121895) (xy 416.759793 -367.103888)
			(xy 416.814636 -367.093758) (xy 416.87037 -367.091721) (xy 416.925807 -367.097821) (xy 416.979764 -367.111927)
			(xy 417.031093 -367.133739) (xy 417.078699 -367.162793) (xy 417.121567 -367.198468) (xy 417.158784 -367.240005)
			(xy 417.189557 -367.286518) (xy 417.213229 -367.337015) (xy 417.229297 -367.390422) (xy 417.237417 -367.445598)
			(xy 417.237773 -367.465102) (xy 418.560502 -367.465102) (xy 418.564573 -367.40948) (xy 418.576699 -367.355043)
			(xy 418.596622 -367.302952) (xy 418.623918 -367.254317) (xy 418.658004 -367.210174) (xy 418.698153 -367.171465)
			(xy 418.743511 -367.139014) (xy 418.793111 -367.113513) (xy 418.845895 -367.095506) (xy 418.900738 -367.085376)
			(xy 418.956472 -367.083339) (xy 419.011909 -367.089439) (xy 419.065866 -367.103545) (xy 419.117195 -367.125357)
			(xy 419.164801 -367.154411) (xy 419.207669 -367.190086) (xy 419.244886 -367.231623) (xy 419.275659 -367.278136)
			(xy 419.299331 -367.328633) (xy 419.315399 -367.38204) (xy 419.323519 -367.437216) (xy 419.324028 -367.465102)
			(xy 419.323519 -367.492988) (xy 419.315399 -367.548164) (xy 419.299331 -367.601571) (xy 419.275659 -367.652068)
			(xy 419.244886 -367.698581) (xy 419.207669 -367.740118) (xy 419.164801 -367.775793) (xy 419.117195 -367.804847)
			(xy 419.065866 -367.826659) (xy 419.011909 -367.840765) (xy 418.956472 -367.846865) (xy 418.900738 -367.844828)
			(xy 418.845895 -367.834698) (xy 418.793111 -367.816691) (xy 418.743511 -367.79119) (xy 418.698153 -367.758739)
			(xy 418.658004 -367.72003) (xy 418.623918 -367.675887) (xy 418.596622 -367.627252) (xy 418.576699 -367.575161)
			(xy 418.564573 -367.520724) (xy 418.560502 -367.465102) (xy 417.237773 -367.465102) (xy 417.237926 -367.473484)
			(xy 417.237417 -367.50137) (xy 417.229297 -367.556546) (xy 417.213229 -367.609953) (xy 417.189557 -367.66045)
			(xy 417.158784 -367.706963) (xy 417.121567 -367.7485) (xy 417.078699 -367.784175) (xy 417.031093 -367.813229)
			(xy 416.979764 -367.835041) (xy 416.925807 -367.849147) (xy 416.87037 -367.855247) (xy 416.814636 -367.85321)
			(xy 416.759793 -367.84308) (xy 416.707009 -367.825073) (xy 416.657409 -367.799572) (xy 416.612051 -367.767121)
			(xy 416.571902 -367.728412) (xy 416.537816 -367.684269) (xy 416.51052 -367.635634) (xy 416.490597 -367.583543)
			(xy 416.478471 -367.529106) (xy 416.4744 -367.473484) (xy 415.967926 -367.473484) (xy 415.967417 -367.50137)
			(xy 415.959297 -367.556546) (xy 415.943229 -367.609953) (xy 415.919557 -367.66045) (xy 415.888784 -367.706963)
			(xy 415.851567 -367.7485) (xy 415.808699 -367.784175) (xy 415.761093 -367.813229) (xy 415.709764 -367.835041)
			(xy 415.655807 -367.849147) (xy 415.60037 -367.855247) (xy 415.544636 -367.85321) (xy 415.489793 -367.84308)
			(xy 415.437009 -367.825073) (xy 415.387409 -367.799572) (xy 415.342051 -367.767121) (xy 415.301902 -367.728412)
			(xy 415.267816 -367.684269) (xy 415.24052 -367.635634) (xy 415.220597 -367.583543) (xy 415.208471 -367.529106)
			(xy 415.2044 -367.473484) (xy 412.911544 -367.473484) (xy 415.394648 -369.956588) (xy 415.397501 -369.959291)
			(xy 415.403883 -369.963876) (xy 415.407348 -369.965732) (xy 415.412775 -369.968313) (xy 415.424455 -369.971134)
			(xy 415.430462 -369.97132)
		)
		(stroke
			(width 0)
			(type solid)
		)
		(fill yes)
		(layer "In4.Cu")
		(net "GND")
	)
	(gr_poly
		(pts
			(xy 123.20143 -440.719972) (xy 123.211395 -440.719492) (xy 123.229826 -440.71191) (xy 123.237244 -440.70524)
			(xy 124.104146 -439.838338) (xy 124.110989 -439.830939) (xy 124.118709 -439.81234) (xy 124.119132 -439.80227)
			(xy 124.119132 -424.634914) (xy 124.119572 -424.624851) (xy 124.127311 -424.606273) (xy 124.134118 -424.598846)
			(xy 126.916434 -421.81653) (xy 126.923833 -421.809686) (xy 126.942431 -421.801959) (xy 126.952502 -421.801544)
			(xy 155.922726 -421.801544) (xy 155.932793 -421.801115) (xy 155.951385 -421.793387) (xy 155.958794 -421.786558)
			(xy 159.998918 -417.746434) (xy 160.006316 -417.739587) (xy 160.024914 -417.731853) (xy 160.034986 -417.731448)
			(xy 163.630102 -417.731448) (xy 163.63823 -417.728654) (xy 163.670682 -417.717904) (xy 163.737661 -417.704209)
			(xy 163.80587 -417.699617) (xy 163.874079 -417.704209) (xy 163.941058 -417.717904) (xy 163.97351 -417.728654)
			(xy 163.981638 -417.731448) (xy 165.248336 -417.731448) (xy 165.258402 -417.731879) (xy 165.276993 -417.739608)
			(xy 165.284404 -417.746434) (xy 165.890194 -418.352224) (xy 165.913054 -418.359844) (xy 165.924992 -418.358066)
			(xy 165.943552 -418.355463) (xy 165.980928 -418.352663) (xy 165.999668 -418.352478) (xy 166.031633 -418.352957)
			(xy 166.095058 -418.360966) (xy 166.156979 -418.376861) (xy 166.21642 -418.400392) (xy 166.272443 -418.431188)
			(xy 166.324164 -418.468762) (xy 166.370768 -418.512523) (xy 166.411519 -418.56178) (xy 166.445775 -418.615756)
			(xy 166.472996 -418.673601) (xy 166.492752 -418.734401) (xy 166.504731 -418.797197) (xy 166.508746 -418.861)
			(xy 166.504731 -418.924803) (xy 166.492752 -418.987599) (xy 166.472996 -419.048399) (xy 166.445775 -419.106244)
			(xy 166.411519 -419.16022) (xy 166.370768 -419.209477) (xy 166.324164 -419.253238) (xy 166.272443 -419.290812)
			(xy 166.21642 -419.321608) (xy 166.156979 -419.345139) (xy 166.095058 -419.361034) (xy 166.031633 -419.369043)
			(xy 165.999668 -419.369494) (xy 165.960298 -419.36797) (xy 165.949122 -419.367208) (xy 165.928294 -419.374828)
			(xy 165.876478 -419.426644) (xy 165.869666 -419.433988) (xy 165.861937 -419.452451) (xy 165.861492 -419.462458)
			(xy 165.861492 -419.557708) (xy 165.861875 -419.566846) (xy 165.868291 -419.583959) (xy 165.880304 -419.597732)
			(xy 165.888162 -419.602412) (xy 165.979094 -419.651688) (xy 166.007034 -419.650418) (xy 166.018718 -419.642798)
			(xy 166.043591 -419.627047) (xy 166.096266 -419.600748) (xy 166.151626 -419.580708) (xy 166.20893 -419.567195)
			(xy 166.26741 -419.560389) (xy 166.296848 -419.559994) (xy 166.328807 -419.560499) (xy 166.39222 -419.568515)
			(xy 166.454129 -419.584416) (xy 166.513557 -419.60795) (xy 166.569566 -419.638746) (xy 166.621275 -419.676319)
			(xy 166.667867 -419.720077) (xy 166.708608 -419.769328) (xy 166.742855 -419.823297) (xy 166.770068 -419.881132)
			(xy 166.789819 -419.941922) (xy 166.801795 -420.004708) (xy 166.805809 -420.0685) (xy 166.801795 -420.132292)
			(xy 166.789819 -420.195078) (xy 166.770068 -420.255868) (xy 166.742855 -420.313703) (xy 166.708608 -420.367672)
			(xy 166.667867 -420.416923) (xy 166.621275 -420.460681) (xy 166.569566 -420.498254) (xy 166.513557 -420.52905)
			(xy 166.454129 -420.552584) (xy 166.39222 -420.568485) (xy 166.328807 -420.576501) (xy 166.296848 -420.57701)
			(xy 166.265337 -420.576533) (xy 166.2028 -420.568739) (xy 166.141704 -420.553276) (xy 166.082988 -420.530383)
			(xy 166.027551 -420.500409) (xy 165.976243 -420.463814) (xy 165.92985 -420.421159) (xy 165.889084 -420.373098)
			(xy 165.85457 -420.320368) (xy 165.826836 -420.263777) (xy 165.806307 -420.204193) (xy 165.793299 -420.142528)
			(xy 165.790118 -420.111174) (xy 165.788848 -420.096442) (xy 165.771068 -420.073074) (xy 165.670484 -420.036244)
			(xy 165.661288 -420.033315) (xy 165.64201 -420.033833) (xy 165.624288 -420.041437) (xy 165.617144 -420.047928)
			(xy 163.243303 -422.421769) (xy 163.946834 -422.421769) (xy 163.946834 -422.357847) (xy 163.954845 -422.294429)
			(xy 163.970742 -422.232515) (xy 163.994274 -422.173082) (xy 164.025068 -422.117067) (xy 164.062641 -422.065352)
			(xy 164.106398 -422.018755) (xy 164.155651 -421.97801) (xy 164.209622 -421.943759) (xy 164.267461 -421.916542)
			(xy 164.328254 -421.896789) (xy 164.391044 -421.884811) (xy 164.45484 -421.880798) (xy 164.518636 -421.884811)
			(xy 164.581426 -421.896789) (xy 164.642219 -421.916542) (xy 164.700058 -421.943759) (xy 164.754029 -421.97801)
			(xy 164.803282 -422.018755) (xy 164.847039 -422.065352) (xy 164.884612 -422.117067) (xy 164.915406 -422.173082)
			(xy 164.938938 -422.232515) (xy 164.954835 -422.294429) (xy 164.962846 -422.357847) (xy 164.963348 -422.389808)
			(xy 164.962846 -422.421769) (xy 164.954835 -422.485187) (xy 164.938938 -422.547101) (xy 164.915406 -422.606534)
			(xy 164.884612 -422.662549) (xy 164.847039 -422.714264) (xy 164.803282 -422.760861) (xy 164.754029 -422.801606)
			(xy 164.700058 -422.835857) (xy 164.642219 -422.863074) (xy 164.581426 -422.882827) (xy 164.518636 -422.894805)
			(xy 164.45484 -422.898819) (xy 164.391044 -422.894805) (xy 164.328254 -422.882827) (xy 164.267461 -422.863074)
			(xy 164.209622 -422.835857) (xy 164.155651 -422.801606) (xy 164.106398 -422.760861) (xy 164.062641 -422.714264)
			(xy 164.025068 -422.662549) (xy 163.994274 -422.606534) (xy 163.970742 -422.547101) (xy 163.954845 -422.485187)
			(xy 163.946834 -422.421769) (xy 163.243303 -422.421769) (xy 163.121594 -422.543478) (xy 163.12134 -422.585388)
			(xy 163.136326 -422.600374) (xy 163.159218 -422.624245) (xy 163.199266 -422.676882) (xy 163.232146 -422.734269)
			(xy 163.257301 -422.795438) (xy 163.274306 -422.859354) (xy 163.282875 -422.924936) (xy 163.283392 -422.958006)
			(xy 163.282842 -422.991113) (xy 163.274218 -423.056762) (xy 163.257155 -423.12074) (xy 163.245038 -423.151554)
			(xy 163.240212 -423.163492) (xy 163.242752 -423.188384) (xy 163.30422 -423.280078) (xy 163.326318 -423.291762)
			(xy 163.339272 -423.291762) (xy 163.340796 -423.291762) (xy 163.372339 -423.292238) (xy 163.434942 -423.30004)
			(xy 163.496098 -423.315527) (xy 163.554869 -423.338459) (xy 163.610352 -423.368485) (xy 163.661695 -423.405144)
			(xy 163.708109 -423.447871) (xy 163.748882 -423.496012) (xy 163.783387 -423.548826) (xy 163.811094 -423.605503)
			(xy 163.831577 -423.665171) (xy 163.844523 -423.726916) (xy 163.849732 -423.789787) (xy 163.849297 -423.8003)
			(xy 163.974759 -423.8003) (xy 163.978773 -423.736501) (xy 163.990752 -423.673707) (xy 164.010506 -423.612911)
			(xy 164.037724 -423.555069) (xy 164.071977 -423.501095) (xy 164.112724 -423.451839) (xy 164.159324 -423.408079)
			(xy 164.21104 -423.370504) (xy 164.267058 -423.339708) (xy 164.326495 -423.316175) (xy 164.388412 -423.300277)
			(xy 164.451833 -423.292264) (xy 164.483796 -423.291762) (xy 164.514493 -423.292212) (xy 164.575438 -423.299621)
			(xy 164.635047 -423.314319) (xy 164.692451 -423.336092) (xy 164.746813 -423.364622) (xy 164.77234 -423.381678)
			(xy 164.781092 -423.387149) (xy 164.801296 -423.391277) (xy 164.8215 -423.387149) (xy 164.830252 -423.381678)
			(xy 164.855783 -423.364632) (xy 164.910152 -423.336122) (xy 164.967556 -423.314361) (xy 165.027161 -423.299662)
			(xy 165.088101 -423.292241) (xy 165.118796 -423.291762) (xy 165.150757 -423.292303) (xy 165.214174 -423.300314)
			(xy 165.276087 -423.31621) (xy 165.33552 -423.33974) (xy 165.391534 -423.370534) (xy 165.443248 -423.408106)
			(xy 165.489845 -423.451863) (xy 165.53059 -423.501115) (xy 165.564841 -423.555086) (xy 165.592057 -423.612923)
			(xy 165.61181 -423.673716) (xy 165.623788 -423.736505) (xy 165.627802 -423.8003) (xy 165.623788 -423.864095)
			(xy 165.61181 -423.926884) (xy 165.592057 -423.987677) (xy 165.564841 -424.045514) (xy 165.53059 -424.099485)
			(xy 165.489845 -424.148737) (xy 165.443248 -424.192494) (xy 165.391534 -424.230066) (xy 165.33552 -424.26086)
			(xy 165.276087 -424.28439) (xy 165.214174 -424.300286) (xy 165.150757 -424.308297) (xy 165.118796 -424.308778)
			(xy 165.0881 -424.308291) (xy 165.027156 -424.300893) (xy 164.967547 -424.286204) (xy 164.910143 -424.264439)
			(xy 164.85578 -424.235915) (xy 164.830252 -424.218862) (xy 164.8215 -424.213391) (xy 164.801296 -424.209263)
			(xy 164.781092 -424.213391) (xy 164.77234 -424.218862) (xy 164.746815 -424.235917) (xy 164.692443 -424.264423)
			(xy 164.635038 -424.286183) (xy 164.575432 -424.30088) (xy 164.514491 -424.3083) (xy 164.483796 -424.308778)
			(xy 164.451833 -424.308336) (xy 164.388412 -424.300323) (xy 164.326495 -424.284425) (xy 164.267058 -424.260892)
			(xy 164.21104 -424.230096) (xy 164.159324 -424.192521) (xy 164.112724 -424.148761) (xy 164.071977 -424.099505)
			(xy 164.037724 -424.045531) (xy 164.010506 -423.987689) (xy 163.990752 -423.926893) (xy 163.978773 -423.864099)
			(xy 163.974759 -423.8003) (xy 163.849297 -423.8003) (xy 163.847124 -423.85282) (xy 163.836739 -423.915046)
			(xy 163.818737 -423.975509) (xy 163.793394 -424.033282) (xy 163.7611 -424.087476) (xy 163.72235 -424.13726)
			(xy 163.67774 -424.181867) (xy 163.627955 -424.220615) (xy 163.573759 -424.252906) (xy 163.515985 -424.278246)
			(xy 163.45552 -424.296245) (xy 163.393294 -424.306627) (xy 163.330261 -424.309231) (xy 163.26739 -424.304019)
			(xy 163.205646 -424.291071) (xy 163.145979 -424.270584) (xy 163.089303 -424.242874) (xy 163.036491 -424.208366)
			(xy 162.988352 -424.167591) (xy 162.945627 -424.121175) (xy 162.908972 -424.06983) (xy 162.878948 -424.014345)
			(xy 162.856019 -423.955573) (xy 162.840536 -423.894416) (xy 162.832736 -423.831813) (xy 162.832288 -423.80027)
			(xy 162.83284 -423.767164) (xy 162.841466 -423.701515) (xy 162.858531 -423.637539) (xy 162.870642 -423.606722)
			(xy 162.875468 -423.594784) (xy 162.872928 -423.569892) (xy 162.81146 -423.478198) (xy 162.789362 -423.466514)
			(xy 162.776408 -423.466514) (xy 162.774884 -423.466514) (xy 162.741815 -423.465983) (xy 162.676235 -423.457407)
			(xy 162.612321 -423.4404) (xy 162.551151 -423.415251) (xy 162.493758 -423.382383) (xy 162.441111 -423.342352)
			(xy 162.417252 -423.319448) (xy 162.402266 -423.304462) (xy 162.360356 -423.304716) (xy 161.16935 -424.495722)
			(xy 161.161829 -424.503983) (xy 161.154181 -424.524945) (xy 161.154618 -424.536108) (xy 161.162238 -424.624754)
			(xy 161.17316 -424.644058) (xy 161.182558 -424.650662) (xy 161.207116 -424.668557) (xy 161.252212 -424.709287)
			(xy 161.292134 -424.755099) (xy 161.326314 -424.805342) (xy 161.354265 -424.859298) (xy 161.375589 -424.9162)
			(xy 161.389981 -424.975237) (xy 161.397238 -425.035569) (xy 161.397696 -425.065952) (xy 161.397197 -425.097807)
			(xy 161.389228 -425.161018) (xy 161.373423 -425.222738) (xy 161.350028 -425.281998) (xy 161.31941 -425.337869)
			(xy 161.28205 -425.389477) (xy 161.238533 -425.436011) (xy 161.189542 -425.476741) (xy 161.135845 -425.51103)
			(xy 161.078284 -425.538339) (xy 161.048192 -425.548806) (xy 161.032444 -425.55414) (xy 161.013394 -425.580556)
			(xy 161.013394 -427.408848) (xy 161.013922 -427.41884) (xy 161.021622 -427.437286) (xy 161.02838 -427.444662)
			(xy 161.105369 -427.521651) (xy 161.997101 -427.521651) (xy 161.997101 -427.467149) (xy 162.004858 -427.413201)
			(xy 162.020214 -427.360907) (xy 162.042857 -427.31133) (xy 162.072324 -427.265481) (xy 162.108018 -427.224292)
			(xy 162.14921 -427.188603) (xy 162.195062 -427.159139) (xy 162.244641 -427.136502) (xy 162.296936 -427.121151)
			(xy 162.350885 -427.113399) (xy 162.378136 -427.112938) (xy 162.404035 -427.113352) (xy 162.455357 -427.12036)
			(xy 162.505261 -427.134243) (xy 162.552829 -427.154746) (xy 162.597188 -427.181492) (xy 162.637524 -427.21399)
			(xy 162.673095 -427.251643) (xy 162.688524 -427.27245) (xy 162.696692 -427.283161) (xy 162.717554 -427.30019)
			(xy 162.742143 -427.31117) (xy 162.768748 -427.315337) (xy 162.795517 -427.312401) (xy 162.820586 -427.302565)
			(xy 162.84221 -427.286516) (xy 162.858883 -427.265369) (xy 162.864546 -427.253146) (xy 162.877969 -427.222974)
			(xy 162.911474 -427.166065) (xy 162.952064 -427.113974) (xy 162.999058 -427.067577) (xy 163.051663 -427.027655)
			(xy 163.108994 -426.99488) (xy 163.170087 -426.969803) (xy 163.233912 -426.952848) (xy 163.299395 -426.9443)
			(xy 163.332414 -426.943774) (xy 163.364373 -426.944313) (xy 163.427788 -426.952325) (xy 163.489698 -426.968223)
			(xy 163.549128 -426.991754) (xy 163.605139 -427.022548) (xy 163.65685 -427.06012) (xy 163.703444 -427.103876)
			(xy 163.744187 -427.153126) (xy 163.778436 -427.207095) (xy 163.80565 -427.26493) (xy 163.825402 -427.325721)
			(xy 163.837379 -427.388507) (xy 163.841393 -427.4523) (xy 163.837379 -427.516093) (xy 163.825402 -427.578879)
			(xy 163.80565 -427.63967) (xy 163.778436 -427.697505) (xy 163.744187 -427.751474) (xy 163.703444 -427.800724)
			(xy 163.65685 -427.84448) (xy 163.605139 -427.882052) (xy 163.549128 -427.912846) (xy 163.489698 -427.936377)
			(xy 163.427788 -427.952275) (xy 163.364373 -427.960287) (xy 163.332414 -427.96079) (xy 163.301884 -427.960336)
			(xy 163.241264 -427.953026) (xy 163.181956 -427.938508) (xy 163.124813 -427.916993) (xy 163.070658 -427.888789)
			(xy 163.02027 -427.854303) (xy 162.974374 -427.814031) (xy 162.933632 -427.768552) (xy 162.898629 -427.718522)
			(xy 162.88385 -427.691804) (xy 162.877086 -427.680147) (xy 162.85862 -427.660536) (xy 162.83566 -427.646447)
			(xy 162.809812 -427.638865) (xy 162.78288 -427.638319) (xy 162.756746 -427.644848) (xy 162.733235 -427.657996)
			(xy 162.713989 -427.676843) (xy 162.706812 -427.688248) (xy 162.691979 -427.712356) (xy 162.656331 -427.756323)
			(xy 162.614581 -427.794542) (xy 162.567644 -427.826176) (xy 162.516549 -427.850531) (xy 162.462418 -427.867072)
			(xy 162.406437 -427.875437) (xy 162.378136 -427.875954) (xy 162.350885 -427.875401) (xy 162.296936 -427.867649)
			(xy 162.244641 -427.852298) (xy 162.195062 -427.829661) (xy 162.14921 -427.800197) (xy 162.108018 -427.764508)
			(xy 162.072324 -427.723319) (xy 162.042857 -427.67747) (xy 162.020214 -427.627893) (xy 162.004858 -427.575599)
			(xy 161.997101 -427.521651) (xy 161.105369 -427.521651) (xy 161.635948 -428.05223) (xy 161.652993 -428.069945)
			(xy 161.681859 -428.109736) (xy 161.704139 -428.153556) (xy 161.719286 -428.200323) (xy 161.726925 -428.248884)
			(xy 161.727388 -428.273464) (xy 161.727388 -430.573688) (xy 161.727926 -430.584708) (xy 161.73714 -430.604729)
			(xy 161.745168 -430.612296) (xy 161.768706 -430.633026) (xy 161.81101 -430.679335) (xy 161.847296 -430.730497)
			(xy 161.877014 -430.785733) (xy 161.899712 -430.844205) (xy 161.915046 -430.905025) (xy 161.922782 -430.967269)
			(xy 161.923222 -430.99863) (xy 161.922756 -431.02936) (xy 161.915345 -431.090372) (xy 161.900634 -431.150046)
			(xy 161.878837 -431.207511) (xy 161.850273 -431.261931) (xy 161.815359 -431.312511) (xy 161.774602 -431.358513)
			(xy 161.728598 -431.399269) (xy 161.678017 -431.434182) (xy 161.623597 -431.462744) (xy 161.56613 -431.484538)
			(xy 161.506456 -431.499248) (xy 161.445444 -431.506657) (xy 161.414714 -431.507138) (xy 161.382044 -431.506654)
			(xy 161.317239 -431.498322) (xy 161.254035 -431.481755) (xy 161.193475 -431.457226) (xy 161.164778 -431.441606)
			(xy 161.153094 -431.434748) (xy 161.12617 -431.435002) (xy 161.03854 -431.486056) (xy 161.031045 -431.490809)
			(xy 161.019693 -431.504438) (xy 161.01369 -431.521128) (xy 161.013394 -431.529998) (xy 161.013394 -432.008491)
			(xy 161.897308 -432.008491) (xy 161.897308 -431.944569) (xy 161.905319 -431.881151) (xy 161.921216 -431.819237)
			(xy 161.944748 -431.759804) (xy 161.975542 -431.703789) (xy 162.013115 -431.652074) (xy 162.056872 -431.605477)
			(xy 162.106125 -431.564732) (xy 162.160096 -431.530481) (xy 162.217935 -431.503264) (xy 162.278728 -431.483511)
			(xy 162.341518 -431.471533) (xy 162.405314 -431.46752) (xy 162.46911 -431.471533) (xy 162.5319 -431.483511)
			(xy 162.592693 -431.503264) (xy 162.650532 -431.530481) (xy 162.704503 -431.564732) (xy 162.753756 -431.605477)
			(xy 162.797513 -431.652074) (xy 162.835086 -431.703789) (xy 162.86588 -431.759804) (xy 162.889412 -431.819237)
			(xy 162.905309 -431.881151) (xy 162.91332 -431.944569) (xy 162.913822 -431.97653) (xy 162.91332 -432.008491)
			(xy 162.905309 -432.071909) (xy 162.889412 -432.133823) (xy 162.86588 -432.193256) (xy 162.835086 -432.249271)
			(xy 162.797513 -432.300986) (xy 162.753756 -432.347583) (xy 162.704503 -432.388328) (xy 162.650532 -432.422579)
			(xy 162.592693 -432.449796) (xy 162.5319 -432.469549) (xy 162.46911 -432.481527) (xy 162.405314 -432.485541)
			(xy 162.341518 -432.481527) (xy 162.278728 -432.469549) (xy 162.217935 -432.449796) (xy 162.160096 -432.422579)
			(xy 162.106125 -432.388328) (xy 162.056872 -432.347583) (xy 162.013115 -432.300986) (xy 161.975542 -432.249271)
			(xy 161.944748 -432.193256) (xy 161.921216 -432.133823) (xy 161.905319 -432.071909) (xy 161.897308 -432.008491)
			(xy 161.013394 -432.008491) (xy 161.013394 -433.939442) (xy 161.013939 -433.949426) (xy 161.021662 -433.967848)
			(xy 161.02838 -433.975256) (xy 161.20872 -434.155596) (xy 164.598096 -434.155596) (xy 164.598608 -434.127101)
			(xy 164.607065 -434.070743) (xy 164.62382 -434.016273) (xy 164.648499 -433.964905) (xy 164.680552 -433.917785)
			(xy 164.719265 -433.875963) (xy 164.763774 -433.840372) (xy 164.813086 -433.811805) (xy 164.866102 -433.7909)
			(xy 164.893752 -433.783994) (xy 164.907058 -433.78039) (xy 164.93124 -433.767182) (xy 164.951016 -433.747995)
			(xy 164.964947 -433.724222) (xy 164.972022 -433.697592) (xy 164.971727 -433.670039) (xy 164.964083 -433.643567)
			(xy 164.957252 -433.631594) (xy 164.939385 -433.601408) (xy 164.911172 -433.537187) (xy 164.892059 -433.469697)
			(xy 164.882407 -433.40022) (xy 164.881814 -433.365148) (xy 164.882316 -433.333187) (xy 164.890327 -433.269769)
			(xy 164.906224 -433.207855) (xy 164.929756 -433.148422) (xy 164.96055 -433.092407) (xy 164.998123 -433.040692)
			(xy 165.04188 -432.994095) (xy 165.091133 -432.95335) (xy 165.145104 -432.919099) (xy 165.202943 -432.891882)
			(xy 165.263736 -432.872129) (xy 165.326526 -432.860151) (xy 165.390322 -432.856138) (xy 165.454118 -432.860151)
			(xy 165.516908 -432.872129) (xy 165.577701 -432.891882) (xy 165.63554 -432.919099) (xy 165.689511 -432.95335)
			(xy 165.738764 -432.994095) (xy 165.782521 -433.040692) (xy 165.820094 -433.092407) (xy 165.850888 -433.148422)
			(xy 165.87442 -433.207855) (xy 165.890317 -433.269769) (xy 165.898328 -433.333187) (xy 165.89883 -433.365148)
			(xy 165.898284 -433.397153) (xy 165.890233 -433.460656) (xy 165.874277 -433.522646) (xy 165.850669 -433.582145)
			(xy 165.819781 -433.63821) (xy 165.782101 -433.689956) (xy 165.738227 -433.736565) (xy 165.68885 -433.7773)
			(xy 165.634752 -433.811517) (xy 165.576788 -433.838675) (xy 165.515874 -433.858345) (xy 165.452973 -433.870216)
			(xy 165.421056 -433.87264) (xy 165.407331 -433.874007) (xy 165.381262 -433.88296) (xy 165.358545 -433.898571)
			(xy 165.340841 -433.919697) (xy 165.329445 -433.944795) (xy 165.32519 -433.972029) (xy 165.328389 -433.999407)
			(xy 165.333172 -434.01234) (xy 165.342022 -434.035174) (xy 165.354462 -434.08254) (xy 165.360734 -434.13111)
			(xy 165.361112 -434.155596) (xy 165.360626 -434.182847) (xy 165.35287 -434.236795) (xy 165.337515 -434.28909)
			(xy 165.314873 -434.338667) (xy 165.285407 -434.384517) (xy 165.249716 -434.425708) (xy 165.208525 -434.461399)
			(xy 165.162675 -434.490865) (xy 165.113098 -434.513507) (xy 165.060803 -434.528862) (xy 165.006855 -434.536618)
			(xy 164.952353 -434.536618) (xy 164.898405 -434.528862) (xy 164.84611 -434.513507) (xy 164.796533 -434.490865)
			(xy 164.750683 -434.461399) (xy 164.709492 -434.425708) (xy 164.673801 -434.384517) (xy 164.644335 -434.338667)
			(xy 164.621693 -434.28909) (xy 164.606338 -434.236795) (xy 164.598582 -434.182847) (xy 164.598096 -434.155596)
			(xy 161.20872 -434.155596) (xy 161.338514 -434.28539) (xy 161.359342 -434.29301) (xy 161.370518 -434.292248)
			(xy 161.409888 -434.290724) (xy 161.441849 -434.291204) (xy 161.505267 -434.299214) (xy 161.56718 -434.31511)
			(xy 161.626614 -434.33864) (xy 161.682629 -434.369433) (xy 161.734343 -434.407005) (xy 161.780941 -434.450762)
			(xy 161.821686 -434.500014) (xy 161.855938 -434.553984) (xy 161.883155 -434.611822) (xy 161.902908 -434.672615)
			(xy 161.914886 -434.735404) (xy 161.9189 -434.7992) (xy 161.914886 -434.862996) (xy 161.902908 -434.925785)
			(xy 161.883155 -434.986578) (xy 161.855938 -435.044416) (xy 161.821686 -435.098386) (xy 161.780941 -435.147638)
			(xy 161.734343 -435.191395) (xy 161.682629 -435.228967) (xy 161.626614 -435.25976) (xy 161.56718 -435.28329)
			(xy 161.505267 -435.299186) (xy 161.441849 -435.307196) (xy 161.409888 -435.30774) (xy 161.377802 -435.30727)
			(xy 161.314134 -435.299234) (xy 161.251984 -435.283254) (xy 161.192337 -435.259583) (xy 161.164016 -435.244494)
			(xy 161.152332 -435.23789) (xy 161.125408 -435.238144) (xy 161.038286 -435.289452) (xy 161.030875 -435.294278)
			(xy 161.019635 -435.307914) (xy 161.013695 -435.324557) (xy 161.013394 -435.333394) (xy 161.013394 -435.537208)
			(xy 167.01862 -435.537208) (xy 167.021228 -435.474184) (xy 167.031612 -435.411966) (xy 167.049611 -435.35151)
			(xy 167.07495 -435.293745) (xy 167.10724 -435.239558) (xy 167.145984 -435.18978) (xy 167.190588 -435.145177)
			(xy 167.240366 -435.106434) (xy 167.294554 -435.074146) (xy 167.35232 -435.048808) (xy 167.412776 -435.030809)
			(xy 167.474994 -435.020427) (xy 167.538018 -435.01782) (xy 167.600881 -435.023029) (xy 167.662617 -435.035973)
			(xy 167.722278 -435.056455) (xy 167.778948 -435.084158) (xy 167.831755 -435.118658) (xy 167.87989 -435.159425)
			(xy 167.922612 -435.205833) (xy 167.959266 -435.257169) (xy 167.989289 -435.312644) (xy 168.01222 -435.371407)
			(xy 168.027706 -435.432555) (xy 168.03551 -435.495149) (xy 168.035986 -435.526688) (xy 168.03563 -435.554231)
			(xy 168.029651 -435.608991) (xy 168.017783 -435.662783) (xy 168.009316 -435.688994) (xy 168.005506 -435.700678)
			(xy 168.009062 -435.724808) (xy 168.072054 -435.81193) (xy 168.093898 -435.822852) (xy 168.10863 -435.822852)
			(xy 168.13588 -435.82335) (xy 168.189825 -435.831109) (xy 168.242117 -435.846466) (xy 168.291692 -435.869108)
			(xy 168.33754 -435.898574) (xy 168.378729 -435.934264) (xy 168.41442 -435.975452) (xy 168.443887 -436.021299)
			(xy 168.46653 -436.070873) (xy 168.481889 -436.123165) (xy 168.48965 -436.17711) (xy 168.490138 -436.20436)
			(xy 168.48966 -436.232293) (xy 168.481511 -436.287561) (xy 168.465396 -436.341052) (xy 168.441659 -436.391625)
			(xy 168.426638 -436.41518) (xy 168.42105 -436.423816) (xy 168.41724 -436.443374) (xy 168.436036 -436.534306)
			(xy 168.447212 -436.550816) (xy 168.455848 -436.556404) (xy 168.482091 -436.574011) (xy 168.530376 -436.614787)
			(xy 168.573236 -436.661231) (xy 168.610011 -436.712627) (xy 168.640136 -436.768185) (xy 168.663144 -436.827046)
			(xy 168.678682 -436.888305) (xy 168.68651 -436.951017) (xy 168.686988 -436.982616) (xy 168.686577 -437.013349)
			(xy 168.679166 -437.074367) (xy 168.664455 -437.134047) (xy 168.642656 -437.191519) (xy 168.61409 -437.245943)
			(xy 168.579171 -437.296528) (xy 168.53841 -437.342535) (xy 168.4924 -437.383293) (xy 168.441813 -437.418208)
			(xy 168.387386 -437.446771) (xy 168.329913 -437.468565) (xy 168.270232 -437.483273) (xy 168.209213 -437.49068)
			(xy 168.17848 -437.491124) (xy 168.144934 -437.490606) (xy 168.078421 -437.481811) (xy 168.045892 -437.473598)
			(xy 168.03624 -437.471058) (xy 168.016682 -437.473344) (xy 167.937434 -437.517286) (xy 167.924988 -437.53278)
			(xy 167.922194 -437.542432) (xy 167.913857 -437.568213) (xy 167.891023 -437.617347) (xy 167.861467 -437.662757)
			(xy 167.825784 -437.703528) (xy 167.784692 -437.738841) (xy 167.739016 -437.767984) (xy 167.689678 -437.790373)
			(xy 167.637667 -437.805555) (xy 167.584032 -437.813227) (xy 167.556942 -437.813704) (xy 167.529687 -437.813252)
			(xy 167.475731 -437.805499) (xy 167.423427 -437.790147) (xy 167.373842 -437.767506) (xy 167.327983 -437.738039)
			(xy 167.286785 -437.702345) (xy 167.251086 -437.661151) (xy 167.221614 -437.615295) (xy 167.198968 -437.565712)
			(xy 167.18361 -437.51341) (xy 167.175851 -437.459455) (xy 167.175851 -437.404945) (xy 167.18361 -437.35099)
			(xy 167.198968 -437.298688) (xy 167.221614 -437.249105) (xy 167.251086 -437.203249) (xy 167.286785 -437.162055)
			(xy 167.327983 -437.126361) (xy 167.373842 -437.096894) (xy 167.423427 -437.074253) (xy 167.475731 -437.058901)
			(xy 167.529687 -437.051148) (xy 167.556942 -437.050688) (xy 167.566594 -437.050688) (xy 167.576754 -437.050942)
			(xy 167.595042 -437.044084) (xy 167.661844 -436.982616) (xy 167.670226 -436.964836) (xy 167.670734 -436.95493)
			(xy 167.672967 -436.922761) (xy 167.68459 -436.859331) (xy 167.70414 -436.79788) (xy 167.731304 -436.739394)
			(xy 167.765645 -436.684813) (xy 167.806612 -436.635012) (xy 167.829738 -436.612538) (xy 167.837104 -436.60568)
			(xy 167.845232 -436.587138) (xy 167.847518 -436.494682) (xy 167.840406 -436.475886) (xy 167.833294 -436.46852)
			(xy 167.81348 -436.447078) (xy 167.779967 -436.399275) (xy 167.754126 -436.346925) (xy 167.736558 -436.291251)
			(xy 167.727674 -436.23355) (xy 167.727122 -436.20436) (xy 167.727273 -436.189181) (xy 167.729691 -436.158919)
			(xy 167.731948 -436.143908) (xy 167.73398 -436.131716) (xy 167.72636 -436.108348) (xy 167.649906 -436.03291)
			(xy 167.626538 -436.025544) (xy 167.614346 -436.02783) (xy 167.592797 -436.0313) (xy 167.549303 -436.034985)
			(xy 167.527478 -436.035196) (xy 167.495939 -436.034709) (xy 167.433345 -436.026904) (xy 167.372197 -436.011417)
			(xy 167.313435 -435.988485) (xy 167.25796 -435.958461) (xy 167.206625 -435.921806) (xy 167.160218 -435.879082)
			(xy 167.119452 -435.830947) (xy 167.084953 -435.778139) (xy 167.057251 -435.721469) (xy 167.036771 -435.661808)
			(xy 167.023828 -435.600072) (xy 167.01862 -435.537208) (xy 161.013394 -435.537208) (xy 161.013394 -436.430166)
			(xy 165.86784 -436.430166) (xy 165.871911 -436.374544) (xy 165.884037 -436.320107) (xy 165.90396 -436.268016)
			(xy 165.931256 -436.219381) (xy 165.965342 -436.175238) (xy 166.005491 -436.136529) (xy 166.050849 -436.104078)
			(xy 166.100449 -436.078577) (xy 166.153233 -436.06057) (xy 166.208076 -436.05044) (xy 166.26381 -436.048403)
			(xy 166.319247 -436.054503) (xy 166.373204 -436.068609) (xy 166.424533 -436.090421) (xy 166.472139 -436.119475)
			(xy 166.515007 -436.15515) (xy 166.552224 -436.196687) (xy 166.582997 -436.2432) (xy 166.606669 -436.293697)
			(xy 166.622737 -436.347104) (xy 166.630857 -436.40228) (xy 166.631366 -436.430166) (xy 166.630857 -436.458052)
			(xy 166.622737 -436.513228) (xy 166.606669 -436.566635) (xy 166.582997 -436.617132) (xy 166.552224 -436.663645)
			(xy 166.515007 -436.705182) (xy 166.472139 -436.740857) (xy 166.424533 -436.769911) (xy 166.373204 -436.791723)
			(xy 166.319247 -436.805829) (xy 166.26381 -436.811929) (xy 166.208076 -436.809892) (xy 166.153233 -436.799762)
			(xy 166.100449 -436.781755) (xy 166.050849 -436.756254) (xy 166.005491 -436.723803) (xy 165.965342 -436.685094)
			(xy 165.931256 -436.640951) (xy 165.90396 -436.592316) (xy 165.884037 -436.540225) (xy 165.871911 -436.485788)
			(xy 165.86784 -436.430166) (xy 161.013394 -436.430166) (xy 161.013394 -436.846726) (xy 161.013768 -436.855485)
			(xy 161.01966 -436.871986) (xy 161.030724 -436.885571) (xy 161.038032 -436.890414) (xy 161.124646 -436.941976)
			(xy 161.151062 -436.942738) (xy 161.163 -436.936134) (xy 161.190909 -436.921906) (xy 161.250217 -436.901746)
			(xy 161.31202 -436.891532) (xy 161.34334 -436.890922) (xy 161.370587 -436.891411) (xy 161.424526 -436.899171)
			(xy 161.476812 -436.914529) (xy 161.52638 -436.93717) (xy 161.572222 -436.966635) (xy 161.613404 -437.002324)
			(xy 161.649089 -437.04351) (xy 161.678549 -437.089355) (xy 161.701185 -437.138925) (xy 161.716537 -437.191213)
			(xy 161.724292 -437.245153) (xy 161.724292 -437.299647) (xy 161.716537 -437.353587) (xy 161.701185 -437.405875)
			(xy 161.678549 -437.455445) (xy 161.649089 -437.50129) (xy 161.613404 -437.542476) (xy 161.572222 -437.578165)
			(xy 161.52638 -437.60763) (xy 161.476812 -437.630271) (xy 161.424526 -437.645629) (xy 161.370587 -437.653389)
			(xy 161.34334 -437.653938) (xy 161.312018 -437.653332) (xy 161.250209 -437.64314) (xy 161.190899 -437.622976)
			(xy 161.163 -437.608726) (xy 161.151062 -437.602122) (xy 161.124646 -437.602884) (xy 161.038032 -437.654446)
			(xy 161.03068 -437.659251) (xy 161.019543 -437.672814) (xy 161.013683 -437.689357) (xy 161.013394 -437.698134)
			(xy 161.013394 -438.241905) (xy 163.315644 -438.241905) (xy 163.315644 -438.177983) (xy 163.323655 -438.114565)
			(xy 163.339552 -438.052651) (xy 163.363084 -437.993218) (xy 163.393878 -437.937203) (xy 163.431451 -437.885488)
			(xy 163.475208 -437.838891) (xy 163.524461 -437.798146) (xy 163.578432 -437.763895) (xy 163.636271 -437.736678)
			(xy 163.697064 -437.716925) (xy 163.759854 -437.704947) (xy 163.82365 -437.700934) (xy 163.887446 -437.704947)
			(xy 163.950236 -437.716925) (xy 164.011029 -437.736678) (xy 164.068868 -437.763895) (xy 164.122839 -437.798146)
			(xy 164.172092 -437.838891) (xy 164.215849 -437.885488) (xy 164.253422 -437.937203) (xy 164.284216 -437.993218)
			(xy 164.307748 -438.052651) (xy 164.323645 -438.114565) (xy 164.331656 -438.177983) (xy 164.332158 -438.209944)
			(xy 164.331656 -438.241905) (xy 164.323645 -438.305323) (xy 164.307748 -438.367237) (xy 164.284216 -438.42667)
			(xy 164.253422 -438.482685) (xy 164.215849 -438.5344) (xy 164.172092 -438.580997) (xy 164.122839 -438.621742)
			(xy 164.068868 -438.655993) (xy 164.011029 -438.68321) (xy 163.950236 -438.702963) (xy 163.887446 -438.714941)
			(xy 163.82365 -438.718955) (xy 163.759854 -438.714941) (xy 163.697064 -438.702963) (xy 163.636271 -438.68321)
			(xy 163.578432 -438.655993) (xy 163.524461 -438.621742) (xy 163.475208 -438.580997) (xy 163.431451 -438.5344)
			(xy 163.393878 -438.482685) (xy 163.363084 -438.42667) (xy 163.339552 -438.367237) (xy 163.323655 -438.305323)
			(xy 163.315644 -438.241905) (xy 161.013394 -438.241905) (xy 161.013394 -438.912) (xy 165.863014 -438.912)
			(xy 165.867085 -438.856378) (xy 165.879211 -438.801941) (xy 165.899134 -438.74985) (xy 165.92643 -438.701215)
			(xy 165.960516 -438.657072) (xy 166.000665 -438.618363) (xy 166.046023 -438.585912) (xy 166.095623 -438.560411)
			(xy 166.148407 -438.542404) (xy 166.20325 -438.532274) (xy 166.258984 -438.530237) (xy 166.314421 -438.536337)
			(xy 166.368378 -438.550443) (xy 166.419707 -438.572255) (xy 166.467313 -438.601309) (xy 166.510181 -438.636984)
			(xy 166.547398 -438.678521) (xy 166.578171 -438.725034) (xy 166.601843 -438.775531) (xy 166.617911 -438.828938)
			(xy 166.626031 -438.884114) (xy 166.62654 -438.912) (xy 166.626031 -438.939886) (xy 166.617911 -438.995062)
			(xy 166.601843 -439.048469) (xy 166.578171 -439.098966) (xy 166.547398 -439.145479) (xy 166.510181 -439.187016)
			(xy 166.467313 -439.222691) (xy 166.419707 -439.251745) (xy 166.368378 -439.273557) (xy 166.314421 -439.287663)
			(xy 166.258984 -439.293763) (xy 166.20325 -439.291726) (xy 166.148407 -439.281596) (xy 166.095623 -439.263589)
			(xy 166.046023 -439.238088) (xy 166.000665 -439.205637) (xy 165.960516 -439.166928) (xy 165.92643 -439.122785)
			(xy 165.899134 -439.07415) (xy 165.879211 -439.022059) (xy 165.867085 -438.967622) (xy 165.863014 -438.912)
			(xy 161.013394 -438.912) (xy 161.013394 -438.9882) (xy 161.013817 -438.99827) (xy 161.02153 -439.016876)
			(xy 161.02838 -439.024268) (xy 162.034474 -440.030362) (xy 162.041875 -440.037201) (xy 162.060473 -440.044914)
			(xy 162.070542 -440.045348) (xy 167.16629 -440.045348) (xy 167.192198 -440.02706) (xy 167.197786 -440.011566)
			(xy 167.207191 -439.986709) (xy 167.2319 -439.939656) (xy 167.262892 -439.896482) (xy 167.299568 -439.85802)
			(xy 167.341221 -439.825013) (xy 167.363902 -439.81116) (xy 167.37203 -439.806588) (xy 167.38346 -439.792618)
			(xy 167.410638 -439.711592) (xy 167.409876 -439.693558) (xy 167.40632 -439.684922) (xy 167.394107 -439.653955)
			(xy 167.376916 -439.589645) (xy 167.368256 -439.523642) (xy 167.367712 -439.490358) (xy 167.36823 -439.457513)
			(xy 167.376695 -439.392371) (xy 167.393478 -439.328862) (xy 167.4183 -439.268042) (xy 167.450748 -439.210926)
			(xy 167.490281 -439.158464) (xy 167.536241 -439.111529) (xy 167.587862 -439.070904) (xy 167.644285 -439.037266)
			(xy 167.704571 -439.011173) (xy 167.736012 -439.001662) (xy 167.744902 -438.999122) (xy 167.75938 -438.9882)
			(xy 167.805862 -438.917334) (xy 167.809926 -438.899808) (xy 167.808656 -438.890664) (xy 167.807106 -438.878149)
			(xy 167.805455 -438.852982) (xy 167.805354 -438.840372) (xy 167.80584 -438.813121) (xy 167.813596 -438.759173)
			(xy 167.828951 -438.706878) (xy 167.851593 -438.657301) (xy 167.881059 -438.611451) (xy 167.91675 -438.57026)
			(xy 167.957941 -438.534569) (xy 168.003791 -438.505103) (xy 168.053368 -438.482461) (xy 168.105663 -438.467106)
			(xy 168.159611 -438.45935) (xy 168.214113 -438.45935) (xy 168.268061 -438.467106) (xy 168.320356 -438.482461)
			(xy 168.369933 -438.505103) (xy 168.415783 -438.534569) (xy 168.456974 -438.57026) (xy 168.492665 -438.611451)
			(xy 168.522131 -438.657301) (xy 168.544773 -438.706878) (xy 168.560128 -438.759173) (xy 168.567884 -438.813121)
			(xy 168.56837 -438.840372) (xy 168.567863 -438.868278) (xy 168.559742 -438.923497) (xy 168.54367 -438.976946)
			(xy 168.519988 -439.027485) (xy 168.489201 -439.074039) (xy 168.451965 -439.115615) (xy 168.409073 -439.151328)
			(xy 168.38549 -439.166254) (xy 168.377362 -439.17108) (xy 168.366186 -439.185304) (xy 168.340278 -439.265822)
			(xy 168.34104 -439.283856) (xy 168.344596 -439.292492) (xy 168.357287 -439.323919) (xy 168.375164 -439.389295)
			(xy 168.384179 -439.45647) (xy 168.384728 -439.490358) (xy 168.384279 -439.520795) (xy 168.377011 -439.581235)
			(xy 168.362584 -439.640376) (xy 168.341205 -439.697373) (xy 168.31318 -439.751413) (xy 168.278908 -439.801725)
			(xy 168.238879 -439.847588) (xy 168.21658 -439.86831) (xy 168.204642 -439.878978) (xy 168.197276 -439.909458)
			(xy 168.237154 -440.012836) (xy 168.241241 -440.022195) (xy 168.255415 -440.036872) (xy 168.274196 -440.044845)
			(xy 168.284398 -440.045348) (xy 171.168822 -440.045348) (xy 171.178889 -440.044919) (xy 171.197483 -440.037194)
			(xy 171.20489 -440.030362) (xy 173.247304 -437.987948) (xy 173.254142 -437.980546) (xy 173.261857 -437.961948)
			(xy 173.26229 -437.95188) (xy 173.26229 -434.256434) (xy 173.262725 -434.246369) (xy 173.270455 -434.227781)
			(xy 173.277276 -434.220366) (xy 177.280824 -430.216818) (xy 177.288223 -430.209973) (xy 177.306821 -430.202245)
			(xy 177.316892 -430.201832) (xy 182.677562 -430.201832) (xy 182.687627 -430.202267) (xy 182.706212 -430.210001)
			(xy 182.71363 -430.216818) (xy 183.204912 -430.7081) (xy 185.635322 -430.7081) (xy 185.639337 -430.644295)
			(xy 185.651316 -430.581496) (xy 185.671072 -430.520694) (xy 185.698293 -430.462848) (xy 185.73255 -430.408869)
			(xy 185.773301 -430.35961) (xy 185.819905 -430.315846) (xy 185.871627 -430.278269) (xy 185.927651 -430.24747)
			(xy 185.987092 -430.223937) (xy 186.049015 -430.208038) (xy 186.112442 -430.200027) (xy 186.144408 -430.199546)
			(xy 186.175812 -430.199996) (xy 186.238143 -430.207729) (xy 186.299048 -430.223075) (xy 186.3576 -430.245801)
			(xy 186.41291 -430.275562) (xy 186.464136 -430.311906) (xy 186.510498 -430.354278) (xy 186.53125 -430.377854)
			(xy 186.538108 -430.385982) (xy 186.556904 -430.395126) (xy 186.6519 -430.399698) (xy 186.671458 -430.392332)
			(xy 186.679078 -430.384966) (xy 186.700548 -430.364971) (xy 186.748481 -430.331144) (xy 186.801026 -430.30505)
			(xy 186.856945 -430.287302) (xy 186.91492 -430.278319) (xy 186.944254 -430.277778) (xy 186.972399 -430.278264)
			(xy 187.028077 -430.286543) (xy 187.081935 -430.302912) (xy 187.132803 -430.327017) (xy 187.179578 -430.358334)
			(xy 187.221243 -430.396184) (xy 187.256896 -430.439744) (xy 187.285761 -430.48807) (xy 187.307212 -430.540113)
			(xy 187.320784 -430.594743) (xy 187.323984 -430.62271) (xy 187.325254 -430.636426) (xy 187.341764 -430.659032)
			(xy 187.449968 -430.704752) (xy 187.477654 -430.700942) (xy 187.488576 -430.692306) (xy 187.522337 -430.666)
			(xy 187.594058 -430.619286) (xy 187.669934 -430.579674) (xy 187.749263 -430.547531) (xy 187.831311 -430.523153)
			(xy 187.91532 -430.506765) (xy 188.000516 -430.498519) (xy 188.043312 -430.497996) (xy 188.085237 -430.498488)
			(xy 188.168714 -430.50638) (xy 188.251077 -430.522093) (xy 188.331597 -430.545487) (xy 188.409558 -430.576355)
			(xy 188.484267 -430.614423) (xy 188.555063 -430.659352) (xy 188.621316 -430.710745) (xy 188.682439 -430.768144)
			(xy 188.704479 -430.793144) (xy 189.170056 -430.793144) (xy 189.170611 -430.760712) (xy 189.178854 -430.696375)
			(xy 189.195212 -430.633608) (xy 189.219419 -430.573431) (xy 189.251082 -430.516821) (xy 189.289687 -430.464697)
			(xy 189.334607 -430.417905) (xy 189.35954 -430.397158) (xy 189.366409 -430.391124) (xy 189.375649 -430.375363)
			(xy 189.377574 -430.366424) (xy 189.382908 -430.336452) (xy 189.384092 -430.327378) (xy 189.380724 -430.30941)
			(xy 189.376304 -430.3014) (xy 189.358882 -430.271478) (xy 189.331411 -430.207922) (xy 189.312823 -430.141225)
			(xy 189.303463 -430.072622) (xy 189.302898 -430.038002) (xy 189.3034 -430.006041) (xy 189.311411 -429.942623)
			(xy 189.327308 -429.880709) (xy 189.35084 -429.821276) (xy 189.381634 -429.765261) (xy 189.419207 -429.713546)
			(xy 189.462964 -429.666949) (xy 189.512217 -429.626204) (xy 189.566188 -429.591953) (xy 189.624027 -429.564736)
			(xy 189.68482 -429.544983) (xy 189.74761 -429.533005) (xy 189.811406 -429.528992) (xy 189.875202 -429.533005)
			(xy 189.937992 -429.544983) (xy 189.986342 -429.560693) (xy 190.547492 -429.560693) (xy 190.547492 -429.496771)
			(xy 190.555503 -429.433353) (xy 190.5714 -429.371439) (xy 190.594932 -429.312006) (xy 190.625726 -429.255991)
			(xy 190.663299 -429.204276) (xy 190.707056 -429.157679) (xy 190.756309 -429.116934) (xy 190.81028 -429.082683)
			(xy 190.868119 -429.055466) (xy 190.928912 -429.035713) (xy 190.991702 -429.023735) (xy 191.055498 -429.019722)
			(xy 191.119294 -429.023735) (xy 191.182084 -429.035713) (xy 191.242877 -429.055466) (xy 191.300716 -429.082683)
			(xy 191.354687 -429.116934) (xy 191.40394 -429.157679) (xy 191.447697 -429.204276) (xy 191.48527 -429.255991)
			(xy 191.516064 -429.312006) (xy 191.539596 -429.371439) (xy 191.555493 -429.433353) (xy 191.563504 -429.496771)
			(xy 191.564006 -429.528732) (xy 191.563504 -429.560693) (xy 191.555493 -429.624111) (xy 191.539596 -429.686025)
			(xy 191.516064 -429.745458) (xy 191.48527 -429.801473) (xy 191.447697 -429.853188) (xy 191.40394 -429.899785)
			(xy 191.354687 -429.94053) (xy 191.300716 -429.974781) (xy 191.242877 -430.001998) (xy 191.182084 -430.021751)
			(xy 191.119294 -430.033729) (xy 191.055498 -430.037743) (xy 190.991702 -430.033729) (xy 190.928912 -430.021751)
			(xy 190.868119 -430.001998) (xy 190.81028 -429.974781) (xy 190.756309 -429.94053) (xy 190.707056 -429.899785)
			(xy 190.663299 -429.853188) (xy 190.625726 -429.801473) (xy 190.594932 -429.745458) (xy 190.5714 -429.686025)
			(xy 190.555503 -429.624111) (xy 190.547492 -429.560693) (xy 189.986342 -429.560693) (xy 189.998785 -429.564736)
			(xy 190.056624 -429.591953) (xy 190.110595 -429.626204) (xy 190.159848 -429.666949) (xy 190.203605 -429.713546)
			(xy 190.241178 -429.765261) (xy 190.271972 -429.821276) (xy 190.295504 -429.880709) (xy 190.311401 -429.942623)
			(xy 190.319412 -430.006041) (xy 190.319914 -430.038002) (xy 190.319403 -430.070435) (xy 190.311154 -430.134775)
			(xy 190.294789 -430.197543) (xy 190.270575 -430.257721) (xy 190.238905 -430.314331) (xy 190.200293 -430.366453)
			(xy 190.155366 -430.413242) (xy 190.13043 -430.433988) (xy 190.123591 -430.440052) (xy 190.114332 -430.455791)
			(xy 190.112396 -430.464722) (xy 190.107062 -430.494694) (xy 190.105858 -430.503766) (xy 190.10924 -430.521736)
			(xy 190.113666 -430.529746) (xy 190.131103 -430.559659) (xy 190.158571 -430.623218) (xy 190.177155 -430.689918)
			(xy 190.18651 -430.758523) (xy 190.187072 -430.793144) (xy 190.18657 -430.825105) (xy 190.178559 -430.888523)
			(xy 190.169538 -430.923657) (xy 191.810888 -430.923657) (xy 191.810888 -430.859735) (xy 191.818899 -430.796317)
			(xy 191.834796 -430.734403) (xy 191.858328 -430.67497) (xy 191.889122 -430.618955) (xy 191.926695 -430.56724)
			(xy 191.970452 -430.520643) (xy 192.019705 -430.479898) (xy 192.073676 -430.445647) (xy 192.131515 -430.41843)
			(xy 192.192308 -430.398677) (xy 192.255098 -430.386699) (xy 192.318894 -430.382686) (xy 192.38269 -430.386699)
			(xy 192.44548 -430.398677) (xy 192.506273 -430.41843) (xy 192.564112 -430.445647) (xy 192.618083 -430.479898)
			(xy 192.667336 -430.520643) (xy 192.711093 -430.56724) (xy 192.748666 -430.618955) (xy 192.77946 -430.67497)
			(xy 192.802992 -430.734403) (xy 192.818889 -430.796317) (xy 192.8269 -430.859735) (xy 192.827402 -430.891696)
			(xy 192.8269 -430.923657) (xy 192.818889 -430.987075) (xy 192.802992 -431.048989) (xy 192.77946 -431.108422)
			(xy 192.748666 -431.164437) (xy 192.711093 -431.216152) (xy 192.667336 -431.262749) (xy 192.618083 -431.303494)
			(xy 192.564112 -431.337745) (xy 192.506273 -431.364962) (xy 192.44548 -431.384715) (xy 192.38269 -431.396693)
			(xy 192.318894 -431.400707) (xy 192.255098 -431.396693) (xy 192.192308 -431.384715) (xy 192.131515 -431.364962)
			(xy 192.073676 -431.337745) (xy 192.019705 -431.303494) (xy 191.970452 -431.262749) (xy 191.926695 -431.216152)
			(xy 191.889122 -431.164437) (xy 191.858328 -431.108422) (xy 191.834796 -431.048989) (xy 191.818899 -430.987075)
			(xy 191.810888 -430.923657) (xy 190.169538 -430.923657) (xy 190.162662 -430.950437) (xy 190.13913 -431.00987)
			(xy 190.108336 -431.065885) (xy 190.070763 -431.1176) (xy 190.027006 -431.164197) (xy 189.977753 -431.204942)
			(xy 189.923782 -431.239193) (xy 189.865943 -431.26641) (xy 189.80515 -431.286163) (xy 189.74236 -431.298141)
			(xy 189.678564 -431.302155) (xy 189.614768 -431.298141) (xy 189.551978 -431.286163) (xy 189.491185 -431.26641)
			(xy 189.433346 -431.239193) (xy 189.379375 -431.204942) (xy 189.330122 -431.164197) (xy 189.286365 -431.1176)
			(xy 189.248792 -431.065885) (xy 189.217998 -431.00987) (xy 189.194466 -430.950437) (xy 189.178569 -430.888523)
			(xy 189.170558 -430.825105) (xy 189.170056 -430.793144) (xy 188.704479 -430.793144) (xy 188.737889 -430.831041)
			(xy 188.787174 -430.898877) (xy 188.829856 -430.97105) (xy 188.865556 -431.046919) (xy 188.893959 -431.125811)
			(xy 188.91481 -431.207026) (xy 188.927927 -431.289843) (xy 188.933191 -431.373527) (xy 188.930556 -431.457335)
			(xy 188.920047 -431.540523) (xy 188.901755 -431.622353) (xy 188.875844 -431.702098) (xy 188.842543 -431.779051)
			(xy 188.802148 -431.852528) (xy 188.755017 -431.921878) (xy 188.701569 -431.986485) (xy 188.642279 -432.045775)
			(xy 188.577671 -432.099222) (xy 188.508321 -432.146352) (xy 188.434843 -432.186746) (xy 188.35789 -432.220047)
			(xy 188.278145 -432.245957) (xy 188.196315 -432.264248) (xy 188.113127 -432.274757) (xy 188.029319 -432.277391)
			(xy 187.945635 -432.272126) (xy 187.862819 -432.259009) (xy 187.781604 -432.238156) (xy 187.702712 -432.209753)
			(xy 187.626843 -432.174052) (xy 187.55467 -432.131369) (xy 187.486834 -432.082084) (xy 187.423938 -432.026634)
			(xy 187.366539 -431.96551) (xy 187.315147 -431.899257) (xy 187.270219 -431.82846) (xy 187.232152 -431.75375)
			(xy 187.201284 -431.675789) (xy 187.177891 -431.59527) (xy 187.162179 -431.512906) (xy 187.154288 -431.429429)
			(xy 187.153804 -431.387504) (xy 187.154281 -431.347032) (xy 187.161671 -431.266426) (xy 187.176346 -431.186823)
			(xy 187.186824 -431.147728) (xy 187.190634 -431.134266) (xy 187.183268 -431.107088) (xy 187.09894 -431.025554)
			(xy 187.071762 -431.019204) (xy 187.058554 -431.023268) (xy 187.030692 -431.03146) (xy 186.97329 -431.040254)
			(xy 186.944254 -431.040794) (xy 186.9134 -431.040188) (xy 186.852495 -431.030269) (xy 186.793978 -431.010682)
			(xy 186.739375 -430.981936) (xy 186.714384 -430.963832) (xy 186.706002 -430.957482) (xy 186.685682 -430.952402)
			(xy 186.591702 -430.968404) (xy 186.574176 -430.979834) (xy 186.568334 -430.988724) (xy 186.550664 -431.014619)
			(xy 186.509903 -431.062249) (xy 186.463593 -431.104506) (xy 186.412439 -431.140748) (xy 186.357217 -431.170425)
			(xy 186.298765 -431.193086) (xy 186.237969 -431.208388) (xy 186.175754 -431.216098) (xy 186.144408 -431.216562)
			(xy 186.112442 -431.216173) (xy 186.049015 -431.208162) (xy 185.987092 -431.192263) (xy 185.927651 -431.16873)
			(xy 185.871627 -431.137931) (xy 185.819905 -431.100354) (xy 185.773301 -431.05659) (xy 185.73255 -431.007331)
			(xy 185.698293 -430.953352) (xy 185.671072 -430.895506) (xy 185.651316 -430.834704) (xy 185.639337 -430.771905)
			(xy 185.635322 -430.7081) (xy 183.204912 -430.7081) (xy 185.0009 -432.504088) (xy 191.422032 -432.504088)
			(xy 191.425998 -432.419557) (xy 191.437863 -432.33577) (xy 191.457521 -432.253461) (xy 191.484801 -432.173355)
			(xy 191.519462 -432.096156) (xy 191.5612 -432.022541) (xy 191.609647 -431.953158) (xy 191.664379 -431.888617)
			(xy 191.724915 -431.829485) (xy 191.790721 -431.776281) (xy 191.861221 -431.729473) (xy 191.935793 -431.689472)
			(xy 192.013784 -431.65663) (xy 192.094508 -431.631236) (xy 192.177255 -431.613513) (xy 192.261297 -431.603615)
			(xy 192.345898 -431.601632) (xy 192.430312 -431.607579) (xy 192.513799 -431.621404) (xy 192.595624 -431.642987)
			(xy 192.675068 -431.672137) (xy 192.751434 -431.708598) (xy 192.82405 -431.75205) (xy 192.892278 -431.802111)
			(xy 192.955518 -431.858341) (xy 193.013215 -431.920246) (xy 193.064862 -431.987282) (xy 193.110004 -432.058859)
			(xy 193.148246 -432.134349) (xy 193.17925 -432.213088) (xy 193.202745 -432.294385) (xy 193.218524 -432.377524)
			(xy 193.226448 -432.461776) (xy 193.226944 -432.504088) (xy 193.226448 -432.5464) (xy 193.218524 -432.630652)
			(xy 193.202745 -432.713791) (xy 193.17925 -432.795088) (xy 193.148246 -432.873827) (xy 193.110004 -432.949317)
			(xy 193.064862 -433.020894) (xy 193.013215 -433.08793) (xy 192.955518 -433.149835) (xy 192.892278 -433.206065)
			(xy 192.82405 -433.256126) (xy 192.751434 -433.299578) (xy 192.675068 -433.336039) (xy 192.595624 -433.365189)
			(xy 192.513799 -433.386772) (xy 192.430312 -433.400597) (xy 192.345898 -433.406544) (xy 192.261297 -433.404561)
			(xy 192.177255 -433.394663) (xy 192.094508 -433.37694) (xy 192.013784 -433.351546) (xy 191.935793 -433.318704)
			(xy 191.861221 -433.278703) (xy 191.790721 -433.231895) (xy 191.724915 -433.178691) (xy 191.664379 -433.119559)
			(xy 191.609647 -433.055018) (xy 191.5612 -432.985635) (xy 191.519462 -432.91202) (xy 191.484801 -432.834821)
			(xy 191.457521 -432.754715) (xy 191.437863 -432.672406) (xy 191.425998 -432.588619) (xy 191.422032 -432.504088)
			(xy 185.0009 -432.504088) (xy 185.385202 -432.88839) (xy 185.39205 -432.895788) (xy 185.399788 -432.914386)
			(xy 185.400188 -432.924458) (xy 185.400188 -435.044088) (xy 191.295024 -435.044088) (xy 191.299053 -434.953082)
			(xy 191.31111 -434.862788) (xy 191.3311 -434.773913) (xy 191.358866 -434.687153) (xy 191.394192 -434.603186)
			(xy 191.4368 -434.52267) (xy 191.486358 -434.446234) (xy 191.542477 -434.374478) (xy 191.604718 -434.307962)
			(xy 191.672595 -434.247207) (xy 191.745575 -434.192689) (xy 191.823088 -434.144835) (xy 191.904527 -434.104018)
			(xy 191.989255 -434.070559) (xy 192.076609 -434.044718) (xy 192.165904 -434.0267) (xy 192.256442 -434.016643)
			(xy 192.347515 -434.014628) (xy 192.43841 -434.02067) (xy 192.528415 -434.034721) (xy 192.616826 -434.056672)
			(xy 192.702951 -434.086351) (xy 192.786116 -434.123525) (xy 192.86567 -434.167904) (xy 192.94099 -434.219141)
			(xy 193.011488 -434.276834) (xy 193.07661 -434.340531) (xy 193.135848 -434.409735) (xy 193.188738 -434.483904)
			(xy 193.234867 -434.562456) (xy 193.273872 -434.644779) (xy 193.305449 -434.730226) (xy 193.32935 -434.81813)
			(xy 193.345389 -434.907802) (xy 193.35344 -434.99854) (xy 193.353944 -435.044088) (xy 193.35344 -435.089636)
			(xy 193.345389 -435.180374) (xy 193.32935 -435.270046) (xy 193.305449 -435.35795) (xy 193.273872 -435.443397)
			(xy 193.234867 -435.52572) (xy 193.188738 -435.604272) (xy 193.135848 -435.678441) (xy 193.07661 -435.747645)
			(xy 193.011488 -435.811342) (xy 192.94099 -435.869035) (xy 192.86567 -435.920272) (xy 192.786116 -435.964651)
			(xy 192.702951 -436.001825) (xy 192.616826 -436.031504) (xy 192.528415 -436.053455) (xy 192.43841 -436.067506)
			(xy 192.347515 -436.073548) (xy 192.256442 -436.071533) (xy 192.165904 -436.061476) (xy 192.076609 -436.043458)
			(xy 191.989255 -436.017617) (xy 191.904527 -435.984158) (xy 191.823088 -435.943341) (xy 191.745575 -435.895487)
			(xy 191.672595 -435.840969) (xy 191.604718 -435.780214) (xy 191.542477 -435.713698) (xy 191.486358 -435.641942)
			(xy 191.4368 -435.565506) (xy 191.394192 -435.48499) (xy 191.358866 -435.401023) (xy 191.3311 -435.314263)
			(xy 191.31111 -435.225388) (xy 191.299053 -435.135094) (xy 191.295024 -435.044088) (xy 185.400188 -435.044088)
			(xy 185.400188 -437.584088) (xy 191.295024 -437.584088) (xy 191.299053 -437.493082) (xy 191.31111 -437.402788)
			(xy 191.3311 -437.313913) (xy 191.358866 -437.227153) (xy 191.394192 -437.143186) (xy 191.4368 -437.06267)
			(xy 191.486358 -436.986234) (xy 191.542477 -436.914478) (xy 191.604718 -436.847962) (xy 191.672595 -436.787207)
			(xy 191.745575 -436.732689) (xy 191.823088 -436.684835) (xy 191.904527 -436.644018) (xy 191.989255 -436.610559)
			(xy 192.076609 -436.584718) (xy 192.165904 -436.5667) (xy 192.256442 -436.556643) (xy 192.347515 -436.554628)
			(xy 192.43841 -436.56067) (xy 192.528415 -436.574721) (xy 192.616826 -436.596672) (xy 192.702951 -436.626351)
			(xy 192.786116 -436.663525) (xy 192.86567 -436.707904) (xy 192.94099 -436.759141) (xy 193.011488 -436.816834)
			(xy 193.07661 -436.880531) (xy 193.135848 -436.949735) (xy 193.188738 -437.023904) (xy 193.234867 -437.102456)
			(xy 193.273872 -437.184779) (xy 193.305449 -437.270226) (xy 193.32935 -437.35813) (xy 193.345389 -437.447802)
			(xy 193.35344 -437.53854) (xy 193.353944 -437.584088) (xy 193.353867 -437.591063) (xy 276.104713 -437.591063)
			(xy 276.109924 -437.528198) (xy 276.122871 -437.46646) (xy 276.143356 -437.406798) (xy 276.171062 -437.350128)
			(xy 276.205566 -437.297321) (xy 276.246337 -437.249187) (xy 276.292748 -437.206465) (xy 276.344088 -437.169812)
			(xy 276.399566 -437.139792) (xy 276.458333 -437.116864) (xy 276.519483 -437.101381) (xy 276.58208 -437.09358)
			(xy 276.61362 -437.093106) (xy 276.643941 -437.093541) (xy 276.704153 -437.100737) (xy 276.763084 -437.115037)
			(xy 276.819899 -437.136237) (xy 276.847046 -437.149748) (xy 276.860035 -437.155953) (xy 276.88826 -437.161548)
			(xy 276.916925 -437.159045) (xy 276.943753 -437.148643) (xy 276.966614 -437.131169) (xy 276.983691 -437.108011)
			(xy 276.993629 -437.081007) (xy 276.995128 -437.06669) (xy 276.997674 -437.038169) (xy 277.010192 -436.982296)
			(xy 277.030921 -436.928921) (xy 277.059397 -436.879245) (xy 277.094978 -436.834384) (xy 277.136866 -436.795346)
			(xy 277.184119 -436.763009) (xy 277.235675 -436.738098) (xy 277.290375 -436.721174) (xy 277.346991 -436.712618)
			(xy 277.37562 -436.712106) (xy 277.402871 -436.712565) (xy 277.456819 -436.720324) (xy 277.509113 -436.735682)
			(xy 277.55869 -436.758325) (xy 277.604539 -436.787793) (xy 277.645729 -436.823486) (xy 277.681419 -436.864677)
			(xy 277.710885 -436.910528) (xy 277.733525 -436.960106) (xy 277.74888 -437.012401) (xy 277.756636 -437.066349)
			(xy 277.756636 -437.120851) (xy 277.74888 -437.174799) (xy 277.733525 -437.227094) (xy 277.710885 -437.276672)
			(xy 277.681419 -437.322523) (xy 277.645729 -437.363714) (xy 277.604539 -437.399407) (xy 277.55869 -437.428875)
			(xy 277.509113 -437.451518) (xy 277.456819 -437.466876) (xy 277.402871 -437.474635) (xy 277.37562 -437.475122)
			(xy 277.344647 -437.474558) (xy 277.283508 -437.464598) (xy 277.253954 -437.45531) (xy 277.240167 -437.451197)
			(xy 277.211436 -437.449973) (xy 277.183505 -437.456814) (xy 277.158592 -437.471178) (xy 277.138677 -437.491923)
			(xy 277.125342 -437.517401) (xy 277.119646 -437.545588) (xy 277.12035 -437.559958) (xy 277.122128 -437.601614)
			(xy 277.121617 -437.633154) (xy 277.113813 -437.69575) (xy 277.098326 -437.7569) (xy 277.075394 -437.815664)
			(xy 277.04537 -437.871141) (xy 277.008713 -437.922478) (xy 277.007601 -437.923686) (xy 281.436316 -437.923686)
			(xy 281.440387 -437.868064) (xy 281.452513 -437.813627) (xy 281.472436 -437.761536) (xy 281.499732 -437.712901)
			(xy 281.533818 -437.668758) (xy 281.573967 -437.630049) (xy 281.619325 -437.597598) (xy 281.668925 -437.572097)
			(xy 281.721709 -437.55409) (xy 281.776552 -437.54396) (xy 281.832286 -437.541923) (xy 281.887723 -437.548023)
			(xy 281.94168 -437.562129) (xy 281.993009 -437.583941) (xy 282.040615 -437.612995) (xy 282.083483 -437.64867)
			(xy 282.1207 -437.690207) (xy 282.151473 -437.73672) (xy 282.175145 -437.787217) (xy 282.191213 -437.840624)
			(xy 282.199333 -437.8958) (xy 282.199842 -437.923686) (xy 282.199333 -437.951572) (xy 282.191213 -438.006748)
			(xy 282.175145 -438.060155) (xy 282.151473 -438.110652) (xy 282.1207 -438.157165) (xy 282.083483 -438.198702)
			(xy 282.040615 -438.234377) (xy 281.993009 -438.263431) (xy 281.94168 -438.285243) (xy 281.887723 -438.299349)
			(xy 281.832286 -438.305449) (xy 281.776552 -438.303412) (xy 281.721709 -438.293282) (xy 281.668925 -438.275275)
			(xy 281.619325 -438.249774) (xy 281.573967 -438.217323) (xy 281.533818 -438.178614) (xy 281.499732 -438.134471)
			(xy 281.472436 -438.085836) (xy 281.452513 -438.033745) (xy 281.440387 -437.979308) (xy 281.436316 -437.923686)
			(xy 277.007601 -437.923686) (xy 276.965989 -437.968887) (xy 276.917852 -438.009654) (xy 276.865042 -438.044154)
			(xy 276.80837 -438.071857) (xy 276.748707 -438.092338) (xy 276.686969 -438.105281) (xy 276.624103 -438.110488)
			(xy 276.561077 -438.107879) (xy 276.498857 -438.097495) (xy 276.4384 -438.079494) (xy 276.380633 -438.054153)
			(xy 276.326444 -438.021861) (xy 276.276666 -437.983114) (xy 276.232063 -437.938508) (xy 276.19332 -437.888727)
			(xy 276.161032 -437.834537) (xy 276.135695 -437.776769) (xy 276.117698 -437.71631) (xy 276.107317 -437.654089)
			(xy 276.104713 -437.591063) (xy 193.353867 -437.591063) (xy 193.35344 -437.629636) (xy 193.345389 -437.720374)
			(xy 193.32935 -437.810046) (xy 193.305449 -437.89795) (xy 193.273872 -437.983397) (xy 193.234867 -438.06572)
			(xy 193.188738 -438.144272) (xy 193.135848 -438.218441) (xy 193.07661 -438.287645) (xy 193.011488 -438.351342)
			(xy 192.949936 -438.401714) (xy 276.993602 -438.401714) (xy 276.997673 -438.346092) (xy 277.009799 -438.291655)
			(xy 277.029722 -438.239564) (xy 277.057018 -438.190929) (xy 277.091104 -438.146786) (xy 277.131253 -438.108077)
			(xy 277.176611 -438.075626) (xy 277.226211 -438.050125) (xy 277.278995 -438.032118) (xy 277.333838 -438.021988)
			(xy 277.389572 -438.019951) (xy 277.445009 -438.026051) (xy 277.498966 -438.040157) (xy 277.550295 -438.061969)
			(xy 277.597901 -438.091023) (xy 277.640769 -438.126698) (xy 277.677986 -438.168235) (xy 277.708759 -438.214748)
			(xy 277.732431 -438.265245) (xy 277.748499 -438.318652) (xy 277.756619 -438.373828) (xy 277.757128 -438.401714)
			(xy 277.756619 -438.4296) (xy 277.748499 -438.484776) (xy 277.732431 -438.538183) (xy 277.708759 -438.58868)
			(xy 277.677986 -438.635193) (xy 277.640769 -438.67673) (xy 277.597901 -438.712405) (xy 277.550295 -438.741459)
			(xy 277.498966 -438.763271) (xy 277.445009 -438.777377) (xy 277.389572 -438.783477) (xy 277.333838 -438.78144)
			(xy 277.278995 -438.77131) (xy 277.226211 -438.753303) (xy 277.176611 -438.727802) (xy 277.131253 -438.695351)
			(xy 277.091104 -438.656642) (xy 277.057018 -438.612499) (xy 277.029722 -438.563864) (xy 277.009799 -438.511773)
			(xy 276.997673 -438.457336) (xy 276.993602 -438.401714) (xy 192.949936 -438.401714) (xy 192.94099 -438.409035)
			(xy 192.86567 -438.460272) (xy 192.786116 -438.504651) (xy 192.702951 -438.541825) (xy 192.616826 -438.571504)
			(xy 192.528415 -438.593455) (xy 192.43841 -438.607506) (xy 192.347515 -438.613548) (xy 192.256442 -438.611533)
			(xy 192.165904 -438.601476) (xy 192.076609 -438.583458) (xy 191.989255 -438.557617) (xy 191.904527 -438.524158)
			(xy 191.823088 -438.483341) (xy 191.745575 -438.435487) (xy 191.672595 -438.380969) (xy 191.604718 -438.320214)
			(xy 191.542477 -438.253698) (xy 191.486358 -438.181942) (xy 191.4368 -438.105506) (xy 191.394192 -438.02499)
			(xy 191.358866 -437.941023) (xy 191.3311 -437.854263) (xy 191.31111 -437.765388) (xy 191.299053 -437.675094)
			(xy 191.295024 -437.584088) (xy 185.400188 -437.584088) (xy 185.400188 -439.11012) (xy 185.400614 -439.120189)
			(xy 185.408332 -439.138789) (xy 185.415174 -439.146188) (xy 186.62142 -440.352434) (xy 186.628816 -440.359284)
			(xy 186.647415 -440.367022) (xy 186.657488 -440.36742) (xy 193.545714 -440.36742) (xy 193.555784 -440.366995)
			(xy 193.574386 -440.359279) (xy 193.581782 -440.352434) (xy 194.684904 -439.249312) (xy 194.692302 -439.242465)
			(xy 194.7109 -439.23473) (xy 194.720972 -439.234326) (xy 278.072342 -439.234326) (xy 278.082408 -439.234757)
			(xy 278.100999 -439.242485) (xy 278.10841 -439.249312) (xy 279.35936 -440.500262) (xy 279.36676 -440.507103)
			(xy 279.385359 -440.514822) (xy 279.395428 -440.515248) (xy 284.066488 -440.515248) (xy 284.076558 -440.514826)
			(xy 284.095161 -440.507108) (xy 284.102556 -440.500262) (xy 286.437578 -438.16524) (xy 286.444417 -438.157839)
			(xy 286.452133 -438.139241) (xy 286.452564 -438.129172) (xy 286.452564 -429.161702) (xy 286.452264 -429.153595)
			(xy 286.447214 -429.138188) (xy 286.442658 -429.131476) (xy 286.426943 -429.10947) (xy 286.401215 -429.061911)
			(xy 286.38246 -429.011194) (xy 286.371054 -428.958337) (xy 286.367227 -428.9044) (xy 286.371054 -428.850463)
			(xy 286.38246 -428.797606) (xy 286.401215 -428.746889) (xy 286.426943 -428.69933) (xy 286.442658 -428.677324)
			(xy 286.447248 -428.670628) (xy 286.452309 -428.655212) (xy 286.452564 -428.647098) (xy 286.452564 -424.552618)
			(xy 286.45104 -424.551348) (xy 285.952946 -424.551348) (xy 285.921133 -424.55092) (xy 285.857908 -424.543797)
			(xy 285.795879 -424.529635) (xy 285.735827 -424.508613) (xy 285.678508 -424.480995) (xy 285.624644 -424.44713)
			(xy 285.574913 -424.407443) (xy 285.552134 -424.385232) (xy 285.077662 -423.91076) (xy 285.070264 -423.903913)
			(xy 285.051665 -423.896183) (xy 285.041594 -423.895774) (xy 281.1526 -423.895774) (xy 281.142529 -423.896196)
			(xy 281.123922 -423.903908) (xy 281.116532 -423.91076) (xy 280.585926 -424.441366) (xy 283.081982 -424.441366)
			(xy 283.086053 -424.385744) (xy 283.098179 -424.331307) (xy 283.118102 -424.279216) (xy 283.145398 -424.230581)
			(xy 283.179484 -424.186438) (xy 283.219633 -424.147729) (xy 283.264991 -424.115278) (xy 283.314591 -424.089777)
			(xy 283.367375 -424.07177) (xy 283.422218 -424.06164) (xy 283.477952 -424.059603) (xy 283.533389 -424.065703)
			(xy 283.587346 -424.079809) (xy 283.638675 -424.101621) (xy 283.686281 -424.130675) (xy 283.729149 -424.16635)
			(xy 283.766366 -424.207887) (xy 283.797139 -424.2544) (xy 283.820811 -424.304897) (xy 283.836879 -424.358304)
			(xy 283.844999 -424.41348) (xy 283.845508 -424.441366) (xy 283.844999 -424.469252) (xy 283.836879 -424.524428)
			(xy 283.820811 -424.577835) (xy 283.797139 -424.628332) (xy 283.766366 -424.674845) (xy 283.729149 -424.716382)
			(xy 283.686281 -424.752057) (xy 283.638675 -424.781111) (xy 283.587346 -424.802923) (xy 283.533389 -424.817029)
			(xy 283.477952 -424.823129) (xy 283.422218 -424.821092) (xy 283.367375 -424.810962) (xy 283.314591 -424.792955)
			(xy 283.264991 -424.767454) (xy 283.219633 -424.735003) (xy 283.179484 -424.696294) (xy 283.145398 -424.652151)
			(xy 283.118102 -424.603516) (xy 283.098179 -424.551425) (xy 283.086053 -424.496988) (xy 283.081982 -424.441366)
			(xy 280.585926 -424.441366) (xy 279.569926 -425.457366) (xy 279.562525 -425.464205) (xy 279.543926 -425.471917)
			(xy 279.533858 -425.472352) (xy 274.649184 -425.472352) (xy 274.639116 -425.47278) (xy 274.620521 -425.480504)
			(xy 274.613116 -425.487338) (xy 274.098512 -426.001942) (xy 274.092162 -426.012864) (xy 274.090384 -426.019214)
			(xy 274.081018 -426.04991) (xy 274.055609 -426.108844) (xy 274.022988 -426.164114) (xy 273.983673 -426.21484)
			(xy 273.960644 -426.237865) (xy 284.634934 -426.237865) (xy 284.634934 -426.173943) (xy 284.642945 -426.110525)
			(xy 284.658842 -426.048611) (xy 284.682374 -425.989178) (xy 284.713168 -425.933163) (xy 284.750741 -425.881448)
			(xy 284.794498 -425.834851) (xy 284.843751 -425.794106) (xy 284.897722 -425.759855) (xy 284.955561 -425.732638)
			(xy 285.016354 -425.712885) (xy 285.079144 -425.700907) (xy 285.14294 -425.696894) (xy 285.206736 -425.700907)
			(xy 285.269526 -425.712885) (xy 285.330319 -425.732638) (xy 285.388158 -425.759855) (xy 285.442129 -425.794106)
			(xy 285.491382 -425.834851) (xy 285.535139 -425.881448) (xy 285.572712 -425.933163) (xy 285.603506 -425.989178)
			(xy 285.627038 -426.048611) (xy 285.642935 -426.110525) (xy 285.650946 -426.173943) (xy 285.651448 -426.205904)
			(xy 285.650946 -426.237865) (xy 285.642935 -426.301283) (xy 285.627038 -426.363197) (xy 285.603506 -426.42263)
			(xy 285.572712 -426.478645) (xy 285.535139 -426.53036) (xy 285.491382 -426.576957) (xy 285.442129 -426.617702)
			(xy 285.388158 -426.651953) (xy 285.330319 -426.67917) (xy 285.269526 -426.698923) (xy 285.206736 -426.710901)
			(xy 285.14294 -426.714915) (xy 285.079144 -426.710901) (xy 285.016354 -426.698923) (xy 284.955561 -426.67917)
			(xy 284.897722 -426.651953) (xy 284.843751 -426.617702) (xy 284.794498 -426.576957) (xy 284.750741 -426.53036)
			(xy 284.713168 -426.478645) (xy 284.682374 -426.42263) (xy 284.658842 -426.363197) (xy 284.642945 -426.301283)
			(xy 284.634934 -426.237865) (xy 273.960644 -426.237865) (xy 273.938288 -426.260218) (xy 273.887556 -426.299526)
			(xy 273.832282 -426.33214) (xy 273.773344 -426.357541) (xy 273.742658 -426.36694) (xy 273.736308 -426.368718)
			(xy 273.725386 -426.375068) (xy 272.838926 -427.261528) (xy 280.287982 -427.261528) (xy 280.292053 -427.205906)
			(xy 280.304179 -427.151469) (xy 280.324102 -427.099378) (xy 280.351398 -427.050743) (xy 280.385484 -427.0066)
			(xy 280.425633 -426.967891) (xy 280.470991 -426.93544) (xy 280.520591 -426.909939) (xy 280.573375 -426.891932)
			(xy 280.628218 -426.881802) (xy 280.683952 -426.879765) (xy 280.739389 -426.885865) (xy 280.793346 -426.899971)
			(xy 280.844675 -426.921783) (xy 280.892281 -426.950837) (xy 280.935149 -426.986512) (xy 280.972366 -427.028049)
			(xy 281.003139 -427.074562) (xy 281.026811 -427.125059) (xy 281.042879 -427.178466) (xy 281.050999 -427.233642)
			(xy 281.051151 -427.24197) (xy 284.174944 -427.24197) (xy 284.179015 -427.186348) (xy 284.191141 -427.131911)
			(xy 284.211064 -427.07982) (xy 284.23836 -427.031185) (xy 284.272446 -426.987042) (xy 284.312595 -426.948333)
			(xy 284.357953 -426.915882) (xy 284.407553 -426.890381) (xy 284.460337 -426.872374) (xy 284.51518 -426.862244)
			(xy 284.570914 -426.860207) (xy 284.626351 -426.866307) (xy 284.680308 -426.880413) (xy 284.731637 -426.902225)
			(xy 284.779243 -426.931279) (xy 284.822111 -426.966954) (xy 284.859328 -427.008491) (xy 284.890101 -427.055004)
			(xy 284.913773 -427.105501) (xy 284.929841 -427.158908) (xy 284.937961 -427.214084) (xy 284.93847 -427.24197)
			(xy 284.937961 -427.269856) (xy 284.929841 -427.325032) (xy 284.913773 -427.378439) (xy 284.890101 -427.428936)
			(xy 284.859328 -427.475449) (xy 284.822111 -427.516986) (xy 284.779243 -427.552661) (xy 284.731637 -427.581715)
			(xy 284.680308 -427.603527) (xy 284.626351 -427.617633) (xy 284.570914 -427.623733) (xy 284.51518 -427.621696)
			(xy 284.460337 -427.611566) (xy 284.407553 -427.593559) (xy 284.357953 -427.568058) (xy 284.312595 -427.535607)
			(xy 284.272446 -427.496898) (xy 284.23836 -427.452755) (xy 284.211064 -427.40412) (xy 284.191141 -427.352029)
			(xy 284.179015 -427.297592) (xy 284.174944 -427.24197) (xy 281.051151 -427.24197) (xy 281.051508 -427.261528)
			(xy 281.050999 -427.289414) (xy 281.042879 -427.34459) (xy 281.026811 -427.397997) (xy 281.003139 -427.448494)
			(xy 280.972366 -427.495007) (xy 280.935149 -427.536544) (xy 280.892281 -427.572219) (xy 280.844675 -427.601273)
			(xy 280.793346 -427.623085) (xy 280.739389 -427.637191) (xy 280.683952 -427.643291) (xy 280.628218 -427.641254)
			(xy 280.573375 -427.631124) (xy 280.520591 -427.613117) (xy 280.470991 -427.587616) (xy 280.425633 -427.555165)
			(xy 280.385484 -427.516456) (xy 280.351398 -427.472313) (xy 280.324102 -427.423678) (xy 280.304179 -427.371587)
			(xy 280.292053 -427.31715) (xy 280.287982 -427.261528) (xy 272.838926 -427.261528) (xy 272.803874 -427.29658)
			(xy 272.796475 -427.303425) (xy 272.777877 -427.311153) (xy 272.767806 -427.311566) (xy 266.503658 -427.311566)
			(xy 266.493593 -427.311998) (xy 266.475005 -427.319731) (xy 266.46759 -427.326552) (xy 266.030499 -427.763643)
			(xy 285.011108 -427.763643) (xy 285.011108 -427.699721) (xy 285.019119 -427.636303) (xy 285.035016 -427.574389)
			(xy 285.058548 -427.514956) (xy 285.089342 -427.458941) (xy 285.126915 -427.407226) (xy 285.170672 -427.360629)
			(xy 285.219925 -427.319884) (xy 285.273896 -427.285633) (xy 285.331735 -427.258416) (xy 285.392528 -427.238663)
			(xy 285.455318 -427.226685) (xy 285.519114 -427.222672) (xy 285.58291 -427.226685) (xy 285.6457 -427.238663)
			(xy 285.706493 -427.258416) (xy 285.764332 -427.285633) (xy 285.818303 -427.319884) (xy 285.867556 -427.360629)
			(xy 285.911313 -427.407226) (xy 285.948886 -427.458941) (xy 285.97968 -427.514956) (xy 286.003212 -427.574389)
			(xy 286.019109 -427.636303) (xy 286.02712 -427.699721) (xy 286.027622 -427.731682) (xy 286.02712 -427.763643)
			(xy 286.019109 -427.827061) (xy 286.003212 -427.888975) (xy 285.97968 -427.948408) (xy 285.948886 -428.004423)
			(xy 285.911313 -428.056138) (xy 285.867556 -428.102735) (xy 285.818303 -428.14348) (xy 285.764332 -428.177731)
			(xy 285.706493 -428.204948) (xy 285.6457 -428.224701) (xy 285.58291 -428.236679) (xy 285.519114 -428.240693)
			(xy 285.455318 -428.236679) (xy 285.392528 -428.224701) (xy 285.331735 -428.204948) (xy 285.273896 -428.177731)
			(xy 285.219925 -428.14348) (xy 285.170672 -428.102735) (xy 285.126915 -428.056138) (xy 285.089342 -428.004423)
			(xy 285.058548 -427.948408) (xy 285.035016 -427.888975) (xy 285.019119 -427.827061) (xy 285.011108 -427.763643)
			(xy 266.030499 -427.763643) (xy 265.545062 -428.24908) (xy 265.538222 -428.25648) (xy 265.530507 -428.275079)
			(xy 265.530076 -428.285148) (xy 265.530076 -428.984156) (xy 275.625306 -428.984156) (xy 275.625808 -428.952195)
			(xy 275.633819 -428.888777) (xy 275.649716 -428.826863) (xy 275.673248 -428.76743) (xy 275.704042 -428.711415)
			(xy 275.741615 -428.6597) (xy 275.785372 -428.613103) (xy 275.834625 -428.572358) (xy 275.888596 -428.538107)
			(xy 275.946435 -428.51089) (xy 276.007228 -428.491137) (xy 276.070018 -428.479159) (xy 276.133814 -428.475146)
			(xy 276.19761 -428.479159) (xy 276.2604 -428.491137) (xy 276.321193 -428.51089) (xy 276.379032 -428.538107)
			(xy 276.433003 -428.572358) (xy 276.482256 -428.613103) (xy 276.526013 -428.6597) (xy 276.563586 -428.711415)
			(xy 276.59438 -428.76743) (xy 276.617912 -428.826863) (xy 276.633809 -428.888777) (xy 276.64182 -428.952195)
			(xy 276.642322 -428.984156) (xy 276.642009 -429.00928) (xy 276.637048 -429.059283) (xy 276.632416 -429.083978)
			(xy 276.630384 -429.09363) (xy 276.63394 -429.11268) (xy 276.681946 -429.188626) (xy 276.697694 -429.199802)
			(xy 276.707092 -429.202342) (xy 276.734191 -429.209639) (xy 276.786003 -429.231208) (xy 276.834095 -429.260136)
			(xy 276.87743 -429.295799) (xy 276.91507 -429.337426) (xy 276.946205 -429.38412) (xy 276.970161 -429.434872)
			(xy 276.986422 -429.488587) (xy 276.994636 -429.544105) (xy 276.995128 -429.572166) (xy 276.994613 -429.599417)
			(xy 276.993936 -429.604127) (xy 278.665426 -429.604127) (xy 278.665426 -429.540205) (xy 278.673437 -429.476787)
			(xy 278.689334 -429.414873) (xy 278.712866 -429.35544) (xy 278.74366 -429.299425) (xy 278.781233 -429.24771)
			(xy 278.82499 -429.201113) (xy 278.874243 -429.160368) (xy 278.928214 -429.126117) (xy 278.986053 -429.0989)
			(xy 279.046846 -429.079147) (xy 279.109636 -429.067169) (xy 279.173432 -429.063156) (xy 279.237228 -429.067169)
			(xy 279.300018 -429.079147) (xy 279.360811 -429.0989) (xy 279.41865 -429.126117) (xy 279.472621 -429.160368)
			(xy 279.521874 -429.201113) (xy 279.565631 -429.24771) (xy 279.603204 -429.299425) (xy 279.633998 -429.35544)
			(xy 279.65753 -429.414873) (xy 279.673427 -429.476787) (xy 279.681438 -429.540205) (xy 279.68194 -429.572166)
			(xy 279.681438 -429.604127) (xy 279.673427 -429.667545) (xy 279.65753 -429.729459) (xy 279.633998 -429.788892)
			(xy 279.603204 -429.844907) (xy 279.565631 -429.896622) (xy 279.521874 -429.943219) (xy 279.472621 -429.983964)
			(xy 279.41865 -430.018215) (xy 279.360811 -430.045432) (xy 279.300018 -430.065185) (xy 279.237228 -430.077163)
			(xy 279.173432 -430.081177) (xy 279.109636 -430.077163) (xy 279.046846 -430.065185) (xy 278.986053 -430.045432)
			(xy 278.928214 -430.018215) (xy 278.874243 -429.983964) (xy 278.82499 -429.943219) (xy 278.781233 -429.896622)
			(xy 278.74366 -429.844907) (xy 278.712866 -429.788892) (xy 278.689334 -429.729459) (xy 278.673437 -429.667545)
			(xy 278.665426 -429.604127) (xy 276.993936 -429.604127) (xy 276.986861 -429.653365) (xy 276.971511 -429.705661)
			(xy 276.948874 -429.755239) (xy 276.919411 -429.801092) (xy 276.883723 -429.842284) (xy 276.842535 -429.877979)
			(xy 276.796687 -429.907448) (xy 276.747111 -429.930092) (xy 276.694818 -429.94545) (xy 276.640871 -429.953209)
			(xy 276.61362 -429.953674) (xy 276.587172 -429.953223) (xy 276.534786 -429.945892) (xy 276.483915 -429.931396)
			(xy 276.435533 -429.910012) (xy 276.390569 -429.882151) (xy 276.349884 -429.848346) (xy 276.314258 -429.809246)
			(xy 276.284374 -429.7656) (xy 276.260805 -429.718245) (xy 276.244003 -429.668088) (xy 276.234289 -429.616091)
			(xy 276.23262 -429.589692) (xy 276.232112 -429.579786) (xy 276.223984 -429.562006) (xy 276.159214 -429.50003)
			(xy 276.141434 -429.492664) (xy 276.131528 -429.492664) (xy 276.098331 -429.492002) (xy 276.032535 -429.483065)
			(xy 275.968462 -429.46564) (xy 275.907202 -429.440023) (xy 275.849798 -429.40665) (xy 275.797226 -429.366089)
			(xy 275.750382 -429.319031) (xy 275.710061 -429.266275) (xy 275.67695 -429.208719) (xy 275.651612 -429.147344)
			(xy 275.634479 -429.083192) (xy 275.625841 -429.017356) (xy 275.625306 -428.984156) (xy 265.530076 -428.984156)
			(xy 265.530076 -433.130706) (xy 266.885409 -433.130706) (xy 266.885409 -432.953414) (xy 266.893363 -432.7763)
			(xy 266.909256 -432.599721) (xy 266.933054 -432.424033) (xy 266.964711 -432.24959) (xy 267.004162 -432.076743)
			(xy 267.051329 -431.90584) (xy 267.106115 -431.737225) (xy 267.168411 -431.571237) (xy 267.238091 -431.408212)
			(xy 267.315016 -431.248477) (xy 267.399029 -431.092354) (xy 267.489962 -430.940158) (xy 267.587632 -430.792194)
			(xy 267.691842 -430.648762) (xy 267.802382 -430.510149) (xy 267.919029 -430.376635) (xy 268.041549 -430.248489)
			(xy 268.169695 -430.125969) (xy 268.303209 -430.009322) (xy 268.441822 -429.898782) (xy 268.585254 -429.794572)
			(xy 268.733218 -429.696902) (xy 268.885414 -429.605969) (xy 269.041537 -429.521956) (xy 269.201272 -429.445031)
			(xy 269.364297 -429.375351) (xy 269.530285 -429.313055) (xy 269.6989 -429.258269) (xy 269.869803 -429.211102)
			(xy 270.04265 -429.171651) (xy 270.217093 -429.139994) (xy 270.392781 -429.116196) (xy 270.56936 -429.100303)
			(xy 270.746474 -429.092349) (xy 270.923766 -429.092349) (xy 271.10088 -429.100303) (xy 271.277459 -429.116196)
			(xy 271.453147 -429.139994) (xy 271.62759 -429.171651) (xy 271.800437 -429.211102) (xy 271.97134 -429.258269)
			(xy 272.139955 -429.313055) (xy 272.305943 -429.375351) (xy 272.468968 -429.445031) (xy 272.628703 -429.521956)
			(xy 272.784826 -429.605969) (xy 272.937022 -429.696902) (xy 273.084986 -429.794572) (xy 273.228418 -429.898782)
			(xy 273.367031 -430.009322) (xy 273.500545 -430.125969) (xy 273.628691 -430.248489) (xy 273.751211 -430.376635)
			(xy 273.867858 -430.510149) (xy 273.978398 -430.648762) (xy 274.082006 -430.791366) (xy 277.234902 -430.791366)
			(xy 277.238973 -430.735744) (xy 277.251099 -430.681307) (xy 277.271022 -430.629216) (xy 277.298318 -430.580581)
			(xy 277.332404 -430.536438) (xy 277.372553 -430.497729) (xy 277.417911 -430.465278) (xy 277.467511 -430.439777)
			(xy 277.520295 -430.42177) (xy 277.575138 -430.41164) (xy 277.630872 -430.409603) (xy 277.686309 -430.415703)
			(xy 277.740266 -430.429809) (xy 277.791595 -430.451621) (xy 277.839201 -430.480675) (xy 277.882069 -430.51635)
			(xy 277.919286 -430.557887) (xy 277.950059 -430.6044) (xy 277.973731 -430.654897) (xy 277.989799 -430.708304)
			(xy 277.997919 -430.76348) (xy 277.998428 -430.791366) (xy 277.997919 -430.819252) (xy 277.989799 -430.874428)
			(xy 277.973731 -430.927835) (xy 277.950059 -430.978332) (xy 277.919286 -431.024845) (xy 277.882069 -431.066382)
			(xy 277.839201 -431.102057) (xy 277.791595 -431.131111) (xy 277.740266 -431.152923) (xy 277.686309 -431.167029)
			(xy 277.630872 -431.173129) (xy 277.575138 -431.171092) (xy 277.520295 -431.160962) (xy 277.467511 -431.142955)
			(xy 277.417911 -431.117454) (xy 277.372553 -431.085003) (xy 277.332404 -431.046294) (xy 277.298318 -431.002151)
			(xy 277.271022 -430.953516) (xy 277.251099 -430.901425) (xy 277.238973 -430.846988) (xy 277.234902 -430.791366)
			(xy 274.082006 -430.791366) (xy 274.082608 -430.792194) (xy 274.180278 -430.940158) (xy 274.271211 -431.092354)
			(xy 274.355224 -431.248477) (xy 274.432149 -431.408212) (xy 274.501829 -431.571237) (xy 274.564125 -431.737225)
			(xy 274.618911 -431.90584) (xy 274.666078 -432.076743) (xy 274.705529 -432.24959) (xy 274.737186 -432.424033)
			(xy 274.760984 -432.599721) (xy 274.776877 -432.7763) (xy 274.784831 -432.953414) (xy 274.785328 -433.04206)
			(xy 274.784831 -433.130706) (xy 274.776877 -433.30782) (xy 274.760984 -433.484399) (xy 274.737186 -433.660087)
			(xy 274.705529 -433.83453) (xy 274.676018 -433.963826) (xy 277.872188 -433.963826) (xy 277.876259 -433.908204)
			(xy 277.888385 -433.853767) (xy 277.908308 -433.801676) (xy 277.935604 -433.753041) (xy 277.96969 -433.708898)
			(xy 278.009839 -433.670189) (xy 278.055197 -433.637738) (xy 278.104797 -433.612237) (xy 278.157581 -433.59423)
			(xy 278.212424 -433.5841) (xy 278.268158 -433.582063) (xy 278.323595 -433.588163) (xy 278.377552 -433.602269)
			(xy 278.428881 -433.624081) (xy 278.476487 -433.653135) (xy 278.519355 -433.68881) (xy 278.556572 -433.730347)
			(xy 278.587345 -433.77686) (xy 278.611017 -433.827357) (xy 278.627085 -433.880764) (xy 278.635205 -433.93594)
			(xy 278.635714 -433.963826) (xy 278.635205 -433.991712) (xy 278.627085 -434.046888) (xy 278.611017 -434.100295)
			(xy 278.587345 -434.150792) (xy 278.556572 -434.197305) (xy 278.519355 -434.238842) (xy 278.476487 -434.274517)
			(xy 278.428881 -434.303571) (xy 278.377552 -434.325383) (xy 278.323595 -434.339489) (xy 278.268158 -434.345589)
			(xy 278.212424 -434.343552) (xy 278.157581 -434.333422) (xy 278.104797 -434.315415) (xy 278.055197 -434.289914)
			(xy 278.009839 -434.257463) (xy 277.96969 -434.218754) (xy 277.935604 -434.174611) (xy 277.908308 -434.125976)
			(xy 277.888385 -434.073885) (xy 277.876259 -434.019448) (xy 277.872188 -433.963826) (xy 274.676018 -433.963826)
			(xy 274.666078 -434.007377) (xy 274.618911 -434.17828) (xy 274.564125 -434.346895) (xy 274.501829 -434.512883)
			(xy 274.440668 -434.655976) (xy 282.434284 -434.655976) (xy 282.434786 -434.624015) (xy 282.442797 -434.560597)
			(xy 282.458694 -434.498683) (xy 282.482226 -434.43925) (xy 282.51302 -434.383235) (xy 282.550593 -434.33152)
			(xy 282.59435 -434.284923) (xy 282.643603 -434.244178) (xy 282.697574 -434.209927) (xy 282.755413 -434.18271)
			(xy 282.816206 -434.162957) (xy 282.878996 -434.150979) (xy 282.942792 -434.146966) (xy 283.006588 -434.150979)
			(xy 283.069378 -434.162957) (xy 283.130171 -434.18271) (xy 283.18801 -434.209927) (xy 283.241981 -434.244178)
			(xy 283.291234 -434.284923) (xy 283.334991 -434.33152) (xy 283.372564 -434.383235) (xy 283.403358 -434.43925)
			(xy 283.42689 -434.498683) (xy 283.442787 -434.560597) (xy 283.450798 -434.624015) (xy 283.4513 -434.655976)
			(xy 283.450818 -434.688126) (xy 283.442721 -434.751915) (xy 283.42664 -434.814173) (xy 283.402834 -434.873904)
			(xy 283.371681 -434.930154) (xy 283.33368 -434.982025) (xy 283.289439 -435.028686) (xy 283.264864 -435.049422)
			(xy 283.257244 -435.055772) (xy 283.247846 -435.07279) (xy 283.236924 -435.162452) (xy 283.242004 -435.180994)
			(xy 283.2481 -435.189122) (xy 283.266003 -435.21406) (xy 283.294466 -435.268448) (xy 283.31386 -435.326689)
			(xy 283.323685 -435.387283) (xy 283.3243 -435.417976) (xy 283.323814 -435.445227) (xy 283.316058 -435.499175)
			(xy 283.300703 -435.55147) (xy 283.278061 -435.601047) (xy 283.248595 -435.646897) (xy 283.212904 -435.688088)
			(xy 283.171713 -435.723779) (xy 283.125863 -435.753245) (xy 283.076286 -435.775887) (xy 283.023991 -435.791242)
			(xy 282.970043 -435.798998) (xy 282.915541 -435.798998) (xy 282.861593 -435.791242) (xy 282.809298 -435.775887)
			(xy 282.759721 -435.753245) (xy 282.713871 -435.723779) (xy 282.67268 -435.688088) (xy 282.636989 -435.646897)
			(xy 282.607523 -435.601047) (xy 282.584881 -435.55147) (xy 282.569526 -435.499175) (xy 282.56177 -435.445227)
			(xy 282.561284 -435.417976) (xy 282.561895 -435.387283) (xy 282.57172 -435.326688) (xy 282.591114 -435.268446)
			(xy 282.619576 -435.214057) (xy 282.637484 -435.189122) (xy 282.64358 -435.180994) (xy 282.64866 -435.162452)
			(xy 282.637738 -435.07279) (xy 282.62834 -435.055772) (xy 282.62072 -435.049422) (xy 282.596158 -435.028674)
			(xy 282.551932 -434.982004) (xy 282.513943 -434.930131) (xy 282.482795 -434.873883) (xy 282.458986 -434.814157)
			(xy 282.442896 -434.751906) (xy 282.434781 -434.688124) (xy 282.434284 -434.655976) (xy 274.440668 -434.655976)
			(xy 274.432149 -434.675908) (xy 274.355224 -434.835643) (xy 274.271211 -434.991766) (xy 274.180278 -435.143962)
			(xy 274.082608 -435.291926) (xy 273.978398 -435.435358) (xy 273.867858 -435.573971) (xy 273.751211 -435.707485)
			(xy 273.628691 -435.835631) (xy 273.500545 -435.958151) (xy 273.367031 -436.074798) (xy 273.228418 -436.185338)
			(xy 273.084986 -436.289548) (xy 273.037243 -436.321063) (xy 276.104713 -436.321063) (xy 276.109924 -436.258198)
			(xy 276.122871 -436.19646) (xy 276.143356 -436.136798) (xy 276.171062 -436.080128) (xy 276.205566 -436.027321)
			(xy 276.246337 -435.979187) (xy 276.292748 -435.936465) (xy 276.344088 -435.899812) (xy 276.399566 -435.869792)
			(xy 276.458333 -435.846864) (xy 276.519483 -435.831381) (xy 276.58208 -435.82358) (xy 276.61362 -435.823106)
			(xy 276.643941 -435.823541) (xy 276.704153 -435.830737) (xy 276.763084 -435.845037) (xy 276.819899 -435.866237)
			(xy 276.847046 -435.879748) (xy 276.860035 -435.885953) (xy 276.88826 -435.891548) (xy 276.916925 -435.889045)
			(xy 276.943753 -435.878643) (xy 276.966614 -435.861169) (xy 276.983691 -435.838011) (xy 276.993629 -435.811007)
			(xy 276.995128 -435.79669) (xy 276.997674 -435.768169) (xy 277.010192 -435.712296) (xy 277.030921 -435.658921)
			(xy 277.059397 -435.609245) (xy 277.094978 -435.564384) (xy 277.136866 -435.525346) (xy 277.184119 -435.493009)
			(xy 277.235675 -435.468098) (xy 277.290375 -435.451174) (xy 277.346991 -435.442618) (xy 277.37562 -435.442106)
			(xy 277.402871 -435.442565) (xy 277.456819 -435.450324) (xy 277.509113 -435.465682) (xy 277.55869 -435.488325)
			(xy 277.604539 -435.517793) (xy 277.645729 -435.553486) (xy 277.681419 -435.594677) (xy 277.710885 -435.640528)
			(xy 277.733525 -435.690106) (xy 277.74888 -435.742401) (xy 277.756636 -435.796349) (xy 277.756636 -435.850851)
			(xy 277.74888 -435.904799) (xy 277.733525 -435.957094) (xy 277.710885 -436.006672) (xy 277.681419 -436.052523)
			(xy 277.645729 -436.093714) (xy 277.604539 -436.129407) (xy 277.55869 -436.158875) (xy 277.509113 -436.181518)
			(xy 277.456819 -436.196876) (xy 277.402871 -436.204635) (xy 277.37562 -436.205122) (xy 277.344647 -436.204558)
			(xy 277.283508 -436.194598) (xy 277.253954 -436.18531) (xy 277.240167 -436.181197) (xy 277.211436 -436.179973)
			(xy 277.183505 -436.186814) (xy 277.158592 -436.201178) (xy 277.138677 -436.221923) (xy 277.125342 -436.247401)
			(xy 277.119646 -436.275588) (xy 277.12035 -436.289958) (xy 277.122128 -436.331614) (xy 277.121617 -436.363154)
			(xy 277.113813 -436.42575) (xy 277.098326 -436.4869) (xy 277.075394 -436.545664) (xy 277.04537 -436.601141)
			(xy 277.029252 -436.623714) (xy 282.066236 -436.623714) (xy 282.070307 -436.568092) (xy 282.082433 -436.513655)
			(xy 282.102356 -436.461564) (xy 282.129652 -436.412929) (xy 282.163738 -436.368786) (xy 282.203887 -436.330077)
			(xy 282.249245 -436.297626) (xy 282.298845 -436.272125) (xy 282.351629 -436.254118) (xy 282.406472 -436.243988)
			(xy 282.462206 -436.241951) (xy 282.517643 -436.248051) (xy 282.5716 -436.262157) (xy 282.622929 -436.283969)
			(xy 282.670535 -436.313023) (xy 282.713403 -436.348698) (xy 282.75062 -436.390235) (xy 282.781393 -436.436748)
			(xy 282.805065 -436.487245) (xy 282.821133 -436.540652) (xy 282.829253 -436.595828) (xy 282.829762 -436.623714)
			(xy 282.829253 -436.6516) (xy 282.821133 -436.706776) (xy 282.805065 -436.760183) (xy 282.781393 -436.81068)
			(xy 282.75062 -436.857193) (xy 282.713403 -436.89873) (xy 282.670535 -436.934405) (xy 282.622929 -436.963459)
			(xy 282.5716 -436.985271) (xy 282.517643 -436.999377) (xy 282.462206 -437.005477) (xy 282.406472 -437.00344)
			(xy 282.351629 -436.99331) (xy 282.298845 -436.975303) (xy 282.249245 -436.949802) (xy 282.203887 -436.917351)
			(xy 282.163738 -436.878642) (xy 282.129652 -436.834499) (xy 282.102356 -436.785864) (xy 282.082433 -436.733773)
			(xy 282.070307 -436.679336) (xy 282.066236 -436.623714) (xy 277.029252 -436.623714) (xy 277.008713 -436.652478)
			(xy 276.965989 -436.698887) (xy 276.917852 -436.739654) (xy 276.865042 -436.774154) (xy 276.80837 -436.801857)
			(xy 276.748707 -436.822338) (xy 276.686969 -436.835281) (xy 276.624103 -436.840488) (xy 276.561077 -436.837879)
			(xy 276.498857 -436.827495) (xy 276.4384 -436.809494) (xy 276.380633 -436.784153) (xy 276.326444 -436.751861)
			(xy 276.276666 -436.713114) (xy 276.232063 -436.668508) (xy 276.19332 -436.618727) (xy 276.161032 -436.564537)
			(xy 276.135695 -436.506769) (xy 276.117698 -436.44631) (xy 276.107317 -436.384089) (xy 276.104713 -436.321063)
			(xy 273.037243 -436.321063) (xy 272.937022 -436.387218) (xy 272.784826 -436.478151) (xy 272.628703 -436.562164)
			(xy 272.468968 -436.639089) (xy 272.305943 -436.708769) (xy 272.139955 -436.771065) (xy 271.97134 -436.825851)
			(xy 271.800437 -436.873018) (xy 271.62759 -436.912469) (xy 271.453147 -436.944126) (xy 271.277459 -436.967924)
			(xy 271.10088 -436.983817) (xy 270.923766 -436.991771) (xy 270.746474 -436.991771) (xy 270.56936 -436.983817)
			(xy 270.392781 -436.967924) (xy 270.217093 -436.944126) (xy 270.04265 -436.912469) (xy 269.869803 -436.873018)
			(xy 269.6989 -436.825851) (xy 269.530285 -436.771065) (xy 269.364297 -436.708769) (xy 269.201272 -436.639089)
			(xy 269.041537 -436.562164) (xy 268.885414 -436.478151) (xy 268.733218 -436.387218) (xy 268.585254 -436.289548)
			(xy 268.441822 -436.185338) (xy 268.303209 -436.074798) (xy 268.169695 -435.958151) (xy 268.041549 -435.835631)
			(xy 267.919029 -435.707485) (xy 267.802382 -435.573971) (xy 267.691842 -435.435358) (xy 267.587632 -435.291926)
			(xy 267.489962 -435.143962) (xy 267.399029 -434.991766) (xy 267.315016 -434.835643) (xy 267.238091 -434.675908)
			(xy 267.168411 -434.512883) (xy 267.106115 -434.346895) (xy 267.051329 -434.17828) (xy 267.004162 -434.007377)
			(xy 266.964711 -433.83453) (xy 266.933054 -433.660087) (xy 266.909256 -433.484399) (xy 266.893363 -433.30782)
			(xy 266.885409 -433.130706) (xy 265.530076 -433.130706) (xy 265.530076 -436.22468) (xy 265.529638 -436.234743)
			(xy 265.5219 -436.253324) (xy 265.51509 -436.260748) (xy 264.691368 -437.08447) (xy 264.683969 -437.091315)
			(xy 264.665371 -437.099042) (xy 264.6553 -437.099456) (xy 229.231698 -437.099456) (xy 229.212902 -437.107076)
			(xy 229.206044 -437.114188) (xy 207.181958 -437.114188) (xy 207.163162 -437.106314) (xy 207.156304 -437.099456)
			(xy 199.533002 -437.099456) (xy 199.522933 -437.099032) (xy 199.504332 -437.091313) (xy 199.496934 -437.08447)
			(xy 198.613268 -436.200804) (xy 198.61022 -436.198518) (xy 198.536696 -436.142527) (xy 198.394359 -436.024618)
			(xy 198.257693 -435.900181) (xy 198.126996 -435.769488) (xy 198.002555 -435.632826) (xy 197.884643 -435.490492)
			(xy 197.828662 -435.41696) (xy 197.826376 -435.413912) (xy 195.322698 -432.910234) (xy 195.315862 -432.902832)
			(xy 195.308152 -432.884234) (xy 195.307712 -432.874166) (xy 195.307712 -430.97958) (xy 195.307262 -430.969553)
			(xy 195.299672 -430.950994) (xy 195.29298 -430.943512) (xy 195.27139 -430.922176) (xy 195.264429 -430.915708)
			(xy 195.247075 -430.907996) (xy 195.237608 -430.90719) (xy 195.205227 -430.905366) (xy 195.141284 -430.894519)
			(xy 195.079239 -430.875628) (xy 195.020101 -430.848999) (xy 194.96483 -430.815066) (xy 194.914323 -430.774379)
			(xy 194.869401 -430.727599) (xy 194.830793 -430.675485) (xy 194.799126 -430.618885) (xy 194.774915 -430.558717)
			(xy 194.758552 -430.495958) (xy 194.750303 -430.431628) (xy 194.750304 -430.366771) (xy 194.758552 -430.302441)
			(xy 194.774915 -430.239683) (xy 194.799126 -430.179514) (xy 194.830793 -430.122914) (xy 194.869401 -430.070801)
			(xy 194.914324 -430.024021) (xy 194.964831 -429.983334) (xy 195.020102 -429.9494) (xy 195.07924 -429.922772)
			(xy 195.141285 -429.903881) (xy 195.205228 -429.893034) (xy 195.237608 -429.89119) (xy 195.247078 -429.890383)
			(xy 195.264441 -429.882687) (xy 195.27139 -429.876204) (xy 195.29298 -429.854868) (xy 195.299755 -429.847443)
			(xy 195.30734 -429.828846) (xy 195.307712 -429.8188) (xy 195.307712 -429.30318) (xy 195.307203 -429.293002)
			(xy 195.299206 -429.274276) (xy 195.292218 -429.266858) (xy 195.232528 -429.208692) (xy 195.213986 -429.201326)
			(xy 195.203318 -429.20158) (xy 195.189602 -429.201834) (xy 195.157638 -429.201353) (xy 195.094214 -429.193341)
			(xy 195.032294 -429.177443) (xy 194.972855 -429.15391) (xy 194.916834 -429.123112) (xy 194.865115 -429.085536)
			(xy 194.818514 -429.041775) (xy 194.777764 -428.992517) (xy 194.74351 -428.938541) (xy 194.71629 -428.880697)
			(xy 194.696536 -428.819898) (xy 194.684557 -428.757102) (xy 194.680542 -428.6933) (xy 194.684557 -428.629498)
			(xy 194.696536 -428.566702) (xy 194.71629 -428.505903) (xy 194.74351 -428.448059) (xy 194.777764 -428.394083)
			(xy 194.818514 -428.344825) (xy 194.865115 -428.301064) (xy 194.916834 -428.263488) (xy 194.972855 -428.23269)
			(xy 195.032294 -428.209157) (xy 195.094214 -428.193259) (xy 195.157638 -428.185247) (xy 195.189602 -428.184818)
			(xy 195.203318 -428.185072) (xy 195.213986 -428.185326) (xy 195.232528 -428.17796) (xy 195.292218 -428.119794)
			(xy 195.299242 -428.112398) (xy 195.307253 -428.09366) (xy 195.307712 -428.083472) (xy 195.307712 -426.240194)
			(xy 195.307333 -426.230767) (xy 195.300508 -426.213192) (xy 195.287785 -426.199277) (xy 195.279518 -426.194728)
			(xy 195.18503 -426.147738) (xy 195.156582 -426.150278) (xy 195.144898 -426.159168) (xy 195.119894 -426.177328)
			(xy 195.065243 -426.206169) (xy 195.006658 -426.225825) (xy 194.945671 -426.235781) (xy 194.914774 -426.236384)
			(xy 194.887526 -426.235896) (xy 194.833584 -426.228137) (xy 194.781296 -426.212781) (xy 194.731725 -426.190139)
			(xy 194.685881 -426.160674) (xy 194.644697 -426.124985) (xy 194.60901 -426.083798) (xy 194.579548 -426.037952)
			(xy 194.55691 -425.98838) (xy 194.541557 -425.93609) (xy 194.533802 -425.882148) (xy 194.533802 -425.827652)
			(xy 194.541557 -425.77371) (xy 194.55691 -425.72142) (xy 194.579548 -425.671848) (xy 194.60901 -425.626002)
			(xy 194.644697 -425.584815) (xy 194.685881 -425.549126) (xy 194.731725 -425.519661) (xy 194.781296 -425.497019)
			(xy 194.833584 -425.481663) (xy 194.887526 -425.473904) (xy 194.914774 -425.473368) (xy 194.945672 -425.473963)
			(xy 195.006661 -425.483918) (xy 195.065248 -425.503572) (xy 195.119903 -425.532411) (xy 195.144898 -425.550584)
			(xy 195.156582 -425.559474) (xy 195.18503 -425.562014) (xy 195.279518 -425.515024) (xy 195.287761 -425.510446)
			(xy 195.300466 -425.496536) (xy 195.30729 -425.478977) (xy 195.307712 -425.469558) (xy 195.307712 -420.829486)
			(xy 195.307287 -420.819417) (xy 195.29957 -420.800815) (xy 195.292726 -420.793418) (xy 192.541398 -418.04209)
			(xy 192.534004 -418.035234) (xy 192.515405 -418.027486) (xy 192.50533 -418.027104) (xy 191.753236 -418.027104)
			(xy 191.743246 -418.027635) (xy 191.724805 -418.03534) (xy 191.717422 -418.04209) (xy 190.384176 -419.375336)
			(xy 190.3775 -419.382748) (xy 190.369935 -419.401185) (xy 190.369444 -419.41115) (xy 190.369444 -421.426132)
			(xy 190.504316 -421.426132) (xy 190.508387 -421.37051) (xy 190.520513 -421.316073) (xy 190.540436 -421.263982)
			(xy 190.567732 -421.215347) (xy 190.601818 -421.171204) (xy 190.641967 -421.132495) (xy 190.687325 -421.100044)
			(xy 190.736925 -421.074543) (xy 190.789709 -421.056536) (xy 190.844552 -421.046406) (xy 190.900286 -421.044369)
			(xy 190.955723 -421.050469) (xy 191.00968 -421.064575) (xy 191.061009 -421.086387) (xy 191.108615 -421.115441)
			(xy 191.151483 -421.151116) (xy 191.1887 -421.192653) (xy 191.219473 -421.239166) (xy 191.243145 -421.289663)
			(xy 191.259213 -421.34307) (xy 191.267333 -421.398246) (xy 191.267842 -421.426132) (xy 191.267333 -421.454018)
			(xy 191.259213 -421.509194) (xy 191.243145 -421.562601) (xy 191.219473 -421.613098) (xy 191.1887 -421.659611)
			(xy 191.151483 -421.701148) (xy 191.108615 -421.736823) (xy 191.061009 -421.765877) (xy 191.00968 -421.787689)
			(xy 190.955723 -421.801795) (xy 190.900286 -421.807895) (xy 190.844552 -421.805858) (xy 190.789709 -421.795728)
			(xy 190.736925 -421.777721) (xy 190.687325 -421.75222) (xy 190.641967 -421.719769) (xy 190.601818 -421.68106)
			(xy 190.567732 -421.636917) (xy 190.540436 -421.588282) (xy 190.520513 -421.536191) (xy 190.508387 -421.481754)
			(xy 190.504316 -421.426132) (xy 190.369444 -421.426132) (xy 190.369444 -423.434256) (xy 190.369875 -423.443643)
			(xy 190.376624 -423.461162) (xy 190.389204 -423.475098) (xy 190.397384 -423.479722) (xy 190.491872 -423.526712)
			(xy 190.52032 -423.524172) (xy 190.532004 -423.515282) (xy 190.556981 -423.49723) (xy 190.611535 -423.468572)
			(xy 190.669983 -423.449045) (xy 190.730808 -423.439154) (xy 190.76162 -423.438574) (xy 190.790084 -423.439101)
			(xy 190.846381 -423.447556) (xy 190.900798 -423.464276) (xy 190.95213 -423.48889) (xy 190.999238 -423.520853)
			(xy 191.041078 -423.559455) (xy 191.059308 -423.581322) (xy 191.065658 -423.58945) (xy 191.083438 -423.599102)
			(xy 191.175386 -423.608754) (xy 191.19469 -423.603166) (xy 191.202564 -423.596562) (xy 191.229906 -423.5751)
			(xy 191.289307 -423.539004) (xy 191.353069 -423.511328) (xy 191.420003 -423.492588) (xy 191.488866 -423.483131)
			(xy 191.52362 -423.482516) (xy 191.554351 -423.482963) (xy 191.615364 -423.490374) (xy 191.675039 -423.505085)
			(xy 191.732506 -423.526882) (xy 191.786926 -423.555447) (xy 191.837507 -423.590363) (xy 191.88351 -423.631122)
			(xy 191.924264 -423.677128) (xy 191.959176 -423.727711) (xy 191.987736 -423.782134) (xy 192.002126 -423.820082)
			(xy 193.173602 -423.820082) (xy 193.177673 -423.76446) (xy 193.189799 -423.710023) (xy 193.209722 -423.657932)
			(xy 193.237018 -423.609297) (xy 193.271104 -423.565154) (xy 193.311253 -423.526445) (xy 193.356611 -423.493994)
			(xy 193.406211 -423.468493) (xy 193.458995 -423.450486) (xy 193.513838 -423.440356) (xy 193.569572 -423.438319)
			(xy 193.625009 -423.444419) (xy 193.678966 -423.458525) (xy 193.730295 -423.480337) (xy 193.777901 -423.509391)
			(xy 193.820769 -423.545066) (xy 193.857986 -423.586603) (xy 193.888759 -423.633116) (xy 193.912431 -423.683613)
			(xy 193.928499 -423.73702) (xy 193.936619 -423.792196) (xy 193.937128 -423.820082) (xy 193.936619 -423.847968)
			(xy 193.928499 -423.903144) (xy 193.912431 -423.956551) (xy 193.888759 -424.007048) (xy 193.857986 -424.053561)
			(xy 193.820769 -424.095098) (xy 193.777901 -424.130773) (xy 193.730295 -424.159827) (xy 193.678966 -424.181639)
			(xy 193.625009 -424.195745) (xy 193.569572 -424.201845) (xy 193.513838 -424.199808) (xy 193.458995 -424.189678)
			(xy 193.406211 -424.171671) (xy 193.356611 -424.14617) (xy 193.311253 -424.113719) (xy 193.271104 -424.07501)
			(xy 193.237018 -424.030867) (xy 193.209722 -423.982232) (xy 193.189799 -423.930141) (xy 193.177673 -423.875704)
			(xy 193.173602 -423.820082) (xy 192.002126 -423.820082) (xy 192.009528 -423.839603) (xy 192.024234 -423.899279)
			(xy 192.03164 -423.960293) (xy 192.032128 -423.991024) (xy 192.031706 -424.020828) (xy 192.024741 -424.080028)
			(xy 192.010899 -424.138007) (xy 191.99037 -424.193969) (xy 191.963435 -424.247145) (xy 191.947292 -424.272202)
			(xy 191.940688 -424.282108) (xy 191.93764 -424.305222) (xy 191.970914 -424.404028) (xy 191.987424 -424.420538)
			(xy 191.9986 -424.424348) (xy 192.023237 -424.433353) (xy 192.069976 -424.457168) (xy 192.113011 -424.487161)
			(xy 192.151531 -424.522768) (xy 192.184809 -424.563316) (xy 192.212219 -424.608041) (xy 192.233242 -424.6561)
			(xy 192.247484 -424.706585) (xy 192.254674 -424.758546) (xy 192.25514 -424.784774) (xy 192.254654 -424.812025)
			(xy 192.246898 -424.865973) (xy 192.231543 -424.918268) (xy 192.208901 -424.967845) (xy 192.179435 -425.013695)
			(xy 192.143744 -425.054886) (xy 192.102553 -425.090577) (xy 192.056703 -425.120043) (xy 192.007126 -425.142685)
			(xy 191.954831 -425.15804) (xy 191.900883 -425.165796) (xy 191.846381 -425.165796) (xy 191.792433 -425.15804)
			(xy 191.740138 -425.142685) (xy 191.690561 -425.120043) (xy 191.644711 -425.090577) (xy 191.60352 -425.054886)
			(xy 191.567829 -425.013695) (xy 191.538363 -424.967845) (xy 191.515721 -424.918268) (xy 191.500366 -424.865973)
			(xy 191.49261 -424.812025) (xy 191.492124 -424.784774) (xy 191.492536 -424.758914) (xy 191.499484 -424.707665)
			(xy 191.513292 -424.657824) (xy 191.523112 -424.633898) (xy 191.527938 -424.622976) (xy 191.526668 -424.599862)
			(xy 191.476376 -424.508676) (xy 191.457326 -424.495214) (xy 191.445388 -424.493436) (xy 191.414985 -424.488242)
			(xy 191.355635 -424.471447) (xy 191.298751 -424.447599) (xy 191.245168 -424.417048) (xy 191.195672 -424.380243)
			(xy 191.15099 -424.337722) (xy 191.111777 -424.290111) (xy 191.078608 -424.238108) (xy 191.064896 -424.21048)
			(xy 191.060578 -424.201336) (xy 191.045592 -424.187874) (xy 190.957962 -424.157394) (xy 190.937896 -424.158664)
			(xy 190.928752 -424.162982) (xy 190.902586 -424.175143) (xy 190.847506 -424.192329) (xy 190.790469 -424.201045)
			(xy 190.76162 -424.20159) (xy 190.730806 -424.201023) (xy 190.669974 -424.191155) (xy 190.611523 -424.171625)
			(xy 190.556978 -424.142941) (xy 190.532004 -424.124882) (xy 190.52032 -424.115992) (xy 190.491872 -424.113452)
			(xy 190.397384 -424.160442) (xy 190.389135 -424.164987) (xy 190.376488 -424.178925) (xy 190.369746 -424.196496)
			(xy 190.369444 -424.205908) (xy 190.369444 -424.966892) (xy 190.369917 -424.977888) (xy 190.378998 -424.997912)
			(xy 190.38697 -425.0055) (xy 190.410507 -425.02623) (xy 190.452811 -425.07254) (xy 190.489097 -425.123701)
			(xy 190.518814 -425.178937) (xy 190.541512 -425.237409) (xy 190.556845 -425.298229) (xy 190.56458 -425.360473)
			(xy 190.565024 -425.391834) (xy 190.564522 -425.423795) (xy 190.556511 -425.487213) (xy 190.540614 -425.549127)
			(xy 190.517082 -425.60856) (xy 190.486288 -425.664575) (xy 190.448715 -425.71629) (xy 190.404958 -425.762887)
			(xy 190.355705 -425.803632) (xy 190.301734 -425.837883) (xy 190.243895 -425.8651) (xy 190.183102 -425.884853)
			(xy 190.120312 -425.896831) (xy 190.056516 -425.900845) (xy 189.99272 -425.896831) (xy 189.92993 -425.884853)
			(xy 189.869137 -425.8651) (xy 189.811298 -425.837883) (xy 189.757327 -425.803632) (xy 189.708074 -425.762887)
			(xy 189.664317 -425.71629) (xy 189.626744 -425.664575) (xy 189.59595 -425.60856) (xy 189.572418 -425.549127)
			(xy 189.556521 -425.487213) (xy 189.54851 -425.423795) (xy 189.548008 -425.391834) (xy 189.548471 -425.360472)
			(xy 189.556188 -425.298224) (xy 189.571508 -425.2374) (xy 189.594199 -425.178924) (xy 189.623916 -425.123686)
			(xy 189.660205 -425.072526) (xy 189.702517 -425.026222) (xy 189.726062 -425.0055) (xy 189.734008 -424.997893)
			(xy 189.743082 -424.977881) (xy 189.743588 -424.966892) (xy 189.743588 -421.922956) (xy 189.743226 -421.912928)
			(xy 189.735621 -421.894376) (xy 189.721447 -421.880194) (xy 189.712346 -421.875966) (xy 189.697868 -421.86987)
			(xy 189.66815 -421.875966) (xy 188.927232 -422.616884) (xy 188.920542 -422.624291) (xy 188.912949 -422.642728)
			(xy 188.9125 -422.652698) (xy 188.9125 -425.609258) (xy 188.912985 -425.619221) (xy 188.92057 -425.637647)
			(xy 188.927232 -425.645072) (xy 189.513718 -426.231558) (xy 189.521062 -426.23837) (xy 189.539525 -426.246103)
			(xy 189.549532 -426.246544) (xy 189.67196 -426.246544) (xy 189.682984 -426.246013) (xy 189.703017 -426.23681)
			(xy 189.710568 -426.228764) (xy 189.731299 -426.205228) (xy 189.777609 -426.162928) (xy 189.828771 -426.126647)
			(xy 189.884007 -426.096935) (xy 189.942479 -426.074243) (xy 190.003299 -426.058917) (xy 190.065542 -426.051189)
			(xy 190.096902 -426.05071) (xy 190.128862 -426.051212) (xy 190.192277 -426.059223) (xy 190.254189 -426.07512)
			(xy 190.31362 -426.09865) (xy 190.369633 -426.129444) (xy 190.421345 -426.167015) (xy 190.46794 -426.210771)
			(xy 190.508684 -426.260022) (xy 190.542934 -426.313992) (xy 190.570149 -426.371828) (xy 190.589902 -426.432619)
			(xy 190.601879 -426.495406) (xy 190.605893 -426.5592) (xy 190.601879 -426.622994) (xy 190.589902 -426.685781)
			(xy 190.570149 -426.746572) (xy 190.542934 -426.804408) (xy 190.508684 -426.858378) (xy 190.46794 -426.907629)
			(xy 190.421345 -426.951385) (xy 190.369633 -426.988956) (xy 190.31362 -427.01975) (xy 190.254189 -427.04328)
			(xy 190.192277 -427.059177) (xy 190.128862 -427.067188) (xy 190.096902 -427.067726) (xy 190.065541 -427.06726)
			(xy 190.003297 -427.059539) (xy 189.942477 -427.044214) (xy 189.884005 -427.021519) (xy 189.828773 -426.991798)
			(xy 189.777619 -426.955504) (xy 189.731322 -426.913188) (xy 189.710568 -426.889672) (xy 189.702993 -426.881657)
			(xy 189.682976 -426.872454) (xy 189.67196 -426.871892) (xy 189.39891 -426.871892) (xy 189.374333 -426.871426)
			(xy 189.325778 -426.86377) (xy 189.279019 -426.848614) (xy 189.235206 -426.826329) (xy 189.195419 -426.797466)
			(xy 189.177676 -426.780452) (xy 188.378338 -425.981114) (xy 188.361259 -425.963414) (xy 188.332323 -425.92364)
			(xy 188.309974 -425.879825) (xy 188.294762 -425.833052) (xy 188.287062 -425.784473) (xy 188.286644 -425.75988)
			(xy 188.286644 -422.502076) (xy 188.287104 -422.477486) (xy 188.294805 -422.428913) (xy 188.310013 -422.382144)
			(xy 188.332353 -422.338331) (xy 188.361275 -422.298554) (xy 188.378338 -422.280842) (xy 189.307216 -421.351964)
			(xy 189.313893 -421.344552) (xy 189.32146 -421.326116) (xy 189.321948 -421.31615) (xy 189.321948 -421.198294)
			(xy 189.32146 -421.188284) (xy 189.313801 -421.169786) (xy 189.29965 -421.155623) (xy 189.281158 -421.147949)
			(xy 189.271148 -421.147494) (xy 189.258448 -421.147494) (xy 189.235842 -421.159686) (xy 189.22873 -421.170608)
			(xy 189.213526 -421.192887) (xy 189.177845 -421.233334) (xy 189.136824 -421.268353) (xy 189.091279 -421.297247)
			(xy 189.04212 -421.319439) (xy 188.990326 -421.334486) (xy 188.936928 -421.34209) (xy 188.90996 -421.342566)
			(xy 188.882714 -421.342077) (xy 188.828776 -421.334317) (xy 188.776492 -421.31896) (xy 188.726925 -421.296319)
			(xy 188.681085 -421.266855) (xy 188.639904 -421.231167) (xy 188.604221 -421.189983) (xy 188.574762 -421.144139)
			(xy 188.552126 -421.09457) (xy 188.536775 -421.042285) (xy 188.52902 -420.988346) (xy 188.52902 -420.933854)
			(xy 188.536775 -420.879915) (xy 188.552126 -420.82763) (xy 188.574762 -420.778061) (xy 188.604221 -420.732217)
			(xy 188.639904 -420.691033) (xy 188.681085 -420.655345) (xy 188.726925 -420.625881) (xy 188.776492 -420.60324)
			(xy 188.828776 -420.587883) (xy 188.882714 -420.580123) (xy 188.90996 -420.57955) (xy 188.936591 -420.580011)
			(xy 188.989335 -420.587413) (xy 189.040538 -420.602079) (xy 189.089203 -420.623724) (xy 189.134384 -420.651927)
			(xy 189.15507 -420.668704) (xy 189.1665 -420.678356) (xy 189.195964 -420.682166) (xy 189.292738 -420.636954)
			(xy 189.301259 -420.632487) (xy 189.314415 -420.618469) (xy 189.321486 -420.600592) (xy 189.321948 -420.59098)
			(xy 189.321948 -418.077904) (xy 189.321461 -418.067892) (xy 189.313804 -418.049391) (xy 189.299653 -418.035225)
			(xy 189.281159 -418.027549) (xy 189.271148 -418.027104) (xy 189.071504 -418.027104) (xy 189.061153 -418.027534)
			(xy 189.0421 -418.03562) (xy 189.02781 -418.050592) (xy 189.023752 -418.060124) (xy 188.984636 -418.16401)
			(xy 188.992256 -418.19449) (xy 189.004448 -418.205158) (xy 189.027387 -418.225884) (xy 189.068582 -418.271984)
			(xy 189.103887 -418.322736) (xy 189.13278 -418.377392) (xy 189.154837 -418.435148) (xy 189.169732 -418.495151)
			(xy 189.177245 -418.556516) (xy 189.177676 -418.587428) (xy 189.177229 -418.618158) (xy 189.169817 -418.67917)
			(xy 189.155105 -418.738844) (xy 189.133308 -418.79631) (xy 189.104742 -418.850729) (xy 189.069826 -418.901308)
			(xy 189.029067 -418.94731) (xy 188.983061 -418.988063) (xy 188.932478 -419.022973) (xy 188.878055 -419.051532)
			(xy 188.820587 -419.073323) (xy 188.760911 -419.088028) (xy 188.699898 -419.095432) (xy 188.669168 -419.095936)
			(xy 188.63532 -419.095377) (xy 188.568221 -419.086395) (xy 188.502907 -419.068593) (xy 188.440531 -419.042285)
			(xy 188.382195 -419.007938) (xy 188.355224 -418.987478) (xy 188.348114 -418.982334) (xy 188.331487 -418.976762)
			(xy 188.322712 -418.976556) (xy 188.29274 -418.977318) (xy 188.283988 -418.977847) (xy 188.267608 -418.984067)
			(xy 188.260736 -418.98951) (xy 188.237632 -419.008759) (xy 188.187699 -419.042271) (xy 188.134162 -419.069661)
			(xy 188.077768 -419.090545) (xy 188.019305 -419.104633) (xy 187.959588 -419.111728) (xy 187.92952 -419.112192)
			(xy 187.898438 -419.111726) (xy 187.836739 -419.104149) (xy 187.776423 -419.089105) (xy 187.718392 -419.06682)
			(xy 187.663511 -419.037624) (xy 187.612599 -419.001955) (xy 187.566417 -418.960345) (xy 187.525652 -418.913414)
			(xy 187.50788 -418.88791) (xy 187.499752 -418.875972) (xy 187.474098 -418.864034) (xy 187.355988 -418.87775)
			(xy 187.333636 -418.895276) (xy 187.328556 -418.908738) (xy 187.317244 -418.937319) (xy 187.288684 -418.991752)
			(xy 187.25377 -419.042345) (xy 187.213012 -419.08836) (xy 187.167003 -419.129125) (xy 187.116415 -419.164046)
			(xy 187.061986 -419.192614) (xy 187.00451 -419.214412) (xy 186.944826 -419.229122) (xy 186.883803 -419.236528)
			(xy 186.853068 -419.236906) (xy 186.821108 -419.236402) (xy 186.757694 -419.228387) (xy 186.695783 -419.212488)
			(xy 186.636354 -419.188955) (xy 186.580342 -419.158159) (xy 186.528632 -419.120586) (xy 186.482038 -419.076829)
			(xy 186.441296 -419.027577) (xy 186.407048 -418.973608) (xy 186.379833 -418.915771) (xy 186.360082 -418.85498)
			(xy 186.348105 -418.792193) (xy 186.344091 -418.7284) (xy 186.348105 -418.664607) (xy 186.360082 -418.60182)
			(xy 186.379833 -418.541029) (xy 186.407048 -418.483192) (xy 186.441296 -418.429223) (xy 186.482038 -418.379971)
			(xy 186.528632 -418.336214) (xy 186.580342 -418.298641) (xy 186.636354 -418.267845) (xy 186.695783 -418.244312)
			(xy 186.757694 -418.228413) (xy 186.821108 -418.220398) (xy 186.853068 -418.21989) (xy 186.88415 -418.220355)
			(xy 186.945851 -418.227931) (xy 187.006168 -418.242973) (xy 187.064201 -418.265257) (xy 187.119083 -418.294451)
			(xy 187.169997 -418.330119) (xy 187.216182 -418.371728) (xy 187.256949 -418.418658) (xy 187.274708 -418.444172)
			(xy 187.282836 -418.45611) (xy 187.30849 -418.468048) (xy 187.4266 -418.454332) (xy 187.448952 -418.436806)
			(xy 187.454032 -418.423344) (xy 187.466964 -418.390891) (xy 187.500445 -418.329578) (xy 187.541994 -418.273418)
			(xy 187.590831 -418.223465) (xy 187.646038 -418.180657) (xy 187.676028 -418.16274) (xy 187.685593 -418.156543)
			(xy 187.698521 -418.137813) (xy 187.70092 -418.126672) (xy 187.705746 -418.095938) (xy 187.707015 -418.08393)
			(xy 187.699577 -418.060994) (xy 187.691522 -418.051996) (xy 187.681362 -418.04209) (xy 187.674014 -418.035287)
			(xy 187.655552 -418.02757) (xy 187.645548 -418.027104) (xy 184.171082 -418.027104) (xy 184.161096 -418.027645)
			(xy 184.142669 -418.035363) (xy 184.135268 -418.04209) (xy 183.735726 -418.441632) (xy 183.718013 -418.458681)
			(xy 183.678223 -418.487555) (xy 183.634405 -418.509845) (xy 183.587637 -418.525001) (xy 183.539073 -418.532648)
			(xy 183.514492 -418.533072) (xy 178.056032 -418.533072) (xy 178.031454 -418.532608) (xy 177.982898 -418.524955)
			(xy 177.936138 -418.5098) (xy 177.892323 -418.487516) (xy 177.852534 -418.458653) (xy 177.834798 -418.441632)
			(xy 177.435256 -418.04209) (xy 177.427908 -418.035287) (xy 177.409445 -418.027573) (xy 177.399442 -418.027104)
			(xy 174.81677 -418.027104) (xy 174.807061 -418.02754) (xy 174.789038 -418.034769) (xy 174.774994 -418.04818)
			(xy 174.770542 -418.056822) (xy 174.726092 -418.154866) (xy 174.73041 -418.18433) (xy 174.740316 -418.19576)
			(xy 174.758084 -418.216721) (xy 174.788036 -418.26279) (xy 174.811061 -418.312683) (xy 174.82668 -418.365365)
			(xy 174.83457 -418.419745) (xy 174.835058 -418.44722) (xy 174.834572 -418.474471) (xy 174.826816 -418.528419)
			(xy 174.811461 -418.580714) (xy 174.788819 -418.630291) (xy 174.759353 -418.676141) (xy 174.723662 -418.717332)
			(xy 174.682471 -418.753023) (xy 174.636621 -418.782489) (xy 174.587044 -418.805131) (xy 174.534749 -418.820486)
			(xy 174.480801 -418.828242) (xy 174.426299 -418.828242) (xy 174.372351 -418.820486) (xy 174.320056 -418.805131)
			(xy 174.270479 -418.782489) (xy 174.224629 -418.753023) (xy 174.183438 -418.717332) (xy 174.147747 -418.676141)
			(xy 174.118281 -418.630291) (xy 174.095639 -418.580714) (xy 174.080284 -418.528419) (xy 174.072528 -418.474471)
			(xy 174.072042 -418.44722) (xy 174.072546 -418.41975) (xy 174.080472 -418.365382) (xy 174.096106 -418.312712)
			(xy 174.119126 -418.262825) (xy 174.149055 -418.216751) (xy 174.166784 -418.19576) (xy 174.17669 -418.18433)
			(xy 174.181008 -418.154866) (xy 174.136558 -418.056822) (xy 174.132138 -418.048158) (xy 174.118083 -418.034737)
			(xy 174.100047 -418.027502) (xy 174.09033 -418.027104) (xy 172.87621 -418.027104) (xy 172.866139 -418.026683)
			(xy 172.847532 -418.018971) (xy 172.840142 -418.012118) (xy 171.517818 -416.689794) (xy 171.510874 -416.683414)
			(xy 171.493675 -416.675722) (xy 171.48429 -416.674808) (xy 171.454318 -416.673538) (xy 171.445537 -416.673508)
			(xy 171.428781 -416.678712) (xy 171.421552 -416.683698) (xy 171.396549 -416.70186) (xy 171.341898 -416.730707)
			(xy 171.283314 -416.75037) (xy 171.222326 -416.760333) (xy 171.191428 -416.760914) (xy 171.17792 -416.760793)
			(xy 171.150971 -416.758886) (xy 171.13758 -416.757104) (xy 171.126404 -416.75558) (xy 171.105576 -416.761676)
			(xy 171.039028 -416.819334) (xy 171.031193 -416.826922) (xy 171.022248 -416.846792) (xy 171.021756 -416.857688)
			(xy 171.021756 -418.110416) (xy 171.022468 -418.123143) (xy 171.034614 -418.145514) (xy 171.04487 -418.153088)
			(xy 171.127166 -418.206682) (xy 171.152566 -418.20846) (xy 171.164504 -418.203126) (xy 171.189005 -418.192763)
			(xy 171.240159 -418.178159) (xy 171.292845 -418.170802) (xy 171.319444 -418.17036) (xy 171.346694 -418.170849)
			(xy 171.400639 -418.17861) (xy 171.45293 -418.193969) (xy 171.502504 -418.216612) (xy 171.548351 -418.246079)
			(xy 171.589538 -418.28177) (xy 171.625228 -418.322959) (xy 171.654694 -418.368807) (xy 171.677335 -418.418381)
			(xy 171.692692 -418.470673) (xy 171.700452 -418.524618) (xy 171.700952 -418.551868) (xy 171.700265 -418.585272)
			(xy 171.688643 -418.651062) (xy 171.677838 -418.682678) (xy 171.67352 -418.694616) (xy 171.676822 -418.719)
			(xy 171.731686 -418.797486) (xy 171.739344 -418.807072) (xy 171.761094 -418.818348) (xy 171.773342 -418.819076)
			(xy 173.262798 -418.819076) (xy 173.287389 -418.819533) (xy 173.335966 -418.827229) (xy 173.38274 -418.842431)
			(xy 173.426559 -418.864766) (xy 173.466343 -418.893682) (xy 173.484032 -418.91077) (xy 173.824349 -419.251087)
			(xy 177.902102 -419.251087) (xy 177.902102 -419.187165) (xy 177.910113 -419.123747) (xy 177.92601 -419.061833)
			(xy 177.949542 -419.0024) (xy 177.980336 -418.946385) (xy 178.017909 -418.89467) (xy 178.061666 -418.848073)
			(xy 178.110919 -418.807328) (xy 178.16489 -418.773077) (xy 178.222729 -418.74586) (xy 178.283522 -418.726107)
			(xy 178.346312 -418.714129) (xy 178.410108 -418.710116) (xy 178.473904 -418.714129) (xy 178.536694 -418.726107)
			(xy 178.597487 -418.74586) (xy 178.655326 -418.773077) (xy 178.709297 -418.807328) (xy 178.75855 -418.848073)
			(xy 178.802307 -418.89467) (xy 178.83988 -418.946385) (xy 178.870674 -419.0024) (xy 178.894206 -419.061833)
			(xy 178.910103 -419.123747) (xy 178.918114 -419.187165) (xy 178.918616 -419.219126) (xy 178.918114 -419.251087)
			(xy 178.910103 -419.314505) (xy 178.894206 -419.376419) (xy 178.870674 -419.435852) (xy 178.83988 -419.491867)
			(xy 178.802307 -419.543582) (xy 178.75855 -419.590179) (xy 178.709297 -419.630924) (xy 178.655326 -419.665175)
			(xy 178.597487 -419.692392) (xy 178.536694 -419.712145) (xy 178.473904 -419.724123) (xy 178.410108 -419.728137)
			(xy 178.346312 -419.724123) (xy 178.283522 -419.712145) (xy 178.222729 -419.692392) (xy 178.16489 -419.665175)
			(xy 178.110919 -419.630924) (xy 178.061666 -419.590179) (xy 178.017909 -419.543582) (xy 177.980336 -419.491867)
			(xy 177.949542 -419.435852) (xy 177.92601 -419.376419) (xy 177.910113 -419.314505) (xy 177.902102 -419.251087)
			(xy 173.824349 -419.251087) (xy 174.922434 -420.349172) (xy 178.894992 -420.349172) (xy 178.899063 -420.29355)
			(xy 178.911189 -420.239113) (xy 178.931112 -420.187022) (xy 178.958408 -420.138387) (xy 178.992494 -420.094244)
			(xy 179.032643 -420.055535) (xy 179.078001 -420.023084) (xy 179.127601 -419.997583) (xy 179.180385 -419.979576)
			(xy 179.235228 -419.969446) (xy 179.290962 -419.967409) (xy 179.346399 -419.973509) (xy 179.400356 -419.987615)
			(xy 179.451685 -420.009427) (xy 179.499291 -420.038481) (xy 179.542159 -420.074156) (xy 179.579376 -420.115693)
			(xy 179.610149 -420.162206) (xy 179.633821 -420.212703) (xy 179.649889 -420.26611) (xy 179.658009 -420.321286)
			(xy 179.658518 -420.349172) (xy 179.658476 -420.351458) (xy 179.899816 -420.351458) (xy 179.903887 -420.295836)
			(xy 179.916013 -420.241399) (xy 179.935936 -420.189308) (xy 179.963232 -420.140673) (xy 179.997318 -420.09653)
			(xy 180.037467 -420.057821) (xy 180.082825 -420.02537) (xy 180.132425 -419.999869) (xy 180.185209 -419.981862)
			(xy 180.240052 -419.971732) (xy 180.295786 -419.969695) (xy 180.351223 -419.975795) (xy 180.40518 -419.989901)
			(xy 180.456509 -420.011713) (xy 180.504115 -420.040767) (xy 180.546983 -420.076442) (xy 180.5842 -420.117979)
			(xy 180.614973 -420.164492) (xy 180.638645 -420.214989) (xy 180.654713 -420.268396) (xy 180.662833 -420.323572)
			(xy 180.663314 -420.349934) (xy 181.926228 -420.349934) (xy 181.930299 -420.294312) (xy 181.942425 -420.239875)
			(xy 181.962348 -420.187784) (xy 181.989644 -420.139149) (xy 182.02373 -420.095006) (xy 182.063879 -420.056297)
			(xy 182.109237 -420.023846) (xy 182.158837 -419.998345) (xy 182.211621 -419.980338) (xy 182.266464 -419.970208)
			(xy 182.322198 -419.968171) (xy 182.377635 -419.974271) (xy 182.431592 -419.988377) (xy 182.482921 -420.010189)
			(xy 182.530527 -420.039243) (xy 182.573395 -420.074918) (xy 182.610612 -420.116455) (xy 182.641385 -420.162968)
			(xy 182.665057 -420.213465) (xy 182.681125 -420.266872) (xy 182.689245 -420.322048) (xy 182.689754 -420.349934)
			(xy 182.689245 -420.37782) (xy 182.681125 -420.432996) (xy 182.665057 -420.486403) (xy 182.641385 -420.5369)
			(xy 182.610612 -420.583413) (xy 182.573395 -420.62495) (xy 182.530527 -420.660625) (xy 182.482921 -420.689679)
			(xy 182.431592 -420.711491) (xy 182.377635 -420.725597) (xy 182.322198 -420.731697) (xy 182.266464 -420.72966)
			(xy 182.211621 -420.71953) (xy 182.158837 -420.701523) (xy 182.109237 -420.676022) (xy 182.063879 -420.643571)
			(xy 182.02373 -420.604862) (xy 181.989644 -420.560719) (xy 181.962348 -420.512084) (xy 181.942425 -420.459993)
			(xy 181.930299 -420.405556) (xy 181.926228 -420.349934) (xy 180.663314 -420.349934) (xy 180.663342 -420.351458)
			(xy 180.662833 -420.379344) (xy 180.654713 -420.43452) (xy 180.638645 -420.487927) (xy 180.614973 -420.538424)
			(xy 180.5842 -420.584937) (xy 180.546983 -420.626474) (xy 180.504115 -420.662149) (xy 180.456509 -420.691203)
			(xy 180.40518 -420.713015) (xy 180.351223 -420.727121) (xy 180.295786 -420.733221) (xy 180.240052 -420.731184)
			(xy 180.185209 -420.721054) (xy 180.132425 -420.703047) (xy 180.082825 -420.677546) (xy 180.037467 -420.645095)
			(xy 179.997318 -420.606386) (xy 179.963232 -420.562243) (xy 179.935936 -420.513608) (xy 179.916013 -420.461517)
			(xy 179.903887 -420.40708) (xy 179.899816 -420.351458) (xy 179.658476 -420.351458) (xy 179.658009 -420.377058)
			(xy 179.649889 -420.432234) (xy 179.633821 -420.485641) (xy 179.610149 -420.536138) (xy 179.579376 -420.582651)
			(xy 179.542159 -420.624188) (xy 179.499291 -420.659863) (xy 179.451685 -420.688917) (xy 179.400356 -420.710729)
			(xy 179.346399 -420.724835) (xy 179.290962 -420.730935) (xy 179.235228 -420.728898) (xy 179.180385 -420.718768)
			(xy 179.127601 -420.700761) (xy 179.078001 -420.67526) (xy 179.032643 -420.642809) (xy 178.992494 -420.6041)
			(xy 178.958408 -420.559957) (xy 178.931112 -420.511322) (xy 178.911189 -420.459231) (xy 178.899063 -420.404794)
			(xy 178.894992 -420.349172) (xy 174.922434 -420.349172) (xy 175.607762 -421.0345) (xy 183.000832 -421.0345)
			(xy 183.004847 -420.970695) (xy 183.016827 -420.907897) (xy 183.036583 -420.847095) (xy 183.063804 -420.789249)
			(xy 183.09806 -420.735271) (xy 183.138812 -420.686012) (xy 183.185417 -420.64225) (xy 183.237139 -420.604673)
			(xy 183.293163 -420.573876) (xy 183.352605 -420.550343) (xy 183.414528 -420.534446) (xy 183.477955 -420.526436)
			(xy 183.50992 -420.525956) (xy 183.542099 -420.526433) (xy 183.60594 -420.534579) (xy 183.668244 -420.550713)
			(xy 183.728014 -420.574576) (xy 183.784298 -420.605789) (xy 183.836194 -420.643851) (xy 183.882875 -420.688156)
			(xy 183.923595 -420.737995) (xy 183.957702 -420.792573) (xy 183.984653 -420.851016) (xy 183.994806 -420.881556)
			(xy 183.999485 -420.894768) (xy 184.014864 -420.918186) (xy 184.036024 -420.936547) (xy 184.061374 -420.948474)
			(xy 184.08901 -420.95307) (xy 184.116856 -420.949989) (xy 184.14282 -420.939463) (xy 184.16495 -420.922284)
			(xy 184.173622 -420.911274) (xy 184.191756 -420.887667) (xy 184.23407 -420.845804) (xy 184.282374 -420.811023)
			(xy 184.335497 -420.784171) (xy 184.392146 -420.765899) (xy 184.450946 -420.756651) (xy 184.480708 -420.75608)
			(xy 184.507958 -420.756591) (xy 184.561903 -420.764348) (xy 184.614195 -420.779703) (xy 184.66377 -420.802344)
			(xy 184.709618 -420.83181) (xy 184.750806 -420.8675) (xy 184.786495 -420.908689) (xy 184.81596 -420.954537)
			(xy 184.8386 -421.004112) (xy 184.853954 -421.056405) (xy 184.86171 -421.11035) (xy 184.86171 -421.1447)
			(xy 185.11469 -421.1447) (xy 185.118761 -421.089078) (xy 185.130887 -421.034641) (xy 185.15081 -420.98255)
			(xy 185.178106 -420.933915) (xy 185.212192 -420.889772) (xy 185.252341 -420.851063) (xy 185.297699 -420.818612)
			(xy 185.347299 -420.793111) (xy 185.400083 -420.775104) (xy 185.454926 -420.764974) (xy 185.51066 -420.762937)
			(xy 185.566097 -420.769037) (xy 185.620054 -420.783143) (xy 185.671383 -420.804955) (xy 185.718989 -420.834009)
			(xy 185.761857 -420.869684) (xy 185.799074 -420.911221) (xy 185.829847 -420.957734) (xy 185.853519 -421.008231)
			(xy 185.869587 -421.061638) (xy 185.873438 -421.087804) (xy 186.288932 -421.087804) (xy 186.293003 -421.032182)
			(xy 186.305129 -420.977745) (xy 186.325052 -420.925654) (xy 186.352348 -420.877019) (xy 186.386434 -420.832876)
			(xy 186.426583 -420.794167) (xy 186.471941 -420.761716) (xy 186.521541 -420.736215) (xy 186.574325 -420.718208)
			(xy 186.629168 -420.708078) (xy 186.684902 -420.706041) (xy 186.740339 -420.712141) (xy 186.794296 -420.726247)
			(xy 186.845625 -420.748059) (xy 186.893231 -420.777113) (xy 186.936099 -420.812788) (xy 186.973316 -420.854325)
			(xy 187.004089 -420.900838) (xy 187.027761 -420.951335) (xy 187.043829 -421.004742) (xy 187.051949 -421.059918)
			(xy 187.052458 -421.087804) (xy 187.051949 -421.11569) (xy 187.043829 -421.170866) (xy 187.027761 -421.224273)
			(xy 187.004089 -421.27477) (xy 186.973316 -421.321283) (xy 186.936099 -421.36282) (xy 186.893231 -421.398495)
			(xy 186.845625 -421.427549) (xy 186.794296 -421.449361) (xy 186.740339 -421.463467) (xy 186.684902 -421.469567)
			(xy 186.629168 -421.46753) (xy 186.574325 -421.4574) (xy 186.521541 -421.439393) (xy 186.471941 -421.413892)
			(xy 186.426583 -421.381441) (xy 186.386434 -421.342732) (xy 186.352348 -421.298589) (xy 186.325052 -421.249954)
			(xy 186.305129 -421.197863) (xy 186.293003 -421.143426) (xy 186.288932 -421.087804) (xy 185.873438 -421.087804)
			(xy 185.877707 -421.116814) (xy 185.878216 -421.1447) (xy 185.877707 -421.172586) (xy 185.869587 -421.227762)
			(xy 185.853519 -421.281169) (xy 185.829847 -421.331666) (xy 185.799074 -421.378179) (xy 185.761857 -421.419716)
			(xy 185.718989 -421.455391) (xy 185.671383 -421.484445) (xy 185.620054 -421.506257) (xy 185.566097 -421.520363)
			(xy 185.51066 -421.526463) (xy 185.454926 -421.524426) (xy 185.400083 -421.514296) (xy 185.347299 -421.496289)
			(xy 185.297699 -421.470788) (xy 185.252341 -421.438337) (xy 185.212192 -421.399628) (xy 185.178106 -421.355485)
			(xy 185.15081 -421.30685) (xy 185.130887 -421.254759) (xy 185.118761 -421.200322) (xy 185.11469 -421.1447)
			(xy 184.86171 -421.1447) (xy 184.86171 -421.16485) (xy 184.853954 -421.218795) (xy 184.8386 -421.271088)
			(xy 184.81596 -421.320663) (xy 184.786495 -421.366511) (xy 184.750806 -421.4077) (xy 184.709618 -421.44339)
			(xy 184.66377 -421.472856) (xy 184.614195 -421.495497) (xy 184.561903 -421.510852) (xy 184.507958 -421.518609)
			(xy 184.480708 -421.519096) (xy 184.453335 -421.518677) (xy 184.399152 -421.51086) (xy 184.346644 -421.495371)
			(xy 184.296892 -421.472529) (xy 184.25092 -421.442804) (xy 184.209674 -421.406808) (xy 184.174002 -421.36528)
			(xy 184.144639 -421.319077) (xy 184.132982 -421.294306) (xy 184.126812 -421.281706) (xy 184.108784 -421.260224)
			(xy 184.085593 -421.244454) (xy 184.058988 -421.235586) (xy 184.030974 -421.234289) (xy 184.003662 -421.240659)
			(xy 183.979113 -421.254218) (xy 183.959177 -421.273942) (xy 183.95188 -421.285924) (xy 183.93484 -421.314765)
			(xy 183.894358 -421.368139) (xy 183.847217 -421.415734) (xy 183.794235 -421.456728) (xy 183.736329 -421.490409)
			(xy 183.674501 -421.516194) (xy 183.609823 -421.533637) (xy 183.543415 -421.542437) (xy 183.50992 -421.542972)
			(xy 183.477955 -421.542564) (xy 183.414528 -421.534554) (xy 183.352605 -421.518657) (xy 183.293163 -421.495124)
			(xy 183.237139 -421.464327) (xy 183.185417 -421.42675) (xy 183.138812 -421.382988) (xy 183.09806 -421.333729)
			(xy 183.063804 -421.279751) (xy 183.036583 -421.221905) (xy 183.016827 -421.161103) (xy 183.004847 -421.098305)
			(xy 183.000832 -421.0345) (xy 175.607762 -421.0345) (xy 175.738282 -421.16502) (xy 175.745692 -421.171705)
			(xy 175.764127 -421.17929) (xy 175.774096 -421.179752) (xy 178.860958 -421.179752) (xy 178.885547 -421.180215)
			(xy 178.934117 -421.18792) (xy 178.980883 -421.203132) (xy 179.024692 -421.225476) (xy 179.064464 -421.2544)
			(xy 179.082192 -421.271446) (xy 183.999174 -426.188886) (xy 187.163962 -426.188886) (xy 187.168033 -426.133264)
			(xy 187.180159 -426.078827) (xy 187.200082 -426.026736) (xy 187.227378 -425.978101) (xy 187.261464 -425.933958)
			(xy 187.301613 -425.895249) (xy 187.346971 -425.862798) (xy 187.396571 -425.837297) (xy 187.449355 -425.81929)
			(xy 187.504198 -425.80916) (xy 187.559932 -425.807123) (xy 187.615369 -425.813223) (xy 187.669326 -425.827329)
			(xy 187.720655 -425.849141) (xy 187.768261 -425.878195) (xy 187.811129 -425.91387) (xy 187.848346 -425.955407)
			(xy 187.879119 -426.00192) (xy 187.902791 -426.052417) (xy 187.918859 -426.105824) (xy 187.926979 -426.161)
			(xy 187.927488 -426.188886) (xy 187.926979 -426.216772) (xy 187.918859 -426.271948) (xy 187.902791 -426.325355)
			(xy 187.879119 -426.375852) (xy 187.848346 -426.422365) (xy 187.811129 -426.463902) (xy 187.768261 -426.499577)
			(xy 187.720655 -426.528631) (xy 187.669326 -426.550443) (xy 187.615369 -426.564549) (xy 187.559932 -426.570649)
			(xy 187.504198 -426.568612) (xy 187.449355 -426.558482) (xy 187.396571 -426.540475) (xy 187.346971 -426.514974)
			(xy 187.301613 -426.482523) (xy 187.261464 -426.443814) (xy 187.227378 -426.399671) (xy 187.200082 -426.351036)
			(xy 187.180159 -426.298945) (xy 187.168033 -426.244508) (xy 187.163962 -426.188886) (xy 183.999174 -426.188886)
			(xy 184.533286 -426.723048) (xy 184.550361 -426.74075) (xy 184.579286 -426.780526) (xy 184.601625 -426.824342)
			(xy 184.616827 -426.871115) (xy 184.624516 -426.919691) (xy 184.62498 -426.944282) (xy 184.62498 -427.029118)
			(xy 184.625459 -427.040111) (xy 184.634552 -427.060122) (xy 184.642506 -427.067726) (xy 184.666041 -427.088458)
			(xy 184.708339 -427.134769) (xy 184.74462 -427.185931) (xy 184.774332 -427.241167) (xy 184.797025 -427.299639)
			(xy 184.812354 -427.360458) (xy 184.820086 -427.4227) (xy 184.82056 -427.45406) (xy 184.820058 -427.486021)
			(xy 184.819673 -427.489069) (xy 185.000132 -427.489069) (xy 185.000132 -427.425147) (xy 185.008143 -427.361729)
			(xy 185.02404 -427.299815) (xy 185.047572 -427.240382) (xy 185.078366 -427.184367) (xy 185.115939 -427.132652)
			(xy 185.159696 -427.086055) (xy 185.208949 -427.04531) (xy 185.26292 -427.011059) (xy 185.320759 -426.983842)
			(xy 185.381552 -426.964089) (xy 185.444342 -426.952111) (xy 185.508138 -426.948098) (xy 185.571934 -426.952111)
			(xy 185.634724 -426.964089) (xy 185.695517 -426.983842) (xy 185.753356 -427.011059) (xy 185.807327 -427.04531)
			(xy 185.85658 -427.086055) (xy 185.900337 -427.132652) (xy 185.93791 -427.184367) (xy 185.968704 -427.240382)
			(xy 185.992236 -427.299815) (xy 186.008133 -427.361729) (xy 186.016144 -427.425147) (xy 186.016646 -427.457108)
			(xy 186.016144 -427.489069) (xy 186.008133 -427.552487) (xy 185.992236 -427.614401) (xy 185.968704 -427.673834)
			(xy 185.93791 -427.729849) (xy 185.900337 -427.781564) (xy 185.85658 -427.828161) (xy 185.83166 -427.848776)
			(xy 192.03746 -427.848776) (xy 192.041531 -427.793154) (xy 192.053657 -427.738717) (xy 192.07358 -427.686626)
			(xy 192.100876 -427.637991) (xy 192.134962 -427.593848) (xy 192.175111 -427.555139) (xy 192.220469 -427.522688)
			(xy 192.270069 -427.497187) (xy 192.322853 -427.47918) (xy 192.377696 -427.46905) (xy 192.43343 -427.467013)
			(xy 192.488867 -427.473113) (xy 192.542824 -427.487219) (xy 192.594153 -427.509031) (xy 192.641759 -427.538085)
			(xy 192.684627 -427.57376) (xy 192.721844 -427.615297) (xy 192.752617 -427.66181) (xy 192.776289 -427.712307)
			(xy 192.792357 -427.765714) (xy 192.800477 -427.82089) (xy 192.800986 -427.848776) (xy 192.800477 -427.876662)
			(xy 192.792357 -427.931838) (xy 192.776289 -427.985245) (xy 192.752617 -428.035742) (xy 192.721844 -428.082255)
			(xy 192.684627 -428.123792) (xy 192.641759 -428.159467) (xy 192.594153 -428.188521) (xy 192.542824 -428.210333)
			(xy 192.488867 -428.224439) (xy 192.43343 -428.230539) (xy 192.377696 -428.228502) (xy 192.322853 -428.218372)
			(xy 192.270069 -428.200365) (xy 192.220469 -428.174864) (xy 192.175111 -428.142413) (xy 192.134962 -428.103704)
			(xy 192.100876 -428.059561) (xy 192.07358 -428.010926) (xy 192.053657 -427.958835) (xy 192.041531 -427.904398)
			(xy 192.03746 -427.848776) (xy 185.83166 -427.848776) (xy 185.807327 -427.868906) (xy 185.753356 -427.903157)
			(xy 185.695517 -427.930374) (xy 185.634724 -427.950127) (xy 185.571934 -427.962105) (xy 185.508138 -427.966119)
			(xy 185.444342 -427.962105) (xy 185.381552 -427.950127) (xy 185.320759 -427.930374) (xy 185.26292 -427.903157)
			(xy 185.208949 -427.868906) (xy 185.159696 -427.828161) (xy 185.115939 -427.781564) (xy 185.078366 -427.729849)
			(xy 185.047572 -427.673834) (xy 185.02404 -427.614401) (xy 185.008143 -427.552487) (xy 185.000132 -427.489069)
			(xy 184.819673 -427.489069) (xy 184.812047 -427.549439) (xy 184.79615 -427.611353) (xy 184.772618 -427.670786)
			(xy 184.741824 -427.726801) (xy 184.704251 -427.778516) (xy 184.660494 -427.825113) (xy 184.611241 -427.865858)
			(xy 184.55727 -427.900109) (xy 184.499431 -427.927326) (xy 184.438638 -427.947079) (xy 184.375848 -427.959057)
			(xy 184.312052 -427.963071) (xy 184.248256 -427.959057) (xy 184.185466 -427.947079) (xy 184.124673 -427.927326)
			(xy 184.066834 -427.900109) (xy 184.012863 -427.865858) (xy 183.96361 -427.825113) (xy 183.919853 -427.778516)
			(xy 183.88228 -427.726801) (xy 183.851486 -427.670786) (xy 183.827954 -427.611353) (xy 183.812057 -427.549439)
			(xy 183.804046 -427.486021) (xy 183.803544 -427.45406) (xy 183.804057 -427.421001) (xy 183.812597 -427.355436)
			(xy 183.829567 -427.291533) (xy 183.854681 -427.230369) (xy 183.887514 -427.172979) (xy 183.927512 -427.120331)
			(xy 183.950356 -427.096428) (xy 183.965342 -427.081442) (xy 183.965088 -427.039786) (xy 179.236624 -422.310814)
			(xy 179.22912 -422.303952) (xy 179.210303 -422.296289) (xy 179.189987 -422.296512) (xy 179.18049 -422.300146)
			(xy 179.079144 -422.344596) (xy 179.062634 -422.371012) (xy 179.063396 -422.38676) (xy 179.06365 -422.402254)
			(xy 179.06319 -422.42951) (xy 179.055439 -422.483468) (xy 179.040087 -422.535774) (xy 179.017448 -422.585363)
			(xy 178.987982 -422.631225) (xy 178.952289 -422.672426) (xy 178.911095 -422.708129) (xy 178.86524 -422.737606)
			(xy 178.815657 -422.760256) (xy 178.763354 -422.77562) (xy 178.709398 -422.783384) (xy 178.682142 -422.783762)
			(xy 178.655456 -422.783311) (xy 178.602606 -422.775861) (xy 178.551311 -422.761115) (xy 178.502573 -422.739361)
			(xy 178.457344 -422.711024) (xy 178.416509 -422.676657) (xy 178.380864 -422.636932) (xy 178.351106 -422.592625)
			(xy 178.327817 -422.544601) (xy 178.319176 -422.519348) (xy 178.31562 -422.50868) (xy 178.300126 -422.49217)
			(xy 178.206908 -422.454578) (xy 178.184302 -422.455594) (xy 178.174396 -422.460928) (xy 178.146596 -422.475314)
			(xy 178.088231 -422.497936) (xy 178.027529 -422.513214) (xy 177.96541 -422.520919) (xy 177.934112 -422.52138)
			(xy 177.901611 -422.520866) (xy 177.83714 -422.512585) (xy 177.774249 -422.496157) (xy 177.713964 -422.471849)
			(xy 177.657267 -422.440059) (xy 177.605084 -422.401303) (xy 177.581306 -422.37914) (xy 177.574452 -422.373063)
			(xy 177.557659 -422.365781) (xy 177.54854 -422.364916) (xy 177.51806 -422.363646) (xy 177.508865 -422.363617)
			(xy 177.49141 -422.369346) (xy 177.484024 -422.374822) (xy 177.456829 -422.395891) (xy 177.397842 -422.431292)
			(xy 177.334624 -422.458421) (xy 177.268326 -422.476786) (xy 177.200159 -422.48605) (xy 177.165762 -422.486582)
			(xy 177.135033 -422.486116) (xy 177.074024 -422.478703) (xy 177.014353 -422.463991) (xy 176.95689 -422.442194)
			(xy 176.902474 -422.413629) (xy 176.851897 -422.378714) (xy 176.805898 -422.337957) (xy 176.765147 -422.291952)
			(xy 176.730238 -422.241371) (xy 176.70168 -422.186951) (xy 176.67989 -422.129486) (xy 176.665185 -422.069813)
			(xy 176.65778 -422.008803) (xy 176.657254 -421.978074) (xy 176.657381 -421.963242) (xy 176.659159 -421.933632)
			(xy 176.66081 -421.918892) (xy 176.66208 -421.90797) (xy 176.655476 -421.88765) (xy 176.597818 -421.822626)
			(xy 176.590255 -421.81489) (xy 176.570526 -421.806059) (xy 176.559718 -421.805608) (xy 175.623474 -421.805608)
			(xy 175.598884 -421.805148) (xy 175.55031 -421.797449) (xy 175.503539 -421.782242) (xy 175.459724 -421.759905)
			(xy 175.419944 -421.730986) (xy 175.40224 -421.713914) (xy 173.14799 -419.459664) (xy 173.140578 -419.452985)
			(xy 173.122142 -419.445412) (xy 173.112176 -419.444932) (xy 171.219114 -419.444932) (xy 171.209118 -419.445427)
			(xy 171.190641 -419.453062) (xy 171.176456 -419.467152) (xy 171.172124 -419.476174) (xy 171.166282 -419.490652)
			(xy 171.172124 -419.52037) (xy 171.405804 -419.75405) (xy 171.427998 -419.776843) (xy 171.467673 -419.826577)
			(xy 171.501529 -419.880442) (xy 171.529141 -419.937759) (xy 171.550161 -419.997807) (xy 171.564324 -420.059831)
			(xy 171.571452 -420.123052) (xy 171.57192 -420.154862) (xy 171.57192 -420.907464) (xy 173.080932 -420.907464)
			(xy 173.085003 -420.851842) (xy 173.097129 -420.797405) (xy 173.117052 -420.745314) (xy 173.144348 -420.696679)
			(xy 173.178434 -420.652536) (xy 173.218583 -420.613827) (xy 173.263941 -420.581376) (xy 173.313541 -420.555875)
			(xy 173.366325 -420.537868) (xy 173.421168 -420.527738) (xy 173.476902 -420.525701) (xy 173.532339 -420.531801)
			(xy 173.586296 -420.545907) (xy 173.637625 -420.567719) (xy 173.685231 -420.596773) (xy 173.728099 -420.632448)
			(xy 173.765316 -420.673985) (xy 173.796089 -420.720498) (xy 173.819761 -420.770995) (xy 173.835829 -420.824402)
			(xy 173.843949 -420.879578) (xy 173.844458 -420.907464) (xy 173.843949 -420.93535) (xy 173.835829 -420.990526)
			(xy 173.819761 -421.043933) (xy 173.796089 -421.09443) (xy 173.765316 -421.140943) (xy 173.728099 -421.18248)
			(xy 173.685231 -421.218155) (xy 173.637625 -421.247209) (xy 173.586296 -421.269021) (xy 173.532339 -421.283127)
			(xy 173.476902 -421.289227) (xy 173.421168 -421.28719) (xy 173.366325 -421.27706) (xy 173.313541 -421.259053)
			(xy 173.263941 -421.233552) (xy 173.218583 -421.201101) (xy 173.178434 -421.162392) (xy 173.144348 -421.118249)
			(xy 173.117052 -421.069614) (xy 173.097129 -421.017523) (xy 173.085003 -420.963086) (xy 173.080932 -420.907464)
			(xy 171.57192 -420.907464) (xy 171.57192 -421.061388) (xy 171.57149 -421.0932) (xy 171.564363 -421.156423)
			(xy 171.550198 -421.21845) (xy 171.529172 -421.278499) (xy 171.501551 -421.335814) (xy 171.467683 -421.389674)
			(xy 171.427993 -421.4394) (xy 171.405804 -421.4622) (xy 171.0944 -421.773604) (xy 171.088195 -421.780293)
			(xy 171.080577 -421.796856) (xy 171.079254 -421.815039) (xy 171.081446 -421.823896) (xy 171.110656 -421.922956)
			(xy 171.130722 -421.941752) (xy 171.144692 -421.9448) (xy 171.172712 -421.951409) (xy 171.226504 -421.971918)
			(xy 171.276603 -422.000278) (xy 171.321872 -422.035844) (xy 171.361282 -422.077809) (xy 171.393939 -422.125219)
			(xy 171.4191 -422.176998) (xy 171.436195 -422.23197) (xy 171.444835 -422.288887) (xy 171.445428 -422.317672)
			(xy 171.444967 -422.344927) (xy 171.439947 -422.379859) (xy 171.733712 -422.379859) (xy 171.733712 -422.315937)
			(xy 171.741723 -422.252519) (xy 171.75762 -422.190605) (xy 171.781152 -422.131172) (xy 171.811946 -422.075157)
			(xy 171.849519 -422.023442) (xy 171.893276 -421.976845) (xy 171.942529 -421.9361) (xy 171.9965 -421.901849)
			(xy 172.054339 -421.874632) (xy 172.115132 -421.854879) (xy 172.177922 -421.842901) (xy 172.241718 -421.838888)
			(xy 172.305514 -421.842901) (xy 172.368304 -421.854879) (xy 172.429097 -421.874632) (xy 172.486936 -421.901849)
			(xy 172.540907 -421.9361) (xy 172.59016 -421.976845) (xy 172.633917 -422.023442) (xy 172.67149 -422.075157)
			(xy 172.702284 -422.131172) (xy 172.725816 -422.190605) (xy 172.741713 -422.252519) (xy 172.749724 -422.315937)
			(xy 172.750226 -422.347898) (xy 172.749724 -422.379859) (xy 172.741713 -422.443277) (xy 172.725816 -422.505191)
			(xy 172.702284 -422.564624) (xy 172.67149 -422.620639) (xy 172.633917 -422.672354) (xy 172.59016 -422.718951)
			(xy 172.540907 -422.759696) (xy 172.486936 -422.793947) (xy 172.429097 -422.821164) (xy 172.368304 -422.840917)
			(xy 172.305514 -422.852895) (xy 172.241718 -422.856909) (xy 172.177922 -422.852895) (xy 172.115132 -422.840917)
			(xy 172.054339 -422.821164) (xy 171.9965 -422.793947) (xy 171.942529 -422.759696) (xy 171.893276 -422.718951)
			(xy 171.849519 -422.672354) (xy 171.811946 -422.620639) (xy 171.781152 -422.564624) (xy 171.75762 -422.505191)
			(xy 171.741723 -422.443277) (xy 171.733712 -422.379859) (xy 171.439947 -422.379859) (xy 171.437213 -422.398882)
			(xy 171.42186 -422.451184) (xy 171.399219 -422.500769) (xy 171.369752 -422.546627) (xy 171.334059 -422.587825)
			(xy 171.292866 -422.623524) (xy 171.247011 -422.652996) (xy 171.197429 -422.675643) (xy 171.145129 -422.691003)
			(xy 171.091175 -422.698764) (xy 171.06392 -422.69918) (xy 171.035131 -422.698657) (xy 170.978206 -422.690009)
			(xy 170.923227 -422.672907) (xy 170.871441 -422.647739) (xy 170.824025 -422.615076) (xy 170.782054 -422.57566)
			(xy 170.746481 -422.530385) (xy 170.718115 -422.48028) (xy 170.697598 -422.426482) (xy 170.691048 -422.398444)
			(xy 170.688 -422.384474) (xy 170.669204 -422.364408) (xy 170.570144 -422.335198) (xy 170.561288 -422.333008)
			(xy 170.543106 -422.334343) (xy 170.526535 -422.341944) (xy 170.519852 -422.348152) (xy 168.113456 -424.754294)
			(xy 168.107419 -424.760872) (xy 168.099961 -424.777082) (xy 168.098504 -424.794867) (xy 168.100502 -424.80357)
			(xy 168.126918 -424.901868) (xy 168.145714 -424.920918) (xy 168.159176 -424.924474) (xy 168.189485 -424.933034)
			(xy 168.247877 -424.956639) (xy 168.302903 -424.987282) (xy 168.328594 -425.0055) (xy 168.337693 -425.011522)
			(xy 168.359036 -425.015959) (xy 168.3803 -425.011162) (xy 168.3893 -425.004992) (xy 168.41591 -424.985501)
			(xy 168.473203 -424.952815) (xy 168.53424 -424.927808) (xy 168.597998 -424.910899) (xy 168.663405 -424.902372)
			(xy 168.696386 -424.901868) (xy 168.72835 -424.902348) (xy 168.791775 -424.910359) (xy 168.853696 -424.926256)
			(xy 168.913136 -424.949789) (xy 168.969158 -424.980585) (xy 169.020878 -425.018161) (xy 169.067481 -425.061923)
			(xy 169.108231 -425.11118) (xy 169.142487 -425.165157) (xy 169.169707 -425.223001) (xy 169.189462 -425.283801)
			(xy 169.198627 -425.331847) (xy 170.52518 -425.331847) (xy 170.52518 -425.267925) (xy 170.533191 -425.204507)
			(xy 170.549088 -425.142593) (xy 170.57262 -425.08316) (xy 170.603414 -425.027145) (xy 170.640987 -424.97543)
			(xy 170.684744 -424.928833) (xy 170.733997 -424.888088) (xy 170.787968 -424.853837) (xy 170.845807 -424.82662)
			(xy 170.9066 -424.806867) (xy 170.96939 -424.794889) (xy 171.033186 -424.790876) (xy 171.096982 -424.794889)
			(xy 171.159772 -424.806867) (xy 171.220565 -424.82662) (xy 171.278404 -424.853837) (xy 171.332375 -424.888088)
			(xy 171.381628 -424.928833) (xy 171.425385 -424.97543) (xy 171.462958 -425.027145) (xy 171.493752 -425.08316)
			(xy 171.517284 -425.142593) (xy 171.533181 -425.204507) (xy 171.541192 -425.267925) (xy 171.541694 -425.299886)
			(xy 171.541192 -425.331847) (xy 171.533181 -425.395265) (xy 171.517284 -425.457179) (xy 171.493752 -425.516612)
			(xy 171.487085 -425.52874) (xy 173.642782 -425.52874) (xy 173.643221 -425.498279) (xy 173.650497 -425.437792)
			(xy 173.664948 -425.378608) (xy 173.686369 -425.321576) (xy 173.714452 -425.267512) (xy 173.748794 -425.217191)
			(xy 173.768512 -425.193968) (xy 173.774023 -425.187117) (xy 173.780381 -425.170738) (xy 173.780958 -425.161964)
			(xy 173.781974 -425.132246) (xy 173.781889 -425.123424) (xy 173.776429 -425.106662) (xy 173.771306 -425.09948)
			(xy 173.751094 -425.072598) (xy 173.717135 -425.014547) (xy 173.691131 -424.952522) (xy 173.673538 -424.887609)
			(xy 173.664663 -424.820942) (xy 173.664118 -424.787314) (xy 173.664582 -424.755594) (xy 173.672477 -424.692646)
			(xy 173.688145 -424.631171) (xy 173.711343 -424.572124) (xy 173.741709 -424.516423) (xy 173.778773 -424.464935)
			(xy 173.800008 -424.441366) (xy 173.806029 -424.434155) (xy 173.81294 -424.416708) (xy 173.81347 -424.40733)
			(xy 173.813724 -424.376342) (xy 173.813349 -424.36694) (xy 173.806705 -424.349353) (xy 173.80077 -424.342052)
			(xy 173.780496 -424.318675) (xy 173.745138 -424.267889) (xy 173.716202 -424.21319) (xy 173.694116 -424.155384)
			(xy 173.679206 -424.095326) (xy 173.671691 -424.033903) (xy 173.67123 -424.002962) (xy 173.671732 -423.971001)
			(xy 173.679743 -423.907583) (xy 173.69564 -423.845669) (xy 173.719172 -423.786236) (xy 173.749966 -423.730221)
			(xy 173.787539 -423.678506) (xy 173.831296 -423.631909) (xy 173.880549 -423.591164) (xy 173.93452 -423.556913)
			(xy 173.992359 -423.529696) (xy 174.053152 -423.509943) (xy 174.115942 -423.497965) (xy 174.179738 -423.493952)
			(xy 174.243534 -423.497965) (xy 174.306324 -423.509943) (xy 174.367117 -423.529696) (xy 174.424956 -423.556913)
			(xy 174.478927 -423.591164) (xy 174.52818 -423.631909) (xy 174.571937 -423.678506) (xy 174.60951 -423.730221)
			(xy 174.640304 -423.786236) (xy 174.663836 -423.845669) (xy 174.679733 -423.907583) (xy 174.687744 -423.971001)
			(xy 174.688246 -424.002962) (xy 174.687777 -424.034682) (xy 174.679884 -424.09763) (xy 174.664218 -424.159106)
			(xy 174.641021 -424.218153) (xy 174.610655 -424.273854) (xy 174.573591 -424.325341) (xy 174.552356 -424.34891)
			(xy 174.546299 -424.356094) (xy 174.53941 -424.373562) (xy 174.538894 -424.382946) (xy 174.53864 -424.413934)
			(xy 174.539035 -424.423334) (xy 174.545666 -424.44092) (xy 174.551594 -424.448224) (xy 174.571899 -424.471576)
			(xy 174.607254 -424.522367) (xy 174.636186 -424.577071) (xy 174.658267 -424.634882) (xy 174.673171 -424.694945)
			(xy 174.680677 -424.756372) (xy 174.681134 -424.787314) (xy 174.680664 -424.817774) (xy 174.673394 -424.87826)
			(xy 174.658948 -424.937443) (xy 174.637533 -424.994475) (xy 174.609456 -425.04854) (xy 174.575119 -425.098862)
			(xy 174.555404 -425.122086) (xy 174.549914 -425.128951) (xy 174.543544 -425.145319) (xy 174.542958 -425.15409)
			(xy 174.542046 -425.18076) (xy 175.635412 -425.18076) (xy 175.635857 -425.150329) (xy 175.643131 -425.089904)
			(xy 175.657559 -425.030777) (xy 175.678935 -424.973793) (xy 175.706954 -424.919765) (xy 175.741215 -424.869463)
			(xy 175.760888 -424.846242) (xy 175.766301 -424.839554) (xy 175.772662 -424.823578) (xy 175.773334 -424.815)
			(xy 175.774604 -424.785536) (xy 175.774551 -424.777) (xy 175.769638 -424.760666) (xy 175.764952 -424.753532)
			(xy 175.746553 -424.727386) (xy 175.715761 -424.671356) (xy 175.692242 -424.611906) (xy 175.676366 -424.549975)
			(xy 175.668386 -424.486541) (xy 175.667924 -424.454574) (xy 175.668426 -424.422613) (xy 175.676437 -424.359195)
			(xy 175.692334 -424.297281) (xy 175.715866 -424.237848) (xy 175.74666 -424.181833) (xy 175.784233 -424.130118)
			(xy 175.82799 -424.083521) (xy 175.877243 -424.042776) (xy 175.931214 -424.008525) (xy 175.989053 -423.981308)
			(xy 176.049846 -423.961555) (xy 176.112636 -423.949577) (xy 176.176432 -423.945564) (xy 176.240228 -423.949577)
			(xy 176.303018 -423.961555) (xy 176.363811 -423.981308) (xy 176.42165 -424.008525) (xy 176.475621 -424.042776)
			(xy 176.524874 -424.083521) (xy 176.568631 -424.130118) (xy 176.606204 -424.181833) (xy 176.636998 -424.237848)
			(xy 176.66053 -424.297281) (xy 176.676427 -424.359195) (xy 176.684438 -424.422613) (xy 176.68494 -424.454574)
			(xy 176.684468 -424.485004) (xy 176.677201 -424.545429) (xy 176.662779 -424.604555) (xy 176.641408 -424.66154)
			(xy 176.613394 -424.715569) (xy 176.579135 -424.765871) (xy 176.559464 -424.789092) (xy 176.554043 -424.795775)
			(xy 176.547686 -424.811754) (xy 176.547018 -424.820334) (xy 176.545748 -424.849798) (xy 176.545777 -424.858336)
			(xy 176.550706 -424.87467) (xy 176.5554 -424.881802) (xy 176.57382 -424.907933) (xy 176.604607 -424.963968)
			(xy 176.628122 -425.023422) (xy 176.643993 -425.085356) (xy 176.651968 -425.148792) (xy 176.652428 -425.18076)
			(xy 176.651926 -425.212721) (xy 176.643915 -425.276139) (xy 176.628018 -425.338053) (xy 176.604486 -425.397486)
			(xy 176.573692 -425.453501) (xy 176.536119 -425.505216) (xy 176.492362 -425.551813) (xy 176.443109 -425.592558)
			(xy 176.389138 -425.626809) (xy 176.331299 -425.654026) (xy 176.270506 -425.673779) (xy 176.207716 -425.685757)
			(xy 176.14392 -425.689771) (xy 176.080124 -425.685757) (xy 176.017334 -425.673779) (xy 175.956541 -425.654026)
			(xy 175.898702 -425.626809) (xy 175.844731 -425.592558) (xy 175.795478 -425.551813) (xy 175.751721 -425.505216)
			(xy 175.714148 -425.453501) (xy 175.683354 -425.397486) (xy 175.659822 -425.338053) (xy 175.643925 -425.276139)
			(xy 175.635914 -425.212721) (xy 175.635412 -425.18076) (xy 174.542046 -425.18076) (xy 174.541942 -425.183808)
			(xy 174.542046 -425.192629) (xy 174.547493 -425.20939) (xy 174.55261 -425.216574) (xy 174.572849 -425.243436)
			(xy 174.606803 -425.301494) (xy 174.632801 -425.363523) (xy 174.650388 -425.428441) (xy 174.659256 -425.495111)
			(xy 174.659798 -425.52874) (xy 174.659296 -425.560701) (xy 174.651285 -425.624119) (xy 174.635388 -425.686033)
			(xy 174.611856 -425.745466) (xy 174.581062 -425.801481) (xy 174.543489 -425.853196) (xy 174.499732 -425.899793)
			(xy 174.450479 -425.940538) (xy 174.396508 -425.974789) (xy 174.338669 -426.002006) (xy 174.277876 -426.021759)
			(xy 174.215086 -426.033737) (xy 174.15129 -426.037751) (xy 174.087494 -426.033737) (xy 174.024704 -426.021759)
			(xy 173.963911 -426.002006) (xy 173.906072 -425.974789) (xy 173.852101 -425.940538) (xy 173.802848 -425.899793)
			(xy 173.759091 -425.853196) (xy 173.721518 -425.801481) (xy 173.690724 -425.745466) (xy 173.667192 -425.686033)
			(xy 173.651295 -425.624119) (xy 173.643284 -425.560701) (xy 173.642782 -425.52874) (xy 171.487085 -425.52874)
			(xy 171.462958 -425.572627) (xy 171.425385 -425.624342) (xy 171.381628 -425.670939) (xy 171.332375 -425.711684)
			(xy 171.278404 -425.745935) (xy 171.220565 -425.773152) (xy 171.159772 -425.792905) (xy 171.096982 -425.804883)
			(xy 171.033186 -425.808897) (xy 170.96939 -425.804883) (xy 170.9066 -425.792905) (xy 170.845807 -425.773152)
			(xy 170.787968 -425.745935) (xy 170.733997 -425.711684) (xy 170.684744 -425.670939) (xy 170.640987 -425.624342)
			(xy 170.603414 -425.572627) (xy 170.57262 -425.516612) (xy 170.549088 -425.457179) (xy 170.533191 -425.395265)
			(xy 170.52518 -425.331847) (xy 169.198627 -425.331847) (xy 169.201441 -425.346597) (xy 169.205456 -425.4104)
			(xy 169.201441 -425.474203) (xy 169.189462 -425.536999) (xy 169.169707 -425.597799) (xy 169.142487 -425.655643)
			(xy 169.108231 -425.70962) (xy 169.067481 -425.758877) (xy 169.020878 -425.802639) (xy 168.969158 -425.840215)
			(xy 168.913136 -425.871011) (xy 168.853696 -425.894544) (xy 168.791775 -425.910441) (xy 168.72835 -425.918452)
			(xy 168.696386 -425.918884) (xy 168.664227 -425.918389) (xy 168.600423 -425.910273) (xy 168.538153 -425.894173)
			(xy 168.478412 -425.870345) (xy 168.422154 -425.839172) (xy 168.395904 -425.820586) (xy 168.386805 -425.814566)
			(xy 168.365463 -425.810131) (xy 168.3442 -425.814927) (xy 168.335198 -425.821094) (xy 168.308588 -425.840586)
			(xy 168.251295 -425.873272) (xy 168.190258 -425.89828) (xy 168.126501 -425.915189) (xy 168.061093 -425.923716)
			(xy 168.028112 -425.924218) (xy 167.994789 -425.923702) (xy 167.928712 -425.915007) (xy 167.864338 -425.897751)
			(xy 167.802771 -425.872231) (xy 167.745067 -425.838884) (xy 167.692217 -425.798281) (xy 167.645125 -425.751121)
			(xy 167.604601 -425.69821) (xy 167.571338 -425.640457) (xy 167.545908 -425.578853) (xy 167.536876 -425.546774)
			(xy 167.53332 -425.533312) (xy 167.51427 -425.514516) (xy 167.415972 -425.4881) (xy 167.407273 -425.486064)
			(xy 167.389478 -425.487523) (xy 167.373263 -425.494998) (xy 167.366696 -425.501054) (xy 166.482776 -426.385228)
			(xy 166.476099 -426.39264) (xy 166.46853 -426.411076) (xy 166.468044 -426.421042) (xy 166.468044 -427.293786)
			(xy 173.731172 -427.293786) (xy 173.735243 -427.238164) (xy 173.747369 -427.183727) (xy 173.767292 -427.131636)
			(xy 173.794588 -427.083001) (xy 173.828674 -427.038858) (xy 173.868823 -427.000149) (xy 173.914181 -426.967698)
			(xy 173.963781 -426.942197) (xy 174.016565 -426.92419) (xy 174.071408 -426.91406) (xy 174.127142 -426.912023)
			(xy 174.182579 -426.918123) (xy 174.236536 -426.932229) (xy 174.287865 -426.954041) (xy 174.335471 -426.983095)
			(xy 174.378339 -427.01877) (xy 174.415556 -427.060307) (xy 174.446329 -427.10682) (xy 174.470001 -427.157317)
			(xy 174.486069 -427.210724) (xy 174.494189 -427.2659) (xy 174.494698 -427.293786) (xy 174.494605 -427.298866)
			(xy 180.555898 -427.298866) (xy 180.559969 -427.243244) (xy 180.572095 -427.188807) (xy 180.592018 -427.136716)
			(xy 180.619314 -427.088081) (xy 180.6534 -427.043938) (xy 180.693549 -427.005229) (xy 180.738907 -426.972778)
			(xy 180.788507 -426.947277) (xy 180.841291 -426.92927) (xy 180.896134 -426.91914) (xy 180.951868 -426.917103)
			(xy 181.007305 -426.923203) (xy 181.061262 -426.937309) (xy 181.112591 -426.959121) (xy 181.160197 -426.988175)
			(xy 181.203065 -427.02385) (xy 181.240282 -427.065387) (xy 181.271055 -427.1119) (xy 181.294727 -427.162397)
			(xy 181.310795 -427.215804) (xy 181.318915 -427.27098) (xy 181.319424 -427.298866) (xy 181.318915 -427.326752)
			(xy 181.310795 -427.381928) (xy 181.294727 -427.435335) (xy 181.29097 -427.443349) (xy 182.147712 -427.443349)
			(xy 182.147712 -427.379427) (xy 182.155723 -427.316009) (xy 182.17162 -427.254095) (xy 182.195152 -427.194662)
			(xy 182.225946 -427.138647) (xy 182.263519 -427.086932) (xy 182.307276 -427.040335) (xy 182.356529 -426.99959)
			(xy 182.4105 -426.965339) (xy 182.468339 -426.938122) (xy 182.529132 -426.918369) (xy 182.591922 -426.906391)
			(xy 182.655718 -426.902378) (xy 182.719514 -426.906391) (xy 182.782304 -426.918369) (xy 182.843097 -426.938122)
			(xy 182.900936 -426.965339) (xy 182.954907 -426.99959) (xy 183.00416 -427.040335) (xy 183.047917 -427.086932)
			(xy 183.08549 -427.138647) (xy 183.116284 -427.194662) (xy 183.139816 -427.254095) (xy 183.155713 -427.316009)
			(xy 183.163724 -427.379427) (xy 183.164226 -427.411388) (xy 183.163724 -427.443349) (xy 183.155713 -427.506767)
			(xy 183.139816 -427.568681) (xy 183.116284 -427.628114) (xy 183.08549 -427.684129) (xy 183.047917 -427.735844)
			(xy 183.00416 -427.782441) (xy 182.954907 -427.823186) (xy 182.900936 -427.857437) (xy 182.843097 -427.884654)
			(xy 182.782304 -427.904407) (xy 182.719514 -427.916385) (xy 182.655718 -427.920399) (xy 182.591922 -427.916385)
			(xy 182.529132 -427.904407) (xy 182.468339 -427.884654) (xy 182.4105 -427.857437) (xy 182.356529 -427.823186)
			(xy 182.307276 -427.782441) (xy 182.263519 -427.735844) (xy 182.225946 -427.684129) (xy 182.195152 -427.628114)
			(xy 182.17162 -427.568681) (xy 182.155723 -427.506767) (xy 182.147712 -427.443349) (xy 181.29097 -427.443349)
			(xy 181.271055 -427.485832) (xy 181.240282 -427.532345) (xy 181.203065 -427.573882) (xy 181.160197 -427.609557)
			(xy 181.112591 -427.638611) (xy 181.061262 -427.660423) (xy 181.007305 -427.674529) (xy 180.951868 -427.680629)
			(xy 180.896134 -427.678592) (xy 180.841291 -427.668462) (xy 180.788507 -427.650455) (xy 180.738907 -427.624954)
			(xy 180.693549 -427.592503) (xy 180.6534 -427.553794) (xy 180.619314 -427.509651) (xy 180.592018 -427.461016)
			(xy 180.572095 -427.408925) (xy 180.559969 -427.354488) (xy 180.555898 -427.298866) (xy 174.494605 -427.298866)
			(xy 174.494189 -427.321672) (xy 174.486069 -427.376848) (xy 174.470001 -427.430255) (xy 174.446329 -427.480752)
			(xy 174.415556 -427.527265) (xy 174.378339 -427.568802) (xy 174.335471 -427.604477) (xy 174.287865 -427.633531)
			(xy 174.236536 -427.655343) (xy 174.182579 -427.669449) (xy 174.127142 -427.675549) (xy 174.071408 -427.673512)
			(xy 174.016565 -427.663382) (xy 173.963781 -427.645375) (xy 173.914181 -427.619874) (xy 173.868823 -427.587423)
			(xy 173.828674 -427.548714) (xy 173.794588 -427.504571) (xy 173.767292 -427.455936) (xy 173.747369 -427.403845)
			(xy 173.735243 -427.349408) (xy 173.731172 -427.293786) (xy 166.468044 -427.293786) (xy 166.468044 -427.54931)
			(xy 166.467599 -427.581378) (xy 166.460356 -427.645105) (xy 166.445964 -427.707606) (xy 166.424606 -427.768083)
			(xy 166.396556 -427.825761) (xy 166.362173 -427.879903) (xy 166.321897 -427.929816) (xy 166.299388 -427.952662)
			(xy 166.299134 -427.952916) (xy 166.292281 -427.96028) (xy 166.284516 -427.97882) (xy 166.284504 -427.99892)
			(xy 166.292246 -428.01747) (xy 166.299134 -428.024798) (xy 166.516887 -428.242551) (xy 176.250576 -428.242551)
			(xy 176.250576 -428.188049) (xy 176.258332 -428.134101) (xy 176.273688 -428.081806) (xy 176.296329 -428.032228)
			(xy 176.325795 -427.986377) (xy 176.361487 -427.945187) (xy 176.402677 -427.909495) (xy 176.448528 -427.880029)
			(xy 176.498106 -427.857388) (xy 176.550401 -427.842032) (xy 176.604349 -427.834276) (xy 176.6316 -427.83379)
			(xy 176.658438 -427.834271) (xy 176.711584 -427.841807) (xy 176.763144 -427.85673) (xy 176.78781 -427.867318)
			(xy 176.79797 -427.87189) (xy 176.819814 -427.871636) (xy 176.909476 -427.830488) (xy 176.9237 -427.814232)
			(xy 176.927002 -427.803564) (xy 176.935157 -427.777603) (xy 176.957836 -427.728139) (xy 176.987316 -427.682401)
			(xy 177.022998 -427.641318) (xy 177.064157 -427.605724) (xy 177.109959 -427.576343) (xy 177.159472 -427.55377)
			(xy 177.21169 -427.538466) (xy 177.265554 -427.530739) (xy 177.292762 -427.53026) (xy 177.320014 -427.530785)
			(xy 177.373965 -427.538537) (xy 177.426263 -427.553888) (xy 177.475844 -427.576526) (xy 177.521698 -427.605991)
			(xy 177.562891 -427.641682) (xy 177.598586 -427.682872) (xy 177.628055 -427.728723) (xy 177.638803 -427.752256)
			(xy 178.780946 -427.752256) (xy 178.785017 -427.696634) (xy 178.797143 -427.642197) (xy 178.817066 -427.590106)
			(xy 178.844362 -427.541471) (xy 178.878448 -427.497328) (xy 178.918597 -427.458619) (xy 178.963955 -427.426168)
			(xy 179.013555 -427.400667) (xy 179.066339 -427.38266) (xy 179.121182 -427.37253) (xy 179.176916 -427.370493)
			(xy 179.232353 -427.376593) (xy 179.28631 -427.390699) (xy 179.337639 -427.412511) (xy 179.385245 -427.441565)
			(xy 179.428113 -427.47724) (xy 179.46533 -427.518777) (xy 179.496103 -427.56529) (xy 179.519775 -427.615787)
			(xy 179.535843 -427.669194) (xy 179.543963 -427.72437) (xy 179.544472 -427.752256) (xy 179.543963 -427.780142)
			(xy 179.535843 -427.835318) (xy 179.519775 -427.888725) (xy 179.496103 -427.939222) (xy 179.46533 -427.985735)
			(xy 179.428113 -428.027272) (xy 179.385245 -428.062947) (xy 179.337639 -428.092001) (xy 179.28631 -428.113813)
			(xy 179.232353 -428.127919) (xy 179.176916 -428.134019) (xy 179.121182 -428.131982) (xy 179.066339 -428.121852)
			(xy 179.013555 -428.103845) (xy 178.963955 -428.078344) (xy 178.918597 -428.045893) (xy 178.878448 -428.007184)
			(xy 178.844362 -427.963041) (xy 178.817066 -427.914406) (xy 178.797143 -427.862315) (xy 178.785017 -427.807878)
			(xy 178.780946 -427.752256) (xy 177.638803 -427.752256) (xy 177.650699 -427.778301) (xy 177.666055 -427.830598)
			(xy 177.673813 -427.884548) (xy 177.673813 -427.939052) (xy 177.666055 -427.993002) (xy 177.650699 -428.045299)
			(xy 177.628055 -428.094877) (xy 177.598586 -428.140728) (xy 177.562891 -428.181918) (xy 177.521698 -428.217609)
			(xy 177.475844 -428.247074) (xy 177.426263 -428.269712) (xy 177.373965 -428.285063) (xy 177.320014 -428.292815)
			(xy 177.292762 -428.293276) (xy 177.265923 -428.292811) (xy 177.212777 -428.285269) (xy 177.161217 -428.27034)
			(xy 177.136552 -428.259748) (xy 177.126392 -428.255176) (xy 177.104548 -428.25543) (xy 177.014886 -428.296578)
			(xy 177.000662 -428.312834) (xy 176.99736 -428.323502) (xy 176.989217 -428.349468) (xy 176.96654 -428.398934)
			(xy 176.93706 -428.444675) (xy 176.901377 -428.485759) (xy 176.860216 -428.521354) (xy 176.814412 -428.550735)
			(xy 176.764897 -428.573305) (xy 176.712675 -428.588607) (xy 176.658809 -428.596329) (xy 176.6316 -428.596806)
			(xy 176.604349 -428.596324) (xy 176.550401 -428.588568) (xy 176.498106 -428.573212) (xy 176.448528 -428.550571)
			(xy 176.402677 -428.521105) (xy 176.361487 -428.485413) (xy 176.325795 -428.444223) (xy 176.296329 -428.398372)
			(xy 176.273688 -428.348794) (xy 176.258332 -428.296499) (xy 176.250576 -428.242551) (xy 166.516887 -428.242551)
			(xy 166.632128 -428.357792) (xy 166.654327 -428.380583) (xy 166.694012 -428.430314) (xy 166.727879 -428.484176)
			(xy 166.7555 -428.541493) (xy 166.776529 -428.601542) (xy 166.7907 -428.663568) (xy 166.797836 -428.726792)
			(xy 166.798244 -428.758604) (xy 166.798244 -428.993511) (xy 183.179968 -428.993511) (xy 183.179968 -428.929589)
			(xy 183.187979 -428.866171) (xy 183.203876 -428.804257) (xy 183.227408 -428.744824) (xy 183.258202 -428.688809)
			(xy 183.295775 -428.637094) (xy 183.339532 -428.590497) (xy 183.388785 -428.549752) (xy 183.442756 -428.515501)
			(xy 183.500595 -428.488284) (xy 183.561388 -428.468531) (xy 183.624178 -428.456553) (xy 183.687974 -428.45254)
			(xy 183.75177 -428.456553) (xy 183.81456 -428.468531) (xy 183.875353 -428.488284) (xy 183.933192 -428.515501)
			(xy 183.987163 -428.549752) (xy 184.036416 -428.590497) (xy 184.080173 -428.637094) (xy 184.117746 -428.688809)
			(xy 184.14854 -428.744824) (xy 184.172072 -428.804257) (xy 184.187969 -428.866171) (xy 184.19598 -428.929589)
			(xy 184.196482 -428.96155) (xy 184.19598 -428.993511) (xy 184.187969 -429.056929) (xy 184.172072 -429.118843)
			(xy 184.14854 -429.178276) (xy 184.117746 -429.234291) (xy 184.080173 -429.286006) (xy 184.036416 -429.332603)
			(xy 183.987163 -429.373348) (xy 183.969253 -429.384714) (xy 184.645298 -429.384714) (xy 184.649369 -429.329092)
			(xy 184.661495 -429.274655) (xy 184.681418 -429.222564) (xy 184.708714 -429.173929) (xy 184.7428 -429.129786)
			(xy 184.782949 -429.091077) (xy 184.828307 -429.058626) (xy 184.877907 -429.033125) (xy 184.930691 -429.015118)
			(xy 184.985534 -429.004988) (xy 185.041268 -429.002951) (xy 185.096705 -429.009051) (xy 185.150662 -429.023157)
			(xy 185.201991 -429.044969) (xy 185.249597 -429.074023) (xy 185.292465 -429.109698) (xy 185.329682 -429.151235)
			(xy 185.360455 -429.197748) (xy 185.384127 -429.248245) (xy 185.400195 -429.301652) (xy 185.408315 -429.356828)
			(xy 185.408824 -429.384714) (xy 185.408315 -429.4126) (xy 185.406102 -429.42764) (xy 185.656218 -429.42764)
			(xy 185.660289 -429.372018) (xy 185.672415 -429.317581) (xy 185.692338 -429.26549) (xy 185.719634 -429.216855)
			(xy 185.75372 -429.172712) (xy 185.793869 -429.134003) (xy 185.839227 -429.101552) (xy 185.888827 -429.076051)
			(xy 185.941611 -429.058044) (xy 185.996454 -429.047914) (xy 186.052188 -429.045877) (xy 186.107625 -429.051977)
			(xy 186.161582 -429.066083) (xy 186.212911 -429.087895) (xy 186.260517 -429.116949) (xy 186.303385 -429.152624)
			(xy 186.340602 -429.194161) (xy 186.371375 -429.240674) (xy 186.395047 -429.291171) (xy 186.411115 -429.344578)
			(xy 186.419235 -429.399754) (xy 186.419744 -429.42764) (xy 186.419235 -429.455526) (xy 186.411115 -429.510702)
			(xy 186.395047 -429.564109) (xy 186.371375 -429.614606) (xy 186.340602 -429.661119) (xy 186.303385 -429.702656)
			(xy 186.260517 -429.738331) (xy 186.212911 -429.767385) (xy 186.161582 -429.789197) (xy 186.107625 -429.803303)
			(xy 186.052188 -429.809403) (xy 185.996454 -429.807366) (xy 185.941611 -429.797236) (xy 185.888827 -429.779229)
			(xy 185.839227 -429.753728) (xy 185.793869 -429.721277) (xy 185.75372 -429.682568) (xy 185.719634 -429.638425)
			(xy 185.692338 -429.58979) (xy 185.672415 -429.537699) (xy 185.660289 -429.483262) (xy 185.656218 -429.42764)
			(xy 185.406102 -429.42764) (xy 185.400195 -429.467776) (xy 185.384127 -429.521183) (xy 185.360455 -429.57168)
			(xy 185.329682 -429.618193) (xy 185.292465 -429.65973) (xy 185.249597 -429.695405) (xy 185.201991 -429.724459)
			(xy 185.150662 -429.746271) (xy 185.096705 -429.760377) (xy 185.041268 -429.766477) (xy 184.985534 -429.76444)
			(xy 184.930691 -429.75431) (xy 184.877907 -429.736303) (xy 184.828307 -429.710802) (xy 184.782949 -429.678351)
			(xy 184.7428 -429.639642) (xy 184.708714 -429.595499) (xy 184.681418 -429.546864) (xy 184.661495 -429.494773)
			(xy 184.649369 -429.440336) (xy 184.645298 -429.384714) (xy 183.969253 -429.384714) (xy 183.933192 -429.407599)
			(xy 183.875353 -429.434816) (xy 183.81456 -429.454569) (xy 183.75177 -429.466547) (xy 183.687974 -429.470561)
			(xy 183.624178 -429.466547) (xy 183.561388 -429.454569) (xy 183.500595 -429.434816) (xy 183.442756 -429.407599)
			(xy 183.388785 -429.373348) (xy 183.339532 -429.332603) (xy 183.295775 -429.286006) (xy 183.258202 -429.234291)
			(xy 183.227408 -429.178276) (xy 183.203876 -429.118843) (xy 183.187979 -429.056929) (xy 183.179968 -428.993511)
			(xy 166.798244 -428.993511) (xy 166.798244 -429.459644) (xy 170.212256 -429.459644) (xy 170.216327 -429.404022)
			(xy 170.228453 -429.349585) (xy 170.248376 -429.297494) (xy 170.275672 -429.248859) (xy 170.309758 -429.204716)
			(xy 170.349907 -429.166007) (xy 170.395265 -429.133556) (xy 170.444865 -429.108055) (xy 170.497649 -429.090048)
			(xy 170.552492 -429.079918) (xy 170.608226 -429.077881) (xy 170.663663 -429.083981) (xy 170.71762 -429.098087)
			(xy 170.768949 -429.119899) (xy 170.816555 -429.148953) (xy 170.859423 -429.184628) (xy 170.89664 -429.226165)
			(xy 170.927413 -429.272678) (xy 170.951085 -429.323175) (xy 170.967153 -429.376582) (xy 170.975273 -429.431758)
			(xy 170.975782 -429.459644) (xy 170.975273 -429.48753) (xy 170.967153 -429.542706) (xy 170.951085 -429.596113)
			(xy 170.927413 -429.64661) (xy 170.89664 -429.693123) (xy 170.859423 -429.73466) (xy 170.816555 -429.770335)
			(xy 170.768949 -429.799389) (xy 170.71762 -429.821201) (xy 170.663663 -429.835307) (xy 170.608226 -429.841407)
			(xy 170.552492 -429.83937) (xy 170.497649 -429.82924) (xy 170.444865 -429.811233) (xy 170.395265 -429.785732)
			(xy 170.349907 -429.753281) (xy 170.309758 -429.714572) (xy 170.275672 -429.670429) (xy 170.248376 -429.621794)
			(xy 170.228453 -429.569703) (xy 170.216327 -429.515266) (xy 170.212256 -429.459644) (xy 166.798244 -429.459644)
			(xy 166.798244 -431.3936) (xy 167.09009 -431.3936) (xy 167.090584 -431.361738) (xy 167.098546 -431.298513)
			(xy 167.114345 -431.236778) (xy 167.137734 -431.177502) (xy 167.168346 -431.121612) (xy 167.205702 -431.069985)
			(xy 167.249215 -431.02343) (xy 167.298204 -430.982676) (xy 167.324786 -430.965102) (xy 167.337263 -430.956505)
			(xy 167.356824 -430.933381) (xy 167.368757 -430.905543) (xy 167.372017 -430.875431) (xy 167.366316 -430.845685)
			(xy 167.352156 -430.818911) (xy 167.330776 -430.797457) (xy 167.317674 -430.789842) (xy 167.291883 -430.775503)
			(xy 167.244654 -430.740129) (xy 167.203439 -430.697901) (xy 167.169222 -430.649827) (xy 167.142821 -430.597055)
			(xy 167.124865 -430.540846) (xy 167.115783 -430.482542) (xy 167.115236 -430.453038) (xy 167.115722 -430.425787)
			(xy 167.123478 -430.371839) (xy 167.138833 -430.319544) (xy 167.161475 -430.269967) (xy 167.190941 -430.224117)
			(xy 167.226632 -430.182926) (xy 167.267823 -430.147235) (xy 167.313673 -430.117769) (xy 167.36325 -430.095127)
			(xy 167.415545 -430.079772) (xy 167.469493 -430.072016) (xy 167.523995 -430.072016) (xy 167.555949 -430.07661)
			(xy 187.209682 -430.07661) (xy 187.213753 -430.020988) (xy 187.225879 -429.966551) (xy 187.245802 -429.91446)
			(xy 187.273098 -429.865825) (xy 187.307184 -429.821682) (xy 187.347333 -429.782973) (xy 187.392691 -429.750522)
			(xy 187.442291 -429.725021) (xy 187.495075 -429.707014) (xy 187.549918 -429.696884) (xy 187.605652 -429.694847)
			(xy 187.661089 -429.700947) (xy 187.715046 -429.715053) (xy 187.766375 -429.736865) (xy 187.813981 -429.765919)
			(xy 187.856849 -429.801594) (xy 187.894066 -429.843131) (xy 187.924839 -429.889644) (xy 187.948511 -429.940141)
			(xy 187.964579 -429.993548) (xy 187.972699 -430.048724) (xy 187.973208 -430.07661) (xy 187.972699 -430.104496)
			(xy 187.964579 -430.159672) (xy 187.948511 -430.213079) (xy 187.924839 -430.263576) (xy 187.894066 -430.310089)
			(xy 187.856849 -430.351626) (xy 187.813981 -430.387301) (xy 187.766375 -430.416355) (xy 187.715046 -430.438167)
			(xy 187.661089 -430.452273) (xy 187.605652 -430.458373) (xy 187.549918 -430.456336) (xy 187.495075 -430.446206)
			(xy 187.442291 -430.428199) (xy 187.392691 -430.402698) (xy 187.347333 -430.370247) (xy 187.307184 -430.331538)
			(xy 187.273098 -430.287395) (xy 187.245802 -430.23876) (xy 187.225879 -430.186669) (xy 187.213753 -430.132232)
			(xy 187.209682 -430.07661) (xy 167.555949 -430.07661) (xy 167.577943 -430.079772) (xy 167.630238 -430.095127)
			(xy 167.679815 -430.117769) (xy 167.725665 -430.147235) (xy 167.766856 -430.182926) (xy 167.802547 -430.224117)
			(xy 167.832013 -430.269967) (xy 167.854655 -430.319544) (xy 167.87001 -430.371839) (xy 167.877766 -430.425787)
			(xy 167.878252 -430.453038) (xy 167.877769 -430.480583) (xy 167.869859 -430.535103) (xy 167.85418 -430.587915)
			(xy 167.831059 -430.637918) (xy 167.800978 -430.684071) (xy 167.764565 -430.725411) (xy 167.743886 -430.743614)
			(xy 167.732754 -430.753914) (xy 167.716434 -430.77945) (xy 167.708306 -430.808646) (xy 167.708604 -430.820279)
			(xy 169.926248 -430.820279) (xy 169.926248 -430.756357) (xy 169.934259 -430.692939) (xy 169.950156 -430.631025)
			(xy 169.973688 -430.571592) (xy 170.004482 -430.515577) (xy 170.042055 -430.463862) (xy 170.085812 -430.417265)
			(xy 170.135065 -430.37652) (xy 170.189036 -430.342269) (xy 170.246875 -430.315052) (xy 170.307668 -430.295299)
			(xy 170.370458 -430.283321) (xy 170.434254 -430.279308) (xy 170.49805 -430.283321) (xy 170.56084 -430.295299)
			(xy 170.621633 -430.315052) (xy 170.679472 -430.342269) (xy 170.733443 -430.37652) (xy 170.782696 -430.417265)
			(xy 170.826453 -430.463862) (xy 170.864026 -430.515577) (xy 170.89482 -430.571592) (xy 170.918352 -430.631025)
			(xy 170.934249 -430.692939) (xy 170.94226 -430.756357) (xy 170.942762 -430.788318) (xy 170.94226 -430.820279)
			(xy 170.934249 -430.883697) (xy 170.918352 -430.945611) (xy 170.89482 -431.005044) (xy 170.864026 -431.061059)
			(xy 170.826453 -431.112774) (xy 170.782696 -431.159371) (xy 170.733443 -431.200116) (xy 170.679472 -431.234367)
			(xy 170.621633 -431.261584) (xy 170.56084 -431.281337) (xy 170.49805 -431.293315) (xy 170.434254 -431.297329)
			(xy 170.370458 -431.293315) (xy 170.307668 -431.281337) (xy 170.246875 -431.261584) (xy 170.189036 -431.234367)
			(xy 170.135065 -431.200116) (xy 170.085812 -431.159371) (xy 170.042055 -431.112774) (xy 170.004482 -431.061059)
			(xy 169.973688 -431.005044) (xy 169.950156 -430.945611) (xy 169.934259 -430.883697) (xy 169.926248 -430.820279)
			(xy 167.708604 -430.820279) (xy 167.709083 -430.838942) (xy 167.718695 -430.867683) (xy 167.736302 -430.89235)
			(xy 167.760359 -430.91078) (xy 167.774366 -430.916588) (xy 167.803274 -430.927707) (xy 167.858371 -430.956005)
			(xy 167.90962 -430.990789) (xy 167.956263 -431.031542) (xy 167.997609 -431.077661) (xy 168.033044 -431.128462)
			(xy 168.062044 -431.183192) (xy 168.084178 -431.241041) (xy 168.099119 -431.301151) (xy 168.106646 -431.362631)
			(xy 168.107106 -431.3936) (xy 168.106604 -431.425561) (xy 168.098593 -431.488979) (xy 168.082696 -431.550893)
			(xy 168.059164 -431.610326) (xy 168.02837 -431.666341) (xy 167.990797 -431.718056) (xy 167.94704 -431.764653)
			(xy 167.897787 -431.805398) (xy 167.843816 -431.839649) (xy 167.785977 -431.866866) (xy 167.725184 -431.886619)
			(xy 167.662394 -431.898597) (xy 167.598598 -431.902611) (xy 167.534802 -431.898597) (xy 167.472012 -431.886619)
			(xy 167.411219 -431.866866) (xy 167.35338 -431.839649) (xy 167.299409 -431.805398) (xy 167.250156 -431.764653)
			(xy 167.206399 -431.718056) (xy 167.168826 -431.666341) (xy 167.138032 -431.610326) (xy 167.1145 -431.550893)
			(xy 167.098603 -431.488979) (xy 167.090592 -431.425561) (xy 167.09009 -431.3936) (xy 166.798244 -431.3936)
			(xy 166.798244 -432.26609) (xy 166.798718 -432.276057) (xy 166.806291 -432.294497) (xy 166.812976 -432.301904)
			(xy 167.101266 -432.590194) (xy 168.27322 -432.590194) (xy 168.277291 -432.534572) (xy 168.289417 -432.480135)
			(xy 168.30934 -432.428044) (xy 168.336636 -432.379409) (xy 168.370722 -432.335266) (xy 168.410871 -432.296557)
			(xy 168.456229 -432.264106) (xy 168.505829 -432.238605) (xy 168.558613 -432.220598) (xy 168.613456 -432.210468)
			(xy 168.66919 -432.208431) (xy 168.724627 -432.214531) (xy 168.778584 -432.228637) (xy 168.829913 -432.250449)
			(xy 168.877519 -432.279503) (xy 168.920387 -432.315178) (xy 168.957604 -432.356715) (xy 168.988377 -432.403228)
			(xy 169.012049 -432.453725) (xy 169.028117 -432.507132) (xy 169.036237 -432.562308) (xy 169.036746 -432.590194)
			(xy 169.036237 -432.61808) (xy 169.028117 -432.673256) (xy 169.012049 -432.726663) (xy 168.988377 -432.77716)
			(xy 168.957604 -432.823673) (xy 168.920387 -432.86521) (xy 168.877519 -432.900885) (xy 168.829913 -432.929939)
			(xy 168.778584 -432.951751) (xy 168.724627 -432.965857) (xy 168.66919 -432.971957) (xy 168.613456 -432.96992)
			(xy 168.558613 -432.95979) (xy 168.505829 -432.941783) (xy 168.456229 -432.916282) (xy 168.410871 -432.883831)
			(xy 168.370722 -432.845122) (xy 168.336636 -432.800979) (xy 168.30934 -432.752344) (xy 168.289417 -432.700253)
			(xy 168.277291 -432.645816) (xy 168.27322 -432.590194) (xy 167.101266 -432.590194) (xy 167.623955 -433.112883)
			(xy 169.088048 -433.112883) (xy 169.088048 -433.048961) (xy 169.096059 -432.985543) (xy 169.111956 -432.923629)
			(xy 169.135488 -432.864196) (xy 169.166282 -432.808181) (xy 169.203855 -432.756466) (xy 169.247612 -432.709869)
			(xy 169.296865 -432.669124) (xy 169.350836 -432.634873) (xy 169.408675 -432.607656) (xy 169.469468 -432.587903)
			(xy 169.532258 -432.575925) (xy 169.596054 -432.571912) (xy 169.65985 -432.575925) (xy 169.72264 -432.587903)
			(xy 169.783433 -432.607656) (xy 169.841272 -432.634873) (xy 169.895243 -432.669124) (xy 169.944496 -432.709869)
			(xy 169.988253 -432.756466) (xy 170.025826 -432.808181) (xy 170.05662 -432.864196) (xy 170.080152 -432.923629)
			(xy 170.096049 -432.985543) (xy 170.10406 -433.048961) (xy 170.104562 -433.080922) (xy 170.10406 -433.112883)
			(xy 170.096049 -433.176301) (xy 170.080152 -433.238215) (xy 170.05662 -433.297648) (xy 170.025826 -433.353663)
			(xy 169.988253 -433.405378) (xy 169.944496 -433.451975) (xy 169.895243 -433.49272) (xy 169.841272 -433.526971)
			(xy 169.783433 -433.554188) (xy 169.72264 -433.573941) (xy 169.65985 -433.585919) (xy 169.596054 -433.589933)
			(xy 169.532258 -433.585919) (xy 169.469468 -433.573941) (xy 169.408675 -433.554188) (xy 169.350836 -433.526971)
			(xy 169.296865 -433.49272) (xy 169.247612 -433.451975) (xy 169.203855 -433.405378) (xy 169.166282 -433.353663)
			(xy 169.135488 -433.297648) (xy 169.111956 -433.238215) (xy 169.096059 -433.176301) (xy 169.088048 -433.112883)
			(xy 167.623955 -433.112883) (xy 167.725598 -433.214526) (xy 167.747765 -433.237336) (xy 167.787411 -433.287078)
			(xy 167.821238 -433.340946) (xy 167.848821 -433.398262) (xy 167.869814 -433.458307) (xy 167.883953 -433.520324)
			(xy 167.891059 -433.583534) (xy 167.89146 -433.615338) (xy 167.890878 -433.65202) (xy 167.881405 -433.724769)
			(xy 167.862623 -433.795687) (xy 167.834845 -433.863588) (xy 167.798537 -433.927336) (xy 167.776906 -433.956968)
			(xy 167.77035 -433.966523) (xy 167.765853 -433.989231) (xy 167.771782 -434.011608) (xy 167.778938 -434.020722)
			(xy 167.798188 -434.043826) (xy 167.831703 -434.093758) (xy 167.859095 -434.147295) (xy 167.879983 -434.203689)
			(xy 167.894075 -434.262152) (xy 167.901174 -434.321869) (xy 167.90162 -434.351938) (xy 167.901118 -434.383899)
			(xy 167.893107 -434.447317) (xy 167.87721 -434.509231) (xy 167.853678 -434.568664) (xy 167.822884 -434.624679)
			(xy 167.785311 -434.676394) (xy 167.741554 -434.722991) (xy 167.692301 -434.763736) (xy 167.63833 -434.797987)
			(xy 167.580491 -434.825204) (xy 167.519698 -434.844957) (xy 167.456908 -434.856935) (xy 167.393112 -434.860949)
			(xy 167.329316 -434.856935) (xy 167.266526 -434.844957) (xy 167.205733 -434.825204) (xy 167.147894 -434.797987)
			(xy 167.093923 -434.763736) (xy 167.04467 -434.722991) (xy 167.000913 -434.676394) (xy 166.96334 -434.624679)
			(xy 166.932546 -434.568664) (xy 166.909014 -434.509231) (xy 166.893117 -434.447317) (xy 166.885106 -434.383899)
			(xy 166.884604 -434.351938) (xy 166.885126 -434.318603) (xy 166.893841 -434.252506) (xy 166.911125 -434.188117)
			(xy 166.936682 -434.126541) (xy 166.95293 -434.09743) (xy 166.958254 -434.087137) (xy 166.959913 -434.064047)
			(xy 166.951278 -434.042568) (xy 166.943024 -434.034438) (xy 166.923974 -434.01615) (xy 165.830504 -432.92268)
			(xy 165.808309 -432.899887) (xy 165.76863 -432.850154) (xy 165.734771 -432.79629) (xy 165.707155 -432.738974)
			(xy 165.686132 -432.678925) (xy 165.671966 -432.6169) (xy 165.664834 -432.553679) (xy 165.664388 -432.521868)
			(xy 165.664388 -429.014382) (xy 165.66391 -429.004416) (xy 165.656334 -428.98598) (xy 165.649656 -428.978568)
			(xy 165.574218 -428.902876) (xy 165.566771 -428.896188) (xy 165.548275 -428.888592) (xy 165.528279 -428.888592)
			(xy 165.509783 -428.896188) (xy 165.502336 -428.902876) (xy 165.502082 -428.90313) (xy 165.478113 -428.926651)
			(xy 165.425063 -428.967827) (xy 165.367057 -429.001665) (xy 165.305103 -429.027577) (xy 165.240278 -429.045112)
			(xy 165.173709 -429.053965) (xy 165.140132 -429.054514) (xy 165.109398 -429.05407) (xy 165.048379 -429.046665)
			(xy 164.988698 -429.031958) (xy 164.931224 -429.010165) (xy 164.876796 -428.981602) (xy 164.826208 -428.946687)
			(xy 164.780198 -428.905929) (xy 164.739436 -428.859921) (xy 164.704518 -428.809336) (xy 164.675951 -428.754911)
			(xy 164.654153 -428.697439) (xy 164.639442 -428.637758) (xy 164.632032 -428.576739) (xy 164.631624 -428.546006)
			(xy 164.632128 -428.513653) (xy 164.64033 -428.44947) (xy 164.656602 -428.386843) (xy 164.680681 -428.326785)
			(xy 164.71218 -428.270264) (xy 164.750589 -428.218192) (xy 164.772594 -428.19447) (xy 164.778505 -428.187827)
			(xy 164.785681 -428.171567) (xy 164.786564 -428.16272) (xy 164.788342 -428.132748) (xy 164.788625 -428.123722)
			(xy 164.783559 -428.106402) (xy 164.778436 -428.098966) (xy 164.7557 -428.067483) (xy 164.718126 -427.999518)
			(xy 164.690174 -427.927064) (xy 164.680646 -427.889416) (xy 164.67836 -427.87951) (xy 164.666422 -427.863)
			(xy 164.587174 -427.81474) (xy 164.567108 -427.811692) (xy 164.557202 -427.814232) (xy 164.534516 -427.81949)
			(xy 164.488285 -427.825091) (xy 164.465 -427.825408) (xy 164.437749 -427.824922) (xy 164.383801 -427.817166)
			(xy 164.331506 -427.801811) (xy 164.281929 -427.779169) (xy 164.236079 -427.749703) (xy 164.194888 -427.714012)
			(xy 164.159197 -427.672821) (xy 164.129731 -427.626971) (xy 164.107089 -427.577394) (xy 164.091734 -427.525099)
			(xy 164.083978 -427.471151) (xy 164.083978 -427.416649) (xy 164.091734 -427.362701) (xy 164.107089 -427.310406)
			(xy 164.129731 -427.260829) (xy 164.159197 -427.214979) (xy 164.194888 -427.173788) (xy 164.236079 -427.138097)
			(xy 164.281929 -427.108631) (xy 164.331506 -427.085989) (xy 164.383801 -427.070634) (xy 164.437749 -427.062878)
			(xy 164.465 -427.062392) (xy 164.484703 -427.062638) (xy 164.523899 -427.066711) (xy 164.543232 -427.07052)
			(xy 164.554408 -427.072806) (xy 164.57676 -427.067472) (xy 164.646864 -427.010576) (xy 164.655301 -427.002908)
			(xy 164.66506 -426.982337) (xy 164.66566 -426.970952) (xy 164.66566 -426.167804) (xy 164.666189 -426.131524)
			(xy 164.675362 -426.059548) (xy 164.683948 -426.024294) (xy 164.68725 -426.011594) (xy 164.6809 -425.986194)
			(xy 164.60343 -425.904152) (xy 164.578538 -425.896278) (xy 164.565584 -425.898818) (xy 164.540706 -425.903546)
			(xy 164.490321 -425.908639) (xy 164.465 -425.908978) (xy 164.431179 -425.908422) (xy 164.364136 -425.899452)
			(xy 164.298873 -425.881671) (xy 164.236545 -425.855392) (xy 164.178253 -425.82108) (xy 164.125025 -425.77934)
			(xy 164.077803 -425.730911) (xy 164.03742 -425.676648) (xy 164.0205 -425.647358) (xy 164.0158 -425.639615)
			(xy 164.002076 -425.627812) (xy 163.985101 -425.621527) (xy 163.97605 -425.621196) (xy 163.88715 -425.621196)
			(xy 163.878107 -425.621567) (xy 163.861147 -425.627856) (xy 163.847421 -425.639635) (xy 163.8427 -425.647358)
			(xy 163.825788 -425.676649) (xy 163.78539 -425.730894) (xy 163.738158 -425.779307) (xy 163.684927 -425.821033)
			(xy 163.626635 -425.855336) (xy 163.564312 -425.88161) (xy 163.499055 -425.899393) (xy 163.432018 -425.90837)
			(xy 163.3982 -425.908978) (xy 163.364641 -425.90844) (xy 163.298104 -425.899613) (xy 163.233307 -425.882112)
			(xy 163.171374 -425.856242) (xy 163.113382 -425.822451) (xy 163.086542 -425.802298) (xy 163.077287 -425.795845)
			(xy 163.0553 -425.790917) (xy 163.033313 -425.795845) (xy 163.024058 -425.802298) (xy 162.99721 -425.82244)
			(xy 162.939223 -425.856237) (xy 162.877292 -425.88211) (xy 162.812495 -425.899609) (xy 162.745959 -425.908428)
			(xy 162.7124 -425.908978) (xy 162.680441 -425.908476) (xy 162.617027 -425.900465) (xy 162.555116 -425.884569)
			(xy 162.495687 -425.861039) (xy 162.439675 -425.830246) (xy 162.387964 -425.792676) (xy 162.341369 -425.748921)
			(xy 162.300626 -425.699671) (xy 162.266377 -425.645703) (xy 162.239162 -425.587868) (xy 162.21941 -425.527078)
			(xy 162.207433 -425.464292) (xy 162.20342 -425.4005) (xy 162.207433 -425.336708) (xy 162.21941 -425.273922)
			(xy 162.239162 -425.213132) (xy 162.266377 -425.155297) (xy 162.300626 -425.101329) (xy 162.341369 -425.052079)
			(xy 162.387964 -425.008324) (xy 162.439675 -424.970754) (xy 162.495687 -424.939961) (xy 162.555116 -424.916431)
			(xy 162.617027 -424.900535) (xy 162.680441 -424.892524) (xy 162.7124 -424.891962) (xy 162.745959 -424.8925)
			(xy 162.812495 -424.901328) (xy 162.877291 -424.91883) (xy 162.939223 -424.944702) (xy 162.997214 -424.978495)
			(xy 163.024058 -424.998642) (xy 163.033313 -425.005095) (xy 163.0553 -425.010023) (xy 163.077287 -425.005095)
			(xy 163.086542 -424.998642) (xy 163.113389 -424.978499) (xy 163.171376 -424.944699) (xy 163.233307 -424.918824)
			(xy 163.298104 -424.901324) (xy 163.364641 -424.892504) (xy 163.3982 -424.891962) (xy 163.43202 -424.892518)
			(xy 163.499063 -424.901488) (xy 163.564324 -424.919271) (xy 163.62665 -424.945551) (xy 163.684941 -424.979864)
			(xy 163.738166 -425.021605) (xy 163.785385 -425.070036) (xy 163.825764 -425.124302) (xy 163.8427 -425.153582)
			(xy 163.847403 -425.16132) (xy 163.86113 -425.173113) (xy 163.878101 -425.179393) (xy 163.88715 -425.179744)
			(xy 163.97605 -425.179744) (xy 163.985092 -425.179372) (xy 164.002045 -425.173079) (xy 164.01576 -425.161292)
			(xy 164.0205 -425.153582) (xy 164.03741 -425.124289) (xy 164.077807 -425.07004) (xy 164.125037 -425.021623)
			(xy 164.178268 -424.979894) (xy 164.23656 -424.945588) (xy 164.298884 -424.919312) (xy 164.364142 -424.901527)
			(xy 164.431181 -424.892549) (xy 164.465 -424.891962) (xy 164.498559 -424.8925) (xy 164.565095 -424.901328)
			(xy 164.629891 -424.91883) (xy 164.691823 -424.944702) (xy 164.749814 -424.978495) (xy 164.776658 -424.998642)
			(xy 164.785913 -425.005095) (xy 164.8079 -425.010023) (xy 164.829887 -425.005095) (xy 164.839142 -424.998642)
			(xy 164.865989 -424.978499) (xy 164.923976 -424.944699) (xy 164.985907 -424.918824) (xy 165.050704 -424.901324)
			(xy 165.117241 -424.892504) (xy 165.1508 -424.891962) (xy 165.182777 -424.892444) (xy 165.246227 -424.900461)
			(xy 165.308171 -424.916369) (xy 165.367632 -424.939917) (xy 165.423673 -424.970733) (xy 165.475408 -425.008331)
			(xy 165.499034 -425.029884) (xy 165.514274 -425.044108) (xy 165.554914 -425.0436) (xy 166.328344 -424.27017)
			(xy 166.334983 -424.26281) (xy 166.342546 -424.24451) (xy 166.343076 -424.23461) (xy 166.343584 -424.153076)
			(xy 166.336218 -424.134788) (xy 166.329106 -424.127422) (xy 166.308888 -424.105915) (xy 166.274661 -424.057826)
			(xy 166.24825 -424.005038) (xy 166.230286 -423.948811) (xy 166.221197 -423.890489) (xy 166.220648 -423.860976)
			(xy 166.221135 -423.833725) (xy 166.228894 -423.779777) (xy 166.244251 -423.727483) (xy 166.266893 -423.677906)
			(xy 166.296359 -423.632055) (xy 166.33205 -423.590864) (xy 166.373239 -423.555171) (xy 166.419088 -423.525703)
			(xy 166.468664 -423.503058) (xy 166.520958 -423.487699) (xy 166.574905 -423.479937) (xy 166.602156 -423.479468)
			(xy 166.63167 -423.480016) (xy 166.689995 -423.489101) (xy 166.746226 -423.50706) (xy 166.799019 -423.533464)
			(xy 166.847116 -423.567685) (xy 166.868602 -423.587926) (xy 166.875968 -423.595038) (xy 166.894256 -423.602404)
			(xy 166.97579 -423.601896) (xy 166.985689 -423.601378) (xy 167.003986 -423.5938) (xy 167.01135 -423.587164)
			(xy 167.232838 -423.365676) (xy 167.239017 -423.359025) (xy 167.246614 -423.342549) (xy 167.247954 -423.324457)
			(xy 167.245792 -423.315638) (xy 167.217344 -423.216832) (xy 167.197278 -423.197782) (xy 167.183562 -423.194734)
			(xy 167.154871 -423.187757) (xy 167.099208 -423.168053) (xy 167.046204 -423.14203) (xy 166.996572 -423.110041)
			(xy 166.973504 -423.09161) (xy 166.966318 -423.086282) (xy 166.949426 -423.080432) (xy 166.940484 -423.08018)
			(xy 166.910512 -423.080434) (xy 166.901515 -423.080925) (xy 166.884726 -423.087435) (xy 166.877746 -423.093134)
			(xy 166.854535 -423.112774) (xy 166.804262 -423.146973) (xy 166.75027 -423.174937) (xy 166.69333 -423.196265)
			(xy 166.634254 -423.210655) (xy 166.573884 -423.2179) (xy 166.543482 -423.218356) (xy 166.511519 -423.217853)
			(xy 166.448096 -423.209839) (xy 166.386178 -423.193939) (xy 166.326741 -423.170405) (xy 166.270723 -423.139607)
			(xy 166.219006 -423.10203) (xy 166.172406 -423.058269) (xy 166.131658 -423.009012) (xy 166.097405 -422.955036)
			(xy 166.070187 -422.897193) (xy 166.050433 -422.836395) (xy 166.038455 -422.773601) (xy 166.034441 -422.7098)
			(xy 166.038455 -422.645999) (xy 166.050433 -422.583205) (xy 166.070187 -422.522407) (xy 166.097405 -422.464564)
			(xy 166.131658 -422.410588) (xy 166.172406 -422.361331) (xy 166.219006 -422.31757) (xy 166.270723 -422.279993)
			(xy 166.326741 -422.249195) (xy 166.386178 -422.225661) (xy 166.448096 -422.209761) (xy 166.511519 -422.201747)
			(xy 166.543482 -422.20134) (xy 166.578507 -422.201924) (xy 166.647895 -422.211536) (xy 166.715306 -422.23058)
			(xy 166.779466 -422.258696) (xy 166.83916 -422.295352) (xy 166.86657 -422.317164) (xy 166.873758 -422.322489)
			(xy 166.890648 -422.328339) (xy 166.89959 -422.328594) (xy 166.929562 -422.32834) (xy 166.938561 -422.327853)
			(xy 166.955353 -422.321346) (xy 166.962328 -422.31564) (xy 166.985539 -422.296) (xy 167.035812 -422.261799)
			(xy 167.089804 -422.233835) (xy 167.146744 -422.212505) (xy 167.20582 -422.198113) (xy 167.26619 -422.190865)
			(xy 167.296592 -422.190418) (xy 167.331814 -422.190998) (xy 167.401587 -422.200695) (xy 167.46935 -422.219945)
			(xy 167.501824 -422.233598) (xy 167.513762 -422.238932) (xy 167.539162 -422.2369) (xy 167.621458 -422.183306)
			(xy 167.628396 -422.178447) (xy 167.638825 -422.165113) (xy 167.644314 -422.149099) (xy 167.644572 -422.140634)
			(xy 167.644572 -420.760906) (xy 167.62349 -420.733728) (xy 167.606726 -420.729156) (xy 167.576261 -420.720459)
			(xy 167.5176 -420.696526) (xy 167.462366 -420.66549) (xy 167.411417 -420.627832) (xy 167.365542 -420.584135)
			(xy 167.325452 -420.535076) (xy 167.291767 -420.481417) (xy 167.265012 -420.423988) (xy 167.245599 -420.363679)
			(xy 167.23383 -420.301426) (xy 167.229887 -420.238193) (xy 167.233831 -420.17496) (xy 167.245602 -420.112707)
			(xy 167.265017 -420.0524) (xy 167.291774 -419.994971) (xy 167.325459 -419.941313) (xy 167.365551 -419.892255)
			(xy 167.411428 -419.848559) (xy 167.462378 -419.810902) (xy 167.517612 -419.779868) (xy 167.576274 -419.755937)
			(xy 167.606726 -419.747192) (xy 167.62349 -419.74262) (xy 167.644572 -419.715442) (xy 167.644572 -419.631114)
			(xy 167.644985 -419.599308) (xy 167.652075 -419.536094) (xy 167.666201 -419.474072) (xy 167.687186 -419.414022)
			(xy 167.714765 -419.356701) (xy 167.748592 -419.30283) (xy 167.788239 -419.253087) (xy 167.810434 -419.230302)
			(xy 168.399714 -418.641022) (xy 168.406557 -418.633623) (xy 168.414277 -418.615024) (xy 168.4147 -418.604954)
			(xy 168.4147 -418.550344) (xy 168.393872 -418.523166) (xy 168.377362 -418.518594) (xy 168.347024 -418.509802)
			(xy 168.288629 -418.485721) (xy 168.233666 -418.454594) (xy 168.182981 -418.416898) (xy 168.137356 -418.373215)
			(xy 168.097492 -418.324218) (xy 168.064004 -418.27066) (xy 168.037407 -418.213368) (xy 168.01811 -418.153222)
			(xy 168.006412 -418.091149) (xy 168.002492 -418.028105) (xy 168.006411 -417.965062) (xy 168.018108 -417.902989)
			(xy 168.037403 -417.842842) (xy 168.063999 -417.785549) (xy 168.097486 -417.731991) (xy 168.137348 -417.682992)
			(xy 168.182973 -417.639309) (xy 168.233657 -417.601612) (xy 168.288619 -417.570483) (xy 168.347014 -417.546402)
			(xy 168.377362 -417.537646) (xy 168.393872 -417.533074) (xy 168.4147 -417.505896) (xy 168.4147 -416.709352)
			(xy 168.414268 -416.699286) (xy 168.406541 -416.680694) (xy 168.399714 -416.673284) (xy 168.090342 -416.363912)
			(xy 168.049956 -416.362896) (xy 168.034716 -416.376866) (xy 168.013524 -416.395507) (xy 167.966676 -416.426982)
			(xy 167.9157 -416.451208) (xy 167.861711 -416.467658) (xy 167.805888 -416.475971) (xy 167.777668 -416.476434)
			(xy 167.750418 -416.475946) (xy 167.696472 -416.468186) (xy 167.64418 -416.452828) (xy 167.594605 -416.430186)
			(xy 167.548756 -416.400719) (xy 167.507568 -416.365028) (xy 167.471877 -416.323839) (xy 167.442411 -416.27799)
			(xy 167.41977 -416.228415) (xy 167.404413 -416.176122) (xy 167.396654 -416.122176) (xy 167.39616 -416.094926)
			(xy 167.396519 -416.070719) (xy 167.402605 -416.02269) (xy 167.41471 -415.975814) (xy 167.423338 -415.953194)
			(xy 167.428164 -415.94151) (xy 167.425624 -415.916364) (xy 167.371268 -415.8361) (xy 167.363743 -415.826074)
			(xy 167.341625 -415.814344) (xy 167.329104 -415.813748) (xy 166.111936 -415.813748) (xy 166.090581 -415.813569)
			(xy 166.047991 -415.810391) (xy 166.026846 -415.807398) (xy 166.023036 -415.80689) (xy 165.84549 -415.80689)
			(xy 165.835421 -415.806465) (xy 165.81682 -415.798747) (xy 165.809422 -415.791904) (xy 164.17417 -414.156652)
			(xy 164.166772 -414.149805) (xy 164.148174 -414.142073) (xy 164.138102 -414.141666) (xy 116.450872 -414.141666)
			(xy 116.440565 -414.142101) (xy 116.42157 -414.150104) (xy 116.414042 -414.15716) (xy 116.396008 -414.175364)
			(xy 116.355907 -414.207264) (xy 116.311893 -414.233504) (xy 116.264761 -414.253611) (xy 116.21536 -414.267224)
			(xy 116.164581 -414.274096) (xy 116.13896 -414.274508) (xy 116.113343 -414.274072) (xy 116.062574 -414.267175)
			(xy 116.013184 -414.25355) (xy 115.966059 -414.233443) (xy 115.922046 -414.207214) (xy 115.881937 -414.175335)
			(xy 115.863878 -414.15716) (xy 115.856375 -414.150068) (xy 115.837365 -414.142062) (xy 115.827048 -414.141666)
			(xy 112.81664 -414.141666) (xy 112.806576 -414.142102) (xy 112.787994 -414.149839) (xy 112.780572 -414.156652)
			(xy 112.440466 -414.496758) (xy 112.433621 -414.504156) (xy 112.425898 -414.522755) (xy 112.42548 -414.532826)
			(xy 112.42548 -415.412682) (xy 162.310062 -415.412682) (xy 162.314133 -415.35706) (xy 162.326259 -415.302623)
			(xy 162.346182 -415.250532) (xy 162.373478 -415.201897) (xy 162.407564 -415.157754) (xy 162.447713 -415.119045)
			(xy 162.493071 -415.086594) (xy 162.542671 -415.061093) (xy 162.595455 -415.043086) (xy 162.650298 -415.032956)
			(xy 162.706032 -415.030919) (xy 162.761469 -415.037019) (xy 162.815426 -415.051125) (xy 162.866755 -415.072937)
			(xy 162.914361 -415.101991) (xy 162.957229 -415.137666) (xy 162.994446 -415.179203) (xy 163.025219 -415.225716)
			(xy 163.048891 -415.276213) (xy 163.064959 -415.32962) (xy 163.073079 -415.384796) (xy 163.073588 -415.412682)
			(xy 163.073079 -415.440568) (xy 163.064959 -415.495744) (xy 163.048891 -415.549151) (xy 163.025219 -415.599648)
			(xy 162.994446 -415.646161) (xy 162.957229 -415.687698) (xy 162.914361 -415.723373) (xy 162.866755 -415.752427)
			(xy 162.815426 -415.774239) (xy 162.761469 -415.788345) (xy 162.706032 -415.794445) (xy 162.650298 -415.792408)
			(xy 162.595455 -415.782278) (xy 162.542671 -415.764271) (xy 162.493071 -415.73877) (xy 162.447713 -415.706319)
			(xy 162.407564 -415.66761) (xy 162.373478 -415.623467) (xy 162.346182 -415.574832) (xy 162.326259 -415.522741)
			(xy 162.314133 -415.468304) (xy 162.310062 -415.412682) (xy 112.42548 -415.412682) (xy 112.42548 -415.939986)
			(xy 114.552982 -415.939986) (xy 114.557053 -415.884364) (xy 114.569179 -415.829927) (xy 114.589102 -415.777836)
			(xy 114.616398 -415.729201) (xy 114.650484 -415.685058) (xy 114.690633 -415.646349) (xy 114.735991 -415.613898)
			(xy 114.785591 -415.588397) (xy 114.838375 -415.57039) (xy 114.893218 -415.56026) (xy 114.948952 -415.558223)
			(xy 115.004389 -415.564323) (xy 115.058346 -415.578429) (xy 115.109675 -415.600241) (xy 115.157281 -415.629295)
			(xy 115.200149 -415.66497) (xy 115.237366 -415.706507) (xy 115.268139 -415.75302) (xy 115.291811 -415.803517)
			(xy 115.307879 -415.856924) (xy 115.315999 -415.9121) (xy 115.316508 -415.939986) (xy 115.315999 -415.967872)
			(xy 115.307879 -416.023048) (xy 115.291811 -416.076455) (xy 115.268139 -416.126952) (xy 115.237366 -416.173465)
			(xy 115.200149 -416.215002) (xy 115.157281 -416.250677) (xy 115.109675 -416.279731) (xy 115.058346 -416.301543)
			(xy 115.004389 -416.315649) (xy 114.948952 -416.321749) (xy 114.893218 -416.319712) (xy 114.838375 -416.309582)
			(xy 114.785591 -416.291575) (xy 114.735991 -416.266074) (xy 114.690633 -416.233623) (xy 114.650484 -416.194914)
			(xy 114.616398 -416.150771) (xy 114.589102 -416.102136) (xy 114.569179 -416.050045) (xy 114.557053 -415.995608)
			(xy 114.552982 -415.939986) (xy 112.42548 -415.939986) (xy 112.42548 -416.926014) (xy 113.25428 -416.926014)
			(xy 113.258351 -416.870392) (xy 113.270477 -416.815955) (xy 113.2904 -416.763864) (xy 113.317696 -416.715229)
			(xy 113.351782 -416.671086) (xy 113.391931 -416.632377) (xy 113.437289 -416.599926) (xy 113.486889 -416.574425)
			(xy 113.539673 -416.556418) (xy 113.594516 -416.546288) (xy 113.65025 -416.544251) (xy 113.705687 -416.550351)
			(xy 113.759644 -416.564457) (xy 113.810973 -416.586269) (xy 113.858579 -416.615323) (xy 113.901447 -416.650998)
			(xy 113.938664 -416.692535) (xy 113.969437 -416.739048) (xy 113.993109 -416.789545) (xy 114.009177 -416.842952)
			(xy 114.017297 -416.898128) (xy 114.017685 -416.919367) (xy 117.031256 -416.919367) (xy 117.031256 -416.855445)
			(xy 117.039267 -416.792027) (xy 117.055164 -416.730113) (xy 117.078696 -416.67068) (xy 117.10949 -416.614665)
			(xy 117.147063 -416.56295) (xy 117.19082 -416.516353) (xy 117.240073 -416.475608) (xy 117.294044 -416.441357)
			(xy 117.351883 -416.41414) (xy 117.412676 -416.394387) (xy 117.475466 -416.382409) (xy 117.539262 -416.378396)
			(xy 117.603058 -416.382409) (xy 117.665848 -416.394387) (xy 117.726641 -416.41414) (xy 117.78448 -416.441357)
			(xy 117.838451 -416.475608) (xy 117.887704 -416.516353) (xy 117.931461 -416.56295) (xy 117.969034 -416.614665)
			(xy 117.999828 -416.67068) (xy 118.02336 -416.730113) (xy 118.039257 -416.792027) (xy 118.047268 -416.855445)
			(xy 118.04777 -416.887406) (xy 118.047268 -416.919367) (xy 118.039257 -416.982785) (xy 118.035258 -416.998361)
			(xy 155.434786 -416.998361) (xy 155.434786 -416.934439) (xy 155.442797 -416.871021) (xy 155.458694 -416.809107)
			(xy 155.482226 -416.749674) (xy 155.51302 -416.693659) (xy 155.550593 -416.641944) (xy 155.59435 -416.595347)
			(xy 155.643603 -416.554602) (xy 155.697574 -416.520351) (xy 155.755413 -416.493134) (xy 155.816206 -416.473381)
			(xy 155.878996 -416.461403) (xy 155.942792 -416.45739) (xy 156.006588 -416.461403) (xy 156.069378 -416.473381)
			(xy 156.130171 -416.493134) (xy 156.18801 -416.520351) (xy 156.222002 -416.541923) (xy 162.846506 -416.541923)
			(xy 162.846506 -416.478001) (xy 162.854517 -416.414583) (xy 162.870414 -416.352669) (xy 162.893946 -416.293236)
			(xy 162.92474 -416.237221) (xy 162.962313 -416.185506) (xy 163.00607 -416.138909) (xy 163.055323 -416.098164)
			(xy 163.109294 -416.063913) (xy 163.167133 -416.036696) (xy 163.227926 -416.016943) (xy 163.290716 -416.004965)
			(xy 163.354512 -416.000952) (xy 163.418308 -416.004965) (xy 163.481098 -416.016943) (xy 163.541891 -416.036696)
			(xy 163.59973 -416.063913) (xy 163.653701 -416.098164) (xy 163.702954 -416.138909) (xy 163.746711 -416.185506)
			(xy 163.784284 -416.237221) (xy 163.815078 -416.293236) (xy 163.83861 -416.352669) (xy 163.854507 -416.414583)
			(xy 163.862518 -416.478001) (xy 163.86302 -416.509962) (xy 163.862518 -416.541923) (xy 163.854507 -416.605341)
			(xy 163.83861 -416.667255) (xy 163.815078 -416.726688) (xy 163.784284 -416.782703) (xy 163.746711 -416.834418)
			(xy 163.702954 -416.881015) (xy 163.653701 -416.92176) (xy 163.59973 -416.956011) (xy 163.541891 -416.983228)
			(xy 163.481098 -417.002981) (xy 163.418308 -417.014959) (xy 163.354512 -417.018973) (xy 163.290716 -417.014959)
			(xy 163.227926 -417.002981) (xy 163.167133 -416.983228) (xy 163.109294 -416.956011) (xy 163.055323 -416.92176)
			(xy 163.00607 -416.881015) (xy 162.962313 -416.834418) (xy 162.92474 -416.782703) (xy 162.893946 -416.726688)
			(xy 162.870414 -416.667255) (xy 162.854517 -416.605341) (xy 162.846506 -416.541923) (xy 156.222002 -416.541923)
			(xy 156.241981 -416.554602) (xy 156.291234 -416.595347) (xy 156.334991 -416.641944) (xy 156.372564 -416.693659)
			(xy 156.403358 -416.749674) (xy 156.42689 -416.809107) (xy 156.442787 -416.871021) (xy 156.450798 -416.934439)
			(xy 156.4513 -416.9664) (xy 156.450798 -416.998361) (xy 156.442787 -417.061779) (xy 156.42689 -417.123693)
			(xy 156.403358 -417.183126) (xy 156.372564 -417.239141) (xy 156.334991 -417.290856) (xy 156.291234 -417.337453)
			(xy 156.241981 -417.378198) (xy 156.18801 -417.412449) (xy 156.130171 -417.439666) (xy 156.069378 -417.459419)
			(xy 156.006588 -417.471397) (xy 155.942792 -417.475411) (xy 155.878996 -417.471397) (xy 155.816206 -417.459419)
			(xy 155.755413 -417.439666) (xy 155.697574 -417.412449) (xy 155.643603 -417.378198) (xy 155.59435 -417.337453)
			(xy 155.550593 -417.290856) (xy 155.51302 -417.239141) (xy 155.482226 -417.183126) (xy 155.458694 -417.123693)
			(xy 155.442797 -417.061779) (xy 155.434786 -416.998361) (xy 118.035258 -416.998361) (xy 118.02336 -417.044699)
			(xy 117.999828 -417.104132) (xy 117.969034 -417.160147) (xy 117.931461 -417.211862) (xy 117.887704 -417.258459)
			(xy 117.838451 -417.299204) (xy 117.78448 -417.333455) (xy 117.726641 -417.360672) (xy 117.665848 -417.380425)
			(xy 117.603058 -417.392403) (xy 117.539262 -417.396417) (xy 117.475466 -417.392403) (xy 117.412676 -417.380425)
			(xy 117.351883 -417.360672) (xy 117.294044 -417.333455) (xy 117.240073 -417.299204) (xy 117.19082 -417.258459)
			(xy 117.147063 -417.211862) (xy 117.10949 -417.160147) (xy 117.078696 -417.104132) (xy 117.055164 -417.044699)
			(xy 117.039267 -416.982785) (xy 117.031256 -416.919367) (xy 114.017685 -416.919367) (xy 114.017806 -416.926014)
			(xy 114.017297 -416.9539) (xy 114.009177 -417.009076) (xy 113.993109 -417.062483) (xy 113.969437 -417.11298)
			(xy 113.938664 -417.159493) (xy 113.901447 -417.20103) (xy 113.858579 -417.236705) (xy 113.810973 -417.265759)
			(xy 113.759644 -417.287571) (xy 113.705687 -417.301677) (xy 113.65025 -417.307777) (xy 113.594516 -417.30574)
			(xy 113.539673 -417.29561) (xy 113.486889 -417.277603) (xy 113.437289 -417.252102) (xy 113.391931 -417.219651)
			(xy 113.351782 -417.180942) (xy 113.317696 -417.136799) (xy 113.2904 -417.088164) (xy 113.270477 -417.036073)
			(xy 113.258351 -416.981636) (xy 113.25428 -416.926014) (xy 112.42548 -416.926014) (xy 112.42548 -417.919154)
			(xy 118.578882 -417.919154) (xy 118.582953 -417.863532) (xy 118.595079 -417.809095) (xy 118.615002 -417.757004)
			(xy 118.642298 -417.708369) (xy 118.676384 -417.664226) (xy 118.716533 -417.625517) (xy 118.761891 -417.593066)
			(xy 118.811491 -417.567565) (xy 118.864275 -417.549558) (xy 118.919118 -417.539428) (xy 118.974852 -417.537391)
			(xy 119.030289 -417.543491) (xy 119.084246 -417.557597) (xy 119.135575 -417.579409) (xy 119.183181 -417.608463)
			(xy 119.226049 -417.644138) (xy 119.263266 -417.685675) (xy 119.294039 -417.732188) (xy 119.317711 -417.782685)
			(xy 119.333779 -417.836092) (xy 119.341899 -417.891268) (xy 119.342408 -417.919154) (xy 119.341899 -417.94704)
			(xy 119.333779 -418.002216) (xy 119.317711 -418.055623) (xy 119.294039 -418.10612) (xy 119.263266 -418.152633)
			(xy 119.226049 -418.19417) (xy 119.183181 -418.229845) (xy 119.135575 -418.258899) (xy 119.084246 -418.280711)
			(xy 119.030289 -418.294817) (xy 118.974852 -418.300917) (xy 118.919118 -418.29888) (xy 118.864275 -418.28875)
			(xy 118.811491 -418.270743) (xy 118.761891 -418.245242) (xy 118.716533 -418.212791) (xy 118.676384 -418.174082)
			(xy 118.642298 -418.129939) (xy 118.615002 -418.081304) (xy 118.595079 -418.029213) (xy 118.582953 -417.974776)
			(xy 118.578882 -417.919154) (xy 112.42548 -417.919154) (xy 112.42548 -418.99205) (xy 114.959128 -418.99205)
			(xy 114.963199 -418.936428) (xy 114.975325 -418.881991) (xy 114.995248 -418.8299) (xy 115.022544 -418.781265)
			(xy 115.05663 -418.737122) (xy 115.096779 -418.698413) (xy 115.142137 -418.665962) (xy 115.191737 -418.640461)
			(xy 115.244521 -418.622454) (xy 115.299364 -418.612324) (xy 115.355098 -418.610287) (xy 115.410535 -418.616387)
			(xy 115.464492 -418.630493) (xy 115.515821 -418.652305) (xy 115.563427 -418.681359) (xy 115.606295 -418.717034)
			(xy 115.643512 -418.758571) (xy 115.674285 -418.805084) (xy 115.697957 -418.855581) (xy 115.714025 -418.908988)
			(xy 115.722145 -418.964164) (xy 115.722654 -418.99205) (xy 115.722145 -419.019936) (xy 115.714025 -419.075112)
			(xy 115.706537 -419.1) (xy 116.711982 -419.1) (xy 116.716053 -419.044378) (xy 116.728179 -418.989941)
			(xy 116.748102 -418.93785) (xy 116.775398 -418.889215) (xy 116.809484 -418.845072) (xy 116.849633 -418.806363)
			(xy 116.894991 -418.773912) (xy 116.944591 -418.748411) (xy 116.997375 -418.730404) (xy 117.052218 -418.720274)
			(xy 117.107952 -418.718237) (xy 117.163389 -418.724337) (xy 117.217346 -418.738443) (xy 117.268675 -418.760255)
			(xy 117.316281 -418.789309) (xy 117.359149 -418.824984) (xy 117.396366 -418.866521) (xy 117.427139 -418.913034)
			(xy 117.450811 -418.963531) (xy 117.466879 -419.016938) (xy 117.474999 -419.072114) (xy 117.475508 -419.1)
			(xy 117.474999 -419.127886) (xy 117.466879 -419.183062) (xy 117.450811 -419.236469) (xy 117.427139 -419.286966)
			(xy 117.396366 -419.333479) (xy 117.359149 -419.375016) (xy 117.316281 -419.410691) (xy 117.268675 -419.439745)
			(xy 117.217346 -419.461557) (xy 117.163389 -419.475663) (xy 117.107952 -419.481763) (xy 117.052218 -419.479726)
			(xy 116.997375 -419.469596) (xy 116.944591 -419.451589) (xy 116.894991 -419.426088) (xy 116.849633 -419.393637)
			(xy 116.809484 -419.354928) (xy 116.775398 -419.310785) (xy 116.748102 -419.26215) (xy 116.728179 -419.210059)
			(xy 116.716053 -419.155622) (xy 116.711982 -419.1) (xy 115.706537 -419.1) (xy 115.697957 -419.128519)
			(xy 115.674285 -419.179016) (xy 115.643512 -419.225529) (xy 115.606295 -419.267066) (xy 115.563427 -419.302741)
			(xy 115.515821 -419.331795) (xy 115.464492 -419.353607) (xy 115.410535 -419.367713) (xy 115.355098 -419.373813)
			(xy 115.299364 -419.371776) (xy 115.244521 -419.361646) (xy 115.191737 -419.343639) (xy 115.142137 -419.318138)
			(xy 115.096779 -419.285687) (xy 115.05663 -419.246978) (xy 115.022544 -419.202835) (xy 114.995248 -419.1542)
			(xy 114.975325 -419.102109) (xy 114.963199 -419.047672) (xy 114.959128 -418.99205) (xy 112.42548 -418.99205)
			(xy 112.42548 -420.497) (xy 117.092982 -420.497) (xy 117.097053 -420.441378) (xy 117.109179 -420.386941)
			(xy 117.129102 -420.33485) (xy 117.156398 -420.286215) (xy 117.190484 -420.242072) (xy 117.230633 -420.203363)
			(xy 117.275991 -420.170912) (xy 117.325591 -420.145411) (xy 117.378375 -420.127404) (xy 117.433218 -420.117274)
			(xy 117.488952 -420.115237) (xy 117.544389 -420.121337) (xy 117.598346 -420.135443) (xy 117.649675 -420.157255)
			(xy 117.697281 -420.186309) (xy 117.740149 -420.221984) (xy 117.777366 -420.263521) (xy 117.808139 -420.310034)
			(xy 117.831811 -420.360531) (xy 117.847879 -420.413938) (xy 117.855999 -420.469114) (xy 117.856508 -420.497)
			(xy 121.156982 -420.497) (xy 121.161053 -420.441378) (xy 121.173179 -420.386941) (xy 121.193102 -420.33485)
			(xy 121.220398 -420.286215) (xy 121.254484 -420.242072) (xy 121.294633 -420.203363) (xy 121.339991 -420.170912)
			(xy 121.389591 -420.145411) (xy 121.442375 -420.127404) (xy 121.497218 -420.117274) (xy 121.552952 -420.115237)
			(xy 121.608389 -420.121337) (xy 121.662346 -420.135443) (xy 121.713675 -420.157255) (xy 121.761281 -420.186309)
			(xy 121.804149 -420.221984) (xy 121.841366 -420.263521) (xy 121.872139 -420.310034) (xy 121.895811 -420.360531)
			(xy 121.911879 -420.413938) (xy 121.919999 -420.469114) (xy 121.920508 -420.497) (xy 121.919999 -420.524886)
			(xy 121.911879 -420.580062) (xy 121.895811 -420.633469) (xy 121.872139 -420.683966) (xy 121.841366 -420.730479)
			(xy 121.804149 -420.772016) (xy 121.761281 -420.807691) (xy 121.713675 -420.836745) (xy 121.662346 -420.858557)
			(xy 121.608389 -420.872663) (xy 121.552952 -420.878763) (xy 121.497218 -420.876726) (xy 121.442375 -420.866596)
			(xy 121.389591 -420.848589) (xy 121.339991 -420.823088) (xy 121.294633 -420.790637) (xy 121.254484 -420.751928)
			(xy 121.220398 -420.707785) (xy 121.193102 -420.65915) (xy 121.173179 -420.607059) (xy 121.161053 -420.552622)
			(xy 121.156982 -420.497) (xy 117.856508 -420.497) (xy 117.855999 -420.524886) (xy 117.847879 -420.580062)
			(xy 117.831811 -420.633469) (xy 117.808139 -420.683966) (xy 117.777366 -420.730479) (xy 117.740149 -420.772016)
			(xy 117.697281 -420.807691) (xy 117.649675 -420.836745) (xy 117.598346 -420.858557) (xy 117.544389 -420.872663)
			(xy 117.488952 -420.878763) (xy 117.433218 -420.876726) (xy 117.378375 -420.866596) (xy 117.325591 -420.848589)
			(xy 117.275991 -420.823088) (xy 117.230633 -420.790637) (xy 117.190484 -420.751928) (xy 117.156398 -420.707785)
			(xy 117.129102 -420.65915) (xy 117.109179 -420.607059) (xy 117.097053 -420.552622) (xy 117.092982 -420.497)
			(xy 112.42548 -420.497) (xy 112.42548 -421.04056) (xy 112.425913 -421.050626) (xy 112.433641 -421.069216)
			(xy 112.440466 -421.076628) (xy 112.781799 -421.417961) (xy 116.204994 -421.417961) (xy 116.204994 -421.354039)
			(xy 116.213005 -421.290621) (xy 116.228902 -421.228707) (xy 116.252434 -421.169274) (xy 116.283228 -421.113259)
			(xy 116.320801 -421.061544) (xy 116.364558 -421.014947) (xy 116.413811 -420.974202) (xy 116.467782 -420.939951)
			(xy 116.525621 -420.912734) (xy 116.586414 -420.892981) (xy 116.649204 -420.881003) (xy 116.713 -420.87699)
			(xy 116.776796 -420.881003) (xy 116.839586 -420.892981) (xy 116.900379 -420.912734) (xy 116.958218 -420.939951)
			(xy 117.012189 -420.974202) (xy 117.061442 -421.014947) (xy 117.105199 -421.061544) (xy 117.142772 -421.113259)
			(xy 117.173566 -421.169274) (xy 117.197098 -421.228707) (xy 117.212995 -421.290621) (xy 117.213038 -421.290961)
			(xy 122.300994 -421.290961) (xy 122.300994 -421.227039) (xy 122.309005 -421.163621) (xy 122.324902 -421.101707)
			(xy 122.348434 -421.042274) (xy 122.379228 -420.986259) (xy 122.416801 -420.934544) (xy 122.460558 -420.887947)
			(xy 122.509811 -420.847202) (xy 122.563782 -420.812951) (xy 122.621621 -420.785734) (xy 122.682414 -420.765981)
			(xy 122.745204 -420.754003) (xy 122.809 -420.74999) (xy 122.872796 -420.754003) (xy 122.935586 -420.765981)
			(xy 122.996379 -420.785734) (xy 123.054218 -420.812951) (xy 123.108189 -420.847202) (xy 123.157442 -420.887947)
			(xy 123.201199 -420.934544) (xy 123.238772 -420.986259) (xy 123.269566 -421.042274) (xy 123.293098 -421.101707)
			(xy 123.308995 -421.163621) (xy 123.317006 -421.227039) (xy 123.317508 -421.259) (xy 123.317006 -421.290961)
			(xy 123.308995 -421.354379) (xy 123.293098 -421.416293) (xy 123.269566 -421.475726) (xy 123.238772 -421.531741)
			(xy 123.201199 -421.583456) (xy 123.157442 -421.630053) (xy 123.108189 -421.670798) (xy 123.054218 -421.705049)
			(xy 122.996379 -421.732266) (xy 122.935586 -421.752019) (xy 122.872796 -421.763997) (xy 122.809 -421.768011)
			(xy 122.745204 -421.763997) (xy 122.682414 -421.752019) (xy 122.621621 -421.732266) (xy 122.563782 -421.705049)
			(xy 122.509811 -421.670798) (xy 122.460558 -421.630053) (xy 122.416801 -421.583456) (xy 122.379228 -421.531741)
			(xy 122.348434 -421.475726) (xy 122.324902 -421.416293) (xy 122.309005 -421.354379) (xy 122.300994 -421.290961)
			(xy 117.213038 -421.290961) (xy 117.221006 -421.354039) (xy 117.221508 -421.386) (xy 117.221006 -421.417961)
			(xy 117.212995 -421.481379) (xy 117.197098 -421.543293) (xy 117.173566 -421.602726) (xy 117.142772 -421.658741)
			(xy 117.105199 -421.710456) (xy 117.061442 -421.757053) (xy 117.012189 -421.797798) (xy 116.958218 -421.832049)
			(xy 116.900379 -421.859266) (xy 116.839586 -421.879019) (xy 116.776796 -421.890997) (xy 116.713 -421.895011)
			(xy 116.649204 -421.890997) (xy 116.586414 -421.879019) (xy 116.525621 -421.859266) (xy 116.467782 -421.832049)
			(xy 116.413811 -421.797798) (xy 116.364558 -421.757053) (xy 116.320801 -421.710456) (xy 116.283228 -421.658741)
			(xy 116.252434 -421.602726) (xy 116.228902 -421.543293) (xy 116.213005 -421.481379) (xy 116.204994 -421.417961)
			(xy 112.781799 -421.417961) (xy 114.25174 -422.887902) (xy 117.992906 -422.887902) (xy 117.9934 -422.861031)
			(xy 118.000955 -422.807822) (xy 118.015901 -422.7562) (xy 118.037943 -422.707186) (xy 118.066645 -422.661749)
			(xy 118.101438 -422.62079) (xy 118.141634 -422.585118) (xy 118.186438 -422.555439) (xy 118.234964 -422.53234)
			(xy 118.28625 -422.516279) (xy 118.312692 -422.511474) (xy 118.323106 -422.509696) (xy 118.340886 -422.498266)
			(xy 118.393972 -422.419272) (xy 118.397782 -422.398698) (xy 118.395242 -422.388538) (xy 118.389275 -422.360534)
			(xy 118.382907 -422.30363) (xy 118.382542 -422.275) (xy 118.382968 -422.24346) (xy 118.39077 -422.180863)
			(xy 118.406255 -422.119713) (xy 118.429185 -422.060947) (xy 118.459208 -422.005469) (xy 118.495862 -421.95413)
			(xy 118.538584 -421.907719) (xy 118.58672 -421.86695) (xy 118.639528 -421.832447) (xy 118.696199 -421.80474)
			(xy 118.755861 -421.784257) (xy 118.817599 -421.77131) (xy 118.880464 -421.766099) (xy 118.943491 -421.768703)
			(xy 119.005712 -421.779084) (xy 119.066171 -421.797081) (xy 119.123939 -421.822417) (xy 119.178131 -421.854705)
			(xy 119.227912 -421.893448) (xy 119.272519 -421.938051) (xy 119.311267 -421.987828) (xy 119.34356 -422.042016)
			(xy 119.368902 -422.099782) (xy 119.386905 -422.16024) (xy 119.397292 -422.222459) (xy 119.399902 -422.285486)
			(xy 119.398124 -422.306961) (xy 119.760994 -422.306961) (xy 119.760994 -422.243039) (xy 119.769005 -422.179621)
			(xy 119.784902 -422.117707) (xy 119.808434 -422.058274) (xy 119.839228 -422.002259) (xy 119.876801 -421.950544)
			(xy 119.920558 -421.903947) (xy 119.969811 -421.863202) (xy 120.023782 -421.828951) (xy 120.081621 -421.801734)
			(xy 120.142414 -421.781981) (xy 120.205204 -421.770003) (xy 120.269 -421.76599) (xy 120.332796 -421.770003)
			(xy 120.395586 -421.781981) (xy 120.456379 -421.801734) (xy 120.514218 -421.828951) (xy 120.568189 -421.863202)
			(xy 120.617442 -421.903947) (xy 120.661199 -421.950544) (xy 120.698772 -422.002259) (xy 120.729566 -422.058274)
			(xy 120.753098 -422.117707) (xy 120.768995 -422.179621) (xy 120.777006 -422.243039) (xy 120.777508 -422.275)
			(xy 120.777006 -422.306961) (xy 120.768995 -422.370379) (xy 120.753098 -422.432293) (xy 120.729566 -422.491726)
			(xy 120.698772 -422.547741) (xy 120.661199 -422.599456) (xy 120.617442 -422.646053) (xy 120.568189 -422.686798)
			(xy 120.514218 -422.721049) (xy 120.456379 -422.748266) (xy 120.395586 -422.768019) (xy 120.332796 -422.779997)
			(xy 120.269 -422.784011) (xy 120.205204 -422.779997) (xy 120.142414 -422.768019) (xy 120.081621 -422.748266)
			(xy 120.023782 -422.721049) (xy 119.969811 -422.686798) (xy 119.920558 -422.646053) (xy 119.876801 -422.599456)
			(xy 119.839228 -422.547741) (xy 119.808434 -422.491726) (xy 119.784902 -422.432293) (xy 119.769005 -422.370379)
			(xy 119.760994 -422.306961) (xy 119.398124 -422.306961) (xy 119.394698 -422.348352) (xy 119.381757 -422.410091)
			(xy 119.361279 -422.469755) (xy 119.333578 -422.526428) (xy 119.29908 -422.57924) (xy 119.258315 -422.627379)
			(xy 119.211909 -422.670107) (xy 119.160574 -422.706766) (xy 119.105098 -422.736794) (xy 119.046335 -422.75973)
			(xy 118.985186 -422.775221) (xy 118.92259 -422.783029) (xy 118.89105 -422.783508) (xy 118.86311 -422.782746)
			(xy 118.852442 -422.782238) (xy 118.832884 -422.78935) (xy 118.76405 -422.855136) (xy 118.755922 -422.87444)
			(xy 118.755922 -422.887902) (xy 118.755436 -422.915153) (xy 118.74768 -422.969101) (xy 118.732325 -423.021396)
			(xy 118.709683 -423.070973) (xy 118.680217 -423.116823) (xy 118.644526 -423.158014) (xy 118.603335 -423.193705)
			(xy 118.557485 -423.223171) (xy 118.507908 -423.245813) (xy 118.455613 -423.261168) (xy 118.401665 -423.268924)
			(xy 118.347163 -423.268924) (xy 118.293215 -423.261168) (xy 118.24092 -423.245813) (xy 118.191343 -423.223171)
			(xy 118.145493 -423.193705) (xy 118.104302 -423.158014) (xy 118.068611 -423.116823) (xy 118.039145 -423.070973)
			(xy 118.016503 -423.021396) (xy 118.001148 -422.969101) (xy 117.993392 -422.915153) (xy 117.992906 -422.887902)
			(xy 114.25174 -422.887902) (xy 114.686799 -423.322961) (xy 121.284994 -423.322961) (xy 121.284994 -423.259039)
			(xy 121.293005 -423.195621) (xy 121.308902 -423.133707) (xy 121.332434 -423.074274) (xy 121.363228 -423.018259)
			(xy 121.400801 -422.966544) (xy 121.444558 -422.919947) (xy 121.493811 -422.879202) (xy 121.547782 -422.844951)
			(xy 121.605621 -422.817734) (xy 121.666414 -422.797981) (xy 121.729204 -422.786003) (xy 121.793 -422.78199)
			(xy 121.856796 -422.786003) (xy 121.919586 -422.797981) (xy 121.980379 -422.817734) (xy 122.038218 -422.844951)
			(xy 122.092189 -422.879202) (xy 122.141442 -422.919947) (xy 122.185199 -422.966544) (xy 122.222772 -423.018259)
			(xy 122.253566 -423.074274) (xy 122.277098 -423.133707) (xy 122.292995 -423.195621) (xy 122.301006 -423.259039)
			(xy 122.301508 -423.291) (xy 122.301006 -423.322961) (xy 122.292995 -423.386379) (xy 122.277098 -423.448293)
			(xy 122.253566 -423.507726) (xy 122.222772 -423.563741) (xy 122.185199 -423.615456) (xy 122.141442 -423.662053)
			(xy 122.092189 -423.702798) (xy 122.038218 -423.737049) (xy 121.980379 -423.764266) (xy 121.919586 -423.784019)
			(xy 121.856796 -423.795997) (xy 121.793 -423.800011) (xy 121.729204 -423.795997) (xy 121.666414 -423.784019)
			(xy 121.605621 -423.764266) (xy 121.547782 -423.737049) (xy 121.493811 -423.702798) (xy 121.444558 -423.662053)
			(xy 121.400801 -423.615456) (xy 121.363228 -423.563741) (xy 121.332434 -423.507726) (xy 121.308902 -423.448293)
			(xy 121.293005 -423.386379) (xy 121.284994 -423.322961) (xy 114.686799 -423.322961) (xy 116.036852 -424.673014)
			(xy 116.043702 -424.680411) (xy 116.051439 -424.699009) (xy 116.051838 -424.709082) (xy 116.051838 -425.21505)
			(xy 119.124982 -425.21505) (xy 119.129053 -425.159428) (xy 119.141179 -425.104991) (xy 119.161102 -425.0529)
			(xy 119.188398 -425.004265) (xy 119.222484 -424.960122) (xy 119.262633 -424.921413) (xy 119.307991 -424.888962)
			(xy 119.357591 -424.863461) (xy 119.410375 -424.845454) (xy 119.465218 -424.835324) (xy 119.520952 -424.833287)
			(xy 119.576389 -424.839387) (xy 119.630346 -424.853493) (xy 119.681675 -424.875305) (xy 119.729281 -424.904359)
			(xy 119.772149 -424.940034) (xy 119.809366 -424.981571) (xy 119.840139 -425.028084) (xy 119.863811 -425.078581)
			(xy 119.879879 -425.131988) (xy 119.887999 -425.187164) (xy 119.888508 -425.21505) (xy 119.887999 -425.242936)
			(xy 119.879879 -425.298112) (xy 119.863811 -425.351519) (xy 119.840139 -425.402016) (xy 119.809366 -425.448529)
			(xy 119.772149 -425.490066) (xy 119.729281 -425.525741) (xy 119.681675 -425.554795) (xy 119.630346 -425.576607)
			(xy 119.576389 -425.590713) (xy 119.520952 -425.596813) (xy 119.465218 -425.594776) (xy 119.410375 -425.584646)
			(xy 119.357591 -425.566639) (xy 119.307991 -425.541138) (xy 119.262633 -425.508687) (xy 119.222484 -425.469978)
			(xy 119.188398 -425.425835) (xy 119.161102 -425.3772) (xy 119.141179 -425.325109) (xy 119.129053 -425.270672)
			(xy 119.124982 -425.21505) (xy 116.051838 -425.21505) (xy 116.051838 -426.72) (xy 120.521982 -426.72)
			(xy 120.526053 -426.664378) (xy 120.538179 -426.609941) (xy 120.558102 -426.55785) (xy 120.585398 -426.509215)
			(xy 120.619484 -426.465072) (xy 120.659633 -426.426363) (xy 120.704991 -426.393912) (xy 120.754591 -426.368411)
			(xy 120.807375 -426.350404) (xy 120.862218 -426.340274) (xy 120.917952 -426.338237) (xy 120.973389 -426.344337)
			(xy 121.027346 -426.358443) (xy 121.078675 -426.380255) (xy 121.126281 -426.409309) (xy 121.169149 -426.444984)
			(xy 121.206366 -426.486521) (xy 121.237139 -426.533034) (xy 121.260811 -426.583531) (xy 121.276879 -426.636938)
			(xy 121.284999 -426.692114) (xy 121.285508 -426.72) (xy 121.284999 -426.747886) (xy 121.276879 -426.803062)
			(xy 121.260811 -426.856469) (xy 121.237139 -426.906966) (xy 121.206366 -426.953479) (xy 121.169149 -426.995016)
			(xy 121.126281 -427.030691) (xy 121.078675 -427.059745) (xy 121.027346 -427.081557) (xy 120.973389 -427.095663)
			(xy 120.917952 -427.101763) (xy 120.862218 -427.099726) (xy 120.807375 -427.089596) (xy 120.754591 -427.071589)
			(xy 120.704991 -427.046088) (xy 120.659633 -427.013637) (xy 120.619484 -426.974928) (xy 120.585398 -426.930785)
			(xy 120.558102 -426.88215) (xy 120.538179 -426.830059) (xy 120.526053 -426.775622) (xy 120.521982 -426.72)
			(xy 116.051838 -426.72) (xy 116.051838 -429.006) (xy 119.076468 -429.006) (xy 119.080539 -428.950378)
			(xy 119.092665 -428.895941) (xy 119.112588 -428.84385) (xy 119.139884 -428.795215) (xy 119.17397 -428.751072)
			(xy 119.214119 -428.712363) (xy 119.259477 -428.679912) (xy 119.309077 -428.654411) (xy 119.361861 -428.636404)
			(xy 119.416704 -428.626274) (xy 119.472438 -428.624237) (xy 119.527875 -428.630337) (xy 119.581832 -428.644443)
			(xy 119.633161 -428.666255) (xy 119.680767 -428.695309) (xy 119.723635 -428.730984) (xy 119.760852 -428.772521)
			(xy 119.791625 -428.819034) (xy 119.815297 -428.869531) (xy 119.831365 -428.922938) (xy 119.839485 -428.978114)
			(xy 119.839994 -429.006) (xy 119.839485 -429.033886) (xy 119.831365 -429.089062) (xy 119.815297 -429.142469)
			(xy 119.791625 -429.192966) (xy 119.760852 -429.239479) (xy 119.723635 -429.281016) (xy 119.680767 -429.316691)
			(xy 119.633161 -429.345745) (xy 119.581832 -429.367557) (xy 119.527875 -429.381663) (xy 119.472438 -429.387763)
			(xy 119.416704 -429.385726) (xy 119.361861 -429.375596) (xy 119.309077 -429.357589) (xy 119.259477 -429.332088)
			(xy 119.214119 -429.299637) (xy 119.17397 -429.260928) (xy 119.139884 -429.216785) (xy 119.112588 -429.16815)
			(xy 119.092665 -429.116059) (xy 119.080539 -429.061622) (xy 119.076468 -429.006) (xy 116.051838 -429.006)
			(xy 116.051838 -432.054) (xy 117.092982 -432.054) (xy 117.097053 -431.998378) (xy 117.109179 -431.943941)
			(xy 117.129102 -431.89185) (xy 117.156398 -431.843215) (xy 117.190484 -431.799072) (xy 117.230633 -431.760363)
			(xy 117.275991 -431.727912) (xy 117.325591 -431.702411) (xy 117.378375 -431.684404) (xy 117.433218 -431.674274)
			(xy 117.488952 -431.672237) (xy 117.544389 -431.678337) (xy 117.598346 -431.692443) (xy 117.649675 -431.714255)
			(xy 117.697281 -431.743309) (xy 117.740149 -431.778984) (xy 117.777366 -431.820521) (xy 117.808139 -431.867034)
			(xy 117.831811 -431.917531) (xy 117.847879 -431.970938) (xy 117.855999 -432.026114) (xy 117.856508 -432.054)
			(xy 121.156982 -432.054) (xy 121.161053 -431.998378) (xy 121.173179 -431.943941) (xy 121.193102 -431.89185)
			(xy 121.220398 -431.843215) (xy 121.254484 -431.799072) (xy 121.294633 -431.760363) (xy 121.339991 -431.727912)
			(xy 121.389591 -431.702411) (xy 121.442375 -431.684404) (xy 121.497218 -431.674274) (xy 121.552952 -431.672237)
			(xy 121.608389 -431.678337) (xy 121.662346 -431.692443) (xy 121.713675 -431.714255) (xy 121.761281 -431.743309)
			(xy 121.804149 -431.778984) (xy 121.841366 -431.820521) (xy 121.872139 -431.867034) (xy 121.895811 -431.917531)
			(xy 121.911879 -431.970938) (xy 121.919999 -432.026114) (xy 121.920508 -432.054) (xy 121.919999 -432.081886)
			(xy 121.911879 -432.137062) (xy 121.895811 -432.190469) (xy 121.872139 -432.240966) (xy 121.841366 -432.287479)
			(xy 121.804149 -432.329016) (xy 121.761281 -432.364691) (xy 121.713675 -432.393745) (xy 121.662346 -432.415557)
			(xy 121.608389 -432.429663) (xy 121.552952 -432.435763) (xy 121.497218 -432.433726) (xy 121.442375 -432.423596)
			(xy 121.389591 -432.405589) (xy 121.339991 -432.380088) (xy 121.294633 -432.347637) (xy 121.254484 -432.308928)
			(xy 121.220398 -432.264785) (xy 121.193102 -432.21615) (xy 121.173179 -432.164059) (xy 121.161053 -432.109622)
			(xy 121.156982 -432.054) (xy 117.856508 -432.054) (xy 117.855999 -432.081886) (xy 117.847879 -432.137062)
			(xy 117.831811 -432.190469) (xy 117.808139 -432.240966) (xy 117.777366 -432.287479) (xy 117.740149 -432.329016)
			(xy 117.697281 -432.364691) (xy 117.649675 -432.393745) (xy 117.598346 -432.415557) (xy 117.544389 -432.429663)
			(xy 117.488952 -432.435763) (xy 117.433218 -432.433726) (xy 117.378375 -432.423596) (xy 117.325591 -432.405589)
			(xy 117.275991 -432.380088) (xy 117.230633 -432.347637) (xy 117.190484 -432.308928) (xy 117.156398 -432.264785)
			(xy 117.129102 -432.21615) (xy 117.109179 -432.164059) (xy 117.097053 -432.109622) (xy 117.092982 -432.054)
			(xy 116.051838 -432.054) (xy 116.051838 -432.847961) (xy 118.510044 -432.847961) (xy 118.510044 -432.784039)
			(xy 118.518055 -432.720621) (xy 118.533952 -432.658707) (xy 118.557484 -432.599274) (xy 118.588278 -432.543259)
			(xy 118.625851 -432.491544) (xy 118.669608 -432.444947) (xy 118.718861 -432.404202) (xy 118.772832 -432.369951)
			(xy 118.830671 -432.342734) (xy 118.891464 -432.322981) (xy 118.954254 -432.311003) (xy 119.01805 -432.30699)
			(xy 119.081846 -432.311003) (xy 119.144636 -432.322981) (xy 119.205429 -432.342734) (xy 119.263268 -432.369951)
			(xy 119.317239 -432.404202) (xy 119.366492 -432.444947) (xy 119.410249 -432.491544) (xy 119.447822 -432.543259)
			(xy 119.478616 -432.599274) (xy 119.502148 -432.658707) (xy 119.518045 -432.720621) (xy 119.526056 -432.784039)
			(xy 119.526558 -432.816) (xy 119.526056 -432.847961) (xy 119.887994 -432.847961) (xy 119.887994 -432.784039)
			(xy 119.896005 -432.720621) (xy 119.911902 -432.658707) (xy 119.935434 -432.599274) (xy 119.966228 -432.543259)
			(xy 120.003801 -432.491544) (xy 120.047558 -432.444947) (xy 120.096811 -432.404202) (xy 120.150782 -432.369951)
			(xy 120.208621 -432.342734) (xy 120.269414 -432.322981) (xy 120.332204 -432.311003) (xy 120.396 -432.30699)
			(xy 120.459796 -432.311003) (xy 120.522586 -432.322981) (xy 120.583379 -432.342734) (xy 120.641218 -432.369951)
			(xy 120.695189 -432.404202) (xy 120.744442 -432.444947) (xy 120.788199 -432.491544) (xy 120.825772 -432.543259)
			(xy 120.856566 -432.599274) (xy 120.880098 -432.658707) (xy 120.895995 -432.720621) (xy 120.904006 -432.784039)
			(xy 120.904508 -432.816) (xy 120.904006 -432.847961) (xy 120.895995 -432.911379) (xy 120.880098 -432.973293)
			(xy 120.856566 -433.032726) (xy 120.825772 -433.088741) (xy 120.788199 -433.140456) (xy 120.744442 -433.187053)
			(xy 120.695189 -433.227798) (xy 120.641218 -433.262049) (xy 120.583379 -433.289266) (xy 120.522586 -433.309019)
			(xy 120.459796 -433.320997) (xy 120.396 -433.325011) (xy 120.332204 -433.320997) (xy 120.269414 -433.309019)
			(xy 120.208621 -433.289266) (xy 120.150782 -433.262049) (xy 120.096811 -433.227798) (xy 120.047558 -433.187053)
			(xy 120.003801 -433.140456) (xy 119.966228 -433.088741) (xy 119.935434 -433.032726) (xy 119.911902 -432.973293)
			(xy 119.896005 -432.911379) (xy 119.887994 -432.847961) (xy 119.526056 -432.847961) (xy 119.518045 -432.911379)
			(xy 119.502148 -432.973293) (xy 119.478616 -433.032726) (xy 119.447822 -433.088741) (xy 119.410249 -433.140456)
			(xy 119.366492 -433.187053) (xy 119.317239 -433.227798) (xy 119.263268 -433.262049) (xy 119.205429 -433.289266)
			(xy 119.144636 -433.309019) (xy 119.081846 -433.320997) (xy 119.01805 -433.325011) (xy 118.954254 -433.320997)
			(xy 118.891464 -433.309019) (xy 118.830671 -433.289266) (xy 118.772832 -433.262049) (xy 118.718861 -433.227798)
			(xy 118.669608 -433.187053) (xy 118.625851 -433.140456) (xy 118.588278 -433.088741) (xy 118.557484 -433.032726)
			(xy 118.533952 -432.973293) (xy 118.518055 -432.911379) (xy 118.510044 -432.847961) (xy 116.051838 -432.847961)
			(xy 116.051838 -433.959) (xy 118.616982 -433.959) (xy 118.621053 -433.903378) (xy 118.633179 -433.848941)
			(xy 118.653102 -433.79685) (xy 118.680398 -433.748215) (xy 118.714484 -433.704072) (xy 118.754633 -433.665363)
			(xy 118.799991 -433.632912) (xy 118.849591 -433.607411) (xy 118.902375 -433.589404) (xy 118.957218 -433.579274)
			(xy 119.012952 -433.577237) (xy 119.068389 -433.583337) (xy 119.122346 -433.597443) (xy 119.173675 -433.619255)
			(xy 119.221281 -433.648309) (xy 119.264149 -433.683984) (xy 119.301366 -433.725521) (xy 119.332139 -433.772034)
			(xy 119.355811 -433.822531) (xy 119.371879 -433.875938) (xy 119.379999 -433.931114) (xy 119.380508 -433.959)
			(xy 119.379999 -433.986886) (xy 119.371879 -434.042062) (xy 119.355811 -434.095469) (xy 119.332139 -434.145966)
			(xy 119.301366 -434.192479) (xy 119.264149 -434.234016) (xy 119.221281 -434.269691) (xy 119.173675 -434.298745)
			(xy 119.122346 -434.320557) (xy 119.068389 -434.334663) (xy 119.012952 -434.340763) (xy 118.957218 -434.338726)
			(xy 118.902375 -434.328596) (xy 118.849591 -434.310589) (xy 118.799991 -434.285088) (xy 118.754633 -434.252637)
			(xy 118.714484 -434.213928) (xy 118.680398 -434.169785) (xy 118.653102 -434.12115) (xy 118.633179 -434.069059)
			(xy 118.621053 -434.014622) (xy 118.616982 -433.959) (xy 116.051838 -433.959) (xy 116.051838 -435.483)
			(xy 121.156982 -435.483) (xy 121.161053 -435.427378) (xy 121.173179 -435.372941) (xy 121.193102 -435.32085)
			(xy 121.220398 -435.272215) (xy 121.254484 -435.228072) (xy 121.294633 -435.189363) (xy 121.339991 -435.156912)
			(xy 121.389591 -435.131411) (xy 121.442375 -435.113404) (xy 121.497218 -435.103274) (xy 121.552952 -435.101237)
			(xy 121.608389 -435.107337) (xy 121.662346 -435.121443) (xy 121.713675 -435.143255) (xy 121.761281 -435.172309)
			(xy 121.804149 -435.207984) (xy 121.841366 -435.249521) (xy 121.872139 -435.296034) (xy 121.895811 -435.346531)
			(xy 121.911879 -435.399938) (xy 121.919999 -435.455114) (xy 121.920508 -435.483) (xy 121.919999 -435.510886)
			(xy 121.911879 -435.566062) (xy 121.895811 -435.619469) (xy 121.872139 -435.669966) (xy 121.841366 -435.716479)
			(xy 121.804149 -435.758016) (xy 121.761281 -435.793691) (xy 121.713675 -435.822745) (xy 121.662346 -435.844557)
			(xy 121.608389 -435.858663) (xy 121.552952 -435.864763) (xy 121.497218 -435.862726) (xy 121.442375 -435.852596)
			(xy 121.389591 -435.834589) (xy 121.339991 -435.809088) (xy 121.294633 -435.776637) (xy 121.254484 -435.737928)
			(xy 121.220398 -435.693785) (xy 121.193102 -435.64515) (xy 121.173179 -435.593059) (xy 121.161053 -435.538622)
			(xy 121.156982 -435.483) (xy 116.051838 -435.483) (xy 116.051838 -438.128447) (xy 118.34271 -438.128447)
			(xy 118.34271 -438.073953) (xy 118.350465 -438.020013) (xy 118.365817 -437.967725) (xy 118.388454 -437.918155)
			(xy 118.417914 -437.87231) (xy 118.453599 -437.831124) (xy 118.494781 -437.795436) (xy 118.540623 -437.765971)
			(xy 118.590192 -437.74333) (xy 118.642478 -437.727973) (xy 118.696417 -437.720213) (xy 118.723664 -437.719724)
			(xy 118.751821 -437.720264) (xy 118.80752 -437.728557) (xy 118.861393 -437.744954) (xy 118.912269 -437.769096)
			(xy 118.95904 -437.80046) (xy 118.980204 -437.819038) (xy 118.987316 -437.825388) (xy 119.005096 -437.832246)
			(xy 119.092218 -437.832246) (xy 119.109998 -437.825388) (xy 119.11711 -437.819038) (xy 119.138299 -437.80049)
			(xy 119.18507 -437.769133) (xy 119.235939 -437.744987) (xy 119.289804 -437.728575) (xy 119.345496 -437.720252)
			(xy 119.37365 -437.719724) (xy 119.400907 -437.72012) (xy 119.454868 -437.727871) (xy 119.507177 -437.743224)
			(xy 119.556767 -437.765866) (xy 119.602631 -437.795335) (xy 119.643833 -437.831032) (xy 119.679535 -437.872229)
			(xy 119.70901 -437.918089) (xy 119.731658 -437.967676) (xy 119.747018 -438.019983) (xy 119.754777 -438.073943)
			(xy 119.754777 -438.128457) (xy 119.747018 -438.182417) (xy 119.731658 -438.234724) (xy 119.70901 -438.284311)
			(xy 119.679535 -438.330171) (xy 119.643833 -438.371368) (xy 119.602631 -438.407065) (xy 119.556767 -438.436534)
			(xy 119.507177 -438.459176) (xy 119.454868 -438.474529) (xy 119.400908 -438.48228) (xy 119.37365 -438.48274)
			(xy 119.345491 -438.48226) (xy 119.289789 -438.473954) (xy 119.235914 -438.457544) (xy 119.185039 -438.433388)
			(xy 119.138272 -438.40201) (xy 119.11711 -438.383426) (xy 119.109998 -438.377076) (xy 119.092218 -438.370218)
			(xy 119.005096 -438.370218) (xy 118.987316 -438.377076) (xy 118.980204 -438.383426) (xy 118.959044 -438.402008)
			(xy 118.912266 -438.433361) (xy 118.861389 -438.457502) (xy 118.807517 -438.473906) (xy 118.75182 -438.482217)
			(xy 118.723664 -438.48274) (xy 118.696417 -438.482187) (xy 118.642478 -438.474427) (xy 118.590192 -438.45907)
			(xy 118.540623 -438.436429) (xy 118.494781 -438.406964) (xy 118.453599 -438.371276) (xy 118.417914 -438.33009)
			(xy 118.388454 -438.284245) (xy 118.365817 -438.234675) (xy 118.350465 -438.182387) (xy 118.34271 -438.128447)
			(xy 116.051838 -438.128447) (xy 116.051838 -438.543954) (xy 116.052272 -438.554019) (xy 116.060004 -438.572606)
			(xy 116.066824 -438.580022) (xy 117.065659 -439.578857) (xy 117.661327 -439.578857) (xy 117.661327 -439.524343)
			(xy 117.669086 -439.470385) (xy 117.684444 -439.418081) (xy 117.707091 -439.368495) (xy 117.736565 -439.322636)
			(xy 117.772265 -439.28144) (xy 117.813465 -439.245743) (xy 117.859326 -439.216274) (xy 117.908915 -439.193632)
			(xy 117.961221 -439.178278) (xy 118.015179 -439.170524) (xy 118.042436 -439.170064) (xy 118.070661 -439.170618)
			(xy 118.126495 -439.178935) (xy 118.180496 -439.195384) (xy 118.231487 -439.219604) (xy 118.278355 -439.251068)
			(xy 118.320079 -439.289091) (xy 118.35575 -439.332842) (xy 118.38459 -439.38137) (xy 118.39575 -439.4073)
			(xy 118.401489 -439.420274) (xy 118.419011 -439.442576) (xy 118.441996 -439.459192) (xy 118.468666 -439.468839)
			(xy 118.496962 -439.470772) (xy 118.524696 -439.464841) (xy 118.549727 -439.451505) (xy 118.570119 -439.431794)
			(xy 118.577614 -439.419746) (xy 118.594732 -439.391182) (xy 118.635281 -439.338359) (xy 118.682376 -439.291278)
			(xy 118.735212 -439.250745) (xy 118.792885 -439.217453) (xy 118.854409 -439.191971) (xy 118.918732 -439.174735)
			(xy 118.984754 -439.166039) (xy 119.01805 -439.165492) (xy 119.050014 -439.16597) (xy 119.11344 -439.173977)
			(xy 119.175361 -439.18987) (xy 119.234802 -439.213399) (xy 119.290826 -439.244193) (xy 119.342547 -439.281767)
			(xy 119.389152 -439.325526) (xy 119.429903 -439.374783) (xy 119.46416 -439.428758) (xy 119.491381 -439.486602)
			(xy 119.511137 -439.547401) (xy 119.523117 -439.610197) (xy 119.527132 -439.674) (xy 119.523117 -439.737803)
			(xy 119.511137 -439.800599) (xy 119.491381 -439.861398) (xy 119.46416 -439.919242) (xy 119.429903 -439.973217)
			(xy 119.389152 -440.022474) (xy 119.342547 -440.066233) (xy 119.290826 -440.103807) (xy 119.234802 -440.134601)
			(xy 119.175361 -440.15813) (xy 119.11344 -440.174023) (xy 119.050014 -440.18203) (xy 119.01805 -440.182508)
			(xy 118.985074 -440.181988) (xy 118.919677 -440.173444) (xy 118.855933 -440.156519) (xy 118.794912 -440.131496)
			(xy 118.737637 -440.098795) (xy 118.68507 -440.058966) (xy 118.638092 -440.012675) (xy 118.597491 -439.960701)
			(xy 118.563949 -439.903915) (xy 118.538028 -439.84327) (xy 118.528592 -439.811668) (xy 118.524249 -439.798136)
			(xy 118.50937 -439.773944) (xy 118.488401 -439.754787) (xy 118.462966 -439.742149) (xy 118.435033 -439.737007)
			(xy 118.406765 -439.739761) (xy 118.380349 -439.750196) (xy 118.357831 -439.767506) (xy 118.349014 -439.778648)
			(xy 118.330883 -439.802162) (xy 118.288577 -439.84382) (xy 118.240328 -439.878423) (xy 118.187302 -439.905134)
			(xy 118.130779 -439.92331) (xy 118.072123 -439.932512) (xy 118.042436 -439.93308) (xy 118.015179 -439.932676)
			(xy 117.961221 -439.924922) (xy 117.908915 -439.909568) (xy 117.859326 -439.886926) (xy 117.813465 -439.857457)
			(xy 117.772265 -439.82176) (xy 117.736565 -439.780564) (xy 117.707091 -439.734705) (xy 117.684444 -439.685119)
			(xy 117.669086 -439.632815) (xy 117.661327 -439.578857) (xy 117.065659 -439.578857) (xy 117.409214 -439.922412)
			(xy 117.430042 -439.930032) (xy 117.441472 -439.929016) (xy 117.475 -439.927492) (xy 117.502251 -439.927978)
			(xy 117.556199 -439.935734) (xy 117.608494 -439.951089) (xy 117.658071 -439.973731) (xy 117.703921 -440.003197)
			(xy 117.745112 -440.038888) (xy 117.780803 -440.080079) (xy 117.810269 -440.125929) (xy 117.832911 -440.175506)
			(xy 117.848266 -440.227801) (xy 117.856022 -440.281749) (xy 117.856508 -440.309) (xy 117.854984 -440.342528)
			(xy 117.853968 -440.353958) (xy 117.861588 -440.374786) (xy 118.192042 -440.70524) (xy 118.199456 -440.711913)
			(xy 118.217891 -440.719474) (xy 118.227856 -440.719972)
		)
		(stroke
			(width 0)
			(type solid)
		)
		(fill yes)
		(layer "In4.Cu")
		(net "P3V3_AUX")
	)
	(gr_poly
		(pts
			(xy 456.414886 -440.514994) (xy 456.425075 -440.514032) (xy 456.443485 -440.505137) (xy 456.456962 -440.489759)
			(xy 456.460606 -440.480196) (xy 456.461876 -440.475878) (xy 456.488546 -440.362086) (xy 456.47356 -440.330336)
			(xy 456.457558 -440.322462) (xy 456.367369 -440.277191) (xy 456.190128 -440.180657) (xy 456.016712 -440.07741)
			(xy 455.847376 -439.967599) (xy 455.682367 -439.851387) (xy 455.521928 -439.728944) (xy 455.366293 -439.600449)
			(xy 455.215692 -439.46609) (xy 455.070344 -439.326065) (xy 454.930463 -439.180578) (xy 454.796253 -439.029843)
			(xy 454.667912 -438.874082) (xy 454.545628 -438.713521) (xy 454.429579 -438.548398) (xy 454.319937 -438.378953)
			(xy 454.216861 -438.205435) (xy 454.120503 -438.028098) (xy 454.031004 -437.847203) (xy 453.948495 -437.663014)
			(xy 453.873098 -437.475802) (xy 453.804922 -437.285841) (xy 453.744068 -437.09341) (xy 453.690625 -436.89879)
			(xy 453.644671 -436.702267) (xy 453.606274 -436.504128) (xy 453.575489 -436.304666) (xy 453.552363 -436.10417)
			(xy 453.536928 -435.902937) (xy 453.529208 -435.70126) (xy 453.528684 -435.600348) (xy 453.529191 -435.496851)
			(xy 453.537316 -435.290017) (xy 453.553554 -435.083661) (xy 453.577881 -434.878102) (xy 453.610259 -434.673657)
			(xy 453.650639 -434.47064) (xy 453.698957 -434.269365) (xy 453.75514 -434.070142) (xy 453.819102 -433.873278)
			(xy 453.890742 -433.679077) (xy 453.969951 -433.487838) (xy 454.056608 -433.299857) (xy 454.150577 -433.115422)
			(xy 454.251714 -432.934819) (xy 454.359864 -432.758325) (xy 454.474859 -432.586213) (xy 454.596523 -432.418749)
			(xy 454.724667 -432.25619) (xy 454.859094 -432.098787) (xy 454.999597 -431.946783) (xy 455.14596 -431.800412)
			(xy 455.297955 -431.6599) (xy 455.45535 -431.525464) (xy 455.617902 -431.39731) (xy 455.785359 -431.275637)
			(xy 455.957464 -431.160631) (xy 456.133951 -431.052471) (xy 456.314549 -430.951323) (xy 456.498978 -430.857343)
			(xy 456.686954 -430.770676) (xy 456.878188 -430.691455) (xy 457.072385 -430.619803) (xy 457.269245 -430.55583)
			(xy 457.468465 -430.499636) (xy 457.669737 -430.451305) (xy 457.872751 -430.410914) (xy 458.077195 -430.378523)
			(xy 458.282753 -430.354184) (xy 458.489108 -430.337934) (xy 458.695941 -430.329797) (xy 458.799438 -430.32934)
			(xy 458.8002 -430.32934) (xy 458.90319 -430.329838) (xy 459.109014 -430.337885) (xy 459.314366 -430.353967)
			(xy 459.518933 -430.378059) (xy 459.722402 -430.410125) (xy 459.924464 -430.450115) (xy 460.124809 -430.497969)
			(xy 460.323132 -430.553613) (xy 460.519129 -430.616962) (xy 460.712502 -430.68792) (xy 460.902955 -430.766378)
			(xy 461.090197 -430.852217) (xy 461.273943 -430.945306) (xy 461.453912 -431.045502) (xy 461.629829 -431.152652)
			(xy 461.801426 -431.266593) (xy 461.968441 -431.387151) (xy 462.130618 -431.514142) (xy 462.28771 -431.647371)
			(xy 462.439478 -431.786636) (xy 462.585689 -431.931724) (xy 462.72612 -432.082413) (xy 462.860557 -432.238473)
			(xy 462.988794 -432.399666) (xy 463.110636 -432.565746) (xy 463.225897 -432.73646) (xy 463.334401 -432.911546)
			(xy 463.435981 -433.090737) (xy 463.530484 -433.273759) (xy 463.617764 -433.460334) (xy 463.697689 -433.650177)
			(xy 463.734404 -433.746402) (xy 463.741008 -433.763928) (xy 463.772758 -433.781962) (xy 463.889344 -433.760626)
			(xy 463.897997 -433.75867) (xy 463.913312 -433.749744) (xy 463.92466 -433.736126) (xy 463.930675 -433.719452)
			(xy 463.931 -433.710588) (xy 463.931 -408.086052) (xy 463.931432 -408.075986) (xy 463.939159 -408.057394)
			(xy 463.945986 -408.049984) (xy 466.986874 -405.009096) (xy 466.993723 -405.001698) (xy 467.00146 -404.9831)
			(xy 467.00186 -404.973028) (xy 467.00186 -376.167396) (xy 467.001435 -376.157327) (xy 466.993715 -376.138727)
			(xy 466.986874 -376.131328) (xy 466.29828 -375.442734) (xy 466.291168 -375.435368) (xy 466.272372 -375.427748)
			(xy 442.440822 -375.427748) (xy 442.430834 -375.428283) (xy 442.412401 -375.435996) (xy 442.405008 -375.442734)
			(xy 439.481468 -378.366274) (xy 439.474819 -378.37363) (xy 439.467234 -378.391931) (xy 439.466736 -378.401834)
			(xy 439.466736 -383.388882) (xy 441.915547 -383.388882) (xy 441.919279 -383.335628) (xy 441.930398 -383.283415)
			(xy 441.948686 -383.233261) (xy 441.973787 -383.186146) (xy 442.005209 -383.14299) (xy 442.042341 -383.104634)
			(xy 442.063124 -383.08788) (xy 442.071895 -383.080327) (xy 442.082072 -383.059561) (xy 442.082682 -383.048002)
			(xy 442.082682 -382.967738) (xy 442.082096 -382.956172) (xy 442.071913 -382.9354) (xy 442.063124 -382.92786)
			(xy 442.042313 -382.911141) (xy 442.005185 -382.872782) (xy 441.973767 -382.829623) (xy 441.948671 -382.782505)
			(xy 441.930388 -382.73235) (xy 441.919274 -382.680135) (xy 441.915547 -382.626882) (xy 441.919279 -382.573628)
			(xy 441.930398 -382.521415) (xy 441.948686 -382.471261) (xy 441.973787 -382.424146) (xy 442.005209 -382.38099)
			(xy 442.042341 -382.342634) (xy 442.063124 -382.32588) (xy 442.071895 -382.318327) (xy 442.082072 -382.297561)
			(xy 442.082682 -382.286002) (xy 442.082682 -382.205738) (xy 442.082096 -382.194172) (xy 442.071913 -382.1734)
			(xy 442.063124 -382.16586) (xy 442.040626 -382.147685) (xy 442.000891 -382.105663) (xy 441.967953 -382.058125)
			(xy 441.942567 -382.00616) (xy 441.925314 -381.950959) (xy 441.91659 -381.893787) (xy 441.916058 -381.86487)
			(xy 441.916544 -381.837619) (xy 441.9243 -381.783671) (xy 441.939655 -381.731376) (xy 441.962297 -381.681799)
			(xy 441.991763 -381.635949) (xy 442.027454 -381.594758) (xy 442.068645 -381.559067) (xy 442.114495 -381.529601)
			(xy 442.164072 -381.506959) (xy 442.216367 -381.491604) (xy 442.270315 -381.483848) (xy 442.324817 -381.483848)
			(xy 442.378765 -381.491604) (xy 442.43106 -381.506959) (xy 442.480637 -381.529601) (xy 442.526487 -381.559067)
			(xy 442.567678 -381.594758) (xy 442.603369 -381.635949) (xy 442.632835 -381.681799) (xy 442.655477 -381.731376)
			(xy 442.670832 -381.783671) (xy 442.678588 -381.837619) (xy 442.679074 -381.86487) (xy 442.678544 -381.893787)
			(xy 442.669819 -381.950958) (xy 442.652564 -382.006157) (xy 442.627174 -382.058119) (xy 442.594232 -382.105653)
			(xy 442.554493 -382.14767) (xy 442.532008 -382.16586) (xy 442.52327 -382.173445) (xy 442.513073 -382.194186)
			(xy 442.51245 -382.205738) (xy 442.51245 -382.286002) (xy 442.513002 -382.297573) (xy 442.523208 -382.318345)
			(xy 442.532008 -382.32588) (xy 442.552763 -382.342668) (xy 442.589896 -382.381016) (xy 442.62132 -382.424166)
			(xy 442.646422 -382.471275) (xy 442.664711 -382.521424) (xy 442.675831 -382.573632) (xy 442.679563 -382.626882)
			(xy 442.675836 -382.680131) (xy 442.664721 -382.732341) (xy 442.646437 -382.782491) (xy 442.621339 -382.829603)
			(xy 442.589919 -382.872756) (xy 442.55279 -382.911107) (xy 442.532008 -382.92786) (xy 442.52327 -382.935445)
			(xy 442.513073 -382.956186) (xy 442.51245 -382.967738) (xy 442.51245 -383.048002) (xy 442.513002 -383.059573)
			(xy 442.523208 -383.080345) (xy 442.532008 -383.08788) (xy 442.552763 -383.104668) (xy 442.589896 -383.143016)
			(xy 442.62132 -383.186166) (xy 442.646422 -383.233275) (xy 442.664711 -383.283424) (xy 442.675831 -383.335632)
			(xy 442.679563 -383.388882) (xy 445.725547 -383.388882) (xy 445.729279 -383.335628) (xy 445.740398 -383.283415)
			(xy 445.758686 -383.233261) (xy 445.783787 -383.186146) (xy 445.815209 -383.14299) (xy 445.852341 -383.104634)
			(xy 445.873124 -383.08788) (xy 445.881895 -383.080327) (xy 445.892072 -383.059561) (xy 445.892682 -383.048002)
			(xy 445.892682 -382.967738) (xy 445.892096 -382.956172) (xy 445.881913 -382.9354) (xy 445.873124 -382.92786)
			(xy 445.852313 -382.911141) (xy 445.815185 -382.872782) (xy 445.783767 -382.829623) (xy 445.758671 -382.782505)
			(xy 445.740388 -382.73235) (xy 445.729274 -382.680135) (xy 445.725547 -382.626882) (xy 445.729279 -382.573628)
			(xy 445.740398 -382.521415) (xy 445.758686 -382.471261) (xy 445.783787 -382.424146) (xy 445.815209 -382.38099)
			(xy 445.852341 -382.342634) (xy 445.873124 -382.32588) (xy 445.881895 -382.318327) (xy 445.892072 -382.297561)
			(xy 445.892682 -382.286002) (xy 445.892682 -382.205738) (xy 445.892096 -382.194172) (xy 445.881913 -382.1734)
			(xy 445.873124 -382.16586) (xy 445.850626 -382.147685) (xy 445.810891 -382.105663) (xy 445.777953 -382.058125)
			(xy 445.752567 -382.00616) (xy 445.735314 -381.950959) (xy 445.72659 -381.893787) (xy 445.726058 -381.86487)
			(xy 445.726544 -381.837619) (xy 445.7343 -381.783671) (xy 445.749655 -381.731376) (xy 445.772297 -381.681799)
			(xy 445.801763 -381.635949) (xy 445.837454 -381.594758) (xy 445.878645 -381.559067) (xy 445.924495 -381.529601)
			(xy 445.974072 -381.506959) (xy 446.026367 -381.491604) (xy 446.080315 -381.483848) (xy 446.134817 -381.483848)
			(xy 446.188765 -381.491604) (xy 446.24106 -381.506959) (xy 446.290637 -381.529601) (xy 446.336487 -381.559067)
			(xy 446.377678 -381.594758) (xy 446.413369 -381.635949) (xy 446.442835 -381.681799) (xy 446.465477 -381.731376)
			(xy 446.480832 -381.783671) (xy 446.488588 -381.837619) (xy 446.489074 -381.86487) (xy 446.488544 -381.893787)
			(xy 446.479819 -381.950958) (xy 446.462564 -382.006157) (xy 446.437174 -382.058119) (xy 446.404232 -382.105653)
			(xy 446.364493 -382.14767) (xy 446.342008 -382.16586) (xy 446.33327 -382.173445) (xy 446.323073 -382.194186)
			(xy 446.32245 -382.205738) (xy 446.32245 -382.286002) (xy 446.323002 -382.297573) (xy 446.333208 -382.318345)
			(xy 446.342008 -382.32588) (xy 446.362763 -382.342668) (xy 446.399896 -382.381016) (xy 446.43132 -382.424166)
			(xy 446.456422 -382.471275) (xy 446.474711 -382.521424) (xy 446.485831 -382.573632) (xy 446.489563 -382.626882)
			(xy 446.485836 -382.680131) (xy 446.474721 -382.732341) (xy 446.456437 -382.782491) (xy 446.431339 -382.829603)
			(xy 446.399919 -382.872756) (xy 446.36279 -382.911107) (xy 446.342008 -382.92786) (xy 446.33327 -382.935445)
			(xy 446.323073 -382.956186) (xy 446.32245 -382.967738) (xy 446.32245 -383.048002) (xy 446.323002 -383.059573)
			(xy 446.333208 -383.080345) (xy 446.342008 -383.08788) (xy 446.362763 -383.104668) (xy 446.399896 -383.143016)
			(xy 446.43132 -383.186166) (xy 446.456422 -383.233275) (xy 446.474711 -383.283424) (xy 446.485831 -383.335632)
			(xy 446.489563 -383.388882) (xy 447.681347 -383.388882) (xy 447.685079 -383.335628) (xy 447.696198 -383.283415)
			(xy 447.714486 -383.233261) (xy 447.739587 -383.186146) (xy 447.771009 -383.14299) (xy 447.808141 -383.104634)
			(xy 447.828924 -383.08788) (xy 447.837695 -383.080327) (xy 447.847872 -383.059561) (xy 447.848482 -383.048002)
			(xy 447.848482 -382.967738) (xy 447.847896 -382.956172) (xy 447.837713 -382.9354) (xy 447.828924 -382.92786)
			(xy 447.808113 -382.911141) (xy 447.770985 -382.872782) (xy 447.739567 -382.829623) (xy 447.714471 -382.782505)
			(xy 447.696188 -382.73235) (xy 447.685074 -382.680135) (xy 447.681347 -382.626882) (xy 447.685079 -382.573628)
			(xy 447.696198 -382.521415) (xy 447.714486 -382.471261) (xy 447.739587 -382.424146) (xy 447.771009 -382.38099)
			(xy 447.808141 -382.342634) (xy 447.828924 -382.32588) (xy 447.837695 -382.318327) (xy 447.847872 -382.297561)
			(xy 447.848482 -382.286002) (xy 447.848482 -382.205738) (xy 447.847896 -382.194172) (xy 447.837713 -382.1734)
			(xy 447.828924 -382.16586) (xy 447.806426 -382.147685) (xy 447.766691 -382.105663) (xy 447.733753 -382.058125)
			(xy 447.708367 -382.00616) (xy 447.691114 -381.950959) (xy 447.68239 -381.893787) (xy 447.681858 -381.86487)
			(xy 447.682344 -381.837619) (xy 447.6901 -381.783671) (xy 447.705455 -381.731376) (xy 447.728097 -381.681799)
			(xy 447.757563 -381.635949) (xy 447.793254 -381.594758) (xy 447.834445 -381.559067) (xy 447.880295 -381.529601)
			(xy 447.929872 -381.506959) (xy 447.982167 -381.491604) (xy 448.036115 -381.483848) (xy 448.090617 -381.483848)
			(xy 448.144565 -381.491604) (xy 448.19686 -381.506959) (xy 448.246437 -381.529601) (xy 448.292287 -381.559067)
			(xy 448.333478 -381.594758) (xy 448.369169 -381.635949) (xy 448.398635 -381.681799) (xy 448.421277 -381.731376)
			(xy 448.436632 -381.783671) (xy 448.444388 -381.837619) (xy 448.444874 -381.86487) (xy 448.444344 -381.893787)
			(xy 448.435619 -381.950958) (xy 448.418364 -382.006157) (xy 448.392974 -382.058119) (xy 448.360032 -382.105653)
			(xy 448.320293 -382.14767) (xy 448.297808 -382.16586) (xy 448.28907 -382.173445) (xy 448.278873 -382.194186)
			(xy 448.27825 -382.205738) (xy 448.27825 -382.286002) (xy 448.278802 -382.297573) (xy 448.289008 -382.318345)
			(xy 448.297808 -382.32588) (xy 448.318563 -382.342668) (xy 448.355696 -382.381016) (xy 448.38712 -382.424166)
			(xy 448.412222 -382.471275) (xy 448.430511 -382.521424) (xy 448.441631 -382.573632) (xy 448.445363 -382.626882)
			(xy 448.441636 -382.680131) (xy 448.430521 -382.732341) (xy 448.412237 -382.782491) (xy 448.387139 -382.829603)
			(xy 448.355719 -382.872756) (xy 448.31859 -382.911107) (xy 448.297808 -382.92786) (xy 448.28907 -382.935445)
			(xy 448.278873 -382.956186) (xy 448.27825 -382.967738) (xy 448.27825 -383.048002) (xy 448.278802 -383.059573)
			(xy 448.289008 -383.080345) (xy 448.297808 -383.08788) (xy 448.318563 -383.104668) (xy 448.355696 -383.143016)
			(xy 448.38712 -383.186166) (xy 448.412222 -383.233275) (xy 448.430511 -383.283424) (xy 448.441631 -383.335632)
			(xy 448.445363 -383.388882) (xy 451.491347 -383.388882) (xy 451.495079 -383.335628) (xy 451.506198 -383.283415)
			(xy 451.524486 -383.233261) (xy 451.549587 -383.186146) (xy 451.581009 -383.14299) (xy 451.618141 -383.104634)
			(xy 451.638924 -383.08788) (xy 451.647695 -383.080327) (xy 451.657872 -383.059561) (xy 451.658482 -383.048002)
			(xy 451.658482 -382.967738) (xy 451.657896 -382.956172) (xy 451.647713 -382.9354) (xy 451.638924 -382.92786)
			(xy 451.618113 -382.911141) (xy 451.580985 -382.872782) (xy 451.549567 -382.829623) (xy 451.524471 -382.782505)
			(xy 451.506188 -382.73235) (xy 451.495074 -382.680135) (xy 451.491347 -382.626882) (xy 451.495079 -382.573628)
			(xy 451.506198 -382.521415) (xy 451.524486 -382.471261) (xy 451.549587 -382.424146) (xy 451.581009 -382.38099)
			(xy 451.618141 -382.342634) (xy 451.638924 -382.32588) (xy 451.647695 -382.318327) (xy 451.657872 -382.297561)
			(xy 451.658482 -382.286002) (xy 451.658482 -382.205738) (xy 451.657896 -382.194172) (xy 451.647713 -382.1734)
			(xy 451.638924 -382.16586) (xy 451.616426 -382.147685) (xy 451.576691 -382.105663) (xy 451.543753 -382.058125)
			(xy 451.518367 -382.00616) (xy 451.501114 -381.950959) (xy 451.49239 -381.893787) (xy 451.491858 -381.86487)
			(xy 451.492344 -381.837619) (xy 451.5001 -381.783671) (xy 451.515455 -381.731376) (xy 451.538097 -381.681799)
			(xy 451.567563 -381.635949) (xy 451.603254 -381.594758) (xy 451.644445 -381.559067) (xy 451.690295 -381.529601)
			(xy 451.739872 -381.506959) (xy 451.792167 -381.491604) (xy 451.846115 -381.483848) (xy 451.900617 -381.483848)
			(xy 451.954565 -381.491604) (xy 452.00686 -381.506959) (xy 452.056437 -381.529601) (xy 452.102287 -381.559067)
			(xy 452.143478 -381.594758) (xy 452.179169 -381.635949) (xy 452.208635 -381.681799) (xy 452.231277 -381.731376)
			(xy 452.246632 -381.783671) (xy 452.254388 -381.837619) (xy 452.254874 -381.86487) (xy 452.254344 -381.893787)
			(xy 452.245619 -381.950958) (xy 452.228364 -382.006157) (xy 452.202974 -382.058119) (xy 452.170032 -382.105653)
			(xy 452.130293 -382.14767) (xy 452.107808 -382.16586) (xy 452.09907 -382.173445) (xy 452.088873 -382.194186)
			(xy 452.08825 -382.205738) (xy 452.08825 -382.286002) (xy 452.088802 -382.297573) (xy 452.099008 -382.318345)
			(xy 452.107808 -382.32588) (xy 452.128563 -382.342668) (xy 452.165696 -382.381016) (xy 452.19712 -382.424166)
			(xy 452.222222 -382.471275) (xy 452.240511 -382.521424) (xy 452.251631 -382.573632) (xy 452.255363 -382.626882)
			(xy 452.251636 -382.680131) (xy 452.240521 -382.732341) (xy 452.222237 -382.782491) (xy 452.197139 -382.829603)
			(xy 452.165719 -382.872756) (xy 452.12859 -382.911107) (xy 452.107808 -382.92786) (xy 452.09907 -382.935445)
			(xy 452.088873 -382.956186) (xy 452.08825 -382.967738) (xy 452.08825 -383.048002) (xy 452.088802 -383.059573)
			(xy 452.099008 -383.080345) (xy 452.107808 -383.08788) (xy 452.128563 -383.104668) (xy 452.165696 -383.143016)
			(xy 452.19712 -383.186166) (xy 452.222222 -383.233275) (xy 452.240511 -383.283424) (xy 452.251631 -383.335632)
			(xy 452.255363 -383.388882) (xy 453.777347 -383.388882) (xy 453.781079 -383.335628) (xy 453.792198 -383.283415)
			(xy 453.810486 -383.233261) (xy 453.835587 -383.186146) (xy 453.867009 -383.14299) (xy 453.904141 -383.104634)
			(xy 453.924924 -383.08788) (xy 453.933695 -383.080327) (xy 453.943872 -383.059561) (xy 453.944482 -383.048002)
			(xy 453.944482 -382.967738) (xy 453.943896 -382.956172) (xy 453.933713 -382.9354) (xy 453.924924 -382.92786)
			(xy 453.904113 -382.911141) (xy 453.866985 -382.872782) (xy 453.835567 -382.829623) (xy 453.810471 -382.782505)
			(xy 453.792188 -382.73235) (xy 453.781074 -382.680135) (xy 453.777347 -382.626882) (xy 453.781079 -382.573628)
			(xy 453.792198 -382.521415) (xy 453.810486 -382.471261) (xy 453.835587 -382.424146) (xy 453.867009 -382.38099)
			(xy 453.904141 -382.342634) (xy 453.924924 -382.32588) (xy 453.933695 -382.318327) (xy 453.943872 -382.297561)
			(xy 453.944482 -382.286002) (xy 453.944482 -382.205738) (xy 453.943896 -382.194172) (xy 453.933713 -382.1734)
			(xy 453.924924 -382.16586) (xy 453.902426 -382.147685) (xy 453.862691 -382.105663) (xy 453.829753 -382.058125)
			(xy 453.804367 -382.00616) (xy 453.787114 -381.950959) (xy 453.77839 -381.893787) (xy 453.777858 -381.86487)
			(xy 453.778344 -381.837619) (xy 453.7861 -381.783671) (xy 453.801455 -381.731376) (xy 453.824097 -381.681799)
			(xy 453.853563 -381.635949) (xy 453.889254 -381.594758) (xy 453.930445 -381.559067) (xy 453.976295 -381.529601)
			(xy 454.025872 -381.506959) (xy 454.078167 -381.491604) (xy 454.132115 -381.483848) (xy 454.186617 -381.483848)
			(xy 454.240565 -381.491604) (xy 454.29286 -381.506959) (xy 454.342437 -381.529601) (xy 454.388287 -381.559067)
			(xy 454.429478 -381.594758) (xy 454.465169 -381.635949) (xy 454.494635 -381.681799) (xy 454.517277 -381.731376)
			(xy 454.532632 -381.783671) (xy 454.540388 -381.837619) (xy 454.540874 -381.86487) (xy 454.540344 -381.893787)
			(xy 454.531619 -381.950958) (xy 454.514364 -382.006157) (xy 454.488974 -382.058119) (xy 454.456032 -382.105653)
			(xy 454.416293 -382.14767) (xy 454.393808 -382.16586) (xy 454.38507 -382.173445) (xy 454.374873 -382.194186)
			(xy 454.37425 -382.205738) (xy 454.37425 -382.286002) (xy 454.374802 -382.297573) (xy 454.385008 -382.318345)
			(xy 454.393808 -382.32588) (xy 454.414563 -382.342668) (xy 454.451696 -382.381016) (xy 454.48312 -382.424166)
			(xy 454.508222 -382.471275) (xy 454.526511 -382.521424) (xy 454.537631 -382.573632) (xy 454.541363 -382.626882)
			(xy 454.537636 -382.680131) (xy 454.526521 -382.732341) (xy 454.508237 -382.782491) (xy 454.483139 -382.829603)
			(xy 454.451719 -382.872756) (xy 454.41459 -382.911107) (xy 454.393808 -382.92786) (xy 454.38507 -382.935445)
			(xy 454.374873 -382.956186) (xy 454.37425 -382.967738) (xy 454.37425 -383.048002) (xy 454.374802 -383.059573)
			(xy 454.385008 -383.080345) (xy 454.393808 -383.08788) (xy 454.414563 -383.104668) (xy 454.451696 -383.143016)
			(xy 454.48312 -383.186166) (xy 454.508222 -383.233275) (xy 454.526511 -383.283424) (xy 454.537631 -383.335632)
			(xy 454.541363 -383.388882) (xy 457.587347 -383.388882) (xy 457.591079 -383.335628) (xy 457.602198 -383.283415)
			(xy 457.620486 -383.233261) (xy 457.645587 -383.186146) (xy 457.677009 -383.14299) (xy 457.714141 -383.104634)
			(xy 457.734924 -383.08788) (xy 457.743695 -383.080327) (xy 457.753872 -383.059561) (xy 457.754482 -383.048002)
			(xy 457.754482 -382.967738) (xy 457.753896 -382.956172) (xy 457.743713 -382.9354) (xy 457.734924 -382.92786)
			(xy 457.714113 -382.911141) (xy 457.676985 -382.872782) (xy 457.645567 -382.829623) (xy 457.620471 -382.782505)
			(xy 457.602188 -382.73235) (xy 457.591074 -382.680135) (xy 457.587347 -382.626882) (xy 457.591079 -382.573628)
			(xy 457.602198 -382.521415) (xy 457.620486 -382.471261) (xy 457.645587 -382.424146) (xy 457.677009 -382.38099)
			(xy 457.714141 -382.342634) (xy 457.734924 -382.32588) (xy 457.743695 -382.318327) (xy 457.753872 -382.297561)
			(xy 457.754482 -382.286002) (xy 457.754482 -382.205738) (xy 457.753896 -382.194172) (xy 457.743713 -382.1734)
			(xy 457.734924 -382.16586) (xy 457.712426 -382.147685) (xy 457.672691 -382.105663) (xy 457.639753 -382.058125)
			(xy 457.614367 -382.00616) (xy 457.597114 -381.950959) (xy 457.58839 -381.893787) (xy 457.587858 -381.86487)
			(xy 457.588344 -381.837619) (xy 457.5961 -381.783671) (xy 457.611455 -381.731376) (xy 457.634097 -381.681799)
			(xy 457.663563 -381.635949) (xy 457.699254 -381.594758) (xy 457.740445 -381.559067) (xy 457.786295 -381.529601)
			(xy 457.835872 -381.506959) (xy 457.888167 -381.491604) (xy 457.942115 -381.483848) (xy 457.996617 -381.483848)
			(xy 458.050565 -381.491604) (xy 458.10286 -381.506959) (xy 458.152437 -381.529601) (xy 458.198287 -381.559067)
			(xy 458.239478 -381.594758) (xy 458.275169 -381.635949) (xy 458.304635 -381.681799) (xy 458.327277 -381.731376)
			(xy 458.342632 -381.783671) (xy 458.350388 -381.837619) (xy 458.350874 -381.86487) (xy 458.350344 -381.893787)
			(xy 458.341619 -381.950958) (xy 458.324364 -382.006157) (xy 458.298974 -382.058119) (xy 458.266032 -382.105653)
			(xy 458.226293 -382.14767) (xy 458.203808 -382.16586) (xy 458.19507 -382.173445) (xy 458.184873 -382.194186)
			(xy 458.18425 -382.205738) (xy 458.18425 -382.286002) (xy 458.184802 -382.297573) (xy 458.195008 -382.318345)
			(xy 458.203808 -382.32588) (xy 458.224563 -382.342668) (xy 458.261696 -382.381016) (xy 458.29312 -382.424166)
			(xy 458.318222 -382.471275) (xy 458.336511 -382.521424) (xy 458.347631 -382.573632) (xy 458.351363 -382.626882)
			(xy 458.347636 -382.680131) (xy 458.336521 -382.732341) (xy 458.318237 -382.782491) (xy 458.293139 -382.829603)
			(xy 458.261719 -382.872756) (xy 458.22459 -382.911107) (xy 458.203808 -382.92786) (xy 458.19507 -382.935445)
			(xy 458.184873 -382.956186) (xy 458.18425 -382.967738) (xy 458.18425 -383.048002) (xy 458.184802 -383.059573)
			(xy 458.195008 -383.080345) (xy 458.203808 -383.08788) (xy 458.224563 -383.104668) (xy 458.261696 -383.143016)
			(xy 458.29312 -383.186166) (xy 458.318222 -383.233275) (xy 458.336511 -383.283424) (xy 458.347631 -383.335632)
			(xy 458.351363 -383.388882) (xy 459.873347 -383.388882) (xy 459.877079 -383.335628) (xy 459.888198 -383.283415)
			(xy 459.906486 -383.233261) (xy 459.931587 -383.186146) (xy 459.963009 -383.14299) (xy 460.000141 -383.104634)
			(xy 460.020924 -383.08788) (xy 460.029695 -383.080327) (xy 460.039872 -383.059561) (xy 460.040482 -383.048002)
			(xy 460.040482 -382.967738) (xy 460.039896 -382.956172) (xy 460.029713 -382.9354) (xy 460.020924 -382.92786)
			(xy 460.000113 -382.911141) (xy 459.962985 -382.872782) (xy 459.931567 -382.829623) (xy 459.906471 -382.782505)
			(xy 459.888188 -382.73235) (xy 459.877074 -382.680135) (xy 459.873347 -382.626882) (xy 459.877079 -382.573628)
			(xy 459.888198 -382.521415) (xy 459.906486 -382.471261) (xy 459.931587 -382.424146) (xy 459.963009 -382.38099)
			(xy 460.000141 -382.342634) (xy 460.020924 -382.32588) (xy 460.029695 -382.318327) (xy 460.039872 -382.297561)
			(xy 460.040482 -382.286002) (xy 460.040482 -382.205738) (xy 460.039896 -382.194172) (xy 460.029713 -382.1734)
			(xy 460.020924 -382.16586) (xy 459.998426 -382.147685) (xy 459.958691 -382.105663) (xy 459.925753 -382.058125)
			(xy 459.900367 -382.00616) (xy 459.883114 -381.950959) (xy 459.87439 -381.893787) (xy 459.873858 -381.86487)
			(xy 459.874344 -381.837619) (xy 459.8821 -381.783671) (xy 459.897455 -381.731376) (xy 459.920097 -381.681799)
			(xy 459.949563 -381.635949) (xy 459.985254 -381.594758) (xy 460.026445 -381.559067) (xy 460.072295 -381.529601)
			(xy 460.121872 -381.506959) (xy 460.174167 -381.491604) (xy 460.228115 -381.483848) (xy 460.282617 -381.483848)
			(xy 460.336565 -381.491604) (xy 460.38886 -381.506959) (xy 460.438437 -381.529601) (xy 460.484287 -381.559067)
			(xy 460.525478 -381.594758) (xy 460.561169 -381.635949) (xy 460.590635 -381.681799) (xy 460.613277 -381.731376)
			(xy 460.628632 -381.783671) (xy 460.636388 -381.837619) (xy 460.636874 -381.86487) (xy 460.636344 -381.893787)
			(xy 460.627619 -381.950958) (xy 460.610364 -382.006157) (xy 460.584974 -382.058119) (xy 460.552032 -382.105653)
			(xy 460.512293 -382.14767) (xy 460.489808 -382.16586) (xy 460.48107 -382.173445) (xy 460.470873 -382.194186)
			(xy 460.47025 -382.205738) (xy 460.47025 -382.286002) (xy 460.470802 -382.297573) (xy 460.481008 -382.318345)
			(xy 460.489808 -382.32588) (xy 460.510563 -382.342668) (xy 460.547696 -382.381016) (xy 460.57912 -382.424166)
			(xy 460.604222 -382.471275) (xy 460.622511 -382.521424) (xy 460.633631 -382.573632) (xy 460.637363 -382.626882)
			(xy 460.633636 -382.680131) (xy 460.622521 -382.732341) (xy 460.604237 -382.782491) (xy 460.579139 -382.829603)
			(xy 460.547719 -382.872756) (xy 460.51059 -382.911107) (xy 460.489808 -382.92786) (xy 460.48107 -382.935445)
			(xy 460.470873 -382.956186) (xy 460.47025 -382.967738) (xy 460.47025 -383.048002) (xy 460.470802 -383.059573)
			(xy 460.481008 -383.080345) (xy 460.489808 -383.08788) (xy 460.510563 -383.104668) (xy 460.547696 -383.143016)
			(xy 460.57912 -383.186166) (xy 460.604222 -383.233275) (xy 460.622511 -383.283424) (xy 460.633631 -383.335632)
			(xy 460.637363 -383.388882) (xy 463.683347 -383.388882) (xy 463.687079 -383.335628) (xy 463.698198 -383.283415)
			(xy 463.716486 -383.233261) (xy 463.741587 -383.186146) (xy 463.773009 -383.14299) (xy 463.810141 -383.104634)
			(xy 463.830924 -383.08788) (xy 463.839695 -383.080327) (xy 463.849872 -383.059561) (xy 463.850482 -383.048002)
			(xy 463.850482 -382.967738) (xy 463.849896 -382.956172) (xy 463.839713 -382.9354) (xy 463.830924 -382.92786)
			(xy 463.810113 -382.911141) (xy 463.772985 -382.872782) (xy 463.741567 -382.829623) (xy 463.716471 -382.782505)
			(xy 463.698188 -382.73235) (xy 463.687074 -382.680135) (xy 463.683347 -382.626882) (xy 463.687079 -382.573628)
			(xy 463.698198 -382.521415) (xy 463.716486 -382.471261) (xy 463.741587 -382.424146) (xy 463.773009 -382.38099)
			(xy 463.810141 -382.342634) (xy 463.830924 -382.32588) (xy 463.839695 -382.318327) (xy 463.849872 -382.297561)
			(xy 463.850482 -382.286002) (xy 463.850482 -382.205738) (xy 463.849896 -382.194172) (xy 463.839713 -382.1734)
			(xy 463.830924 -382.16586) (xy 463.808426 -382.147685) (xy 463.768691 -382.105663) (xy 463.735753 -382.058125)
			(xy 463.710367 -382.00616) (xy 463.693114 -381.950959) (xy 463.68439 -381.893787) (xy 463.683858 -381.86487)
			(xy 463.684344 -381.837619) (xy 463.6921 -381.783671) (xy 463.707455 -381.731376) (xy 463.730097 -381.681799)
			(xy 463.759563 -381.635949) (xy 463.795254 -381.594758) (xy 463.836445 -381.559067) (xy 463.882295 -381.529601)
			(xy 463.931872 -381.506959) (xy 463.984167 -381.491604) (xy 464.038115 -381.483848) (xy 464.092617 -381.483848)
			(xy 464.146565 -381.491604) (xy 464.19886 -381.506959) (xy 464.248437 -381.529601) (xy 464.294287 -381.559067)
			(xy 464.335478 -381.594758) (xy 464.371169 -381.635949) (xy 464.400635 -381.681799) (xy 464.423277 -381.731376)
			(xy 464.438632 -381.783671) (xy 464.446388 -381.837619) (xy 464.446874 -381.86487) (xy 464.446344 -381.893787)
			(xy 464.437619 -381.950958) (xy 464.420364 -382.006157) (xy 464.394974 -382.058119) (xy 464.362032 -382.105653)
			(xy 464.322293 -382.14767) (xy 464.299808 -382.16586) (xy 464.29107 -382.173445) (xy 464.280873 -382.194186)
			(xy 464.28025 -382.205738) (xy 464.28025 -382.286002) (xy 464.280802 -382.297573) (xy 464.291008 -382.318345)
			(xy 464.299808 -382.32588) (xy 464.320563 -382.342668) (xy 464.357696 -382.381016) (xy 464.38912 -382.424166)
			(xy 464.414222 -382.471275) (xy 464.432511 -382.521424) (xy 464.443631 -382.573632) (xy 464.447363 -382.626882)
			(xy 464.443636 -382.680131) (xy 464.432521 -382.732341) (xy 464.414237 -382.782491) (xy 464.389139 -382.829603)
			(xy 464.357719 -382.872756) (xy 464.32059 -382.911107) (xy 464.299808 -382.92786) (xy 464.29107 -382.935445)
			(xy 464.280873 -382.956186) (xy 464.28025 -382.967738) (xy 464.28025 -383.048002) (xy 464.280802 -383.059573)
			(xy 464.291008 -383.080345) (xy 464.299808 -383.08788) (xy 464.320563 -383.104668) (xy 464.357696 -383.143016)
			(xy 464.38912 -383.186166) (xy 464.414222 -383.233275) (xy 464.432511 -383.283424) (xy 464.443631 -383.335632)
			(xy 464.447363 -383.388882) (xy 464.443636 -383.442131) (xy 464.432521 -383.494341) (xy 464.414237 -383.544491)
			(xy 464.389139 -383.591603) (xy 464.357719 -383.634756) (xy 464.32059 -383.673107) (xy 464.299808 -383.68986)
			(xy 464.29107 -383.697445) (xy 464.280873 -383.718186) (xy 464.28025 -383.729738) (xy 464.28025 -383.810002)
			(xy 464.280802 -383.821573) (xy 464.291008 -383.842345) (xy 464.299808 -383.84988) (xy 464.322284 -383.86808)
			(xy 464.362019 -383.910098) (xy 464.394959 -383.957631) (xy 464.420348 -384.009591) (xy 464.437606 -384.064787)
			(xy 464.446338 -384.121955) (xy 464.446874 -384.15087) (xy 464.446388 -384.178121) (xy 464.438632 -384.232069)
			(xy 464.423277 -384.284364) (xy 464.400635 -384.333941) (xy 464.371169 -384.379791) (xy 464.335478 -384.420982)
			(xy 464.294287 -384.456673) (xy 464.248437 -384.486139) (xy 464.19886 -384.508781) (xy 464.146565 -384.524136)
			(xy 464.092617 -384.531892) (xy 464.038115 -384.531892) (xy 463.984167 -384.524136) (xy 463.931872 -384.508781)
			(xy 463.882295 -384.486139) (xy 463.836445 -384.456673) (xy 463.795254 -384.420982) (xy 463.759563 -384.379791)
			(xy 463.730097 -384.333941) (xy 463.707455 -384.284364) (xy 463.6921 -384.232069) (xy 463.684344 -384.178121)
			(xy 463.683858 -384.15087) (xy 463.684405 -384.121954) (xy 463.693125 -384.064783) (xy 463.710376 -384.009584)
			(xy 463.735762 -383.957622) (xy 463.768702 -383.910087) (xy 463.80844 -383.86807) (xy 463.830924 -383.84988)
			(xy 463.839695 -383.842327) (xy 463.849872 -383.821561) (xy 463.850482 -383.810002) (xy 463.850482 -383.729738)
			(xy 463.849896 -383.718172) (xy 463.839713 -383.6974) (xy 463.830924 -383.68986) (xy 463.810113 -383.673141)
			(xy 463.772985 -383.634782) (xy 463.741567 -383.591623) (xy 463.716471 -383.544505) (xy 463.698188 -383.49435)
			(xy 463.687074 -383.442135) (xy 463.683347 -383.388882) (xy 460.637363 -383.388882) (xy 460.633636 -383.442131)
			(xy 460.622521 -383.494341) (xy 460.604237 -383.544491) (xy 460.579139 -383.591603) (xy 460.547719 -383.634756)
			(xy 460.51059 -383.673107) (xy 460.489808 -383.68986) (xy 460.48107 -383.697445) (xy 460.470873 -383.718186)
			(xy 460.47025 -383.729738) (xy 460.47025 -383.810002) (xy 460.470802 -383.821573) (xy 460.481008 -383.842345)
			(xy 460.489808 -383.84988) (xy 460.512284 -383.86808) (xy 460.552019 -383.910098) (xy 460.584959 -383.957631)
			(xy 460.610348 -384.009591) (xy 460.627606 -384.064787) (xy 460.636338 -384.121955) (xy 460.636874 -384.15087)
			(xy 460.636388 -384.178121) (xy 460.628632 -384.232069) (xy 460.613277 -384.284364) (xy 460.590635 -384.333941)
			(xy 460.561169 -384.379791) (xy 460.525478 -384.420982) (xy 460.484287 -384.456673) (xy 460.438437 -384.486139)
			(xy 460.38886 -384.508781) (xy 460.336565 -384.524136) (xy 460.282617 -384.531892) (xy 460.228115 -384.531892)
			(xy 460.174167 -384.524136) (xy 460.121872 -384.508781) (xy 460.072295 -384.486139) (xy 460.026445 -384.456673)
			(xy 459.985254 -384.420982) (xy 459.949563 -384.379791) (xy 459.920097 -384.333941) (xy 459.897455 -384.284364)
			(xy 459.8821 -384.232069) (xy 459.874344 -384.178121) (xy 459.873858 -384.15087) (xy 459.874405 -384.121954)
			(xy 459.883125 -384.064783) (xy 459.900376 -384.009584) (xy 459.925762 -383.957622) (xy 459.958702 -383.910087)
			(xy 459.99844 -383.86807) (xy 460.020924 -383.84988) (xy 460.029695 -383.842327) (xy 460.039872 -383.821561)
			(xy 460.040482 -383.810002) (xy 460.040482 -383.729738) (xy 460.039896 -383.718172) (xy 460.029713 -383.6974)
			(xy 460.020924 -383.68986) (xy 460.000113 -383.673141) (xy 459.962985 -383.634782) (xy 459.931567 -383.591623)
			(xy 459.906471 -383.544505) (xy 459.888188 -383.49435) (xy 459.877074 -383.442135) (xy 459.873347 -383.388882)
			(xy 458.351363 -383.388882) (xy 458.347636 -383.442131) (xy 458.336521 -383.494341) (xy 458.318237 -383.544491)
			(xy 458.293139 -383.591603) (xy 458.261719 -383.634756) (xy 458.22459 -383.673107) (xy 458.203808 -383.68986)
			(xy 458.19507 -383.697445) (xy 458.184873 -383.718186) (xy 458.18425 -383.729738) (xy 458.18425 -383.810002)
			(xy 458.184802 -383.821573) (xy 458.195008 -383.842345) (xy 458.203808 -383.84988) (xy 458.226284 -383.86808)
			(xy 458.266019 -383.910098) (xy 458.298959 -383.957631) (xy 458.324348 -384.009591) (xy 458.341606 -384.064787)
			(xy 458.350338 -384.121955) (xy 458.350874 -384.15087) (xy 458.350388 -384.178121) (xy 458.342632 -384.232069)
			(xy 458.327277 -384.284364) (xy 458.304635 -384.333941) (xy 458.275169 -384.379791) (xy 458.239478 -384.420982)
			(xy 458.198287 -384.456673) (xy 458.152437 -384.486139) (xy 458.10286 -384.508781) (xy 458.050565 -384.524136)
			(xy 457.996617 -384.531892) (xy 457.942115 -384.531892) (xy 457.888167 -384.524136) (xy 457.835872 -384.508781)
			(xy 457.786295 -384.486139) (xy 457.740445 -384.456673) (xy 457.699254 -384.420982) (xy 457.663563 -384.379791)
			(xy 457.634097 -384.333941) (xy 457.611455 -384.284364) (xy 457.5961 -384.232069) (xy 457.588344 -384.178121)
			(xy 457.587858 -384.15087) (xy 457.588405 -384.121954) (xy 457.597125 -384.064783) (xy 457.614376 -384.009584)
			(xy 457.639762 -383.957622) (xy 457.672702 -383.910087) (xy 457.71244 -383.86807) (xy 457.734924 -383.84988)
			(xy 457.743695 -383.842327) (xy 457.753872 -383.821561) (xy 457.754482 -383.810002) (xy 457.754482 -383.729738)
			(xy 457.753896 -383.718172) (xy 457.743713 -383.6974) (xy 457.734924 -383.68986) (xy 457.714113 -383.673141)
			(xy 457.676985 -383.634782) (xy 457.645567 -383.591623) (xy 457.620471 -383.544505) (xy 457.602188 -383.49435)
			(xy 457.591074 -383.442135) (xy 457.587347 -383.388882) (xy 454.541363 -383.388882) (xy 454.537636 -383.442131)
			(xy 454.526521 -383.494341) (xy 454.508237 -383.544491) (xy 454.483139 -383.591603) (xy 454.451719 -383.634756)
			(xy 454.41459 -383.673107) (xy 454.393808 -383.68986) (xy 454.38507 -383.697445) (xy 454.374873 -383.718186)
			(xy 454.37425 -383.729738) (xy 454.37425 -383.810002) (xy 454.374802 -383.821573) (xy 454.385008 -383.842345)
			(xy 454.393808 -383.84988) (xy 454.416284 -383.86808) (xy 454.456019 -383.910098) (xy 454.488959 -383.957631)
			(xy 454.514348 -384.009591) (xy 454.531606 -384.064787) (xy 454.540338 -384.121955) (xy 454.540874 -384.15087)
			(xy 454.540388 -384.178121) (xy 454.532632 -384.232069) (xy 454.517277 -384.284364) (xy 454.494635 -384.333941)
			(xy 454.465169 -384.379791) (xy 454.429478 -384.420982) (xy 454.388287 -384.456673) (xy 454.342437 -384.486139)
			(xy 454.29286 -384.508781) (xy 454.240565 -384.524136) (xy 454.186617 -384.531892) (xy 454.132115 -384.531892)
			(xy 454.078167 -384.524136) (xy 454.025872 -384.508781) (xy 453.976295 -384.486139) (xy 453.930445 -384.456673)
			(xy 453.889254 -384.420982) (xy 453.853563 -384.379791) (xy 453.824097 -384.333941) (xy 453.801455 -384.284364)
			(xy 453.7861 -384.232069) (xy 453.778344 -384.178121) (xy 453.777858 -384.15087) (xy 453.778405 -384.121954)
			(xy 453.787125 -384.064783) (xy 453.804376 -384.009584) (xy 453.829762 -383.957622) (xy 453.862702 -383.910087)
			(xy 453.90244 -383.86807) (xy 453.924924 -383.84988) (xy 453.933695 -383.842327) (xy 453.943872 -383.821561)
			(xy 453.944482 -383.810002) (xy 453.944482 -383.729738) (xy 453.943896 -383.718172) (xy 453.933713 -383.6974)
			(xy 453.924924 -383.68986) (xy 453.904113 -383.673141) (xy 453.866985 -383.634782) (xy 453.835567 -383.591623)
			(xy 453.810471 -383.544505) (xy 453.792188 -383.49435) (xy 453.781074 -383.442135) (xy 453.777347 -383.388882)
			(xy 452.255363 -383.388882) (xy 452.251636 -383.442131) (xy 452.240521 -383.494341) (xy 452.222237 -383.544491)
			(xy 452.197139 -383.591603) (xy 452.165719 -383.634756) (xy 452.12859 -383.673107) (xy 452.107808 -383.68986)
			(xy 452.09907 -383.697445) (xy 452.088873 -383.718186) (xy 452.08825 -383.729738) (xy 452.08825 -383.810002)
			(xy 452.088802 -383.821573) (xy 452.099008 -383.842345) (xy 452.107808 -383.84988) (xy 452.130284 -383.86808)
			(xy 452.170019 -383.910098) (xy 452.202959 -383.957631) (xy 452.228348 -384.009591) (xy 452.245606 -384.064787)
			(xy 452.254338 -384.121955) (xy 452.254874 -384.15087) (xy 452.254388 -384.178121) (xy 452.246632 -384.232069)
			(xy 452.231277 -384.284364) (xy 452.208635 -384.333941) (xy 452.179169 -384.379791) (xy 452.143478 -384.420982)
			(xy 452.102287 -384.456673) (xy 452.056437 -384.486139) (xy 452.00686 -384.508781) (xy 451.954565 -384.524136)
			(xy 451.900617 -384.531892) (xy 451.846115 -384.531892) (xy 451.792167 -384.524136) (xy 451.739872 -384.508781)
			(xy 451.690295 -384.486139) (xy 451.644445 -384.456673) (xy 451.603254 -384.420982) (xy 451.567563 -384.379791)
			(xy 451.538097 -384.333941) (xy 451.515455 -384.284364) (xy 451.5001 -384.232069) (xy 451.492344 -384.178121)
			(xy 451.491858 -384.15087) (xy 451.492405 -384.121954) (xy 451.501125 -384.064783) (xy 451.518376 -384.009584)
			(xy 451.543762 -383.957622) (xy 451.576702 -383.910087) (xy 451.61644 -383.86807) (xy 451.638924 -383.84988)
			(xy 451.647695 -383.842327) (xy 451.657872 -383.821561) (xy 451.658482 -383.810002) (xy 451.658482 -383.729738)
			(xy 451.657896 -383.718172) (xy 451.647713 -383.6974) (xy 451.638924 -383.68986) (xy 451.618113 -383.673141)
			(xy 451.580985 -383.634782) (xy 451.549567 -383.591623) (xy 451.524471 -383.544505) (xy 451.506188 -383.49435)
			(xy 451.495074 -383.442135) (xy 451.491347 -383.388882) (xy 448.445363 -383.388882) (xy 448.441636 -383.442131)
			(xy 448.430521 -383.494341) (xy 448.412237 -383.544491) (xy 448.387139 -383.591603) (xy 448.355719 -383.634756)
			(xy 448.31859 -383.673107) (xy 448.297808 -383.68986) (xy 448.28907 -383.697445) (xy 448.278873 -383.718186)
			(xy 448.27825 -383.729738) (xy 448.27825 -383.810002) (xy 448.278802 -383.821573) (xy 448.289008 -383.842345)
			(xy 448.297808 -383.84988) (xy 448.320284 -383.86808) (xy 448.360019 -383.910098) (xy 448.392959 -383.957631)
			(xy 448.418348 -384.009591) (xy 448.435606 -384.064787) (xy 448.444338 -384.121955) (xy 448.444874 -384.15087)
			(xy 448.444388 -384.178121) (xy 448.436632 -384.232069) (xy 448.421277 -384.284364) (xy 448.398635 -384.333941)
			(xy 448.369169 -384.379791) (xy 448.333478 -384.420982) (xy 448.292287 -384.456673) (xy 448.246437 -384.486139)
			(xy 448.19686 -384.508781) (xy 448.144565 -384.524136) (xy 448.090617 -384.531892) (xy 448.036115 -384.531892)
			(xy 447.982167 -384.524136) (xy 447.929872 -384.508781) (xy 447.880295 -384.486139) (xy 447.834445 -384.456673)
			(xy 447.793254 -384.420982) (xy 447.757563 -384.379791) (xy 447.728097 -384.333941) (xy 447.705455 -384.284364)
			(xy 447.6901 -384.232069) (xy 447.682344 -384.178121) (xy 447.681858 -384.15087) (xy 447.682405 -384.121954)
			(xy 447.691125 -384.064783) (xy 447.708376 -384.009584) (xy 447.733762 -383.957622) (xy 447.766702 -383.910087)
			(xy 447.80644 -383.86807) (xy 447.828924 -383.84988) (xy 447.837695 -383.842327) (xy 447.847872 -383.821561)
			(xy 447.848482 -383.810002) (xy 447.848482 -383.729738) (xy 447.847896 -383.718172) (xy 447.837713 -383.6974)
			(xy 447.828924 -383.68986) (xy 447.808113 -383.673141) (xy 447.770985 -383.634782) (xy 447.739567 -383.591623)
			(xy 447.714471 -383.544505) (xy 447.696188 -383.49435) (xy 447.685074 -383.442135) (xy 447.681347 -383.388882)
			(xy 446.489563 -383.388882) (xy 446.485836 -383.442131) (xy 446.474721 -383.494341) (xy 446.456437 -383.544491)
			(xy 446.431339 -383.591603) (xy 446.399919 -383.634756) (xy 446.36279 -383.673107) (xy 446.342008 -383.68986)
			(xy 446.33327 -383.697445) (xy 446.323073 -383.718186) (xy 446.32245 -383.729738) (xy 446.32245 -383.810002)
			(xy 446.323002 -383.821573) (xy 446.333208 -383.842345) (xy 446.342008 -383.84988) (xy 446.364484 -383.86808)
			(xy 446.404219 -383.910098) (xy 446.437159 -383.957631) (xy 446.462548 -384.009591) (xy 446.479806 -384.064787)
			(xy 446.488538 -384.121955) (xy 446.489074 -384.15087) (xy 446.488588 -384.178121) (xy 446.480832 -384.232069)
			(xy 446.465477 -384.284364) (xy 446.442835 -384.333941) (xy 446.413369 -384.379791) (xy 446.377678 -384.420982)
			(xy 446.336487 -384.456673) (xy 446.290637 -384.486139) (xy 446.24106 -384.508781) (xy 446.188765 -384.524136)
			(xy 446.134817 -384.531892) (xy 446.080315 -384.531892) (xy 446.026367 -384.524136) (xy 445.974072 -384.508781)
			(xy 445.924495 -384.486139) (xy 445.878645 -384.456673) (xy 445.837454 -384.420982) (xy 445.801763 -384.379791)
			(xy 445.772297 -384.333941) (xy 445.749655 -384.284364) (xy 445.7343 -384.232069) (xy 445.726544 -384.178121)
			(xy 445.726058 -384.15087) (xy 445.726605 -384.121954) (xy 445.735325 -384.064783) (xy 445.752576 -384.009584)
			(xy 445.777962 -383.957622) (xy 445.810902 -383.910087) (xy 445.85064 -383.86807) (xy 445.873124 -383.84988)
			(xy 445.881895 -383.842327) (xy 445.892072 -383.821561) (xy 445.892682 -383.810002) (xy 445.892682 -383.729738)
			(xy 445.892096 -383.718172) (xy 445.881913 -383.6974) (xy 445.873124 -383.68986) (xy 445.852313 -383.673141)
			(xy 445.815185 -383.634782) (xy 445.783767 -383.591623) (xy 445.758671 -383.544505) (xy 445.740388 -383.49435)
			(xy 445.729274 -383.442135) (xy 445.725547 -383.388882) (xy 442.679563 -383.388882) (xy 442.675836 -383.442131)
			(xy 442.664721 -383.494341) (xy 442.646437 -383.544491) (xy 442.621339 -383.591603) (xy 442.589919 -383.634756)
			(xy 442.55279 -383.673107) (xy 442.532008 -383.68986) (xy 442.52327 -383.697445) (xy 442.513073 -383.718186)
			(xy 442.51245 -383.729738) (xy 442.51245 -383.810002) (xy 442.513002 -383.821573) (xy 442.523208 -383.842345)
			(xy 442.532008 -383.84988) (xy 442.554484 -383.86808) (xy 442.594219 -383.910098) (xy 442.627159 -383.957631)
			(xy 442.652548 -384.009591) (xy 442.669806 -384.064787) (xy 442.678538 -384.121955) (xy 442.679074 -384.15087)
			(xy 442.678588 -384.178121) (xy 442.670832 -384.232069) (xy 442.655477 -384.284364) (xy 442.632835 -384.333941)
			(xy 442.603369 -384.379791) (xy 442.567678 -384.420982) (xy 442.526487 -384.456673) (xy 442.480637 -384.486139)
			(xy 442.43106 -384.508781) (xy 442.378765 -384.524136) (xy 442.324817 -384.531892) (xy 442.270315 -384.531892)
			(xy 442.216367 -384.524136) (xy 442.164072 -384.508781) (xy 442.114495 -384.486139) (xy 442.068645 -384.456673)
			(xy 442.027454 -384.420982) (xy 441.991763 -384.379791) (xy 441.962297 -384.333941) (xy 441.939655 -384.284364)
			(xy 441.9243 -384.232069) (xy 441.916544 -384.178121) (xy 441.916058 -384.15087) (xy 441.916605 -384.121954)
			(xy 441.925325 -384.064783) (xy 441.942576 -384.009584) (xy 441.967962 -383.957622) (xy 442.000902 -383.910087)
			(xy 442.04064 -383.86807) (xy 442.063124 -383.84988) (xy 442.071895 -383.842327) (xy 442.082072 -383.821561)
			(xy 442.082682 -383.810002) (xy 442.082682 -383.729738) (xy 442.082096 -383.718172) (xy 442.071913 -383.6974)
			(xy 442.063124 -383.68986) (xy 442.042313 -383.673141) (xy 442.005185 -383.634782) (xy 441.973767 -383.591623)
			(xy 441.948671 -383.544505) (xy 441.930388 -383.49435) (xy 441.919274 -383.442135) (xy 441.915547 -383.388882)
			(xy 439.466736 -383.388882) (xy 439.466736 -385.039108) (xy 447.973196 -385.039108) (xy 447.973663 -385.011855)
			(xy 447.981419 -384.957904) (xy 447.996774 -384.905606) (xy 448.019416 -384.856026) (xy 448.048883 -384.810172)
			(xy 448.084577 -384.76898) (xy 448.125769 -384.733286) (xy 448.171622 -384.703818) (xy 448.221202 -384.681175)
			(xy 448.2735 -384.66582) (xy 448.327451 -384.658063) (xy 448.354704 -384.6576) (xy 448.383621 -384.658116)
			(xy 448.440792 -384.666845) (xy 448.495991 -384.684104) (xy 448.547953 -384.709496) (xy 448.595487 -384.74244)
			(xy 448.637504 -384.782181) (xy 448.655694 -384.804666) (xy 448.663251 -384.813432) (xy 448.684014 -384.82361)
			(xy 448.695572 -384.824224) (xy 448.775836 -384.824224) (xy 448.787403 -384.823643) (xy 448.808176 -384.813459)
			(xy 448.815714 -384.804666) (xy 448.833889 -384.782169) (xy 448.875913 -384.742436) (xy 448.923451 -384.7095)
			(xy 448.975416 -384.684114) (xy 449.030616 -384.66686) (xy 449.087787 -384.658134) (xy 449.116704 -384.6576)
			(xy 449.145443 -384.658121) (xy 449.20227 -384.666744) (xy 449.257161 -384.683795) (xy 449.308873 -384.708887)
			(xy 449.356235 -384.741453) (xy 449.377562 -384.760724) (xy 449.384674 -384.767328) (xy 449.4022 -384.77444)
			(xy 449.491608 -384.77444) (xy 449.509134 -384.767328) (xy 449.516246 -384.760724) (xy 449.537569 -384.741449)
			(xy 449.584933 -384.708884) (xy 449.636645 -384.683792) (xy 449.691537 -384.666743) (xy 449.748365 -384.658121)
			(xy 449.777104 -384.6576) (xy 449.804357 -384.658052) (xy 449.858309 -384.665809) (xy 449.910608 -384.681166)
			(xy 449.960188 -384.70381) (xy 450.006042 -384.733279) (xy 450.047235 -384.768974) (xy 450.082928 -384.810168)
			(xy 450.112396 -384.856022) (xy 450.135038 -384.905604) (xy 450.150393 -384.957903) (xy 450.158149 -385.011855)
			(xy 450.158612 -385.039108) (xy 450.158178 -385.06581) (xy 450.150724 -385.11869) (xy 450.135962 -385.170013)
			(xy 450.114183 -385.218773) (xy 450.085811 -385.264017) (xy 450.06895 -385.284726) (xy 450.062854 -385.292092)
			(xy 450.056758 -385.310126) (xy 450.060568 -385.397756) (xy 450.068188 -385.415282) (xy 450.074792 -385.421886)
			(xy 450.095606 -385.443472) (xy 450.130859 -385.491977) (xy 450.158087 -385.545401) (xy 450.176618 -385.602428)
			(xy 450.185997 -385.661653) (xy 450.186552 -385.691634) (xy 450.186008 -385.720693) (xy 450.177172 -385.778134)
			(xy 450.159725 -385.833571) (xy 450.134071 -385.88572) (xy 450.100803 -385.933374) (xy 450.081142 -385.954778)
			(xy 450.074538 -385.96189) (xy 450.067172 -385.979924) (xy 450.067172 -386.06984) (xy 450.074538 -386.087874)
			(xy 450.081142 -386.094986) (xy 450.100804 -386.116391) (xy 450.134085 -386.164037) (xy 450.159743 -386.216185)
			(xy 450.177186 -386.271625) (xy 450.186007 -386.329071) (xy 450.186552 -386.35813) (xy 450.186034 -386.386232)
			(xy 450.18508 -386.392674) (xy 450.3547 -386.392674) (xy 450.355208 -386.363935) (xy 450.363834 -386.307106)
			(xy 450.380888 -386.252216) (xy 450.405983 -386.200504) (xy 450.438552 -386.153142) (xy 450.457824 -386.131816)
			(xy 450.464428 -386.124704) (xy 450.47154 -386.107178) (xy 450.47154 -386.01777) (xy 450.464428 -386.000244)
			(xy 450.457824 -385.993132) (xy 450.438527 -385.971828) (xy 450.405963 -385.924461) (xy 450.380873 -385.872746)
			(xy 450.363825 -385.817852) (xy 450.355205 -385.761021) (xy 450.355207 -385.703541) (xy 450.363833 -385.646711)
			(xy 450.380887 -385.591819) (xy 450.405982 -385.540106) (xy 450.438551 -385.492743) (xy 450.457824 -385.471416)
			(xy 450.464428 -385.464304) (xy 450.47154 -385.446778) (xy 450.47154 -385.35737) (xy 450.464428 -385.339844)
			(xy 450.457824 -385.332732) (xy 450.438539 -385.311418) (xy 450.405975 -385.264052) (xy 450.380885 -385.212337)
			(xy 450.363838 -385.157444) (xy 450.355219 -385.100614) (xy 450.3547 -385.071874) (xy 450.355154 -385.044622)
			(xy 450.362914 -384.990672) (xy 450.378273 -384.938377) (xy 450.400917 -384.888799) (xy 450.430387 -384.842948)
			(xy 450.466082 -384.801758) (xy 450.507275 -384.766067) (xy 450.553129 -384.736601) (xy 450.602709 -384.713961)
			(xy 450.655006 -384.698607) (xy 450.708956 -384.690851) (xy 450.736208 -384.690366) (xy 450.764947 -384.690894)
			(xy 450.821773 -384.699517) (xy 450.876664 -384.716566) (xy 450.928376 -384.741657) (xy 450.975739 -384.77422)
			(xy 450.997066 -384.79349) (xy 451.004178 -384.800094) (xy 451.021704 -384.807206) (xy 451.111112 -384.807206)
			(xy 451.128638 -384.800094) (xy 451.13575 -384.79349) (xy 451.157082 -384.774224) (xy 451.204442 -384.741656)
			(xy 451.256152 -384.716561) (xy 451.311042 -384.69951) (xy 451.367869 -384.690887) (xy 451.396608 -384.690366)
			(xy 451.42367 -384.690813) (xy 451.477248 -384.69848) (xy 451.529203 -384.713646) (xy 451.578493 -384.736004)
			(xy 451.624126 -384.765107) (xy 451.665187 -384.800369) (xy 451.683374 -384.820414) (xy 451.690944 -384.828277)
			(xy 451.710823 -384.83723) (xy 451.721728 -384.837686) (xy 451.797928 -384.837686) (xy 451.808828 -384.83722)
			(xy 451.828698 -384.828258) (xy 451.836282 -384.820414) (xy 451.854456 -384.800357) (xy 451.895516 -384.765093)
			(xy 451.941151 -384.735992) (xy 451.990445 -384.71364) (xy 452.042405 -384.698487) (xy 452.095986 -384.690836)
			(xy 452.123048 -384.690366) (xy 452.150299 -384.690833) (xy 452.204246 -384.698595) (xy 452.25654 -384.713955)
			(xy 452.306115 -384.7366) (xy 452.351964 -384.766069) (xy 452.393153 -384.801762) (xy 452.428844 -384.842953)
			(xy 452.45831 -384.888804) (xy 452.480952 -384.938381) (xy 452.496309 -384.990675) (xy 452.504068 -385.044623)
			(xy 452.504556 -385.071874) (xy 452.504001 -385.100612) (xy 452.495384 -385.157437) (xy 452.47834 -385.212327)
			(xy 452.453256 -385.264039) (xy 452.420699 -385.311403) (xy 452.401432 -385.332732) (xy 452.394828 -385.339844)
			(xy 452.387716 -385.35737) (xy 452.387716 -385.446778) (xy 452.394828 -385.464304) (xy 452.401432 -385.471416)
			(xy 452.420675 -385.492766) (xy 452.453236 -385.540126) (xy 452.478325 -385.591835) (xy 452.495374 -385.646721)
			(xy 452.503998 -385.703544) (xy 452.504001 -385.761018) (xy 452.495383 -385.817842) (xy 452.478339 -385.87273)
			(xy 452.453255 -385.924441) (xy 452.420698 -385.971804) (xy 452.401432 -385.993132) (xy 452.394828 -386.000244)
			(xy 452.387716 -386.01777) (xy 452.387716 -386.107178) (xy 452.394828 -386.124704) (xy 452.401432 -386.131816)
			(xy 452.420675 -386.153166) (xy 452.453236 -386.200526) (xy 452.478325 -386.252235) (xy 452.495374 -386.307121)
			(xy 452.503998 -386.363944) (xy 452.504001 -386.421418) (xy 452.495383 -386.478242) (xy 452.478339 -386.53313)
			(xy 452.453255 -386.584841) (xy 452.420698 -386.632204) (xy 452.401432 -386.653532) (xy 452.394574 -386.660898)
			(xy 452.387716 -386.678678) (xy 452.388478 -386.768848) (xy 452.395844 -386.786882) (xy 452.402956 -386.793994)
			(xy 452.423192 -386.815485) (xy 452.457414 -386.86358) (xy 452.48382 -386.916372) (xy 452.50178 -386.972601)
			(xy 452.510866 -387.030926) (xy 452.511414 -387.06044) (xy 452.510909 -387.087809) (xy 452.5031 -387.141986)
			(xy 452.48762 -387.194489) (xy 452.464787 -387.244236) (xy 452.435071 -387.290205) (xy 452.417434 -387.311138)
			(xy 452.411338 -387.31825) (xy 452.404988 -387.335268) (xy 452.404988 -387.420612) (xy 452.411338 -387.43763)
			(xy 452.417434 -387.444742) (xy 452.435065 -387.465681) (xy 452.464777 -387.511652) (xy 452.487614 -387.561398)
			(xy 452.503107 -387.613897) (xy 452.503953 -387.619748) (xy 455.361802 -387.619748) (xy 455.362294 -387.591008)
			(xy 455.370924 -387.534179) (xy 455.387981 -387.479288) (xy 455.41308 -387.427577) (xy 455.445652 -387.380216)
			(xy 455.464926 -387.35889) (xy 455.47153 -387.351778) (xy 455.478642 -387.334252) (xy 455.478642 -387.244844)
			(xy 455.47153 -387.227318) (xy 455.464926 -387.220206) (xy 455.445703 -387.198838) (xy 455.413136 -387.151483)
			(xy 455.388041 -387.099778) (xy 455.370988 -387.044893) (xy 455.362361 -386.988071) (xy 455.362355 -386.930599)
			(xy 455.370972 -386.873775) (xy 455.388016 -386.818888) (xy 455.4131 -386.767178) (xy 455.445659 -386.719817)
			(xy 455.464926 -386.69849) (xy 455.47153 -386.691378) (xy 455.478642 -386.673852) (xy 455.478642 -386.584444)
			(xy 455.47153 -386.566918) (xy 455.464926 -386.559806) (xy 455.445703 -386.538438) (xy 455.413136 -386.491083)
			(xy 455.388041 -386.439378) (xy 455.370988 -386.384493) (xy 455.362361 -386.327671) (xy 455.362355 -386.270199)
			(xy 455.370972 -386.213375) (xy 455.388016 -386.158488) (xy 455.4131 -386.106778) (xy 455.445659 -386.059417)
			(xy 455.464926 -386.03809) (xy 455.47153 -386.030978) (xy 455.478642 -386.013452) (xy 455.478642 -385.924044)
			(xy 455.47153 -385.906518) (xy 455.464926 -385.899406) (xy 455.445629 -385.878102) (xy 455.413066 -385.830734)
			(xy 455.387979 -385.779016) (xy 455.370935 -385.72412) (xy 455.362319 -385.667289) (xy 455.361802 -385.638548)
			(xy 455.3623 -385.611296) (xy 455.370051 -385.557346) (xy 455.385401 -385.505048) (xy 455.408039 -385.455467)
			(xy 455.437503 -385.409613) (xy 455.473193 -385.36842) (xy 455.514383 -385.332725) (xy 455.560234 -385.303257)
			(xy 455.609812 -385.280614) (xy 455.662108 -385.265259) (xy 455.716058 -385.257503) (xy 455.74331 -385.25704)
			(xy 455.769625 -385.257509) (xy 455.821757 -385.264732) (xy 455.8724 -385.279054) (xy 455.920594 -385.300203)
			(xy 455.965422 -385.327778) (xy 456.006034 -385.361253) (xy 456.041657 -385.399994) (xy 456.057 -385.421378)
			(xy 456.064112 -385.431538) (xy 456.085448 -385.442968) (xy 456.193144 -385.444492) (xy 456.214988 -385.43357)
			(xy 456.222354 -385.423664) (xy 456.240463 -385.399945) (xy 456.2828 -385.357892) (xy 456.33117 -385.322946)
			(xy 456.384392 -385.295959) (xy 456.441168 -385.277591) (xy 456.500112 -385.26829) (xy 456.529948 -385.267708)
			(xy 456.557716 -385.26821) (xy 456.612668 -385.276252) (xy 456.665873 -385.292172) (xy 456.71621 -385.315634)
			(xy 456.762615 -385.346145) (xy 456.783694 -385.364228) (xy 456.790552 -385.370324) (xy 456.807824 -385.377182)
			(xy 456.89393 -385.377436) (xy 456.911202 -385.370832) (xy 456.918314 -385.364736) (xy 456.939286 -385.346929)
			(xy 456.985399 -385.316922) (xy 457.035341 -385.293845) (xy 457.088079 -385.278176) (xy 457.14252 -385.27024)
			(xy 457.170028 -385.26974) (xy 457.197284 -385.270129) (xy 457.25124 -385.277891) (xy 457.303542 -385.293253)
			(xy 457.353126 -385.315902) (xy 457.398981 -385.345378) (xy 457.440175 -385.381079) (xy 457.475868 -385.42228)
			(xy 457.505334 -385.468141) (xy 457.527974 -385.517729) (xy 457.543325 -385.570034) (xy 457.551076 -385.623992)
			(xy 457.551536 -385.651248) (xy 457.551032 -385.679988) (xy 457.542403 -385.736815) (xy 457.525348 -385.791706)
			(xy 457.500252 -385.843417) (xy 457.467684 -385.890779) (xy 457.448412 -385.912106) (xy 457.441808 -385.919218)
			(xy 457.434696 -385.936744) (xy 457.434696 -386.026152) (xy 457.441808 -386.043678) (xy 457.448412 -386.05079)
			(xy 457.467729 -386.072076) (xy 457.500289 -386.119447) (xy 457.525376 -386.171165) (xy 457.542421 -386.226062)
			(xy 457.551038 -386.282894) (xy 457.551033 -386.340376) (xy 457.542405 -386.397206) (xy 457.52535 -386.4521)
			(xy 457.500254 -386.503814) (xy 457.467685 -386.551178) (xy 457.448412 -386.572506) (xy 457.441808 -386.579618)
			(xy 457.434696 -386.597144) (xy 457.434696 -386.686552) (xy 457.441808 -386.704078) (xy 457.448412 -386.71119)
			(xy 457.467729 -386.732476) (xy 457.500289 -386.779847) (xy 457.525376 -386.831565) (xy 457.542421 -386.886462)
			(xy 457.551038 -386.943294) (xy 457.551033 -387.000776) (xy 457.542405 -387.057606) (xy 457.52535 -387.1125)
			(xy 457.500254 -387.164214) (xy 457.467685 -387.211578) (xy 457.448412 -387.232906) (xy 457.441808 -387.240018)
			(xy 457.434696 -387.257544) (xy 457.434696 -387.258347) (xy 458.670706 -387.258347) (xy 458.670706 -387.203853)
			(xy 458.678461 -387.149912) (xy 458.693813 -387.097625) (xy 458.716449 -387.048054) (xy 458.74591 -387.002209)
			(xy 458.781594 -386.961023) (xy 458.822777 -386.925334) (xy 458.868619 -386.895869) (xy 458.918187 -386.873227)
			(xy 458.970473 -386.857869) (xy 459.024413 -386.850109) (xy 459.05166 -386.84962) (xy 459.080399 -386.850129)
			(xy 459.137226 -386.858758) (xy 459.192116 -386.875813) (xy 459.243828 -386.900907) (xy 459.291191 -386.933473)
			(xy 459.312518 -386.952744) (xy 459.31963 -386.959348) (xy 459.337156 -386.96646) (xy 459.426564 -386.96646)
			(xy 459.44409 -386.959348) (xy 459.451202 -386.952744) (xy 459.472546 -386.933493) (xy 459.519904 -386.900924)
			(xy 459.571611 -386.875828) (xy 459.626498 -386.858772) (xy 459.683322 -386.850144) (xy 459.71206 -386.84962)
			(xy 459.739317 -386.850024) (xy 459.793276 -386.857777) (xy 459.845583 -386.873131) (xy 459.895171 -386.895773)
			(xy 459.941033 -386.925242) (xy 459.982234 -386.960938) (xy 460.017934 -387.002135) (xy 460.047408 -387.047993)
			(xy 460.070055 -387.09758) (xy 460.085414 -387.149885) (xy 460.093173 -387.203843) (xy 460.093173 -387.258357)
			(xy 460.087696 -387.296447) (xy 460.851306 -387.296447) (xy 460.851306 -387.241953) (xy 460.859061 -387.188014)
			(xy 460.874412 -387.135727) (xy 460.897048 -387.086157) (xy 460.926507 -387.040312) (xy 460.962191 -386.999126)
			(xy 461.003372 -386.963437) (xy 461.049213 -386.933972) (xy 461.09878 -386.91133) (xy 461.151065 -386.895971)
			(xy 461.205003 -386.88821) (xy 461.23225 -386.88772) (xy 461.260989 -386.888235) (xy 461.317816 -386.896863)
			(xy 461.372706 -386.913916) (xy 461.424417 -386.939009) (xy 461.47178 -386.971574) (xy 461.493108 -386.990844)
			(xy 461.50022 -386.997448) (xy 461.517746 -387.00456) (xy 461.607154 -387.00456) (xy 461.62468 -386.997448)
			(xy 461.631792 -386.990844) (xy 461.653099 -386.971551) (xy 461.700467 -386.938987) (xy 461.752183 -386.913899)
			(xy 461.807078 -386.896854) (xy 461.86391 -386.888237) (xy 461.89265 -386.88772) (xy 461.919907 -386.888124)
			(xy 461.973868 -386.895875) (xy 462.026175 -386.911228) (xy 462.075765 -386.933869) (xy 462.121628 -386.963338)
			(xy 462.16283 -386.999035) (xy 462.198532 -387.040232) (xy 462.228007 -387.086091) (xy 462.250654 -387.135678)
			(xy 462.266014 -387.187983) (xy 462.273773 -387.241943) (xy 462.273773 -387.296457) (xy 462.266014 -387.350416)
			(xy 462.255395 -387.386576) (xy 462.824828 -387.386576) (xy 462.828899 -387.330954) (xy 462.841025 -387.276517)
			(xy 462.860948 -387.224426) (xy 462.888244 -387.175791) (xy 462.92233 -387.131648) (xy 462.962479 -387.092939)
			(xy 463.007837 -387.060488) (xy 463.057437 -387.034987) (xy 463.110221 -387.01698) (xy 463.165064 -387.00685)
			(xy 463.220798 -387.004813) (xy 463.276235 -387.010913) (xy 463.330192 -387.025019) (xy 463.381521 -387.046831)
			(xy 463.429127 -387.075885) (xy 463.471995 -387.11156) (xy 463.509212 -387.153097) (xy 463.539985 -387.19961)
			(xy 463.563657 -387.250107) (xy 463.579725 -387.303514) (xy 463.587845 -387.35869) (xy 463.588354 -387.386576)
			(xy 463.587845 -387.414462) (xy 463.579725 -387.469638) (xy 463.563657 -387.523045) (xy 463.539985 -387.573542)
			(xy 463.509212 -387.620055) (xy 463.471995 -387.661592) (xy 463.429127 -387.697267) (xy 463.381521 -387.726321)
			(xy 463.330192 -387.748133) (xy 463.276235 -387.762239) (xy 463.220798 -387.768339) (xy 463.165064 -387.766302)
			(xy 463.110221 -387.756172) (xy 463.057437 -387.738165) (xy 463.007837 -387.712664) (xy 462.962479 -387.680213)
			(xy 462.92233 -387.641504) (xy 462.888244 -387.597361) (xy 462.860948 -387.548726) (xy 462.841025 -387.496635)
			(xy 462.828899 -387.442198) (xy 462.824828 -387.386576) (xy 462.255395 -387.386576) (xy 462.250654 -387.402722)
			(xy 462.228007 -387.452309) (xy 462.198532 -387.498168) (xy 462.16283 -387.539365) (xy 462.121628 -387.575062)
			(xy 462.075765 -387.604531) (xy 462.026175 -387.627172) (xy 461.973868 -387.642525) (xy 461.919907 -387.650276)
			(xy 461.89265 -387.650736) (xy 461.86391 -387.650233) (xy 461.807083 -387.641604) (xy 461.752192 -387.624548)
			(xy 461.700481 -387.599453) (xy 461.653119 -387.566884) (xy 461.631792 -387.547612) (xy 461.62468 -387.541008)
			(xy 461.607154 -387.533896) (xy 461.517746 -387.533896) (xy 461.50022 -387.541008) (xy 461.493108 -387.547612)
			(xy 461.471794 -387.566898) (xy 461.424429 -387.599464) (xy 461.372715 -387.624555) (xy 461.317821 -387.641601)
			(xy 461.26099 -387.650219) (xy 461.23225 -387.650736) (xy 461.205003 -387.65019) (xy 461.151065 -387.642429)
			(xy 461.09878 -387.62707) (xy 461.049213 -387.604428) (xy 461.003372 -387.574963) (xy 460.962191 -387.539274)
			(xy 460.926507 -387.498088) (xy 460.897048 -387.452243) (xy 460.874412 -387.402673) (xy 460.859061 -387.350386)
			(xy 460.851306 -387.296447) (xy 460.087696 -387.296447) (xy 460.085414 -387.312315) (xy 460.070055 -387.36462)
			(xy 460.047408 -387.414207) (xy 460.017934 -387.460065) (xy 459.982234 -387.501262) (xy 459.941033 -387.536958)
			(xy 459.895171 -387.566427) (xy 459.845583 -387.589069) (xy 459.793276 -387.604423) (xy 459.739317 -387.612176)
			(xy 459.71206 -387.612636) (xy 459.683321 -387.612127) (xy 459.626493 -387.603499) (xy 459.571603 -387.586445)
			(xy 459.519891 -387.561351) (xy 459.472529 -387.528783) (xy 459.451202 -387.509512) (xy 459.44409 -387.502908)
			(xy 459.426564 -387.495796) (xy 459.337156 -387.495796) (xy 459.31963 -387.502908) (xy 459.312518 -387.509512)
			(xy 459.2912 -387.528793) (xy 459.243836 -387.56136) (xy 459.192123 -387.586451) (xy 459.137229 -387.603499)
			(xy 459.0804 -387.612118) (xy 459.05166 -387.612636) (xy 459.024413 -387.612091) (xy 458.970473 -387.604331)
			(xy 458.918187 -387.588973) (xy 458.868619 -387.566331) (xy 458.822777 -387.536866) (xy 458.781594 -387.501177)
			(xy 458.74591 -387.459991) (xy 458.716449 -387.414146) (xy 458.693813 -387.364575) (xy 458.678461 -387.312288)
			(xy 458.670706 -387.258347) (xy 457.434696 -387.258347) (xy 457.434696 -387.346952) (xy 457.441808 -387.364478)
			(xy 457.448412 -387.37159) (xy 457.467697 -387.392905) (xy 457.500263 -387.440269) (xy 457.525354 -387.491984)
			(xy 457.542401 -387.546878) (xy 457.551018 -387.603708) (xy 457.551536 -387.632448) (xy 457.551061 -387.659007)
			(xy 457.543703 -387.711613) (xy 457.529123 -387.762691) (xy 457.507601 -387.811254) (xy 457.479554 -387.856364)
			(xy 457.46289 -387.87705) (xy 457.45654 -387.884416) (xy 457.450698 -387.90245) (xy 457.454508 -387.989826)
			(xy 457.462128 -388.007098) (xy 457.468732 -388.013956) (xy 457.489405 -388.035575) (xy 457.524504 -388.084004)
			(xy 457.542741 -388.119874) (xy 457.846428 -388.119874) (xy 457.850499 -388.064252) (xy 457.862625 -388.009815)
			(xy 457.882548 -387.957724) (xy 457.909844 -387.909089) (xy 457.94393 -387.864946) (xy 457.984079 -387.826237)
			(xy 458.029437 -387.793786) (xy 458.079037 -387.768285) (xy 458.131821 -387.750278) (xy 458.186664 -387.740148)
			(xy 458.242398 -387.738111) (xy 458.297835 -387.744211) (xy 458.351792 -387.758317) (xy 458.403121 -387.780129)
			(xy 458.450727 -387.809183) (xy 458.493595 -387.844858) (xy 458.530812 -387.886395) (xy 458.561585 -387.932908)
			(xy 458.585257 -387.983405) (xy 458.601325 -388.036812) (xy 458.609445 -388.091988) (xy 458.609954 -388.119874)
			(xy 458.609445 -388.14776) (xy 458.601325 -388.202936) (xy 458.585257 -388.256343) (xy 458.561585 -388.30684)
			(xy 458.530812 -388.353353) (xy 458.493595 -388.39489) (xy 458.450727 -388.430565) (xy 458.403121 -388.459619)
			(xy 458.351792 -388.481431) (xy 458.297835 -388.495537) (xy 458.242398 -388.501637) (xy 458.186664 -388.4996)
			(xy 458.131821 -388.48947) (xy 458.079037 -388.471463) (xy 458.029437 -388.445962) (xy 457.984079 -388.413511)
			(xy 457.94393 -388.374802) (xy 457.909844 -388.330659) (xy 457.882548 -388.282024) (xy 457.862625 -388.229933)
			(xy 457.850499 -388.175496) (xy 457.846428 -388.119874) (xy 457.542741 -388.119874) (xy 457.551611 -388.137319)
			(xy 457.570061 -388.194213) (xy 457.5794 -388.253291) (xy 457.579984 -388.283196) (xy 457.579541 -388.31045)
			(xy 457.571784 -388.364403) (xy 457.556427 -388.416702) (xy 457.533783 -388.466284) (xy 457.504313 -388.512138)
			(xy 457.468618 -388.553332) (xy 457.427422 -388.589025) (xy 457.381567 -388.618493) (xy 457.331984 -388.641134)
			(xy 457.279683 -388.656488) (xy 457.22573 -388.664242) (xy 457.198476 -388.664704) (xy 457.171906 -388.664233)
			(xy 457.119283 -388.656837) (xy 457.068197 -388.642205) (xy 457.019637 -388.620622) (xy 456.974545 -388.592504)
			(xy 456.953874 -388.575804) (xy 456.946508 -388.569708) (xy 456.928982 -388.563866) (xy 456.84186 -388.566914)
			(xy 456.824842 -388.57428) (xy 456.817984 -388.580884) (xy 456.796502 -388.600972) (xy 456.748506 -388.634959)
			(xy 456.695863 -388.66118) (xy 456.639821 -388.679013) (xy 456.581706 -388.688037) (xy 456.5523 -388.68858)
			(xy 456.524869 -388.688153) (xy 456.470576 -388.680275) (xy 456.417969 -388.66471) (xy 456.36813 -388.641778)
			(xy 456.322085 -388.611952) (xy 456.280781 -388.575844) (xy 456.245068 -388.534198) (xy 456.229974 -388.511288)
			(xy 456.223116 -388.500366) (xy 456.200764 -388.48792) (xy 456.09002 -388.486142) (xy 456.067414 -388.497826)
			(xy 456.060048 -388.508748) (xy 456.044731 -388.530502) (xy 456.009069 -388.569982) (xy 455.968269 -388.604127)
			(xy 455.923123 -388.632275) (xy 455.874505 -388.65388) (xy 455.823358 -388.668523) (xy 455.770673 -388.675922)
			(xy 455.744072 -388.676388) (xy 455.716819 -388.675948) (xy 455.662869 -388.668187) (xy 455.610572 -388.652828)
			(xy 455.560993 -388.630182) (xy 455.515142 -388.600711) (xy 455.473952 -388.565014) (xy 455.43826 -388.523819)
			(xy 455.408795 -388.477965) (xy 455.386156 -388.428383) (xy 455.370802 -388.376084) (xy 455.363048 -388.322133)
			(xy 455.362564 -388.29488) (xy 455.363074 -388.265401) (xy 455.372148 -388.207146) (xy 455.390076 -388.15098)
			(xy 455.416433 -388.098241) (xy 455.450589 -388.050185) (xy 455.470768 -388.028688) (xy 455.47788 -388.021322)
			(xy 455.485246 -388.003034) (xy 455.485246 -387.912102) (xy 455.477626 -387.893814) (xy 455.470768 -387.886702)
			(xy 455.450437 -387.865202) (xy 455.416059 -387.817042) (xy 455.389529 -387.764151) (xy 455.371483 -387.707798)
			(xy 455.362355 -387.649334) (xy 455.361802 -387.619748) (xy 452.503953 -387.619748) (xy 452.510938 -387.668071)
			(xy 452.511414 -387.69544) (xy 452.510874 -387.723834) (xy 452.502458 -387.779995) (xy 452.485804 -387.834286)
			(xy 452.46128 -387.885505) (xy 452.429428 -387.932519) (xy 452.410576 -387.953758) (xy 452.404226 -387.960616)
			(xy 452.397368 -387.977888) (xy 452.396098 -388.064248) (xy 452.402194 -388.08152) (xy 452.408544 -388.088632)
			(xy 452.425852 -388.109521) (xy 452.455038 -388.155246) (xy 452.47745 -388.204647) (xy 452.492635 -388.256725)
			(xy 452.500286 -388.310429) (xy 452.500746 -388.337552) (xy 452.50026 -388.364803) (xy 452.492504 -388.418751)
			(xy 452.477149 -388.471046) (xy 452.454507 -388.520623) (xy 452.425041 -388.566473) (xy 452.38935 -388.607664)
			(xy 452.348159 -388.643355) (xy 452.302309 -388.672821) (xy 452.252732 -388.695463) (xy 452.200437 -388.710818)
			(xy 452.146489 -388.718574) (xy 452.091987 -388.718574) (xy 452.038039 -388.710818) (xy 451.985744 -388.695463)
			(xy 451.936167 -388.672821) (xy 451.890317 -388.643355) (xy 451.849126 -388.607664) (xy 451.813435 -388.566473)
			(xy 451.783969 -388.520623) (xy 451.761327 -388.471046) (xy 451.745972 -388.418751) (xy 451.738216 -388.364803)
			(xy 451.73773 -388.337552) (xy 451.738128 -388.312092) (xy 451.744897 -388.261624) (xy 451.758321 -388.212505)
			(xy 451.778162 -388.16561) (xy 451.804066 -388.121772) (xy 451.835573 -388.08177) (xy 451.853554 -388.06374)
			(xy 451.860334 -388.056435) (xy 451.86817 -388.038128) (xy 451.868794 -388.02818) (xy 451.869556 -387.996176)
			(xy 451.869232 -387.98619) (xy 451.861915 -387.967623) (xy 451.855332 -387.960108) (xy 451.84314 -387.9469)
			(xy 451.835578 -387.93903) (xy 451.815692 -387.930084) (xy 451.804786 -387.929628) (xy 451.728586 -387.929628)
			(xy 451.717691 -387.930128) (xy 451.697822 -387.939068) (xy 451.690232 -387.9469) (xy 451.672054 -387.966953)
			(xy 451.630995 -388.002217) (xy 451.58536 -388.031318) (xy 451.536067 -388.05367) (xy 451.484108 -388.068825)
			(xy 451.430528 -388.076477) (xy 451.403466 -388.076948) (xy 451.374727 -388.076432) (xy 451.3179 -388.067806)
			(xy 451.263009 -388.050753) (xy 451.211298 -388.02566) (xy 451.163935 -387.993095) (xy 451.142608 -387.973824)
			(xy 451.135496 -387.96722) (xy 451.11797 -387.960108) (xy 451.028562 -387.960108) (xy 451.011036 -387.96722)
			(xy 451.003924 -387.973824) (xy 450.982605 -387.993105) (xy 450.935242 -388.025671) (xy 450.883528 -388.050762)
			(xy 450.828635 -388.06781) (xy 450.771806 -388.076429) (xy 450.743066 -388.076948) (xy 450.715816 -388.076454)
			(xy 450.66187 -388.068694) (xy 450.609578 -388.053336) (xy 450.560004 -388.030694) (xy 450.514155 -388.001228)
			(xy 450.472966 -387.965538) (xy 450.437275 -387.92435) (xy 450.407809 -387.878502) (xy 450.385166 -387.828927)
			(xy 450.369807 -387.776635) (xy 450.362046 -387.72269) (xy 450.361558 -387.69544) (xy 450.362033 -387.66807)
			(xy 450.369847 -387.613891) (xy 450.385333 -387.561387) (xy 450.408173 -387.51164) (xy 450.437897 -387.465673)
			(xy 450.455538 -387.444742) (xy 450.461634 -387.43763) (xy 450.467984 -387.420612) (xy 450.467984 -387.335268)
			(xy 450.461634 -387.31825) (xy 450.455538 -387.311138) (xy 450.437909 -387.290198) (xy 450.408194 -387.244228)
			(xy 450.385356 -387.194482) (xy 450.369863 -387.141983) (xy 450.362033 -387.087809) (xy 450.361558 -387.06044)
			(xy 450.362056 -387.0317) (xy 450.370687 -386.974872) (xy 450.387744 -386.919982) (xy 450.41284 -386.86827)
			(xy 450.44541 -386.820909) (xy 450.464682 -386.799582) (xy 450.47154 -386.792216) (xy 450.478398 -386.774436)
			(xy 450.477636 -386.684266) (xy 450.47027 -386.666232) (xy 450.463158 -386.65912) (xy 450.442931 -386.637621)
			(xy 450.408707 -386.589528) (xy 450.382299 -386.536738) (xy 450.364337 -386.480511) (xy 450.35525 -386.422187)
			(xy 450.3547 -386.392674) (xy 450.18508 -386.392674) (xy 450.177797 -386.441828) (xy 450.16149 -386.495614)
			(xy 450.137467 -386.546424) (xy 450.106249 -386.59316) (xy 450.06851 -386.634808) (xy 450.047106 -386.653024)
			(xy 450.03847 -386.660136) (xy 450.028818 -386.680202) (xy 450.027294 -386.780532) (xy 450.036438 -386.800598)
			(xy 450.045074 -386.808218) (xy 450.065287 -386.826445) (xy 450.100884 -386.867614) (xy 450.130271 -386.913424)
			(xy 450.152851 -386.962944) (xy 450.168167 -387.015169) (xy 450.175906 -387.069041) (xy 450.176392 -387.096254)
			(xy 450.175903 -387.124994) (xy 450.167272 -387.181823) (xy 450.150214 -387.236714) (xy 450.125115 -387.288426)
			(xy 450.092542 -387.335786) (xy 450.073268 -387.357112) (xy 450.066664 -387.364224) (xy 450.059552 -387.38175)
			(xy 450.059552 -387.471158) (xy 450.066664 -387.488684) (xy 450.073268 -387.495796) (xy 450.092565 -387.5171)
			(xy 450.125128 -387.564468) (xy 450.150215 -387.616186) (xy 450.167259 -387.671082) (xy 450.175875 -387.727913)
			(xy 450.176392 -387.756654) (xy 450.175902 -387.783906) (xy 450.168151 -387.837857) (xy 450.1528 -387.890156)
			(xy 450.130161 -387.939737) (xy 450.100697 -387.985591) (xy 450.065006 -388.026784) (xy 450.023815 -388.062479)
			(xy 449.977963 -388.091947) (xy 449.928384 -388.114589) (xy 449.876087 -388.129944) (xy 449.822136 -388.1377)
			(xy 449.794884 -388.138162) (xy 449.769022 -388.137724) (xy 449.717771 -388.13074) (xy 449.667935 -388.11689)
			(xy 449.620431 -388.096427) (xy 449.57613 -388.069728) (xy 449.535847 -388.037283) (xy 449.51777 -388.018782)
			(xy 449.510244 -388.011554) (xy 449.491108 -388.003288) (xy 449.480686 -388.00278) (xy 449.448682 -388.00278)
			(xy 449.43825 -388.003245) (xy 449.419097 -388.011514) (xy 449.411598 -388.018782) (xy 449.407534 -388.0231)
			(xy 449.400168 -388.030466) (xy 449.392802 -388.04977) (xy 449.39585 -388.14375) (xy 449.404486 -388.162546)
			(xy 449.41236 -388.169404) (xy 449.431867 -388.187546) (xy 449.466085 -388.228374) (xy 449.494285 -388.27357)
			(xy 449.515917 -388.322252) (xy 449.530559 -388.373472) (xy 449.537926 -388.426232) (xy 449.538344 -388.452868)
			(xy 449.537792 -388.480117) (xy 449.530041 -388.53406) (xy 449.514692 -388.586352) (xy 449.492057 -388.635926)
			(xy 449.462597 -388.681775) (xy 449.426913 -388.722965) (xy 449.385729 -388.758657) (xy 449.339886 -388.788124)
			(xy 449.290315 -388.810768) (xy 449.238027 -388.826126) (xy 449.184085 -388.833887) (xy 449.156836 -388.834376)
			(xy 449.12792 -388.833841) (xy 449.070749 -388.825117) (xy 449.01555 -388.807863) (xy 448.963588 -388.782474)
			(xy 448.916054 -388.749533) (xy 448.874036 -388.709794) (xy 448.855846 -388.68731) (xy 448.848258 -388.678575)
			(xy 448.827519 -388.668376) (xy 448.815968 -388.667752) (xy 448.735704 -388.667752) (xy 448.724134 -388.668307)
			(xy 448.703362 -388.678511) (xy 448.695826 -388.68731) (xy 448.677623 -388.709783) (xy 448.635605 -388.749519)
			(xy 448.588073 -388.782458) (xy 448.536114 -388.807848) (xy 448.480919 -388.825107) (xy 448.423751 -388.833839)
			(xy 448.394836 -388.834376) (xy 448.367583 -388.833911) (xy 448.31363 -388.826158) (xy 448.26133 -388.810805)
			(xy 448.211748 -388.788164) (xy 448.165893 -388.758697) (xy 448.124699 -388.723003) (xy 448.089005 -388.68181)
			(xy 448.059537 -388.635955) (xy 448.036896 -388.586374) (xy 448.021543 -388.534074) (xy 448.013789 -388.480121)
			(xy 448.013328 -388.452868) (xy 448.013848 -388.423354) (xy 448.022944 -388.36503) (xy 448.040916 -388.308804)
			(xy 448.067333 -388.256017) (xy 448.101565 -388.207928) (xy 448.121786 -388.186422) (xy 448.129152 -388.179056)
			(xy 448.136518 -388.159752) (xy 448.13347 -388.065772) (xy 448.124834 -388.046976) (xy 448.11696 -388.040118)
			(xy 448.097468 -388.021961) (xy 448.063247 -387.981136) (xy 448.035045 -387.935944) (xy 448.013411 -387.887265)
			(xy 447.998766 -387.836047) (xy 447.991395 -387.783289) (xy 447.990976 -387.756654) (xy 447.991478 -387.727914)
			(xy 448.000107 -387.671086) (xy 448.017162 -387.616196) (xy 448.042259 -387.564484) (xy 448.074828 -387.517122)
			(xy 448.0941 -387.495796) (xy 448.100704 -387.488684) (xy 448.107816 -387.471158) (xy 448.107816 -387.38175)
			(xy 448.100704 -387.364224) (xy 448.0941 -387.357112) (xy 448.074818 -387.335794) (xy 448.042251 -387.288431)
			(xy 448.01716 -387.236717) (xy 448.000112 -387.181824) (xy 447.991494 -387.124994) (xy 447.990976 -387.096254)
			(xy 447.991473 -387.068151) (xy 447.999713 -387.012554) (xy 448.016023 -386.958767) (xy 448.04005 -386.907956)
			(xy 448.071273 -386.861222) (xy 448.109016 -386.819575) (xy 448.130422 -386.80136) (xy 448.139058 -386.794248)
			(xy 448.14871 -386.774182) (xy 448.150234 -386.673852) (xy 448.14109 -386.653786) (xy 448.132454 -386.646166)
			(xy 448.112239 -386.627941) (xy 448.076641 -386.586772) (xy 448.047253 -386.540963) (xy 448.024673 -386.491442)
			(xy 448.009359 -386.439215) (xy 448.001621 -386.385343) (xy 448.001136 -386.35813) (xy 448.001696 -386.329072)
			(xy 448.010524 -386.27163) (xy 448.027966 -386.216192) (xy 448.053618 -386.164043) (xy 448.086885 -386.11639)
			(xy 448.106546 -386.094986) (xy 448.11315 -386.087874) (xy 448.120516 -386.06984) (xy 448.120516 -385.979924)
			(xy 448.11315 -385.96189) (xy 448.106546 -385.954778) (xy 448.086865 -385.93339) (xy 448.053587 -385.885739)
			(xy 448.027932 -385.833586) (xy 448.010495 -385.778143) (xy 448.001679 -385.720695) (xy 448.001136 -385.691634)
			(xy 448.001606 -385.664934) (xy 448.009054 -385.612055) (xy 448.023807 -385.560733) (xy 448.045578 -385.511973)
			(xy 448.073941 -385.466727) (xy 448.090798 -385.446016) (xy 448.096894 -385.43865) (xy 448.10299 -385.420616)
			(xy 448.09918 -385.332986) (xy 448.09156 -385.31546) (xy 448.084956 -385.308856) (xy 448.064171 -385.287243)
			(xy 448.028912 -385.238746) (xy 448.001679 -385.185329) (xy 447.98314 -385.128308) (xy 447.973755 -385.069088)
			(xy 447.973196 -385.039108) (xy 439.466736 -385.039108) (xy 439.466736 -386.394706) (xy 442.279024 -386.394706)
			(xy 442.279461 -386.367452) (xy 442.287218 -386.313498) (xy 442.302575 -386.261198) (xy 442.325219 -386.211616)
			(xy 442.354689 -386.165761) (xy 442.390386 -386.124568) (xy 442.431582 -386.088874) (xy 442.477439 -386.059407)
			(xy 442.527022 -386.036766) (xy 442.579324 -386.021412) (xy 442.633278 -386.013659) (xy 442.660532 -386.013198)
			(xy 442.687801 -386.013699) (xy 442.741781 -386.02148) (xy 442.794103 -386.036866) (xy 442.843704 -386.059542)
			(xy 442.889571 -386.089047) (xy 442.930772 -386.124781) (xy 442.966467 -386.166015) (xy 442.981588 -386.188712)
			(xy 442.989127 -386.198999) (xy 443.011525 -386.21113) (xy 443.02426 -386.211826) (xy 443.055756 -386.211826)
			(xy 443.06422 -386.211559) (xy 443.080231 -386.20607) (xy 443.093566 -386.195646) (xy 443.098428 -386.188712)
			(xy 443.118748 -386.16001) (xy 443.12459 -386.152644) (xy 443.129924 -386.134356) (xy 443.123066 -386.04698)
			(xy 443.114938 -386.029708) (xy 443.107826 -386.023358) (xy 443.089012 -386.005256) (xy 443.056035 -385.96478)
			(xy 443.028882 -385.920186) (xy 443.008061 -385.872308) (xy 442.993959 -385.822039) (xy 442.986841 -385.770317)
			(xy 442.986414 -385.744212) (xy 442.986867 -385.716958) (xy 442.994622 -385.663006) (xy 443.009978 -385.610707)
			(xy 443.032621 -385.561125) (xy 443.06209 -385.515271) (xy 443.097785 -385.474077) (xy 443.138979 -385.438384)
			(xy 443.184834 -385.408916) (xy 443.234416 -385.386275) (xy 443.286716 -385.37092) (xy 443.340668 -385.363166)
			(xy 443.367922 -385.362704) (xy 443.394158 -385.363146) (xy 443.446135 -385.370344) (xy 443.496634 -385.384602)
			(xy 443.5447 -385.405649) (xy 443.589427 -385.433089) (xy 443.629968 -385.466403) (xy 443.648084 -385.485386)
			(xy 443.65545 -385.493006) (xy 443.6745 -385.501642) (xy 443.769496 -385.502404) (xy 443.7888 -385.494276)
			(xy 443.796166 -385.486656) (xy 443.814239 -385.468464) (xy 443.854381 -385.436556) (xy 443.898434 -385.41031)
			(xy 443.945606 -385.390201) (xy 443.995046 -385.37659) (xy 444.045863 -385.369723) (xy 444.071502 -385.369308)
			(xy 444.097485 -385.369722) (xy 444.148968 -385.376788) (xy 444.199017 -385.390774) (xy 444.246704 -385.411422)
			(xy 444.291149 -385.43835) (xy 444.331529 -385.471061) (xy 444.349632 -385.489704) (xy 444.357159 -385.496931)
			(xy 444.376294 -385.505198) (xy 444.386716 -385.505706) (xy 444.460884 -385.505706) (xy 444.471315 -385.505227)
			(xy 444.490468 -385.496968) (xy 444.497968 -385.489704) (xy 444.516083 -385.471073) (xy 444.556457 -385.438359)
			(xy 444.600899 -385.41143) (xy 444.648585 -385.390784) (xy 444.698633 -385.376803) (xy 444.750116 -385.369748)
			(xy 444.776098 -385.369308) (xy 444.803352 -385.369757) (xy 444.857304 -385.377514) (xy 444.909603 -385.392871)
			(xy 444.959184 -385.415514) (xy 445.005038 -385.444984) (xy 445.046231 -385.480679) (xy 445.081925 -385.521873)
			(xy 445.111392 -385.567728) (xy 445.134034 -385.61731) (xy 445.149389 -385.66961) (xy 445.157144 -385.723562)
			(xy 445.157606 -385.750816) (xy 445.157128 -385.77795) (xy 445.149441 -385.831671) (xy 445.134212 -385.883758)
			(xy 445.111748 -385.933158) (xy 445.082504 -385.978871) (xy 445.06515 -385.999736) (xy 445.059054 -386.006848)
			(xy 445.052704 -386.02412) (xy 445.053974 -386.110226) (xy 445.060832 -386.127244) (xy 445.066928 -386.134356)
			(xy 445.085435 -386.155533) (xy 445.116711 -386.202273) (xy 445.140793 -386.253095) (xy 445.157162 -386.3069)
			(xy 445.165462 -386.362523) (xy 445.165988 -386.390642) (xy 445.165412 -386.419767) (xy 445.156552 -386.477339)
			(xy 445.139044 -386.532895) (xy 445.113296 -386.585145) (xy 445.079906 -386.632874) (xy 445.039649 -386.674974)
			(xy 445.01689 -386.693156) (xy 445.007492 -386.700268) (xy 444.997078 -386.721604) (xy 444.997586 -386.826252)
			(xy 445.008 -386.847588) (xy 445.017652 -386.8547) (xy 445.040752 -386.872847) (xy 445.081617 -386.915042)
			(xy 445.115533 -386.963003) (xy 445.141697 -387.015595) (xy 445.159491 -387.071575) (xy 445.168495 -387.129622)
			(xy 445.169036 -387.158992) (xy 445.168581 -387.186363) (xy 445.160763 -387.240543) (xy 445.145272 -387.293047)
			(xy 445.122427 -387.342794) (xy 445.092699 -387.388759) (xy 445.075056 -387.40969) (xy 445.06896 -387.416802)
			(xy 445.06261 -387.43382) (xy 445.06261 -387.519164) (xy 445.06896 -387.536182) (xy 445.075056 -387.543294)
			(xy 445.09269 -387.564233) (xy 445.122416 -387.610199) (xy 445.145263 -387.659944) (xy 445.16076 -387.712446)
			(xy 445.16859 -387.766624) (xy 445.168591 -387.821364) (xy 445.160763 -387.875543) (xy 445.145267 -387.928044)
			(xy 445.122422 -387.97779) (xy 445.092697 -388.023758) (xy 445.075056 -388.04469) (xy 445.06896 -388.051802)
			(xy 445.06261 -388.06882) (xy 445.06261 -388.154164) (xy 445.06896 -388.171182) (xy 445.075056 -388.178294)
			(xy 445.092699 -388.199223) (xy 445.122412 -388.245196) (xy 445.145248 -388.294944) (xy 445.160738 -388.347446)
			(xy 445.168564 -388.401623) (xy 445.169036 -388.428992) (xy 445.168515 -388.456242) (xy 445.16076 -388.510187)
			(xy 445.145407 -388.562479) (xy 445.122769 -388.612055) (xy 445.093306 -388.657904) (xy 445.057619 -388.699093)
			(xy 445.016432 -388.734785) (xy 444.970586 -388.764252) (xy 444.921013 -388.786895) (xy 444.868722 -388.802253)
			(xy 444.814778 -388.810012) (xy 444.787528 -388.8105) (xy 444.761546 -388.810064) (xy 444.710064 -388.803002)
			(xy 444.660016 -388.78902) (xy 444.612328 -388.768376) (xy 444.567883 -388.741452) (xy 444.527502 -388.708746)
			(xy 444.509398 -388.690104) (xy 444.501859 -388.682891) (xy 444.482733 -388.674616) (xy 444.472314 -388.674102)
			(xy 444.398146 -388.674102) (xy 444.387711 -388.674541) (xy 444.368558 -388.682828) (xy 444.361062 -388.690104)
			(xy 444.342982 -388.70877) (xy 444.3026 -388.741481) (xy 444.258151 -388.768405) (xy 444.210458 -388.789045)
			(xy 444.160404 -388.803018) (xy 444.108916 -388.810065) (xy 444.082932 -388.8105) (xy 444.05568 -388.810015)
			(xy 444.001729 -388.802262) (xy 443.949431 -388.78691) (xy 443.899851 -388.76427) (xy 443.853997 -388.734805)
			(xy 443.812804 -388.699113) (xy 443.777109 -388.657922) (xy 443.747641 -388.612071) (xy 443.724999 -388.562491)
			(xy 443.709643 -388.510194) (xy 443.701887 -388.456244) (xy 443.701424 -388.428992) (xy 443.70188 -388.401621)
			(xy 443.709699 -388.347442) (xy 443.72519 -388.294938) (xy 443.748034 -388.245191) (xy 443.777762 -388.199225)
			(xy 443.795404 -388.178294) (xy 443.8015 -388.171182) (xy 443.80785 -388.154164) (xy 443.80785 -388.06882)
			(xy 443.8015 -388.051802) (xy 443.795404 -388.04469) (xy 443.777747 -388.023772) (xy 443.748038 -387.977795)
			(xy 443.725205 -387.928044) (xy 443.709718 -387.875541) (xy 443.701895 -387.821362) (xy 443.701424 -387.793992)
			(xy 443.701952 -387.764514) (xy 443.711023 -387.70626) (xy 443.728948 -387.650095) (xy 443.7553 -387.597356)
			(xy 443.789452 -387.549299) (xy 443.809628 -387.5278) (xy 443.816159 -387.520463) (xy 443.823606 -387.502304)
			(xy 443.824106 -387.492494) (xy 443.824106 -387.439154) (xy 443.81039 -387.425946) (xy 443.802262 -387.417564)
			(xy 443.780672 -387.40969) (xy 443.678818 -387.419596) (xy 443.65926 -387.431534) (xy 443.65291 -387.441186)
			(xy 443.637716 -387.463474) (xy 443.602042 -387.503932) (xy 443.561022 -387.538959) (xy 443.515476 -387.567856)
			(xy 443.466313 -387.590047) (xy 443.414513 -387.605089) (xy 443.36111 -387.612682) (xy 443.33414 -387.613144)
			(xy 443.3054 -387.612645) (xy 443.248572 -387.604015) (xy 443.193682 -387.586958) (xy 443.141971 -387.561861)
			(xy 443.094609 -387.529292) (xy 443.073282 -387.51002) (xy 443.06617 -387.503416) (xy 443.048644 -387.496304)
			(xy 442.959236 -387.496304) (xy 442.94171 -387.503416) (xy 442.934598 -387.51002) (xy 442.913248 -387.529265)
			(xy 442.865893 -387.561836) (xy 442.814187 -387.586934) (xy 442.759301 -387.603991) (xy 442.702478 -387.61262)
			(xy 442.67374 -387.613144) (xy 442.64649 -387.612608) (xy 442.592543 -387.604857) (xy 442.540249 -387.589508)
			(xy 442.490671 -387.566873) (xy 442.44482 -387.537412) (xy 442.403628 -387.501726) (xy 442.367933 -387.460541)
			(xy 442.338464 -387.414695) (xy 442.315819 -387.365122) (xy 442.300459 -387.312831) (xy 442.292698 -387.258886)
			(xy 442.292232 -387.231636) (xy 442.292795 -387.203509) (xy 442.30105 -387.147864) (xy 442.317387 -387.094035)
			(xy 442.341452 -387.043188) (xy 442.372723 -386.996426) (xy 442.410521 -386.954764) (xy 442.454028 -386.919103)
			(xy 442.477906 -386.90423) (xy 442.489844 -386.897118) (xy 442.503052 -386.87375) (xy 442.50102 -386.757926)
			(xy 442.487304 -386.734812) (xy 442.475112 -386.728208) (xy 442.450014 -386.713677) (xy 442.404186 -386.678139)
			(xy 442.364263 -386.636074) (xy 442.331165 -386.588453) (xy 442.305654 -386.536372) (xy 442.288319 -386.481031)
			(xy 442.279557 -386.423703) (xy 442.279024 -386.394706) (xy 439.466736 -386.394706) (xy 439.466736 -387.314948)
			(xy 439.466275 -387.339538) (xy 439.458572 -387.388111) (xy 439.443365 -387.43488) (xy 439.421027 -387.478694)
			(xy 439.392108 -387.518473) (xy 439.375042 -387.536182) (xy 438.772554 -388.13867) (xy 441.467492 -388.13867)
			(xy 441.471563 -388.083048) (xy 441.483689 -388.028611) (xy 441.503612 -387.97652) (xy 441.530908 -387.927885)
			(xy 441.564994 -387.883742) (xy 441.605143 -387.845033) (xy 441.650501 -387.812582) (xy 441.700101 -387.787081)
			(xy 441.752885 -387.769074) (xy 441.807728 -387.758944) (xy 441.863462 -387.756907) (xy 441.918899 -387.763007)
			(xy 441.972856 -387.777113) (xy 442.024185 -387.798925) (xy 442.071791 -387.827979) (xy 442.114659 -387.863654)
			(xy 442.151876 -387.905191) (xy 442.182649 -387.951704) (xy 442.206321 -388.002201) (xy 442.222389 -388.055608)
			(xy 442.230509 -388.110784) (xy 442.231018 -388.13867) (xy 442.230509 -388.166556) (xy 442.222389 -388.221732)
			(xy 442.206321 -388.275139) (xy 442.182649 -388.325636) (xy 442.151876 -388.372149) (xy 442.114659 -388.413686)
			(xy 442.071791 -388.449361) (xy 442.024185 -388.478415) (xy 441.972856 -388.500227) (xy 441.918899 -388.514333)
			(xy 441.863462 -388.520433) (xy 441.807728 -388.518396) (xy 441.752885 -388.508266) (xy 441.700101 -388.490259)
			(xy 441.650501 -388.464758) (xy 441.605143 -388.432307) (xy 441.564994 -388.393598) (xy 441.530908 -388.349455)
			(xy 441.503612 -388.30082) (xy 441.483689 -388.248729) (xy 441.471563 -388.194292) (xy 441.467492 -388.13867)
			(xy 438.772554 -388.13867) (xy 438.667652 -388.243572) (xy 438.660847 -388.250919) (xy 438.653132 -388.269382)
			(xy 438.652666 -388.279386) (xy 438.652666 -388.40918) (xy 438.652228 -388.419243) (xy 438.644489 -388.437823)
			(xy 438.63768 -388.445248) (xy 435.649273 -391.433655) (xy 438.176335 -391.433655) (xy 438.176335 -391.379145)
			(xy 438.184093 -391.32519) (xy 438.19945 -391.272888) (xy 438.222095 -391.223304) (xy 438.251566 -391.177448)
			(xy 438.287264 -391.136252) (xy 438.32846 -391.100557) (xy 438.374318 -391.071088) (xy 438.423903 -391.048445)
			(xy 438.476205 -391.033089) (xy 438.530161 -391.025334) (xy 438.557416 -391.024872) (xy 438.583782 -391.025269)
			(xy 438.636008 -391.032558) (xy 438.686734 -391.046966) (xy 438.734993 -391.068221) (xy 438.779867 -391.095916)
			(xy 438.820502 -391.129524) (xy 438.856123 -391.168407) (xy 438.886053 -391.211822) (xy 438.898284 -391.235184)
			(xy 438.904969 -391.24758) (xy 438.924002 -391.268328) (xy 438.947979 -391.283088) (xy 438.975075 -391.290738)
			(xy 439.003231 -391.290696) (xy 439.030304 -391.282964) (xy 439.054235 -391.268131) (xy 439.073206 -391.247326)
			(xy 439.079894 -391.23493) (xy 439.092167 -391.211565) (xy 439.122096 -391.168096) (xy 439.157728 -391.129165)
			(xy 439.198386 -391.095516) (xy 439.243291 -391.06779) (xy 439.291589 -391.046516) (xy 439.342358 -391.032099)
			(xy 439.394628 -391.024816) (xy 439.421016 -391.024364) (xy 439.448264 -391.024907) (xy 439.502206 -391.032665)
			(xy 439.554495 -391.04802) (xy 439.604067 -391.070661) (xy 439.649912 -391.100125) (xy 439.691097 -391.135814)
			(xy 439.726784 -391.177001) (xy 439.756247 -391.222847) (xy 439.778885 -391.27242) (xy 439.794238 -391.324709)
			(xy 439.801994 -391.378652) (xy 439.801994 -391.433148) (xy 439.794238 -391.487091) (xy 439.778885 -391.53938)
			(xy 439.756247 -391.588953) (xy 439.726784 -391.634799) (xy 439.691097 -391.675986) (xy 439.649912 -391.711675)
			(xy 439.604067 -391.741139) (xy 439.554495 -391.76378) (xy 439.502206 -391.779135) (xy 439.448264 -391.786893)
			(xy 439.421016 -391.78738) (xy 439.394652 -391.786928) (xy 439.34243 -391.779645) (xy 439.291707 -391.765243)
			(xy 439.243449 -391.743996) (xy 439.198575 -391.716308) (xy 439.157939 -391.682708) (xy 439.122316 -391.643833)
			(xy 439.092382 -391.600426) (xy 439.080148 -391.577068) (xy 439.073412 -391.564705) (xy 439.054384 -391.54397)
			(xy 439.030417 -391.529218) (xy 439.003333 -391.52157) (xy 438.97519 -391.521609) (xy 438.948127 -391.52933)
			(xy 438.924201 -391.544148) (xy 438.90523 -391.564935) (xy 438.898538 -391.577322) (xy 438.886339 -391.600728)
			(xy 438.856398 -391.644196) (xy 438.820754 -391.683123) (xy 438.780085 -391.716769) (xy 438.735169 -391.74449)
			(xy 438.686862 -391.765757) (xy 438.636085 -391.780166) (xy 438.583807 -391.787441) (xy 438.557416 -391.787888)
			(xy 438.530161 -391.787466) (xy 438.476205 -391.779711) (xy 438.423903 -391.764355) (xy 438.374318 -391.741712)
			(xy 438.32846 -391.712243) (xy 438.287264 -391.676548) (xy 438.251566 -391.635352) (xy 438.222095 -391.589496)
			(xy 438.19945 -391.539912) (xy 438.184093 -391.48761) (xy 438.176335 -391.433655) (xy 435.649273 -391.433655)
			(xy 433.00777 -394.075158) (xy 433.000404 -394.08227) (xy 432.992784 -394.101066) (xy 432.992784 -396.38097)
			(xy 432.992348 -396.391034) (xy 432.984614 -396.409619) (xy 432.977798 -396.417038) (xy 432.8033 -396.591536)
			(xy 432.79568 -396.601188) (xy 432.792886 -396.606014) (xy 432.790854 -396.611856) (xy 432.7906 -396.612364)
			(xy 432.782615 -396.635676) (xy 432.760349 -396.679633) (xy 432.73146 -396.71955) (xy 432.7144 -396.737332)
			(xy 432.321716 -397.130016) (xy 432.314906 -397.137361) (xy 432.307177 -397.155824) (xy 432.30673 -397.16583)
			(xy 432.30673 -397.835628) (xy 440.404248 -397.835628) (xy 440.408319 -397.780006) (xy 440.420445 -397.725569)
			(xy 440.440368 -397.673478) (xy 440.467664 -397.624843) (xy 440.50175 -397.5807) (xy 440.541899 -397.541991)
			(xy 440.587257 -397.50954) (xy 440.636857 -397.484039) (xy 440.689641 -397.466032) (xy 440.744484 -397.455902)
			(xy 440.800218 -397.453865) (xy 440.855655 -397.459965) (xy 440.909612 -397.474071) (xy 440.960941 -397.495883)
			(xy 441.008547 -397.524937) (xy 441.051415 -397.560612) (xy 441.088632 -397.602149) (xy 441.119405 -397.648662)
			(xy 441.143077 -397.699159) (xy 441.159145 -397.752566) (xy 441.167265 -397.807742) (xy 441.167774 -397.835628)
			(xy 441.167265 -397.863514) (xy 441.159145 -397.91869) (xy 441.145926 -397.962628) (xy 449.472048 -397.962628)
			(xy 449.476119 -397.907006) (xy 449.488245 -397.852569) (xy 449.508168 -397.800478) (xy 449.535464 -397.751843)
			(xy 449.56955 -397.7077) (xy 449.609699 -397.668991) (xy 449.655057 -397.63654) (xy 449.704657 -397.611039)
			(xy 449.757441 -397.593032) (xy 449.812284 -397.582902) (xy 449.868018 -397.580865) (xy 449.923455 -397.586965)
			(xy 449.977412 -397.601071) (xy 450.028741 -397.622883) (xy 450.076347 -397.651937) (xy 450.119215 -397.687612)
			(xy 450.156432 -397.729149) (xy 450.187205 -397.775662) (xy 450.210877 -397.826159) (xy 450.226945 -397.879566)
			(xy 450.235065 -397.934742) (xy 450.235574 -397.962628) (xy 450.235065 -397.990514) (xy 450.226945 -398.04569)
			(xy 450.210877 -398.099097) (xy 450.187205 -398.149594) (xy 450.156432 -398.196107) (xy 450.119215 -398.237644)
			(xy 450.076347 -398.273319) (xy 450.028741 -398.302373) (xy 449.977412 -398.324185) (xy 449.923455 -398.338291)
			(xy 449.868018 -398.344391) (xy 449.812284 -398.342354) (xy 449.757441 -398.332224) (xy 449.704657 -398.314217)
			(xy 449.655057 -398.288716) (xy 449.609699 -398.256265) (xy 449.56955 -398.217556) (xy 449.535464 -398.173413)
			(xy 449.508168 -398.124778) (xy 449.488245 -398.072687) (xy 449.476119 -398.01825) (xy 449.472048 -397.962628)
			(xy 441.145926 -397.962628) (xy 441.143077 -397.972097) (xy 441.119405 -398.022594) (xy 441.088632 -398.069107)
			(xy 441.051415 -398.110644) (xy 441.008547 -398.146319) (xy 440.960941 -398.175373) (xy 440.909612 -398.197185)
			(xy 440.855655 -398.211291) (xy 440.800218 -398.217391) (xy 440.744484 -398.215354) (xy 440.689641 -398.205224)
			(xy 440.636857 -398.187217) (xy 440.587257 -398.161716) (xy 440.541899 -398.129265) (xy 440.50175 -398.090556)
			(xy 440.467664 -398.046413) (xy 440.440368 -397.997778) (xy 440.420445 -397.945687) (xy 440.408319 -397.89125)
			(xy 440.404248 -397.835628) (xy 432.30673 -397.835628) (xy 432.30673 -398.737328) (xy 440.397136 -398.737328)
			(xy 440.401207 -398.681706) (xy 440.413333 -398.627269) (xy 440.433256 -398.575178) (xy 440.460552 -398.526543)
			(xy 440.494638 -398.4824) (xy 440.534787 -398.443691) (xy 440.580145 -398.41124) (xy 440.629745 -398.385739)
			(xy 440.682529 -398.367732) (xy 440.737372 -398.357602) (xy 440.793106 -398.355565) (xy 440.848543 -398.361665)
			(xy 440.9025 -398.375771) (xy 440.953829 -398.397583) (xy 441.001435 -398.426637) (xy 441.044303 -398.462312)
			(xy 441.08152 -398.503849) (xy 441.112293 -398.550362) (xy 441.135965 -398.600859) (xy 441.152033 -398.654266)
			(xy 441.160153 -398.709442) (xy 441.160662 -398.737328) (xy 441.160153 -398.765214) (xy 441.152033 -398.82039)
			(xy 441.138814 -398.864328) (xy 449.475858 -398.864328) (xy 449.479929 -398.808706) (xy 449.492055 -398.754269)
			(xy 449.511978 -398.702178) (xy 449.539274 -398.653543) (xy 449.57336 -398.6094) (xy 449.613509 -398.570691)
			(xy 449.658867 -398.53824) (xy 449.708467 -398.512739) (xy 449.761251 -398.494732) (xy 449.816094 -398.484602)
			(xy 449.871828 -398.482565) (xy 449.927265 -398.488665) (xy 449.981222 -398.502771) (xy 450.032551 -398.524583)
			(xy 450.080157 -398.553637) (xy 450.123025 -398.589312) (xy 450.160242 -398.630849) (xy 450.191015 -398.677362)
			(xy 450.214687 -398.727859) (xy 450.230755 -398.781266) (xy 450.238875 -398.836442) (xy 450.239384 -398.864328)
			(xy 450.238875 -398.892214) (xy 450.230755 -398.94739) (xy 450.214687 -399.000797) (xy 450.191015 -399.051294)
			(xy 450.160242 -399.097807) (xy 450.123025 -399.139344) (xy 450.080157 -399.175019) (xy 450.032551 -399.204073)
			(xy 449.981222 -399.225885) (xy 449.927265 -399.239991) (xy 449.871828 -399.246091) (xy 449.816094 -399.244054)
			(xy 449.761251 -399.233924) (xy 449.708467 -399.215917) (xy 449.658867 -399.190416) (xy 449.613509 -399.157965)
			(xy 449.57336 -399.119256) (xy 449.539274 -399.075113) (xy 449.511978 -399.026478) (xy 449.492055 -398.974387)
			(xy 449.479929 -398.91995) (xy 449.475858 -398.864328) (xy 441.138814 -398.864328) (xy 441.135965 -398.873797)
			(xy 441.112293 -398.924294) (xy 441.08152 -398.970807) (xy 441.044303 -399.012344) (xy 441.001435 -399.048019)
			(xy 440.953829 -399.077073) (xy 440.9025 -399.098885) (xy 440.848543 -399.112991) (xy 440.793106 -399.119091)
			(xy 440.737372 -399.117054) (xy 440.682529 -399.106924) (xy 440.629745 -399.088917) (xy 440.580145 -399.063416)
			(xy 440.534787 -399.030965) (xy 440.494638 -398.992256) (xy 440.460552 -398.948113) (xy 440.433256 -398.899478)
			(xy 440.413333 -398.847387) (xy 440.401207 -398.79295) (xy 440.397136 -398.737328) (xy 432.30673 -398.737328)
			(xy 432.30673 -399.2834) (xy 445.415396 -399.2834) (xy 445.419379 -399.230248) (xy 445.431241 -399.178283)
			(xy 445.450715 -399.128667) (xy 445.477367 -399.082508) (xy 445.510601 -399.040836) (xy 445.549675 -399.004584)
			(xy 445.593717 -398.974561) (xy 445.641741 -398.951438) (xy 445.692675 -398.935731) (xy 445.745381 -398.927791)
			(xy 445.772032 -398.92732) (xy 445.798392 -398.927815) (xy 445.850533 -398.9356) (xy 445.900956 -398.950994)
			(xy 445.948554 -398.973661) (xy 445.992286 -399.003103) (xy 446.012062 -399.020538) (xy 446.019174 -399.026888)
			(xy 446.036954 -399.033746) (xy 446.12433 -399.033746) (xy 446.14211 -399.026888) (xy 446.149222 -399.020538)
			(xy 446.169016 -399.003127) (xy 446.212754 -398.973702) (xy 446.260349 -398.95104) (xy 446.310763 -398.935634)
			(xy 446.362895 -398.92782) (xy 446.389252 -398.92732) (xy 446.415612 -398.927803) (xy 446.467754 -398.935591)
			(xy 446.518177 -398.950988) (xy 446.565775 -398.973657) (xy 446.609506 -399.003102) (xy 446.629282 -399.020538)
			(xy 446.636394 -399.026888) (xy 446.654174 -399.033746) (xy 446.74155 -399.033746) (xy 446.75933 -399.026888)
			(xy 446.766442 -399.020538) (xy 446.786228 -399.003117) (xy 446.829969 -398.973694) (xy 446.877566 -398.951034)
			(xy 446.927981 -398.93563) (xy 446.980115 -398.927819) (xy 447.006472 -398.92732) (xy 447.031468 -398.927745)
			(xy 447.080968 -398.93474) (xy 447.129005 -398.948582) (xy 447.174638 -398.968999) (xy 447.21697 -398.995592)
			(xy 447.236342 -399.011394) (xy 447.243454 -399.01749) (xy 447.259964 -399.023586) (xy 447.344038 -399.023586)
			(xy 447.360548 -399.01749) (xy 447.36766 -399.011394) (xy 447.387032 -398.995591) (xy 447.42936 -398.968989)
			(xy 447.474992 -398.948567) (xy 447.523031 -398.934727) (xy 447.572533 -398.92774) (xy 447.59753 -398.92732)
			(xy 447.624436 -398.927823) (xy 447.677639 -398.9359) (xy 447.72902 -398.951895) (xy 447.777406 -398.975444)
			(xy 447.821695 -399.00601) (xy 447.841624 -399.024094) (xy 447.848736 -399.030698) (xy 447.865754 -399.03781)
			(xy 447.953384 -399.039588) (xy 447.970656 -399.033238) (xy 447.978022 -399.026888) (xy 447.998965 -399.009317)
			(xy 448.044897 -398.979676) (xy 448.094591 -398.956895) (xy 448.147027 -398.941443) (xy 448.201133 -398.933634)
			(xy 448.228466 -398.933162) (xy 448.255718 -398.933683) (xy 448.309669 -398.941435) (xy 448.361966 -398.956787)
			(xy 448.411547 -398.979426) (xy 448.457401 -399.008891) (xy 448.498594 -399.044582) (xy 448.534289 -399.085772)
			(xy 448.563758 -399.131623) (xy 448.586401 -399.181202) (xy 448.601757 -399.233498) (xy 448.608933 -399.2834)
			(xy 454.494221 -399.2834) (xy 454.498203 -399.230259) (xy 454.51006 -399.178305) (xy 454.529528 -399.128698)
			(xy 454.556171 -399.082546) (xy 454.589394 -399.040881) (xy 454.628456 -399.004632) (xy 454.672484 -398.974609)
			(xy 454.720494 -398.951483) (xy 454.771415 -398.93577) (xy 454.824109 -398.927821) (xy 454.850754 -398.92732)
			(xy 454.877114 -398.927802) (xy 454.929257 -398.93559) (xy 454.979679 -398.950987) (xy 455.027277 -398.973657)
			(xy 455.071008 -399.003102) (xy 455.090784 -399.020538) (xy 455.097896 -399.026888) (xy 455.115676 -399.033746)
			(xy 455.203052 -399.033746) (xy 455.220832 -399.026888) (xy 455.227944 -399.020538) (xy 455.247729 -399.003116)
			(xy 455.29147 -398.973694) (xy 455.339067 -398.951033) (xy 455.389482 -398.93563) (xy 455.441616 -398.927819)
			(xy 455.467974 -398.92732) (xy 455.494335 -398.92779) (xy 455.546478 -398.935581) (xy 455.5969 -398.950981)
			(xy 455.644498 -398.973653) (xy 455.688228 -399.003101) (xy 455.708004 -399.020538) (xy 455.715116 -399.026888)
			(xy 455.732896 -399.033746) (xy 455.820272 -399.033746) (xy 455.838052 -399.026888) (xy 455.845164 -399.020538)
			(xy 455.864941 -399.003107) (xy 455.908684 -398.973685) (xy 455.956283 -398.951027) (xy 456.0067 -398.935626)
			(xy 456.058836 -398.927817) (xy 456.085194 -398.92732) (xy 456.11019 -398.927733) (xy 456.159691 -398.93473)
			(xy 456.207729 -398.948575) (xy 456.253361 -398.968996) (xy 456.295692 -398.995591) (xy 456.315064 -399.011394)
			(xy 456.322176 -399.01749) (xy 456.338686 -399.023586) (xy 456.42276 -399.023586) (xy 456.43927 -399.01749)
			(xy 456.446382 -399.011394) (xy 456.465746 -398.995581) (xy 456.508076 -398.96898) (xy 456.55371 -398.94856)
			(xy 456.601751 -398.934722) (xy 456.651255 -398.927738) (xy 456.676252 -398.92732) (xy 456.701833 -398.927781)
			(xy 456.75247 -398.935097) (xy 456.801538 -398.949585) (xy 456.848027 -398.970947) (xy 456.89098 -398.998743)
			(xy 456.929513 -399.032401) (xy 456.946508 -399.051526) (xy 456.952858 -399.059146) (xy 456.97013 -399.068036)
			(xy 457.059792 -399.076926) (xy 457.078334 -399.071338) (xy 457.086208 -399.065242) (xy 457.106427 -399.049888)
			(xy 457.150186 -399.024146) (xy 457.196972 -399.004433) (xy 457.245959 -398.991098) (xy 457.296281 -398.984375)
			(xy 457.321666 -398.983962) (xy 457.348918 -398.984483) (xy 457.402869 -398.992235) (xy 457.455166 -399.007587)
			(xy 457.504747 -399.030226) (xy 457.550601 -399.059691) (xy 457.591794 -399.095382) (xy 457.627489 -399.136572)
			(xy 457.656958 -399.182423) (xy 457.679601 -399.232002) (xy 457.694957 -399.284298) (xy 457.702715 -399.338248)
			(xy 457.702715 -399.392752) (xy 457.694957 -399.446702) (xy 457.679601 -399.498998) (xy 457.656958 -399.548577)
			(xy 457.627489 -399.594428) (xy 457.591794 -399.635618) (xy 457.550601 -399.671309) (xy 457.504747 -399.700774)
			(xy 457.455166 -399.723413) (xy 457.402869 -399.738765) (xy 457.348918 -399.746517) (xy 457.321666 -399.746978)
			(xy 457.292465 -399.746417) (xy 457.234744 -399.737518) (xy 457.179057 -399.719918) (xy 457.126706 -399.694029)
			(xy 457.078917 -399.660458) (xy 457.036808 -399.619989) (xy 457.018644 -399.597118) (xy 457.012548 -399.589244)
			(xy 456.996038 -399.579338) (xy 456.906884 -399.565622) (xy 456.888088 -399.56994) (xy 456.87996 -399.575528)
			(xy 456.857414 -399.59061) (xy 456.808731 -399.61453) (xy 456.756986 -399.630793) (xy 456.703373 -399.639024)
			(xy 456.676252 -399.639536) (xy 456.651257 -399.639084) (xy 456.601759 -399.632094) (xy 456.553722 -399.618257)
			(xy 456.508089 -399.597846) (xy 456.465756 -399.57126) (xy 456.446382 -399.555462) (xy 456.43927 -399.549366)
			(xy 456.42276 -399.54327) (xy 456.338686 -399.54327) (xy 456.322176 -399.549366) (xy 456.315064 -399.555462)
			(xy 456.29569 -399.571262) (xy 456.253362 -399.597863) (xy 456.207731 -399.618285) (xy 456.159692 -399.632126)
			(xy 456.11019 -399.639114) (xy 456.085194 -399.639536) (xy 456.058833 -399.639071) (xy 456.006691 -399.631277)
			(xy 455.956269 -399.615875) (xy 455.908672 -399.593202) (xy 455.86494 -399.563754) (xy 455.845164 -399.546318)
			(xy 455.838052 -399.539968) (xy 455.820272 -399.53311) (xy 455.732896 -399.53311) (xy 455.715116 -399.539968)
			(xy 455.708004 -399.546318) (xy 455.688233 -399.563757) (xy 455.644489 -399.593179) (xy 455.596888 -399.615836)
			(xy 455.54647 -399.631236) (xy 455.494333 -399.639041) (xy 455.467974 -399.639536) (xy 455.441615 -399.639023)
			(xy 455.389475 -399.63124) (xy 455.339054 -399.615849) (xy 455.291455 -399.593187) (xy 455.247722 -399.56375)
			(xy 455.227944 -399.546318) (xy 455.220832 -399.539968) (xy 455.203052 -399.53311) (xy 455.115676 -399.53311)
			(xy 455.097896 -399.539968) (xy 455.090784 -399.546318) (xy 455.070981 -399.563719) (xy 455.027246 -399.593146)
			(xy 454.979653 -399.615811) (xy 454.929242 -399.631219) (xy 454.87711 -399.639035) (xy 454.850754 -399.639536)
			(xy 454.824109 -399.638979) (xy 454.771415 -399.63103) (xy 454.720494 -399.615317) (xy 454.672484 -399.592191)
			(xy 454.628456 -399.562168) (xy 454.589394 -399.525919) (xy 454.556171 -399.484254) (xy 454.529528 -399.438102)
			(xy 454.51006 -399.388495) (xy 454.498203 -399.336541) (xy 454.494221 -399.2834) (xy 448.608933 -399.2834)
			(xy 448.609515 -399.287448) (xy 448.609515 -399.341952) (xy 448.601757 -399.395902) (xy 448.586401 -399.448198)
			(xy 448.563758 -399.497777) (xy 448.534289 -399.543628) (xy 448.498594 -399.584818) (xy 448.457401 -399.620509)
			(xy 448.411547 -399.649974) (xy 448.361966 -399.672613) (xy 448.309669 -399.687965) (xy 448.255718 -399.695717)
			(xy 448.228466 -399.696178) (xy 448.202545 -399.69574) (xy 448.151182 -399.688705) (xy 448.101244 -399.674782)
			(xy 448.05365 -399.654229) (xy 448.009276 -399.627422) (xy 447.968939 -399.594855) (xy 447.950844 -399.57629)
			(xy 447.94424 -399.569178) (xy 447.927476 -399.561304) (xy 447.840354 -399.554446) (xy 447.822574 -399.559526)
			(xy 447.814954 -399.565622) (xy 447.79142 -399.582994) (xy 447.739865 -399.610621) (xy 447.684487 -399.629448)
			(xy 447.626776 -399.638967) (xy 447.59753 -399.639536) (xy 447.572535 -399.639096) (xy 447.523036 -399.632103)
			(xy 447.474999 -399.618264) (xy 447.429367 -399.59785) (xy 447.387033 -399.571261) (xy 447.36766 -399.555462)
			(xy 447.360548 -399.549366) (xy 447.344038 -399.54327) (xy 447.259964 -399.54327) (xy 447.243454 -399.549366)
			(xy 447.236342 -399.555462) (xy 447.216976 -399.571273) (xy 447.174646 -399.597872) (xy 447.129012 -399.618291)
			(xy 447.080972 -399.63213) (xy 447.031469 -399.639116) (xy 447.006472 -399.639536) (xy 446.980113 -399.639024)
			(xy 446.927973 -399.631241) (xy 446.877551 -399.61585) (xy 446.829953 -399.593188) (xy 446.78622 -399.56375)
			(xy 446.766442 -399.546318) (xy 446.75933 -399.539968) (xy 446.74155 -399.53311) (xy 446.654174 -399.53311)
			(xy 446.636394 -399.539968) (xy 446.629282 -399.546318) (xy 446.60948 -399.56372) (xy 446.565744 -399.593147)
			(xy 446.518152 -399.615812) (xy 446.46774 -399.63122) (xy 446.415608 -399.639035) (xy 446.389252 -399.639536)
			(xy 446.362893 -399.639036) (xy 446.310752 -399.63125) (xy 446.26033 -399.615856) (xy 446.212732 -399.593191)
			(xy 446.168999 -399.563751) (xy 446.149222 -399.546318) (xy 446.14211 -399.539968) (xy 446.12433 -399.53311)
			(xy 446.036954 -399.53311) (xy 446.019174 -399.539968) (xy 446.012062 -399.546318) (xy 445.992268 -399.563729)
			(xy 445.94853 -399.593155) (xy 445.900935 -399.615818) (xy 445.850522 -399.631224) (xy 445.798389 -399.639036)
			(xy 445.772032 -399.639536) (xy 445.745381 -399.639009) (xy 445.692675 -399.631069) (xy 445.641741 -399.615362)
			(xy 445.593716 -399.592239) (xy 445.549675 -399.562216) (xy 445.510601 -399.525964) (xy 445.477367 -399.484292)
			(xy 445.450715 -399.438133) (xy 445.431241 -399.388517) (xy 445.419379 -399.336552) (xy 445.415396 -399.2834)
			(xy 432.30673 -399.2834) (xy 432.30673 -400.15287) (xy 447.338958 -400.15287) (xy 447.33945 -400.12562)
			(xy 447.34721 -400.071674) (xy 447.362567 -400.019381) (xy 447.385209 -399.969806) (xy 447.414675 -399.923958)
			(xy 447.450366 -399.882769) (xy 447.491554 -399.847078) (xy 447.537403 -399.817611) (xy 447.586978 -399.794968)
			(xy 447.63927 -399.77961) (xy 447.693216 -399.77185) (xy 447.720466 -399.771362) (xy 447.749383 -399.771881)
			(xy 447.806555 -399.780607) (xy 447.861755 -399.797863) (xy 447.913718 -399.823254) (xy 447.961251 -399.856199)
			(xy 448.003267 -399.895941) (xy 448.021456 -399.918428) (xy 448.029036 -399.92717) (xy 448.049781 -399.937363)
			(xy 448.061334 -399.937986) (xy 448.141598 -399.937986) (xy 448.153166 -399.937419) (xy 448.173937 -399.927222)
			(xy 448.181476 -399.918428) (xy 448.199688 -399.895962) (xy 448.241702 -399.856224) (xy 448.289233 -399.823282)
			(xy 448.34119 -399.797891) (xy 448.396384 -399.780631) (xy 448.453551 -399.771899) (xy 448.482466 -399.771362)
			(xy 448.509717 -399.771887) (xy 448.563664 -399.779638) (xy 448.615959 -399.794989) (xy 448.665537 -399.817625)
			(xy 448.711389 -399.847087) (xy 448.752581 -399.882774) (xy 448.788275 -399.92396) (xy 448.817744 -399.969807)
			(xy 448.840389 -400.019381) (xy 448.855748 -400.071674) (xy 448.863509 -400.125619) (xy 448.863649 -400.13382)
			(xy 449.300598 -400.13382) (xy 449.304669 -400.078198) (xy 449.316795 -400.023761) (xy 449.336718 -399.97167)
			(xy 449.364014 -399.923035) (xy 449.3981 -399.878892) (xy 449.438249 -399.840183) (xy 449.483607 -399.807732)
			(xy 449.533207 -399.782231) (xy 449.585991 -399.764224) (xy 449.640834 -399.754094) (xy 449.696568 -399.752057)
			(xy 449.752005 -399.758157) (xy 449.805962 -399.772263) (xy 449.857291 -399.794075) (xy 449.904897 -399.823129)
			(xy 449.947765 -399.858804) (xy 449.984982 -399.900341) (xy 450.015755 -399.946854) (xy 450.039427 -399.997351)
			(xy 450.055495 -400.050758) (xy 450.063615 -400.105934) (xy 450.064124 -400.13382) (xy 450.063615 -400.161706)
			(xy 450.057439 -400.20367) (xy 456.432158 -400.20367) (xy 456.43265 -400.17642) (xy 456.44041 -400.122474)
			(xy 456.455767 -400.070181) (xy 456.478409 -400.020606) (xy 456.507875 -399.974758) (xy 456.543566 -399.933569)
			(xy 456.584754 -399.897878) (xy 456.630603 -399.868411) (xy 456.680178 -399.845768) (xy 456.73247 -399.83041)
			(xy 456.786416 -399.82265) (xy 456.813666 -399.822162) (xy 456.842583 -399.822681) (xy 456.899755 -399.831407)
			(xy 456.954955 -399.848663) (xy 457.006918 -399.874054) (xy 457.054451 -399.906999) (xy 457.096467 -399.946741)
			(xy 457.114656 -399.969228) (xy 457.122236 -399.97797) (xy 457.142981 -399.988163) (xy 457.154534 -399.988786)
			(xy 457.234798 -399.988786) (xy 457.246366 -399.988219) (xy 457.267137 -399.978022) (xy 457.274676 -399.969228)
			(xy 457.292888 -399.946762) (xy 457.334902 -399.907024) (xy 457.382433 -399.874082) (xy 457.43439 -399.848691)
			(xy 457.489584 -399.831431) (xy 457.546751 -399.822699) (xy 457.575666 -399.822162) (xy 457.602917 -399.822687)
			(xy 457.656864 -399.830438) (xy 457.709159 -399.845789) (xy 457.758737 -399.868425) (xy 457.804589 -399.897887)
			(xy 457.845781 -399.933574) (xy 457.881475 -399.97476) (xy 457.910944 -400.020607) (xy 457.933589 -400.070181)
			(xy 457.948948 -400.122474) (xy 457.956709 -400.176419) (xy 457.957174 -400.20367) (xy 457.956772 -400.22936)
			(xy 457.949869 -400.280274) (xy 457.936196 -400.329801) (xy 457.916 -400.377046) (xy 457.889648 -400.421154)
			(xy 457.857616 -400.461326) (xy 457.820483 -400.496838) (xy 457.799948 -400.51228) (xy 457.788772 -400.520408)
			(xy 457.777596 -400.545808) (xy 457.791566 -400.661378) (xy 457.80833 -400.683476) (xy 457.821284 -400.688556)
			(xy 457.847233 -400.699707) (xy 457.895816 -400.728508) (xy 457.939623 -400.764156) (xy 457.977696 -400.805872)
			(xy 458.009205 -400.852744) (xy 458.03346 -400.903748) (xy 458.049932 -400.95777) (xy 458.058262 -401.013631)
			(xy 458.058774 -401.04187) (xy 458.058317 -401.069124) (xy 458.050563 -401.123077) (xy 458.035209 -401.175377)
			(xy 458.012567 -401.224959) (xy 457.983099 -401.270814) (xy 457.947405 -401.312008) (xy 457.906211 -401.347702)
			(xy 457.860355 -401.377169) (xy 457.810773 -401.39981) (xy 457.758473 -401.415164) (xy 457.70452 -401.422917)
			(xy 457.677266 -401.423378) (xy 457.64835 -401.422821) (xy 457.591181 -401.414101) (xy 457.535982 -401.396851)
			(xy 457.48402 -401.371467) (xy 457.436485 -401.33853) (xy 457.394467 -401.298795) (xy 457.376276 -401.276312)
			(xy 457.368718 -401.267546) (xy 457.347957 -401.257364) (xy 457.336398 -401.256754) (xy 457.256134 -401.256754)
			(xy 457.244566 -401.257325) (xy 457.223794 -401.267517) (xy 457.216256 -401.276312) (xy 457.198093 -401.298819)
			(xy 457.156067 -401.338552) (xy 457.108526 -401.371488) (xy 457.056559 -401.396872) (xy 457.001357 -401.414123)
			(xy 456.944184 -401.422846) (xy 456.915266 -401.423378) (xy 456.888013 -401.422954) (xy 456.834061 -401.415192)
			(xy 456.781763 -401.399831) (xy 456.732184 -401.377184) (xy 456.686332 -401.347711) (xy 456.645142 -401.312013)
			(xy 456.609451 -401.270816) (xy 456.579986 -401.22496) (xy 456.557347 -401.175377) (xy 456.541995 -401.123076)
			(xy 456.534242 -401.069124) (xy 456.533758 -401.04187) (xy 456.534176 -401.01618) (xy 456.541075 -400.965267)
			(xy 456.554745 -400.915739) (xy 456.574937 -400.868494) (xy 456.601286 -400.824386) (xy 456.633317 -400.784213)
			(xy 456.670449 -400.748702) (xy 456.690984 -400.73326) (xy 456.70216 -400.725132) (xy 456.713336 -400.699732)
			(xy 456.699366 -400.584162) (xy 456.682602 -400.562064) (xy 456.669648 -400.556984) (xy 456.643698 -400.545835)
			(xy 456.595119 -400.517029) (xy 456.551316 -400.481379) (xy 456.513245 -400.439663) (xy 456.481737 -400.392791)
			(xy 456.457481 -400.341788) (xy 456.441006 -400.287767) (xy 456.432673 -400.231908) (xy 456.432158 -400.20367)
			(xy 450.057439 -400.20367) (xy 450.055495 -400.216882) (xy 450.039427 -400.270289) (xy 450.015755 -400.320786)
			(xy 449.984982 -400.367299) (xy 449.947765 -400.408836) (xy 449.904897 -400.444511) (xy 449.857291 -400.473565)
			(xy 449.805962 -400.495377) (xy 449.752005 -400.509483) (xy 449.696568 -400.515583) (xy 449.640834 -400.513546)
			(xy 449.585991 -400.503416) (xy 449.533207 -400.485409) (xy 449.483607 -400.459908) (xy 449.438249 -400.427457)
			(xy 449.3981 -400.388748) (xy 449.364014 -400.344605) (xy 449.336718 -400.29597) (xy 449.316795 -400.243879)
			(xy 449.304669 -400.189442) (xy 449.300598 -400.13382) (xy 448.863649 -400.13382) (xy 448.863974 -400.15287)
			(xy 448.863572 -400.17856) (xy 448.856669 -400.229474) (xy 448.842996 -400.279001) (xy 448.8228 -400.326246)
			(xy 448.796448 -400.370354) (xy 448.764416 -400.410526) (xy 448.727283 -400.446038) (xy 448.706748 -400.46148)
			(xy 448.695572 -400.469608) (xy 448.684396 -400.495008) (xy 448.698366 -400.610578) (xy 448.71513 -400.632676)
			(xy 448.728084 -400.637756) (xy 448.754033 -400.648907) (xy 448.802616 -400.677708) (xy 448.846423 -400.713356)
			(xy 448.884496 -400.755072) (xy 448.916005 -400.801944) (xy 448.94026 -400.852948) (xy 448.956732 -400.90697)
			(xy 448.965062 -400.962831) (xy 448.965574 -400.99107) (xy 448.965117 -401.018324) (xy 448.957363 -401.072277)
			(xy 448.953672 -401.084848) (xy 452.907696 -401.084848) (xy 452.907696 -401.030352) (xy 452.915451 -400.976411)
			(xy 452.930803 -400.924123) (xy 452.95344 -400.874551) (xy 452.9829 -400.828705) (xy 453.018585 -400.787518)
			(xy 453.059768 -400.751828) (xy 453.10561 -400.722362) (xy 453.155179 -400.699719) (xy 453.207466 -400.684361)
			(xy 453.261406 -400.676599) (xy 453.288654 -400.67611) (xy 453.314407 -400.676537) (xy 453.365442 -400.683484)
			(xy 453.415079 -400.697231) (xy 453.462417 -400.717528) (xy 453.506596 -400.744006) (xy 453.546812 -400.776185)
			(xy 453.582336 -400.813479) (xy 453.597772 -400.834098) (xy 453.603868 -400.842226) (xy 453.620632 -400.85264)
			(xy 453.711056 -400.867626) (xy 453.73036 -400.863308) (xy 453.738742 -400.857466) (xy 453.763002 -400.840983)
			(xy 453.815524 -400.814883) (xy 453.871423 -400.797134) (xy 453.929381 -400.788154) (xy 453.958706 -400.787616)
			(xy 453.985959 -400.788054) (xy 454.039909 -400.795812) (xy 454.092206 -400.811169) (xy 454.141786 -400.833811)
			(xy 454.187639 -400.86328) (xy 454.228831 -400.898974) (xy 454.264524 -400.940166) (xy 454.293991 -400.986019)
			(xy 454.316634 -401.035599) (xy 454.331989 -401.087897) (xy 454.339746 -401.141847) (xy 454.339746 -401.196353)
			(xy 454.331989 -401.250303) (xy 454.316634 -401.302601) (xy 454.293991 -401.352181) (xy 454.264524 -401.398034)
			(xy 454.228831 -401.439226) (xy 454.187639 -401.47492) (xy 454.141786 -401.504389) (xy 454.092206 -401.527031)
			(xy 454.039909 -401.542388) (xy 453.985959 -401.550146) (xy 453.958706 -401.550632) (xy 453.932954 -401.550184)
			(xy 453.881919 -401.543244) (xy 453.832281 -401.529503) (xy 453.784942 -401.50921) (xy 453.740763 -401.482734)
			(xy 453.700546 -401.450557) (xy 453.665023 -401.413263) (xy 453.649588 -401.392644) (xy 453.643492 -401.384516)
			(xy 453.626728 -401.374102) (xy 453.536304 -401.359116) (xy 453.517 -401.363434) (xy 453.508618 -401.369276)
			(xy 453.484365 -401.385769) (xy 453.431841 -401.411869) (xy 453.375939 -401.429615) (xy 453.317979 -401.438591)
			(xy 453.288654 -401.439126) (xy 453.261406 -401.438601) (xy 453.207466 -401.430839) (xy 453.155179 -401.415481)
			(xy 453.10561 -401.392838) (xy 453.059768 -401.363372) (xy 453.018585 -401.327682) (xy 452.9829 -401.286495)
			(xy 452.95344 -401.240649) (xy 452.930803 -401.191077) (xy 452.915451 -401.138789) (xy 452.907696 -401.084848)
			(xy 448.953672 -401.084848) (xy 448.942009 -401.124577) (xy 448.919367 -401.174159) (xy 448.889899 -401.220014)
			(xy 448.854205 -401.261208) (xy 448.813011 -401.296902) (xy 448.767155 -401.326369) (xy 448.717573 -401.34901)
			(xy 448.665273 -401.364364) (xy 448.61132 -401.372117) (xy 448.584066 -401.372578) (xy 448.55515 -401.372021)
			(xy 448.497981 -401.363301) (xy 448.442782 -401.346051) (xy 448.39082 -401.320667) (xy 448.343285 -401.28773)
			(xy 448.301267 -401.247995) (xy 448.283076 -401.225512) (xy 448.275518 -401.216746) (xy 448.254757 -401.206564)
			(xy 448.243198 -401.205954) (xy 448.162934 -401.205954) (xy 448.151366 -401.206525) (xy 448.130594 -401.216717)
			(xy 448.123056 -401.225512) (xy 448.104893 -401.248019) (xy 448.062867 -401.287752) (xy 448.015326 -401.320688)
			(xy 447.963359 -401.346072) (xy 447.908157 -401.363323) (xy 447.850984 -401.372046) (xy 447.822066 -401.372578)
			(xy 447.794813 -401.372154) (xy 447.740861 -401.364392) (xy 447.688563 -401.349031) (xy 447.638984 -401.326384)
			(xy 447.593132 -401.296911) (xy 447.551942 -401.261213) (xy 447.516251 -401.220016) (xy 447.486786 -401.17416)
			(xy 447.464147 -401.124577) (xy 447.448795 -401.072276) (xy 447.441042 -401.018324) (xy 447.440558 -400.99107)
			(xy 447.440976 -400.96538) (xy 447.447875 -400.914467) (xy 447.461545 -400.864939) (xy 447.481737 -400.817694)
			(xy 447.508086 -400.773586) (xy 447.540117 -400.733413) (xy 447.577249 -400.697902) (xy 447.597784 -400.68246)
			(xy 447.60896 -400.674332) (xy 447.620136 -400.648932) (xy 447.606166 -400.533362) (xy 447.589402 -400.511264)
			(xy 447.576448 -400.506184) (xy 447.550498 -400.495035) (xy 447.501919 -400.466229) (xy 447.458116 -400.430579)
			(xy 447.420045 -400.388863) (xy 447.388537 -400.341991) (xy 447.364281 -400.290988) (xy 447.347806 -400.236967)
			(xy 447.339473 -400.181108) (xy 447.338958 -400.15287) (xy 432.30673 -400.15287) (xy 432.30673 -401.44192)
			(xy 440.397898 -401.44192) (xy 440.401969 -401.386298) (xy 440.414095 -401.331861) (xy 440.434018 -401.27977)
			(xy 440.461314 -401.231135) (xy 440.4954 -401.186992) (xy 440.535549 -401.148283) (xy 440.580907 -401.115832)
			(xy 440.630507 -401.090331) (xy 440.683291 -401.072324) (xy 440.738134 -401.062194) (xy 440.793868 -401.060157)
			(xy 440.849305 -401.066257) (xy 440.903262 -401.080363) (xy 440.954591 -401.102175) (xy 441.002197 -401.131229)
			(xy 441.025147 -401.150328) (xy 444.513714 -401.150328) (xy 444.517785 -401.094706) (xy 444.529911 -401.040269)
			(xy 444.549834 -400.988178) (xy 444.57713 -400.939543) (xy 444.611216 -400.8954) (xy 444.651365 -400.856691)
			(xy 444.696723 -400.82424) (xy 444.746323 -400.798739) (xy 444.799107 -400.780732) (xy 444.85395 -400.770602)
			(xy 444.909684 -400.768565) (xy 444.965121 -400.774665) (xy 445.019078 -400.788771) (xy 445.070407 -400.810583)
			(xy 445.118013 -400.839637) (xy 445.160881 -400.875312) (xy 445.198098 -400.916849) (xy 445.228871 -400.963362)
			(xy 445.252543 -401.013859) (xy 445.268611 -401.067266) (xy 445.276731 -401.122442) (xy 445.27724 -401.150328)
			(xy 445.276731 -401.178214) (xy 445.268611 -401.23339) (xy 445.252543 -401.286797) (xy 445.228871 -401.337294)
			(xy 445.198098 -401.383807) (xy 445.160881 -401.425344) (xy 445.118013 -401.461019) (xy 445.070407 -401.490073)
			(xy 445.019078 -401.511885) (xy 444.965121 -401.525991) (xy 444.909684 -401.532091) (xy 444.85395 -401.530054)
			(xy 444.799107 -401.519924) (xy 444.746323 -401.501917) (xy 444.696723 -401.476416) (xy 444.651365 -401.443965)
			(xy 444.611216 -401.405256) (xy 444.57713 -401.361113) (xy 444.549834 -401.312478) (xy 444.529911 -401.260387)
			(xy 444.517785 -401.20595) (xy 444.513714 -401.150328) (xy 441.025147 -401.150328) (xy 441.045065 -401.166904)
			(xy 441.082282 -401.208441) (xy 441.113055 -401.254954) (xy 441.136727 -401.305451) (xy 441.152795 -401.358858)
			(xy 441.160915 -401.414034) (xy 441.161424 -401.44192) (xy 441.160915 -401.469806) (xy 441.152795 -401.524982)
			(xy 441.136727 -401.578389) (xy 441.113055 -401.628886) (xy 441.082282 -401.675399) (xy 441.045065 -401.716936)
			(xy 441.002197 -401.752611) (xy 440.954591 -401.781665) (xy 440.903262 -401.803477) (xy 440.849305 -401.817583)
			(xy 440.793868 -401.823683) (xy 440.738134 -401.821646) (xy 440.683291 -401.811516) (xy 440.630507 -401.793509)
			(xy 440.580907 -401.768008) (xy 440.535549 -401.735557) (xy 440.4954 -401.696848) (xy 440.461314 -401.652705)
			(xy 440.434018 -401.60407) (xy 440.414095 -401.551979) (xy 440.401969 -401.497542) (xy 440.397898 -401.44192)
			(xy 432.30673 -401.44192) (xy 432.30673 -402.41982) (xy 440.683648 -402.41982) (xy 440.687719 -402.364198)
			(xy 440.699845 -402.309761) (xy 440.719768 -402.25767) (xy 440.747064 -402.209035) (xy 440.78115 -402.164892)
			(xy 440.821299 -402.126183) (xy 440.866657 -402.093732) (xy 440.916257 -402.068231) (xy 440.969041 -402.050224)
			(xy 441.023884 -402.040094) (xy 441.079618 -402.038057) (xy 441.135055 -402.044157) (xy 441.189012 -402.058263)
			(xy 441.240341 -402.080075) (xy 441.287947 -402.109129) (xy 441.330815 -402.144804) (xy 441.360569 -402.178012)
			(xy 443.299848 -402.178012) (xy 443.303919 -402.12239) (xy 443.316045 -402.067953) (xy 443.335968 -402.015862)
			(xy 443.363264 -401.967227) (xy 443.39735 -401.923084) (xy 443.437499 -401.884375) (xy 443.482857 -401.851924)
			(xy 443.532457 -401.826423) (xy 443.585241 -401.808416) (xy 443.640084 -401.798286) (xy 443.695818 -401.796249)
			(xy 443.751255 -401.802349) (xy 443.805212 -401.816455) (xy 443.856541 -401.838267) (xy 443.904147 -401.867321)
			(xy 443.947015 -401.902996) (xy 443.984232 -401.944533) (xy 444.015005 -401.991046) (xy 444.038677 -402.041543)
			(xy 444.054745 -402.09495) (xy 444.062865 -402.150126) (xy 444.063374 -402.178012) (xy 444.062865 -402.205898)
			(xy 444.054745 -402.261074) (xy 444.038677 -402.314481) (xy 444.015005 -402.364978) (xy 443.984232 -402.411491)
			(xy 443.947015 -402.453028) (xy 443.904147 -402.488703) (xy 443.856541 -402.517757) (xy 443.805212 -402.539569)
			(xy 443.751255 -402.553675) (xy 443.695818 -402.559775) (xy 443.640084 -402.557738) (xy 443.585241 -402.547608)
			(xy 443.532457 -402.529601) (xy 443.482857 -402.5041) (xy 443.437499 -402.471649) (xy 443.39735 -402.43294)
			(xy 443.363264 -402.388797) (xy 443.335968 -402.340162) (xy 443.316045 -402.288071) (xy 443.303919 -402.233634)
			(xy 443.299848 -402.178012) (xy 441.360569 -402.178012) (xy 441.368032 -402.186341) (xy 441.398805 -402.232854)
			(xy 441.422477 -402.283351) (xy 441.438545 -402.336758) (xy 441.446665 -402.391934) (xy 441.447174 -402.41982)
			(xy 441.446665 -402.447706) (xy 441.438545 -402.502882) (xy 441.422477 -402.556289) (xy 441.398805 -402.606786)
			(xy 441.368032 -402.653299) (xy 441.330815 -402.694836) (xy 441.287947 -402.730511) (xy 441.240341 -402.759565)
			(xy 441.189012 -402.781377) (xy 441.135055 -402.795483) (xy 441.079618 -402.801583) (xy 441.023884 -402.799546)
			(xy 440.969041 -402.789416) (xy 440.916257 -402.771409) (xy 440.866657 -402.745908) (xy 440.821299 -402.713457)
			(xy 440.78115 -402.674748) (xy 440.747064 -402.630605) (xy 440.719768 -402.58197) (xy 440.699845 -402.529879)
			(xy 440.687719 -402.475442) (xy 440.683648 -402.41982) (xy 432.30673 -402.41982) (xy 432.30673 -403.00021)
			(xy 434.686962 -403.00021) (xy 434.691033 -402.944588) (xy 434.703159 -402.890151) (xy 434.723082 -402.83806)
			(xy 434.750378 -402.789425) (xy 434.784464 -402.745282) (xy 434.824613 -402.706573) (xy 434.869971 -402.674122)
			(xy 434.919571 -402.648621) (xy 434.972355 -402.630614) (xy 435.027198 -402.620484) (xy 435.082932 -402.618447)
			(xy 435.138369 -402.624547) (xy 435.192326 -402.638653) (xy 435.243655 -402.660465) (xy 435.291261 -402.689519)
			(xy 435.334129 -402.725194) (xy 435.371346 -402.766731) (xy 435.402119 -402.813244) (xy 435.425791 -402.863741)
			(xy 435.441859 -402.917148) (xy 435.449979 -402.972324) (xy 435.450488 -403.00021) (xy 435.449979 -403.028096)
			(xy 435.441859 -403.083272) (xy 435.425791 -403.136679) (xy 435.402119 -403.187176) (xy 435.371346 -403.233689)
			(xy 435.334129 -403.275226) (xy 435.331913 -403.27707) (xy 443.122048 -403.27707) (xy 443.126119 -403.221448)
			(xy 443.138245 -403.167011) (xy 443.158168 -403.11492) (xy 443.185464 -403.066285) (xy 443.21955 -403.022142)
			(xy 443.259699 -402.983433) (xy 443.305057 -402.950982) (xy 443.354657 -402.925481) (xy 443.407441 -402.907474)
			(xy 443.462284 -402.897344) (xy 443.518018 -402.895307) (xy 443.573455 -402.901407) (xy 443.627412 -402.915513)
			(xy 443.678741 -402.937325) (xy 443.726347 -402.966379) (xy 443.769215 -403.002054) (xy 443.806432 -403.043591)
			(xy 443.837205 -403.090104) (xy 443.860877 -403.140601) (xy 443.876945 -403.194008) (xy 443.885065 -403.249184)
			(xy 443.885574 -403.27707) (xy 443.885065 -403.304956) (xy 443.876945 -403.360132) (xy 443.860877 -403.413539)
			(xy 443.837205 -403.464036) (xy 443.806432 -403.510549) (xy 443.769215 -403.552086) (xy 443.726347 -403.587761)
			(xy 443.678741 -403.616815) (xy 443.627412 -403.638627) (xy 443.573455 -403.652733) (xy 443.518018 -403.658833)
			(xy 443.462284 -403.656796) (xy 443.407441 -403.646666) (xy 443.354657 -403.628659) (xy 443.305057 -403.603158)
			(xy 443.259699 -403.570707) (xy 443.21955 -403.531998) (xy 443.185464 -403.487855) (xy 443.158168 -403.43922)
			(xy 443.138245 -403.387129) (xy 443.126119 -403.332692) (xy 443.122048 -403.27707) (xy 435.331913 -403.27707)
			(xy 435.291261 -403.310901) (xy 435.243655 -403.339955) (xy 435.192326 -403.361767) (xy 435.138369 -403.375873)
			(xy 435.082932 -403.381973) (xy 435.027198 -403.379936) (xy 434.972355 -403.369806) (xy 434.919571 -403.351799)
			(xy 434.869971 -403.326298) (xy 434.824613 -403.293847) (xy 434.784464 -403.255138) (xy 434.750378 -403.210995)
			(xy 434.723082 -403.16236) (xy 434.703159 -403.110269) (xy 434.691033 -403.055832) (xy 434.686962 -403.00021)
			(xy 432.30673 -403.00021) (xy 432.30673 -405.76246) (xy 433.948838 -405.76246) (xy 433.952909 -405.706838)
			(xy 433.965035 -405.652401) (xy 433.984958 -405.60031) (xy 434.012254 -405.551675) (xy 434.04634 -405.507532)
			(xy 434.086489 -405.468823) (xy 434.131847 -405.436372) (xy 434.181447 -405.410871) (xy 434.234231 -405.392864)
			(xy 434.289074 -405.382734) (xy 434.344808 -405.380697) (xy 434.400245 -405.386797) (xy 434.454202 -405.400903)
			(xy 434.505531 -405.422715) (xy 434.553137 -405.451769) (xy 434.596005 -405.487444) (xy 434.633222 -405.528981)
			(xy 434.663995 -405.575494) (xy 434.687667 -405.625991) (xy 434.703735 -405.679398) (xy 434.704745 -405.68626)
			(xy 435.404004 -405.68626) (xy 435.408075 -405.630638) (xy 435.420201 -405.576201) (xy 435.440124 -405.52411)
			(xy 435.46742 -405.475475) (xy 435.501506 -405.431332) (xy 435.541655 -405.392623) (xy 435.587013 -405.360172)
			(xy 435.636613 -405.334671) (xy 435.689397 -405.316664) (xy 435.74424 -405.306534) (xy 435.799974 -405.304497)
			(xy 435.855411 -405.310597) (xy 435.909368 -405.324703) (xy 435.960697 -405.346515) (xy 436.008303 -405.375569)
			(xy 436.051171 -405.411244) (xy 436.088388 -405.452781) (xy 436.119161 -405.499294) (xy 436.142833 -405.549791)
			(xy 436.158901 -405.603198) (xy 436.167021 -405.658374) (xy 436.16753 -405.68626) (xy 436.167021 -405.714146)
			(xy 436.158901 -405.769322) (xy 436.142833 -405.822729) (xy 436.119161 -405.873226) (xy 436.088388 -405.919739)
			(xy 436.051171 -405.961276) (xy 436.008303 -405.996951) (xy 435.960697 -406.026005) (xy 435.909368 -406.047817)
			(xy 435.855411 -406.061923) (xy 435.799974 -406.068023) (xy 435.74424 -406.065986) (xy 435.689397 -406.055856)
			(xy 435.636613 -406.037849) (xy 435.587013 -406.012348) (xy 435.541655 -405.979897) (xy 435.501506 -405.941188)
			(xy 435.46742 -405.897045) (xy 435.440124 -405.84841) (xy 435.420201 -405.796319) (xy 435.408075 -405.741882)
			(xy 435.404004 -405.68626) (xy 434.704745 -405.68626) (xy 434.711855 -405.734574) (xy 434.712364 -405.76246)
			(xy 434.711855 -405.790346) (xy 434.703735 -405.845522) (xy 434.687667 -405.898929) (xy 434.663995 -405.949426)
			(xy 434.633222 -405.995939) (xy 434.596005 -406.037476) (xy 434.553137 -406.073151) (xy 434.505531 -406.102205)
			(xy 434.454202 -406.124017) (xy 434.400245 -406.138123) (xy 434.344808 -406.144223) (xy 434.289074 -406.142186)
			(xy 434.234231 -406.132056) (xy 434.181447 -406.114049) (xy 434.131847 -406.088548) (xy 434.086489 -406.056097)
			(xy 434.04634 -406.017388) (xy 434.012254 -405.973245) (xy 433.984958 -405.92461) (xy 433.965035 -405.872519)
			(xy 433.952909 -405.818082) (xy 433.948838 -405.76246) (xy 432.30673 -405.76246) (xy 432.30673 -407.17216)
			(xy 434.870604 -407.17216) (xy 434.874675 -407.116538) (xy 434.886801 -407.062101) (xy 434.906724 -407.01001)
			(xy 434.93402 -406.961375) (xy 434.968106 -406.917232) (xy 435.008255 -406.878523) (xy 435.053613 -406.846072)
			(xy 435.103213 -406.820571) (xy 435.155997 -406.802564) (xy 435.21084 -406.792434) (xy 435.266574 -406.790397)
			(xy 435.322011 -406.796497) (xy 435.375968 -406.810603) (xy 435.427297 -406.832415) (xy 435.474903 -406.861469)
			(xy 435.517771 -406.897144) (xy 435.548663 -406.931622) (xy 439.08929 -406.931622) (xy 439.093361 -406.876)
			(xy 439.105487 -406.821563) (xy 439.12541 -406.769472) (xy 439.152706 -406.720837) (xy 439.186792 -406.676694)
			(xy 439.226941 -406.637985) (xy 439.272299 -406.605534) (xy 439.321899 -406.580033) (xy 439.374683 -406.562026)
			(xy 439.429526 -406.551896) (xy 439.48526 -406.549859) (xy 439.540697 -406.555959) (xy 439.594654 -406.570065)
			(xy 439.645983 -406.591877) (xy 439.693589 -406.620931) (xy 439.736457 -406.656606) (xy 439.773674 -406.698143)
			(xy 439.804447 -406.744656) (xy 439.828119 -406.795153) (xy 439.844187 -406.84856) (xy 439.852307 -406.903736)
			(xy 439.852816 -406.931622) (xy 439.852307 -406.959508) (xy 439.844187 -407.014684) (xy 439.828119 -407.068091)
			(xy 439.804447 -407.118588) (xy 439.773674 -407.165101) (xy 439.736457 -407.206638) (xy 439.693589 -407.242313)
			(xy 439.645983 -407.271367) (xy 439.594654 -407.293179) (xy 439.540697 -407.307285) (xy 439.48526 -407.313385)
			(xy 439.429526 -407.311348) (xy 439.374683 -407.301218) (xy 439.321899 -407.283211) (xy 439.272299 -407.25771)
			(xy 439.226941 -407.225259) (xy 439.186792 -407.18655) (xy 439.152706 -407.142407) (xy 439.12541 -407.093772)
			(xy 439.105487 -407.041681) (xy 439.093361 -406.987244) (xy 439.08929 -406.931622) (xy 435.548663 -406.931622)
			(xy 435.554988 -406.938681) (xy 435.585761 -406.985194) (xy 435.609433 -407.035691) (xy 435.625501 -407.089098)
			(xy 435.633621 -407.144274) (xy 435.63413 -407.17216) (xy 435.633621 -407.200046) (xy 435.625501 -407.255222)
			(xy 435.609433 -407.308629) (xy 435.585761 -407.359126) (xy 435.554988 -407.405639) (xy 435.517771 -407.447176)
			(xy 435.474903 -407.482851) (xy 435.427297 -407.511905) (xy 435.375968 -407.533717) (xy 435.322011 -407.547823)
			(xy 435.266574 -407.553923) (xy 435.21084 -407.551886) (xy 435.155997 -407.541756) (xy 435.103213 -407.523749)
			(xy 435.053613 -407.498248) (xy 435.008255 -407.465797) (xy 434.968106 -407.427088) (xy 434.93402 -407.382945)
			(xy 434.906724 -407.33431) (xy 434.886801 -407.282219) (xy 434.874675 -407.227782) (xy 434.870604 -407.17216)
			(xy 432.30673 -407.17216) (xy 432.30673 -408.01036) (xy 433.915564 -408.01036) (xy 433.919635 -407.954738)
			(xy 433.931761 -407.900301) (xy 433.951684 -407.84821) (xy 433.97898 -407.799575) (xy 434.013066 -407.755432)
			(xy 434.053215 -407.716723) (xy 434.098573 -407.684272) (xy 434.148173 -407.658771) (xy 434.200957 -407.640764)
			(xy 434.2558 -407.630634) (xy 434.311534 -407.628597) (xy 434.366971 -407.634697) (xy 434.420928 -407.648803)
			(xy 434.472257 -407.670615) (xy 434.519863 -407.699669) (xy 434.562731 -407.735344) (xy 434.599948 -407.776881)
			(xy 434.630721 -407.823394) (xy 434.654393 -407.873891) (xy 434.670461 -407.927298) (xy 434.678581 -407.982474)
			(xy 434.67909 -408.01036) (xy 434.678581 -408.038246) (xy 434.670461 -408.093422) (xy 434.654393 -408.146829)
			(xy 434.630721 -408.197326) (xy 434.599948 -408.243839) (xy 434.562731 -408.285376) (xy 434.519863 -408.321051)
			(xy 434.472257 -408.350105) (xy 434.420928 -408.371917) (xy 434.366971 -408.386023) (xy 434.311534 -408.392123)
			(xy 434.2558 -408.390086) (xy 434.200957 -408.379956) (xy 434.148173 -408.361949) (xy 434.098573 -408.336448)
			(xy 434.053215 -408.303997) (xy 434.013066 -408.265288) (xy 433.97898 -408.221145) (xy 433.951684 -408.17251)
			(xy 433.931761 -408.120419) (xy 433.919635 -408.065982) (xy 433.915564 -408.01036) (xy 432.30673 -408.01036)
			(xy 432.30673 -408.84856) (xy 434.870604 -408.84856) (xy 434.874675 -408.792938) (xy 434.886801 -408.738501)
			(xy 434.906724 -408.68641) (xy 434.93402 -408.637775) (xy 434.968106 -408.593632) (xy 435.008255 -408.554923)
			(xy 435.053613 -408.522472) (xy 435.103213 -408.496971) (xy 435.155997 -408.478964) (xy 435.21084 -408.468834)
			(xy 435.266574 -408.466797) (xy 435.322011 -408.472897) (xy 435.375968 -408.487003) (xy 435.427297 -408.508815)
			(xy 435.474903 -408.537869) (xy 435.517771 -408.573544) (xy 435.554988 -408.615081) (xy 435.585761 -408.661594)
			(xy 435.609433 -408.712091) (xy 435.625501 -408.765498) (xy 435.633621 -408.820674) (xy 435.63413 -408.84856)
			(xy 435.633621 -408.876446) (xy 435.625501 -408.931622) (xy 435.609433 -408.985029) (xy 435.585761 -409.035526)
			(xy 435.554988 -409.082039) (xy 435.517771 -409.123576) (xy 435.474903 -409.159251) (xy 435.427297 -409.188305)
			(xy 435.375968 -409.210117) (xy 435.322011 -409.224223) (xy 435.266574 -409.230323) (xy 435.21084 -409.228286)
			(xy 435.155997 -409.218156) (xy 435.103213 -409.200149) (xy 435.053613 -409.174648) (xy 435.008255 -409.142197)
			(xy 434.968106 -409.103488) (xy 434.93402 -409.059345) (xy 434.906724 -409.01071) (xy 434.886801 -408.958619)
			(xy 434.874675 -408.904182) (xy 434.870604 -408.84856) (xy 432.30673 -408.84856) (xy 432.30673 -409.68676)
			(xy 433.915564 -409.68676) (xy 433.919635 -409.631138) (xy 433.931761 -409.576701) (xy 433.951684 -409.52461)
			(xy 433.97898 -409.475975) (xy 434.013066 -409.431832) (xy 434.053215 -409.393123) (xy 434.098573 -409.360672)
			(xy 434.148173 -409.335171) (xy 434.200957 -409.317164) (xy 434.2558 -409.307034) (xy 434.311534 -409.304997)
			(xy 434.366971 -409.311097) (xy 434.420928 -409.325203) (xy 434.472257 -409.347015) (xy 434.519863 -409.376069)
			(xy 434.562731 -409.411744) (xy 434.599948 -409.453281) (xy 434.630721 -409.499794) (xy 434.654393 -409.550291)
			(xy 434.670461 -409.603698) (xy 434.678581 -409.658874) (xy 434.67909 -409.68676) (xy 434.678581 -409.714646)
			(xy 434.670461 -409.769822) (xy 434.654393 -409.823229) (xy 434.630721 -409.873726) (xy 434.599948 -409.920239)
			(xy 434.562731 -409.961776) (xy 434.519863 -409.997451) (xy 434.472257 -410.026505) (xy 434.420928 -410.048317)
			(xy 434.366971 -410.062423) (xy 434.311534 -410.068523) (xy 434.2558 -410.066486) (xy 434.200957 -410.056356)
			(xy 434.148173 -410.038349) (xy 434.098573 -410.012848) (xy 434.053215 -409.980397) (xy 434.013066 -409.941688)
			(xy 433.97898 -409.897545) (xy 433.951684 -409.84891) (xy 433.931761 -409.796819) (xy 433.919635 -409.742382)
			(xy 433.915564 -409.68676) (xy 432.30673 -409.68676) (xy 432.30673 -424.16222) (xy 432.307107 -424.171397)
			(xy 432.313563 -424.188576) (xy 432.325671 -424.202367) (xy 432.34187 -424.210992) (xy 432.350926 -424.212512)
			(xy 432.35118 -424.212512) (xy 432.378515 -424.216398) (xy 432.431753 -424.231028) (xy 432.482325 -424.253182)
			(xy 432.529175 -424.282397) (xy 432.571322 -424.318061) (xy 432.607886 -424.35943) (xy 432.638103 -424.405639)
			(xy 432.661341 -424.455722) (xy 432.677114 -424.508633) (xy 432.685094 -424.563265) (xy 432.685113 -424.618477)
			(xy 432.67717 -424.673114) (xy 432.661433 -424.726035) (xy 432.638228 -424.776134) (xy 432.608043 -424.822364)
			(xy 432.571507 -424.863757) (xy 432.529384 -424.89945) (xy 432.482555 -424.928697) (xy 432.431998 -424.950885)
			(xy 432.37877 -424.965552) (xy 432.351434 -424.969432) (xy 432.350926 -424.969432) (xy 432.341889 -424.971014)
			(xy 432.325716 -424.97965) (xy 432.313608 -424.993416) (xy 432.307108 -425.010559) (xy 432.30673 -425.019724)
			(xy 432.30673 -426.503846) (xy 435.82844 -426.503846) (xy 435.82844 -412.907988) (xy 435.829064 -412.882991)
			(xy 435.838871 -412.833968) (xy 435.858048 -412.787797) (xy 435.885859 -412.746252) (xy 435.903116 -412.728156)
			(xy 444.428626 -404.202646) (xy 444.435442 -404.195227) (xy 444.443175 -404.176642) (xy 444.443612 -404.166578)
			(xy 444.443612 -402.897594) (xy 444.444249 -402.872612) (xy 444.453986 -402.823606) (xy 444.473086 -402.777436)
			(xy 444.500817 -402.735874) (xy 444.518034 -402.717762) (xy 445.00292 -402.232876) (xy 445.01054 -402.214334)
			(xy 445.01054 -402.20392) (xy 445.010932 -402.176642) (xy 445.01863 -402.122632) (xy 445.033943 -402.070269)
			(xy 445.056559 -402.020622) (xy 445.086016 -401.974703) (xy 445.121714 -401.933448) (xy 445.162925 -401.897699)
			(xy 445.208807 -401.868185) (xy 445.258426 -401.845508) (xy 445.31077 -401.83013) (xy 445.36477 -401.822366)
			(xy 445.392048 -401.821904) (xy 445.419311 -401.822347) (xy 445.473281 -401.830116) (xy 445.525595 -401.84549)
			(xy 445.575188 -401.868154) (xy 445.583053 -401.873212) (xy 451.885048 -401.873212) (xy 451.889119 -401.81759)
			(xy 451.901245 -401.763153) (xy 451.921168 -401.711062) (xy 451.948464 -401.662427) (xy 451.98255 -401.618284)
			(xy 452.022699 -401.579575) (xy 452.068057 -401.547124) (xy 452.117657 -401.521623) (xy 452.170441 -401.503616)
			(xy 452.225284 -401.493486) (xy 452.281018 -401.491449) (xy 452.336455 -401.497549) (xy 452.390412 -401.511655)
			(xy 452.441741 -401.533467) (xy 452.489347 -401.562521) (xy 452.532215 -401.598196) (xy 452.569432 -401.639733)
			(xy 452.600205 -401.686246) (xy 452.623877 -401.736743) (xy 452.639945 -401.79015) (xy 452.648065 -401.845326)
			(xy 452.648574 -401.873212) (xy 452.648065 -401.901098) (xy 452.639945 -401.956274) (xy 452.623877 -402.009681)
			(xy 452.600205 -402.060178) (xy 452.569432 -402.106691) (xy 452.532215 -402.148228) (xy 452.489347 -402.183903)
			(xy 452.441741 -402.212957) (xy 452.390412 -402.234769) (xy 452.336455 -402.248875) (xy 452.281018 -402.254975)
			(xy 452.225284 -402.252938) (xy 452.170441 -402.242808) (xy 452.117657 -402.224801) (xy 452.068057 -402.1993)
			(xy 452.022699 -402.166849) (xy 451.98255 -402.12814) (xy 451.948464 -402.083997) (xy 451.921168 -402.035362)
			(xy 451.901245 -401.983271) (xy 451.889119 -401.928834) (xy 451.885048 -401.873212) (xy 445.583053 -401.873212)
			(xy 445.621049 -401.897648) (xy 445.662243 -401.93337) (xy 445.697933 -401.974594) (xy 445.727391 -402.020478)
			(xy 445.750016 -402.070088) (xy 445.765348 -402.122415) (xy 445.773075 -402.176391) (xy 445.773039 -402.230917)
			(xy 445.76524 -402.284882) (xy 445.749838 -402.337188) (xy 445.727147 -402.386769) (xy 445.697628 -402.432614)
			(xy 445.661884 -402.473789) (xy 445.620641 -402.509457) (xy 445.574741 -402.53889) (xy 445.525118 -402.561488)
			(xy 445.472784 -402.576792) (xy 445.418804 -402.584489) (xy 445.39154 -402.58492) (xy 445.381126 -402.58492)
			(xy 445.362584 -402.59254) (xy 445.253576 -402.701548) (xy 450.670706 -402.701548) (xy 450.670706 -402.647052)
			(xy 450.678461 -402.59311) (xy 450.693814 -402.540821) (xy 450.716452 -402.491249) (xy 450.745914 -402.445404)
			(xy 450.7816 -402.404217) (xy 450.822784 -402.368528) (xy 450.868628 -402.339063) (xy 450.918199 -402.316423)
			(xy 450.970487 -402.301067) (xy 451.024428 -402.293308) (xy 451.051676 -402.29282) (xy 451.080593 -402.293348)
			(xy 451.137764 -402.302074) (xy 451.192963 -402.31933) (xy 451.244925 -402.344719) (xy 451.292459 -402.377661)
			(xy 451.334476 -402.417401) (xy 451.352666 -402.439886) (xy 451.360249 -402.448626) (xy 451.380992 -402.458822)
			(xy 451.392544 -402.459444) (xy 451.472808 -402.459444) (xy 451.48438 -402.458898) (xy 451.505151 -402.448688)
			(xy 451.512686 -402.439886) (xy 451.530881 -402.417406) (xy 451.572901 -402.377672) (xy 451.620435 -402.344732)
			(xy 451.672395 -402.319344) (xy 451.727592 -402.302086) (xy 451.78476 -402.293356) (xy 451.813676 -402.29282)
			(xy 451.840932 -402.293225) (xy 451.89489 -402.30098) (xy 451.947194 -402.316335) (xy 451.996781 -402.338978)
			(xy 452.042641 -402.368448) (xy 452.083839 -402.404144) (xy 452.119538 -402.44534) (xy 452.149011 -402.491198)
			(xy 452.171656 -402.540783) (xy 452.187015 -402.593087) (xy 452.194773 -402.647044) (xy 452.194773 -402.701556)
			(xy 452.187015 -402.755513) (xy 452.171656 -402.807817) (xy 452.149011 -402.857402) (xy 452.119538 -402.90326)
			(xy 452.083839 -402.944456) (xy 452.042641 -402.980152) (xy 451.996781 -403.009622) (xy 451.947194 -403.032265)
			(xy 451.89489 -403.04762) (xy 451.840932 -403.055375) (xy 451.813676 -403.055836) (xy 451.78476 -403.055287)
			(xy 451.727589 -403.046568) (xy 451.67239 -403.029318) (xy 451.620427 -403.003932) (xy 451.572893 -402.970992)
			(xy 451.530876 -402.931254) (xy 451.512686 -402.90877) (xy 451.505131 -402.900001) (xy 451.484367 -402.889823)
			(xy 451.472808 -402.889212) (xy 451.392544 -402.889212) (xy 451.380979 -402.889803) (xy 451.360207 -402.899983)
			(xy 451.352666 -402.90877) (xy 451.334487 -402.931264) (xy 451.292465 -402.970999) (xy 451.244928 -403.003938)
			(xy 451.192965 -403.029325) (xy 451.137765 -403.046579) (xy 451.080593 -403.055304) (xy 451.051676 -403.055836)
			(xy 451.024428 -403.055292) (xy 450.970487 -403.047533) (xy 450.918199 -403.032177) (xy 450.868628 -403.009537)
			(xy 450.822784 -402.980072) (xy 450.7816 -402.944383) (xy 450.745914 -402.903196) (xy 450.716452 -402.857351)
			(xy 450.693814 -402.807779) (xy 450.678461 -402.75549) (xy 450.670706 -402.701548) (xy 445.253576 -402.701548)
			(xy 444.967106 -402.988018) (xy 444.960266 -402.995418) (xy 444.952546 -403.014017) (xy 444.95212 -403.024086)
			(xy 444.95212 -404.29307) (xy 444.951541 -404.318055) (xy 444.941789 -404.367065) (xy 444.922672 -404.413235)
			(xy 444.894924 -404.454794) (xy 444.877698 -404.472902) (xy 443.141354 -406.209246) (xy 448.698112 -406.209246)
			(xy 448.698678 -406.179635) (xy 448.707823 -406.121123) (xy 448.7259 -406.064727) (xy 448.752476 -406.011803)
			(xy 448.786911 -405.963621) (xy 448.828378 -405.92134) (xy 448.875882 -405.885974) (xy 448.90182 -405.87168)
			(xy 448.913621 -405.865041) (xy 448.933432 -405.846593) (xy 448.947695 -405.823585) (xy 448.955406 -405.797636)
			(xy 448.956023 -405.770573) (xy 448.949502 -405.7443) (xy 448.936302 -405.720666) (xy 448.917353 -405.701334)
			(xy 448.905884 -405.694134) (xy 448.881637 -405.679373) (xy 448.837444 -405.643748) (xy 448.799017 -405.601968)
			(xy 448.767207 -405.554953) (xy 448.742716 -405.503744) (xy 448.726084 -405.449471) (xy 448.717679 -405.393332)
			(xy 448.717162 -405.36495) (xy 448.717648 -405.337699) (xy 448.725404 -405.283751) (xy 448.740759 -405.231456)
			(xy 448.763401 -405.181879) (xy 448.792867 -405.136029) (xy 448.828558 -405.094838) (xy 448.869749 -405.059147)
			(xy 448.915599 -405.029681) (xy 448.965176 -405.007039) (xy 449.017471 -404.991684) (xy 449.071419 -404.983928)
			(xy 449.125921 -404.983928) (xy 449.179869 -404.991684) (xy 449.232164 -405.007039) (xy 449.281741 -405.029681)
			(xy 449.327591 -405.059147) (xy 449.368782 -405.094838) (xy 449.404473 -405.136029) (xy 449.433939 -405.181879)
			(xy 449.456581 -405.231456) (xy 449.471936 -405.283751) (xy 449.479692 -405.337699) (xy 449.480178 -405.36495)
			(xy 449.479614 -405.394561) (xy 449.47047 -405.453073) (xy 449.452392 -405.509469) (xy 449.425817 -405.562394)
			(xy 449.391381 -405.610576) (xy 449.349913 -405.652857) (xy 449.302409 -405.688222) (xy 449.27647 -405.702516)
			(xy 449.264673 -405.709161) (xy 449.244864 -405.727609) (xy 449.230603 -405.750616) (xy 449.222893 -405.776563)
			(xy 449.222275 -405.803624) (xy 449.228795 -405.829896) (xy 449.241992 -405.853529) (xy 449.260939 -405.872861)
			(xy 449.272406 -405.880062) (xy 449.296649 -405.894829) (xy 449.340843 -405.930453) (xy 449.37927 -405.972232)
			(xy 449.41108 -406.019245) (xy 449.435572 -406.070453) (xy 449.452205 -406.124726) (xy 449.46061 -406.180864)
			(xy 449.461128 -406.209246) (xy 449.460642 -406.236497) (xy 449.452886 -406.290445) (xy 449.437531 -406.34274)
			(xy 449.414889 -406.392317) (xy 449.385423 -406.438167) (xy 449.349732 -406.479358) (xy 449.308541 -406.515049)
			(xy 449.262691 -406.544515) (xy 449.213114 -406.567157) (xy 449.160819 -406.582512) (xy 449.106871 -406.590268)
			(xy 449.052369 -406.590268) (xy 448.998421 -406.582512) (xy 448.946126 -406.567157) (xy 448.896549 -406.544515)
			(xy 448.850699 -406.515049) (xy 448.809508 -406.479358) (xy 448.773817 -406.438167) (xy 448.744351 -406.392317)
			(xy 448.721709 -406.34274) (xy 448.706354 -406.290445) (xy 448.698598 -406.236497) (xy 448.698112 -406.209246)
			(xy 443.141354 -406.209246) (xy 442.150754 -407.199846) (xy 448.698112 -407.199846) (xy 448.698598 -407.172595)
			(xy 448.706354 -407.118647) (xy 448.721709 -407.066352) (xy 448.744351 -407.016775) (xy 448.773817 -406.970925)
			(xy 448.809508 -406.929734) (xy 448.850699 -406.894043) (xy 448.896549 -406.864577) (xy 448.946126 -406.841935)
			(xy 448.998421 -406.82658) (xy 449.052369 -406.818824) (xy 449.106871 -406.818824) (xy 449.160819 -406.82658)
			(xy 449.213114 -406.841935) (xy 449.262691 -406.864577) (xy 449.308541 -406.894043) (xy 449.349732 -406.929734)
			(xy 449.385423 -406.970925) (xy 449.414889 -407.016775) (xy 449.437531 -407.066352) (xy 449.452886 -407.118647)
			(xy 449.460642 -407.172595) (xy 449.461128 -407.199846) (xy 449.460563 -407.228837) (xy 449.451777 -407.286151)
			(xy 449.434427 -407.341477) (xy 449.408913 -407.393546) (xy 449.375822 -407.441159) (xy 449.335914 -407.483223)
			(xy 449.290106 -407.51877) (xy 449.26504 -407.533348) (xy 449.25296 -407.540612) (xy 449.233005 -407.560503)
			(xy 449.219245 -407.585089) (xy 449.212726 -407.6125) (xy 449.213945 -407.640649) (xy 449.222808 -407.667394)
			(xy 449.238641 -407.690699) (xy 449.260239 -407.708792) (xy 449.272914 -407.714958) (xy 449.29783 -407.726553)
			(xy 449.344309 -407.755877) (xy 449.386098 -407.791567) (xy 449.422332 -407.832886) (xy 449.452262 -407.878977)
			(xy 449.475267 -407.928886) (xy 449.490871 -407.98158) (xy 449.498752 -408.035968) (xy 449.499228 -408.063446)
			(xy 449.498742 -408.090697) (xy 449.490986 -408.144645) (xy 449.475631 -408.19694) (xy 449.452989 -408.246517)
			(xy 449.423523 -408.292367) (xy 449.387832 -408.333558) (xy 449.346641 -408.369249) (xy 449.300791 -408.398715)
			(xy 449.251214 -408.421357) (xy 449.198919 -408.436712) (xy 449.144971 -408.444468) (xy 449.090469 -408.444468)
			(xy 449.036521 -408.436712) (xy 448.984226 -408.421357) (xy 448.934649 -408.398715) (xy 448.888799 -408.369249)
			(xy 448.847608 -408.333558) (xy 448.811917 -408.292367) (xy 448.782451 -408.246517) (xy 448.759809 -408.19694)
			(xy 448.744454 -408.144645) (xy 448.736698 -408.090697) (xy 448.736212 -408.063446) (xy 448.73675 -408.034453)
			(xy 448.745539 -407.977138) (xy 448.762892 -407.92181) (xy 448.788409 -407.869741) (xy 448.821505 -407.822128)
			(xy 448.861418 -407.780065) (xy 448.907232 -407.74452) (xy 448.9323 -407.729944) (xy 448.944382 -407.722687)
			(xy 448.964329 -407.702791) (xy 448.978083 -407.678204) (xy 448.984598 -407.650795) (xy 448.983379 -407.622649)
			(xy 448.974518 -407.595905) (xy 448.95869 -407.5726) (xy 448.937098 -407.554503) (xy 448.924426 -407.548334)
			(xy 448.899516 -407.536726) (xy 448.853036 -407.507406) (xy 448.811245 -407.471718) (xy 448.775009 -407.430402)
			(xy 448.745078 -407.384313) (xy 448.722072 -407.334405) (xy 448.706468 -407.281711) (xy 448.698588 -407.227324)
			(xy 448.698112 -407.199846) (xy 442.150754 -407.199846) (xy 436.352188 -412.998412) (xy 436.345505 -413.005902)
			(xy 436.337908 -413.024454) (xy 436.337456 -413.03448) (xy 436.337456 -418.436044) (xy 438.118756 -418.436044)
			(xy 438.122827 -418.380422) (xy 438.134953 -418.325985) (xy 438.154876 -418.273894) (xy 438.182172 -418.225259)
			(xy 438.216258 -418.181116) (xy 438.256407 -418.142407) (xy 438.301765 -418.109956) (xy 438.351365 -418.084455)
			(xy 438.404149 -418.066448) (xy 438.458992 -418.056318) (xy 438.514726 -418.054281) (xy 438.570163 -418.060381)
			(xy 438.62412 -418.074487) (xy 438.675449 -418.096299) (xy 438.723055 -418.125353) (xy 438.765923 -418.161028)
			(xy 438.80314 -418.202565) (xy 438.833913 -418.249078) (xy 438.857585 -418.299575) (xy 438.873653 -418.352982)
			(xy 438.881773 -418.408158) (xy 438.882282 -418.436044) (xy 439.134756 -418.436044) (xy 439.138827 -418.380422)
			(xy 439.150953 -418.325985) (xy 439.170876 -418.273894) (xy 439.198172 -418.225259) (xy 439.232258 -418.181116)
			(xy 439.272407 -418.142407) (xy 439.317765 -418.109956) (xy 439.367365 -418.084455) (xy 439.420149 -418.066448)
			(xy 439.474992 -418.056318) (xy 439.530726 -418.054281) (xy 439.586163 -418.060381) (xy 439.64012 -418.074487)
			(xy 439.691449 -418.096299) (xy 439.739055 -418.125353) (xy 439.781923 -418.161028) (xy 439.81914 -418.202565)
			(xy 439.849913 -418.249078) (xy 439.873585 -418.299575) (xy 439.889653 -418.352982) (xy 439.897773 -418.408158)
			(xy 439.898282 -418.436044) (xy 439.897773 -418.46393) (xy 439.889653 -418.519106) (xy 439.873585 -418.572513)
			(xy 439.849913 -418.62301) (xy 439.81914 -418.669523) (xy 439.781923 -418.71106) (xy 439.739055 -418.746735)
			(xy 439.691449 -418.775789) (xy 439.64012 -418.797601) (xy 439.586163 -418.811707) (xy 439.530726 -418.817807)
			(xy 439.474992 -418.81577) (xy 439.420149 -418.80564) (xy 439.367365 -418.787633) (xy 439.317765 -418.762132)
			(xy 439.272407 -418.729681) (xy 439.232258 -418.690972) (xy 439.198172 -418.646829) (xy 439.170876 -418.598194)
			(xy 439.150953 -418.546103) (xy 439.138827 -418.491666) (xy 439.134756 -418.436044) (xy 438.882282 -418.436044)
			(xy 438.881773 -418.46393) (xy 438.873653 -418.519106) (xy 438.857585 -418.572513) (xy 438.833913 -418.62301)
			(xy 438.80314 -418.669523) (xy 438.765923 -418.71106) (xy 438.723055 -418.746735) (xy 438.675449 -418.775789)
			(xy 438.62412 -418.797601) (xy 438.570163 -418.811707) (xy 438.514726 -418.817807) (xy 438.458992 -418.81577)
			(xy 438.404149 -418.80564) (xy 438.351365 -418.787633) (xy 438.301765 -418.762132) (xy 438.256407 -418.729681)
			(xy 438.216258 -418.690972) (xy 438.182172 -418.646829) (xy 438.154876 -418.598194) (xy 438.134953 -418.546103)
			(xy 438.122827 -418.491666) (xy 438.118756 -418.436044) (xy 436.337456 -418.436044) (xy 436.337456 -419.59911)
			(xy 440.425584 -419.59911) (xy 440.429655 -419.543488) (xy 440.441781 -419.489051) (xy 440.461704 -419.43696)
			(xy 440.489 -419.388325) (xy 440.523086 -419.344182) (xy 440.563235 -419.305473) (xy 440.608593 -419.273022)
			(xy 440.658193 -419.247521) (xy 440.710977 -419.229514) (xy 440.76582 -419.219384) (xy 440.821554 -419.217347)
			(xy 440.876991 -419.223447) (xy 440.930948 -419.237553) (xy 440.982277 -419.259365) (xy 441.029883 -419.288419)
			(xy 441.072751 -419.324094) (xy 441.109968 -419.365631) (xy 441.140741 -419.412144) (xy 441.164413 -419.462641)
			(xy 441.180481 -419.516048) (xy 441.188601 -419.571224) (xy 441.18911 -419.59911) (xy 441.188601 -419.626996)
			(xy 441.180481 -419.682172) (xy 441.164413 -419.735579) (xy 441.140741 -419.786076) (xy 441.109968 -419.832589)
			(xy 441.072751 -419.874126) (xy 441.029883 -419.909801) (xy 440.982277 -419.938855) (xy 440.930948 -419.960667)
			(xy 440.876991 -419.974773) (xy 440.821554 -419.980873) (xy 440.76582 -419.978836) (xy 440.710977 -419.968706)
			(xy 440.658193 -419.950699) (xy 440.608593 -419.925198) (xy 440.563235 -419.892747) (xy 440.523086 -419.854038)
			(xy 440.489 -419.809895) (xy 440.461704 -419.76126) (xy 440.441781 -419.709169) (xy 440.429655 -419.654732)
			(xy 440.425584 -419.59911) (xy 436.337456 -419.59911) (xy 436.337456 -420.86911) (xy 440.180982 -420.86911)
			(xy 440.185053 -420.813488) (xy 440.197179 -420.759051) (xy 440.217102 -420.70696) (xy 440.244398 -420.658325)
			(xy 440.278484 -420.614182) (xy 440.318633 -420.575473) (xy 440.363991 -420.543022) (xy 440.413591 -420.517521)
			(xy 440.466375 -420.499514) (xy 440.521218 -420.489384) (xy 440.576952 -420.487347) (xy 440.632389 -420.493447)
			(xy 440.686346 -420.507553) (xy 440.737675 -420.529365) (xy 440.785281 -420.558419) (xy 440.828149 -420.594094)
			(xy 440.865366 -420.635631) (xy 440.896139 -420.682144) (xy 440.919811 -420.732641) (xy 440.935879 -420.786048)
			(xy 440.943999 -420.841224) (xy 440.944508 -420.86911) (xy 440.943999 -420.896996) (xy 440.935879 -420.952172)
			(xy 440.919811 -421.005579) (xy 440.896139 -421.056076) (xy 440.865366 -421.102589) (xy 440.828149 -421.144126)
			(xy 440.785281 -421.179801) (xy 440.737675 -421.208855) (xy 440.686346 -421.230667) (xy 440.632389 -421.244773)
			(xy 440.576952 -421.250873) (xy 440.521218 -421.248836) (xy 440.466375 -421.238706) (xy 440.413591 -421.220699)
			(xy 440.363991 -421.195198) (xy 440.318633 -421.162747) (xy 440.278484 -421.124038) (xy 440.244398 -421.079895)
			(xy 440.217102 -421.03126) (xy 440.197179 -420.979169) (xy 440.185053 -420.924732) (xy 440.180982 -420.86911)
			(xy 436.337456 -420.86911) (xy 436.337456 -423.215562) (xy 440.204098 -423.215562) (xy 440.204539 -423.188278)
			(xy 440.212331 -423.134267) (xy 440.227736 -423.081918) (xy 440.25044 -423.032296) (xy 440.279981 -422.986414)
			(xy 440.315756 -422.945208) (xy 440.357035 -422.909517) (xy 440.402977 -422.880069) (xy 440.427618 -422.868344)
			(xy 440.44102 -422.861668) (xy 440.463477 -422.841883) (xy 440.479241 -422.816442) (xy 440.486961 -422.787526)
			(xy 440.485975 -422.757613) (xy 440.476368 -422.729268) (xy 440.458964 -422.70492) (xy 440.44743 -422.69537)
			(xy 440.424753 -422.677154) (xy 440.384614 -422.63506) (xy 440.351326 -422.587363) (xy 440.325662 -422.535167)
			(xy 440.308214 -422.479682) (xy 440.299387 -422.422192) (xy 440.29884 -422.39311) (xy 440.299326 -422.365859)
			(xy 440.307082 -422.311911) (xy 440.322437 -422.259616) (xy 440.345079 -422.210039) (xy 440.374545 -422.164189)
			(xy 440.410236 -422.122998) (xy 440.451427 -422.087307) (xy 440.497277 -422.057841) (xy 440.546854 -422.035199)
			(xy 440.599149 -422.019844) (xy 440.653097 -422.012088) (xy 440.707599 -422.012088) (xy 440.761547 -422.019844)
			(xy 440.813842 -422.035199) (xy 440.863419 -422.057841) (xy 440.909269 -422.087307) (xy 440.95046 -422.122998)
			(xy 440.986151 -422.164189) (xy 441.015617 -422.210039) (xy 441.038259 -422.259616) (xy 441.053614 -422.311911)
			(xy 441.06137 -422.365859) (xy 441.061856 -422.39311) (xy 441.061419 -422.420395) (xy 441.05363 -422.474406)
			(xy 441.038226 -422.526757) (xy 441.015522 -422.57638) (xy 440.98598 -422.622263) (xy 440.950204 -422.663469)
			(xy 440.908923 -422.699159) (xy 440.862979 -422.728605) (xy 440.838336 -422.740328) (xy 440.824956 -422.747048)
			(xy 440.802492 -422.76682) (xy 440.786721 -422.792252) (xy 440.778996 -422.821163) (xy 440.779978 -422.851072)
			(xy 440.789584 -422.879414) (xy 440.80699 -422.903756) (xy 440.818524 -422.913302) (xy 440.841247 -422.931463)
			(xy 440.881381 -422.97357) (xy 440.914661 -423.021279) (xy 440.940317 -423.073485) (xy 440.957756 -423.128979)
			(xy 440.966572 -423.186477) (xy 440.967114 -423.215562) (xy 440.966628 -423.242813) (xy 440.958872 -423.296761)
			(xy 440.943517 -423.349056) (xy 440.920875 -423.398633) (xy 440.891409 -423.444483) (xy 440.855718 -423.485674)
			(xy 440.814527 -423.521365) (xy 440.768677 -423.550831) (xy 440.7191 -423.573473) (xy 440.666805 -423.588828)
			(xy 440.612857 -423.596584) (xy 440.558355 -423.596584) (xy 440.504407 -423.588828) (xy 440.452112 -423.573473)
			(xy 440.402535 -423.550831) (xy 440.356685 -423.521365) (xy 440.315494 -423.485674) (xy 440.279803 -423.444483)
			(xy 440.250337 -423.398633) (xy 440.227695 -423.349056) (xy 440.21234 -423.296761) (xy 440.204584 -423.242813)
			(xy 440.204098 -423.215562) (xy 436.337456 -423.215562) (xy 436.337456 -423.798492) (xy 436.712612 -423.798492)
			(xy 436.716683 -423.74287) (xy 436.728809 -423.688433) (xy 436.748732 -423.636342) (xy 436.776028 -423.587707)
			(xy 436.810114 -423.543564) (xy 436.850263 -423.504855) (xy 436.895621 -423.472404) (xy 436.945221 -423.446903)
			(xy 436.998005 -423.428896) (xy 437.052848 -423.418766) (xy 437.108582 -423.416729) (xy 437.164019 -423.422829)
			(xy 437.217976 -423.436935) (xy 437.269305 -423.458747) (xy 437.316911 -423.487801) (xy 437.359779 -423.523476)
			(xy 437.396996 -423.565013) (xy 437.427769 -423.611526) (xy 437.451441 -423.662023) (xy 437.467509 -423.71543)
			(xy 437.475629 -423.770606) (xy 437.476138 -423.798492) (xy 437.475629 -423.826378) (xy 437.467509 -423.881554)
			(xy 437.451441 -423.934961) (xy 437.427769 -423.985458) (xy 437.396996 -424.031971) (xy 437.359779 -424.073508)
			(xy 437.316911 -424.109183) (xy 437.269305 -424.138237) (xy 437.217976 -424.160049) (xy 437.164019 -424.174155)
			(xy 437.108582 -424.180255) (xy 437.052848 -424.178218) (xy 436.998005 -424.168088) (xy 436.945221 -424.150081)
			(xy 436.895621 -424.12458) (xy 436.850263 -424.092129) (xy 436.810114 -424.05342) (xy 436.776028 -424.009277)
			(xy 436.748732 -423.960642) (xy 436.728809 -423.908551) (xy 436.716683 -423.854114) (xy 436.712612 -423.798492)
			(xy 436.337456 -423.798492) (xy 436.337456 -424.80611) (xy 437.580784 -424.80611) (xy 437.584855 -424.750488)
			(xy 437.596981 -424.696051) (xy 437.616904 -424.64396) (xy 437.6442 -424.595325) (xy 437.678286 -424.551182)
			(xy 437.718435 -424.512473) (xy 437.763793 -424.480022) (xy 437.813393 -424.454521) (xy 437.866177 -424.436514)
			(xy 437.92102 -424.426384) (xy 437.976754 -424.424347) (xy 438.032191 -424.430447) (xy 438.086148 -424.444553)
			(xy 438.137477 -424.466365) (xy 438.185083 -424.495419) (xy 438.227951 -424.531094) (xy 438.265168 -424.572631)
			(xy 438.295941 -424.619144) (xy 438.319613 -424.669641) (xy 438.335681 -424.723048) (xy 438.343801 -424.778224)
			(xy 438.34431 -424.80611) (xy 438.343801 -424.833996) (xy 438.335681 -424.889172) (xy 438.319613 -424.942579)
			(xy 438.295941 -424.993076) (xy 438.265168 -425.039589) (xy 438.246781 -425.06011) (xy 440.298584 -425.06011)
			(xy 440.302655 -425.004488) (xy 440.314781 -424.950051) (xy 440.334704 -424.89796) (xy 440.362 -424.849325)
			(xy 440.396086 -424.805182) (xy 440.436235 -424.766473) (xy 440.481593 -424.734022) (xy 440.531193 -424.708521)
			(xy 440.583977 -424.690514) (xy 440.63882 -424.680384) (xy 440.694554 -424.678347) (xy 440.749991 -424.684447)
			(xy 440.803948 -424.698553) (xy 440.855277 -424.720365) (xy 440.902883 -424.749419) (xy 440.945751 -424.785094)
			(xy 440.982968 -424.826631) (xy 441.013741 -424.873144) (xy 441.037413 -424.923641) (xy 441.053481 -424.977048)
			(xy 441.061601 -425.032224) (xy 441.06211 -425.06011) (xy 441.061601 -425.087996) (xy 441.053481 -425.143172)
			(xy 441.037413 -425.196579) (xy 441.013741 -425.247076) (xy 440.982968 -425.293589) (xy 440.945751 -425.335126)
			(xy 440.902883 -425.370801) (xy 440.855277 -425.399855) (xy 440.803948 -425.421667) (xy 440.749991 -425.435773)
			(xy 440.694554 -425.441873) (xy 440.63882 -425.439836) (xy 440.583977 -425.429706) (xy 440.531193 -425.411699)
			(xy 440.481593 -425.386198) (xy 440.436235 -425.353747) (xy 440.396086 -425.315038) (xy 440.362 -425.270895)
			(xy 440.334704 -425.22226) (xy 440.314781 -425.170169) (xy 440.302655 -425.115732) (xy 440.298584 -425.06011)
			(xy 438.246781 -425.06011) (xy 438.227951 -425.081126) (xy 438.185083 -425.116801) (xy 438.137477 -425.145855)
			(xy 438.086148 -425.167667) (xy 438.032191 -425.181773) (xy 437.976754 -425.187873) (xy 437.92102 -425.185836)
			(xy 437.866177 -425.175706) (xy 437.813393 -425.157699) (xy 437.763793 -425.132198) (xy 437.718435 -425.099747)
			(xy 437.678286 -425.061038) (xy 437.6442 -425.016895) (xy 437.616904 -424.96826) (xy 437.596981 -424.916169)
			(xy 437.584855 -424.861732) (xy 437.580784 -424.80611) (xy 436.337456 -424.80611) (xy 436.337456 -426.377354)
			(xy 436.337808 -426.387401) (xy 436.345408 -426.405998) (xy 436.352188 -426.413422) (xy 436.776876 -426.83811)
			(xy 440.247784 -426.83811) (xy 440.251855 -426.782488) (xy 440.263981 -426.728051) (xy 440.283904 -426.67596)
			(xy 440.3112 -426.627325) (xy 440.345286 -426.583182) (xy 440.385435 -426.544473) (xy 440.430793 -426.512022)
			(xy 440.480393 -426.486521) (xy 440.533177 -426.468514) (xy 440.58802 -426.458384) (xy 440.643754 -426.456347)
			(xy 440.699191 -426.462447) (xy 440.753148 -426.476553) (xy 440.804477 -426.498365) (xy 440.852083 -426.527419)
			(xy 440.894951 -426.563094) (xy 440.932168 -426.604631) (xy 440.962941 -426.651144) (xy 440.986613 -426.701641)
			(xy 441.002681 -426.755048) (xy 441.010801 -426.810224) (xy 441.01131 -426.83811) (xy 441.010801 -426.865996)
			(xy 441.002681 -426.921172) (xy 440.986613 -426.974579) (xy 440.962941 -427.025076) (xy 440.932168 -427.071589)
			(xy 440.894951 -427.113126) (xy 440.852083 -427.148801) (xy 440.804477 -427.177855) (xy 440.753148 -427.199667)
			(xy 440.699191 -427.213773) (xy 440.643754 -427.219873) (xy 440.58802 -427.217836) (xy 440.533177 -427.207706)
			(xy 440.480393 -427.189699) (xy 440.430793 -427.164198) (xy 440.385435 -427.131747) (xy 440.345286 -427.093038)
			(xy 440.3112 -427.048895) (xy 440.283904 -427.00026) (xy 440.263981 -426.948169) (xy 440.251855 -426.893732)
			(xy 440.247784 -426.83811) (xy 436.776876 -426.83811) (xy 437.85917 -427.920404) (xy 437.866629 -427.927125)
			(xy 437.885206 -427.934697) (xy 437.895238 -427.935136) (xy 443.871858 -427.935136) (xy 443.87897 -427.933104)
			(xy 443.905713 -427.925598) (xy 443.960672 -427.917559) (xy 443.988444 -427.917102) (xy 444.017293 -427.917646)
			(xy 444.074335 -427.926313) (xy 444.129421 -427.943475) (xy 444.181293 -427.968738) (xy 444.228767 -428.001527)
			(xy 444.270761 -428.041093) (xy 444.306316 -428.086533) (xy 444.32093 -428.111412) (xy 444.327788 -428.123604)
			(xy 444.351918 -428.137574) (xy 444.470028 -428.13478) (xy 444.49365 -428.120048) (xy 444.5 -428.107348)
			(xy 444.507369 -428.093159) (xy 444.524155 -428.065945) (xy 444.533528 -428.052992) (xy 444.538617 -428.04549)
			(xy 444.54363 -428.028083) (xy 444.542241 -428.010022) (xy 444.534626 -427.993586) (xy 444.528448 -427.986952)
			(xy 443.105286 -426.563536) (xy 443.097803 -426.556845) (xy 443.079245 -426.549254) (xy 443.069218 -426.548804)
			(xy 442.385704 -426.548804) (xy 442.360707 -426.548187) (xy 442.311682 -426.53838) (xy 442.265511 -426.519201)
			(xy 442.223966 -426.491387) (xy 442.205872 -426.474128) (xy 441.520326 -425.788582) (xy 441.503077 -425.770496)
			(xy 441.475342 -425.728928) (xy 441.456242 -425.682751) (xy 441.44651 -425.633736) (xy 441.445904 -425.60875)
			(xy 441.445904 -416.297618) (xy 441.446558 -416.272637) (xy 441.45629 -416.223632) (xy 441.475385 -416.177462)
			(xy 441.503111 -416.135899) (xy 441.520326 -416.117786) (xy 442.644022 -414.99409) (xy 442.662147 -414.976868)
			(xy 442.703716 -414.949104) (xy 442.726572 -414.938972) (xy 445.261238 -413.88919) (xy 445.270356 -413.884991)
			(xy 445.28453 -413.870797) (xy 445.292126 -413.852232) (xy 445.29248 -413.8422) (xy 445.29248 -410.394404)
			(xy 445.293102 -410.369407) (xy 445.302908 -410.320383) (xy 445.322085 -410.274212) (xy 445.349898 -410.232667)
			(xy 445.367156 -410.214572) (xy 446.433448 -409.14828) (xy 446.451526 -409.131005) (xy 446.493078 -409.103199)
			(xy 446.539254 -409.084031) (xy 446.588282 -409.074238) (xy 446.61328 -409.073604) (xy 449.504562 -409.073604)
			(xy 449.514611 -409.073266) (xy 449.533208 -409.065657) (xy 449.54063 -409.058872) (xy 453.518016 -405.081486)
			(xy 453.5247 -405.073997) (xy 453.532297 -405.055444) (xy 453.532748 -405.045418) (xy 453.532748 -402.720048)
			(xy 453.533426 -402.695063) (xy 453.543272 -402.64607) (xy 453.552306 -402.622766) (xy 453.658732 -402.365972)
			(xy 453.668807 -402.343084) (xy 453.696574 -402.301503) (xy 453.71385 -402.283422) (xy 454.024492 -401.97278)
			(xy 454.040154 -401.957742) (xy 454.075615 -401.932694) (xy 454.114815 -401.914032) (xy 454.156615 -401.902299)
			(xy 454.178162 -401.899628) (xy 454.186882 -401.898357) (xy 454.202729 -401.890679) (xy 454.20915 -401.884642)
			(xy 454.230814 -401.863548) (xy 454.279533 -401.827741) (xy 454.333291 -401.80007) (xy 454.390741 -401.781227)
			(xy 454.450445 -401.771683) (xy 454.480676 -401.771104) (xy 454.507931 -401.771541) (xy 454.561886 -401.779296)
			(xy 454.614189 -401.79465) (xy 454.663773 -401.817292) (xy 454.709631 -401.84676) (xy 454.750828 -401.882455)
			(xy 454.786525 -401.92365) (xy 454.815996 -401.969506) (xy 454.838641 -402.019089) (xy 454.853999 -402.07139)
			(xy 454.861757 -402.125345) (xy 454.861757 -402.179855) (xy 454.853999 -402.23381) (xy 454.838641 -402.286111)
			(xy 454.815996 -402.335694) (xy 454.786525 -402.38155) (xy 454.750828 -402.422745) (xy 454.709631 -402.45844)
			(xy 454.663773 -402.487908) (xy 454.614189 -402.51055) (xy 454.561886 -402.525904) (xy 454.507931 -402.533659)
			(xy 454.480676 -402.53412) (xy 454.45544 -402.533731) (xy 454.405406 -402.52711) (xy 454.356686 -402.513935)
			(xy 454.310134 -402.494436) (xy 454.288144 -402.48205) (xy 454.278235 -402.476886) (xy 454.255998 -402.474886)
			(xy 454.234996 -402.482459) (xy 454.226676 -402.489924) (xy 454.11644 -402.60016) (xy 454.113018 -402.603786)
			(xy 454.107523 -402.612105) (xy 454.105518 -402.61667) (xy 454.045574 -402.76145) (xy 454.043813 -402.766082)
			(xy 454.041887 -402.7758) (xy 454.041764 -402.780754) (xy 454.041764 -405.17191) (xy 454.041138 -405.196907)
			(xy 454.031331 -405.24593) (xy 454.012154 -405.2921) (xy 453.984344 -405.333646) (xy 453.967088 -405.351742)
			(xy 452.966836 -406.351994) (xy 456.067414 -406.351994) (xy 456.067927 -406.323785) (xy 456.076229 -406.267981)
			(xy 456.092666 -406.214011) (xy 456.116878 -406.163053) (xy 456.148338 -406.11622) (xy 456.186356 -406.074536)
			(xy 456.230104 -406.038912) (xy 456.254104 -406.02408) (xy 456.266496 -406.016145) (xy 456.286401 -405.994487)
			(xy 456.299322 -405.968061) (xy 456.30419 -405.939051) (xy 456.300602 -405.909854) (xy 456.288857 -405.882886)
			(xy 456.269923 -405.860373) (xy 456.257914 -405.851868) (xy 456.235704 -405.836632) (xy 456.195365 -405.800945)
			(xy 456.160445 -405.759942) (xy 456.131636 -405.714436) (xy 456.109511 -405.665331) (xy 456.09451 -405.613604)
			(xy 456.08693 -405.560281) (xy 456.086464 -405.533352) (xy 456.08695 -405.506101) (xy 456.094706 -405.452153)
			(xy 456.110061 -405.399858) (xy 456.132703 -405.350281) (xy 456.162169 -405.304431) (xy 456.19786 -405.26324)
			(xy 456.239051 -405.227549) (xy 456.284901 -405.198083) (xy 456.334478 -405.175441) (xy 456.386773 -405.160086)
			(xy 456.440721 -405.15233) (xy 456.495223 -405.15233) (xy 456.549171 -405.160086) (xy 456.601466 -405.175441)
			(xy 456.651043 -405.198083) (xy 456.696893 -405.227549) (xy 456.738084 -405.26324) (xy 456.773775 -405.304431)
			(xy 456.803241 -405.350281) (xy 456.825883 -405.399858) (xy 456.841238 -405.452153) (xy 456.848994 -405.506101)
			(xy 456.84948 -405.533352) (xy 456.848927 -405.56156) (xy 456.840633 -405.617362) (xy 456.824203 -405.671331)
			(xy 456.799998 -405.722289) (xy 456.768544 -405.769122) (xy 456.730531 -405.810808) (xy 456.686788 -405.846434)
			(xy 456.66279 -405.861266) (xy 456.650449 -405.869273) (xy 456.630548 -405.890916) (xy 456.617626 -405.917326)
			(xy 456.612753 -405.946321) (xy 456.61633 -405.975505) (xy 456.628062 -406.002465) (xy 456.646979 -406.024973)
			(xy 456.65898 -406.033478) (xy 456.68121 -406.048686) (xy 456.721549 -406.084377) (xy 456.756468 -406.125386)
			(xy 456.785275 -406.170896) (xy 456.807396 -406.220005) (xy 456.822393 -406.271737) (xy 456.829967 -406.325063)
			(xy 456.83043 -406.351994) (xy 456.829944 -406.379245) (xy 456.822188 -406.433193) (xy 456.806833 -406.485488)
			(xy 456.784191 -406.535065) (xy 456.754725 -406.580915) (xy 456.719034 -406.622106) (xy 456.677843 -406.657797)
			(xy 456.631993 -406.687263) (xy 456.582416 -406.709905) (xy 456.530121 -406.72526) (xy 456.476173 -406.733016)
			(xy 456.421671 -406.733016) (xy 456.367723 -406.72526) (xy 456.315428 -406.709905) (xy 456.265851 -406.687263)
			(xy 456.220001 -406.657797) (xy 456.17881 -406.622106) (xy 456.143119 -406.580915) (xy 456.113653 -406.535065)
			(xy 456.091011 -406.485488) (xy 456.075656 -406.433193) (xy 456.0679 -406.379245) (xy 456.067414 -406.351994)
			(xy 452.966836 -406.351994) (xy 451.988682 -407.330148) (xy 456.075796 -407.330148) (xy 456.076282 -407.302897)
			(xy 456.084038 -407.248949) (xy 456.099393 -407.196654) (xy 456.122035 -407.147077) (xy 456.151501 -407.101227)
			(xy 456.187192 -407.060036) (xy 456.228383 -407.024345) (xy 456.274233 -406.994879) (xy 456.32381 -406.972237)
			(xy 456.376105 -406.956882) (xy 456.430053 -406.949126) (xy 456.484555 -406.949126) (xy 456.538503 -406.956882)
			(xy 456.590798 -406.972237) (xy 456.640375 -406.994879) (xy 456.686225 -407.024345) (xy 456.727416 -407.060036)
			(xy 456.763107 -407.101227) (xy 456.792573 -407.147077) (xy 456.815215 -407.196654) (xy 456.83057 -407.248949)
			(xy 456.838326 -407.302897) (xy 456.838812 -407.330148) (xy 456.838291 -407.35901) (xy 456.829609 -407.416078)
			(xy 456.812419 -407.471184) (xy 456.787116 -407.523067) (xy 456.754278 -407.570541) (xy 456.714656 -407.612519)
			(xy 456.669156 -407.648043) (xy 456.644248 -407.662634) (xy 456.632498 -407.669733) (xy 456.61303 -407.689076)
			(xy 456.599416 -407.712904) (xy 456.592637 -407.739497) (xy 456.593184 -407.766935) (xy 456.601016 -407.793237)
			(xy 456.615569 -407.816504) (xy 456.635792 -407.835056) (xy 456.647804 -407.841704) (xy 456.670957 -407.854001)
			(xy 456.713937 -407.884023) (xy 456.752403 -407.919644) (xy 456.785633 -407.960193) (xy 456.813001 -408.004909)
			(xy 456.833993 -408.05295) (xy 456.848213 -408.103411) (xy 456.855393 -408.155343) (xy 456.85583 -408.181556)
			(xy 456.855344 -408.208807) (xy 456.847588 -408.262755) (xy 456.832233 -408.31505) (xy 456.809591 -408.364627)
			(xy 456.780125 -408.410477) (xy 456.744434 -408.451668) (xy 456.703243 -408.487359) (xy 456.657393 -408.516825)
			(xy 456.607816 -408.539467) (xy 456.555521 -408.554822) (xy 456.501573 -408.562578) (xy 456.447071 -408.562578)
			(xy 456.393123 -408.554822) (xy 456.340828 -408.539467) (xy 456.291251 -408.516825) (xy 456.245401 -408.487359)
			(xy 456.20421 -408.451668) (xy 456.168519 -408.410477) (xy 456.139053 -408.364627) (xy 456.116411 -408.31505)
			(xy 456.101056 -408.262755) (xy 456.0933 -408.208807) (xy 456.092814 -408.181556) (xy 456.093325 -408.152693)
			(xy 456.102008 -408.095624) (xy 456.119198 -408.040518) (xy 456.144503 -407.988634) (xy 456.177343 -407.94116)
			(xy 456.216967 -407.899183) (xy 456.262469 -407.863661) (xy 456.287378 -407.84907) (xy 456.299122 -407.841963)
			(xy 456.318584 -407.822619) (xy 456.332195 -407.798793) (xy 456.338971 -407.772203) (xy 456.338425 -407.744769)
			(xy 456.330596 -407.718469) (xy 456.316048 -407.695203) (xy 456.295831 -407.67665) (xy 456.283822 -407.67)
			(xy 456.260676 -407.657689) (xy 456.217696 -407.62767) (xy 456.179228 -407.592052) (xy 456.145997 -407.551504)
			(xy 456.118628 -407.50679) (xy 456.097635 -407.458752) (xy 456.083415 -407.408292) (xy 456.076233 -407.356361)
			(xy 456.075796 -407.330148) (xy 451.988682 -407.330148) (xy 449.810886 -409.507944) (xy 449.792781 -409.52519)
			(xy 449.751241 -409.553005) (xy 449.705072 -409.572181) (xy 449.65605 -409.581983) (xy 449.631054 -409.58262)
			(xy 446.739772 -409.58262) (xy 446.729727 -409.582995) (xy 446.711131 -409.59058) (xy 446.703704 -409.597352)
			(xy 445.816228 -410.484828) (xy 445.80953 -410.492306) (xy 445.801943 -410.510868) (xy 445.801496 -410.520896)
			(xy 445.801496 -410.578554) (xy 446.710306 -410.578554) (xy 446.714377 -410.522932) (xy 446.726503 -410.468495)
			(xy 446.746426 -410.416404) (xy 446.773722 -410.367769) (xy 446.807808 -410.323626) (xy 446.847957 -410.284917)
			(xy 446.893315 -410.252466) (xy 446.942915 -410.226965) (xy 446.995699 -410.208958) (xy 447.050542 -410.198828)
			(xy 447.106276 -410.196791) (xy 447.161713 -410.202891) (xy 447.21567 -410.216997) (xy 447.266999 -410.238809)
			(xy 447.314605 -410.267863) (xy 447.357473 -410.303538) (xy 447.39469 -410.345075) (xy 447.425463 -410.391588)
			(xy 447.449135 -410.442085) (xy 447.465203 -410.495492) (xy 447.473323 -410.550668) (xy 447.473832 -410.578554)
			(xy 447.599306 -410.578554) (xy 447.603377 -410.522932) (xy 447.615503 -410.468495) (xy 447.635426 -410.416404)
			(xy 447.662722 -410.367769) (xy 447.696808 -410.323626) (xy 447.736957 -410.284917) (xy 447.782315 -410.252466)
			(xy 447.831915 -410.226965) (xy 447.884699 -410.208958) (xy 447.939542 -410.198828) (xy 447.995276 -410.196791)
			(xy 448.050713 -410.202891) (xy 448.10467 -410.216997) (xy 448.155999 -410.238809) (xy 448.203605 -410.267863)
			(xy 448.246473 -410.303538) (xy 448.28369 -410.345075) (xy 448.314463 -410.391588) (xy 448.338135 -410.442085)
			(xy 448.354203 -410.495492) (xy 448.362323 -410.550668) (xy 448.362832 -410.578554) (xy 448.488306 -410.578554)
			(xy 448.492377 -410.522932) (xy 448.504503 -410.468495) (xy 448.524426 -410.416404) (xy 448.551722 -410.367769)
			(xy 448.585808 -410.323626) (xy 448.625957 -410.284917) (xy 448.671315 -410.252466) (xy 448.720915 -410.226965)
			(xy 448.773699 -410.208958) (xy 448.828542 -410.198828) (xy 448.884276 -410.196791) (xy 448.939713 -410.202891)
			(xy 448.99367 -410.216997) (xy 449.044999 -410.238809) (xy 449.092605 -410.267863) (xy 449.135473 -410.303538)
			(xy 449.17269 -410.345075) (xy 449.203463 -410.391588) (xy 449.227135 -410.442085) (xy 449.243203 -410.495492)
			(xy 449.251323 -410.550668) (xy 449.251832 -410.578554) (xy 449.251323 -410.60644) (xy 449.243203 -410.661616)
			(xy 449.227135 -410.715023) (xy 449.203463 -410.76552) (xy 449.17269 -410.812033) (xy 449.135473 -410.85357)
			(xy 449.092605 -410.889245) (xy 449.071044 -410.902404) (xy 451.091808 -410.902404) (xy 451.092365 -410.87228)
			(xy 451.101847 -410.812782) (xy 451.12056 -410.755513) (xy 451.14804 -410.701897) (xy 451.183603 -410.653264)
			(xy 451.204584 -410.63164) (xy 451.21195 -410.624528) (xy 451.21957 -410.605732) (xy 451.21957 -410.513276)
			(xy 451.21195 -410.49448) (xy 451.204584 -410.487368) (xy 451.183608 -410.465739) (xy 451.14804 -410.417111)
			(xy 451.12056 -410.363495) (xy 451.10185 -410.306226) (xy 451.092377 -410.246728) (xy 451.091808 -410.216604)
			(xy 451.092259 -410.189351) (xy 451.100016 -410.135398) (xy 451.115372 -410.083099) (xy 451.138015 -410.033518)
			(xy 451.167485 -409.987664) (xy 451.20318 -409.946471) (xy 451.244374 -409.910777) (xy 451.290229 -409.88131)
			(xy 451.339811 -409.858668) (xy 451.39211 -409.843313) (xy 451.446063 -409.835558) (xy 451.473316 -409.835096)
			(xy 451.503441 -409.835643) (xy 451.562939 -409.845128) (xy 451.620207 -409.863844) (xy 451.673824 -409.891325)
			(xy 451.722457 -409.92689) (xy 451.74408 -409.947872) (xy 451.751192 -409.955238) (xy 451.769988 -409.962858)
			(xy 451.862444 -409.962858) (xy 451.88124 -409.955238) (xy 451.888352 -409.947872) (xy 451.909987 -409.926903)
			(xy 451.958612 -409.89133) (xy 452.012225 -409.863847) (xy 452.069494 -409.845136) (xy 452.128992 -409.835665)
			(xy 452.159116 -409.835096) (xy 452.186487 -409.835554) (xy 452.240666 -409.843374) (xy 452.293169 -409.858865)
			(xy 452.342916 -409.881708) (xy 452.388882 -409.911434) (xy 452.409814 -409.929076) (xy 452.416926 -409.935172)
			(xy 452.433944 -409.941522) (xy 452.519288 -409.941522) (xy 452.536306 -409.935172) (xy 452.543418 -409.929076)
			(xy 452.564367 -409.911458) (xy 452.610336 -409.881744) (xy 452.660079 -409.858904) (xy 452.712576 -409.843408)
			(xy 452.766748 -409.835574) (xy 452.794116 -409.835096) (xy 452.821368 -409.835563) (xy 452.875316 -409.843322)
			(xy 452.927612 -409.858679) (xy 452.977189 -409.881322) (xy 453.02304 -409.910791) (xy 453.06423 -409.946484)
			(xy 453.099921 -409.987676) (xy 453.129387 -410.033528) (xy 453.152028 -410.083107) (xy 453.167383 -410.135403)
			(xy 453.175139 -410.189352) (xy 453.175624 -410.216604) (xy 453.175063 -410.246728) (xy 453.165581 -410.306225)
			(xy 453.146868 -410.363493) (xy 453.11939 -410.41711) (xy 453.083828 -410.465744) (xy 453.062848 -410.487368)
			(xy 453.055482 -410.49448) (xy 453.047862 -410.513276) (xy 453.047862 -410.6037) (xy 454.780648 -410.6037)
			(xy 454.784719 -410.548078) (xy 454.796845 -410.493641) (xy 454.816768 -410.44155) (xy 454.844064 -410.392915)
			(xy 454.87815 -410.348772) (xy 454.918299 -410.310063) (xy 454.963657 -410.277612) (xy 455.013257 -410.252111)
			(xy 455.066041 -410.234104) (xy 455.120884 -410.223974) (xy 455.176618 -410.221937) (xy 455.232055 -410.228037)
			(xy 455.286012 -410.242143) (xy 455.337341 -410.263955) (xy 455.384947 -410.293009) (xy 455.427815 -410.328684)
			(xy 455.465032 -410.370221) (xy 455.495805 -410.416734) (xy 455.519477 -410.467231) (xy 455.535545 -410.520638)
			(xy 455.543665 -410.575814) (xy 455.544174 -410.6037) (xy 455.669648 -410.6037) (xy 455.673719 -410.548078)
			(xy 455.685845 -410.493641) (xy 455.705768 -410.44155) (xy 455.733064 -410.392915) (xy 455.76715 -410.348772)
			(xy 455.807299 -410.310063) (xy 455.852657 -410.277612) (xy 455.902257 -410.252111) (xy 455.955041 -410.234104)
			(xy 456.009884 -410.223974) (xy 456.065618 -410.221937) (xy 456.121055 -410.228037) (xy 456.175012 -410.242143)
			(xy 456.226341 -410.263955) (xy 456.273947 -410.293009) (xy 456.316815 -410.328684) (xy 456.354032 -410.370221)
			(xy 456.384805 -410.416734) (xy 456.408477 -410.467231) (xy 456.424545 -410.520638) (xy 456.432665 -410.575814)
			(xy 456.433174 -410.6037) (xy 456.558648 -410.6037) (xy 456.562719 -410.548078) (xy 456.574845 -410.493641)
			(xy 456.594768 -410.44155) (xy 456.622064 -410.392915) (xy 456.65615 -410.348772) (xy 456.696299 -410.310063)
			(xy 456.741657 -410.277612) (xy 456.791257 -410.252111) (xy 456.844041 -410.234104) (xy 456.898884 -410.223974)
			(xy 456.954618 -410.221937) (xy 457.010055 -410.228037) (xy 457.064012 -410.242143) (xy 457.115341 -410.263955)
			(xy 457.162947 -410.293009) (xy 457.205815 -410.328684) (xy 457.243032 -410.370221) (xy 457.273805 -410.416734)
			(xy 457.297477 -410.467231) (xy 457.313545 -410.520638) (xy 457.321665 -410.575814) (xy 457.322174 -410.6037)
			(xy 457.321665 -410.631586) (xy 457.313545 -410.686762) (xy 457.297477 -410.740169) (xy 457.273805 -410.790666)
			(xy 457.243032 -410.837179) (xy 457.205815 -410.878716) (xy 457.162947 -410.914391) (xy 457.115341 -410.943445)
			(xy 457.064012 -410.965257) (xy 457.010055 -410.979363) (xy 456.954618 -410.985463) (xy 456.898884 -410.983426)
			(xy 456.844041 -410.973296) (xy 456.791257 -410.955289) (xy 456.741657 -410.929788) (xy 456.696299 -410.897337)
			(xy 456.65615 -410.858628) (xy 456.622064 -410.814485) (xy 456.594768 -410.76585) (xy 456.574845 -410.713759)
			(xy 456.562719 -410.659322) (xy 456.558648 -410.6037) (xy 456.433174 -410.6037) (xy 456.432665 -410.631586)
			(xy 456.424545 -410.686762) (xy 456.408477 -410.740169) (xy 456.384805 -410.790666) (xy 456.354032 -410.837179)
			(xy 456.316815 -410.878716) (xy 456.273947 -410.914391) (xy 456.226341 -410.943445) (xy 456.175012 -410.965257)
			(xy 456.121055 -410.979363) (xy 456.065618 -410.985463) (xy 456.009884 -410.983426) (xy 455.955041 -410.973296)
			(xy 455.902257 -410.955289) (xy 455.852657 -410.929788) (xy 455.807299 -410.897337) (xy 455.76715 -410.858628)
			(xy 455.733064 -410.814485) (xy 455.705768 -410.76585) (xy 455.685845 -410.713759) (xy 455.673719 -410.659322)
			(xy 455.669648 -410.6037) (xy 455.544174 -410.6037) (xy 455.543665 -410.631586) (xy 455.535545 -410.686762)
			(xy 455.519477 -410.740169) (xy 455.495805 -410.790666) (xy 455.465032 -410.837179) (xy 455.427815 -410.878716)
			(xy 455.384947 -410.914391) (xy 455.337341 -410.943445) (xy 455.286012 -410.965257) (xy 455.232055 -410.979363)
			(xy 455.176618 -410.985463) (xy 455.120884 -410.983426) (xy 455.066041 -410.973296) (xy 455.013257 -410.955289)
			(xy 454.963657 -410.929788) (xy 454.918299 -410.897337) (xy 454.87815 -410.858628) (xy 454.844064 -410.814485)
			(xy 454.816768 -410.76585) (xy 454.796845 -410.713759) (xy 454.784719 -410.659322) (xy 454.780648 -410.6037)
			(xy 453.047862 -410.6037) (xy 453.047862 -410.605732) (xy 453.055482 -410.624528) (xy 453.062848 -410.63164)
			(xy 453.083816 -410.653277) (xy 453.119388 -410.701901) (xy 453.146871 -410.755515) (xy 453.165582 -410.812783)
			(xy 453.175055 -410.87228) (xy 453.175624 -410.902404) (xy 453.175126 -410.929655) (xy 453.167369 -410.983601)
			(xy 453.152015 -411.035895) (xy 453.129374 -411.085471) (xy 453.099909 -411.13132) (xy 453.064219 -411.17251)
			(xy 453.02303 -411.208202) (xy 452.977181 -411.237668) (xy 452.927606 -411.26031) (xy 452.875313 -411.275667)
			(xy 452.821367 -411.283425) (xy 452.794116 -411.283912) (xy 452.766746 -411.283434) (xy 452.712568 -411.275618)
			(xy 452.660065 -411.260132) (xy 452.610318 -411.237293) (xy 452.56435 -411.207572) (xy 452.543418 -411.189932)
			(xy 452.536306 -411.183836) (xy 452.519288 -411.177486) (xy 452.433944 -411.177486) (xy 452.416926 -411.183836)
			(xy 452.409814 -411.189932) (xy 452.388892 -411.207583) (xy 452.342916 -411.237292) (xy 452.293166 -411.260125)
			(xy 452.240663 -411.275613) (xy 452.186486 -411.283439) (xy 452.159116 -411.283912) (xy 452.128992 -411.283342)
			(xy 452.069496 -411.273862) (xy 452.012227 -411.255152) (xy 451.95861 -411.227675) (xy 451.909976 -411.192116)
			(xy 451.888352 -411.171136) (xy 451.88124 -411.16377) (xy 451.862444 -411.15615) (xy 451.769988 -411.15615)
			(xy 451.751192 -411.16377) (xy 451.74408 -411.171136) (xy 451.722432 -411.192091) (xy 451.673811 -411.227665)
			(xy 451.6202 -411.255151) (xy 451.562935 -411.273865) (xy 451.503439 -411.283341) (xy 451.473316 -411.283912)
			(xy 451.446064 -411.28343) (xy 451.392114 -411.275675) (xy 451.339816 -411.260321) (xy 451.290237 -411.237681)
			(xy 451.244384 -411.208215) (xy 451.203191 -411.172523) (xy 451.167497 -411.131332) (xy 451.138029 -411.085481)
			(xy 451.115386 -411.035902) (xy 451.100029 -410.983606) (xy 451.092272 -410.929656) (xy 451.091808 -410.902404)
			(xy 449.071044 -410.902404) (xy 449.044999 -410.918299) (xy 448.99367 -410.940111) (xy 448.939713 -410.954217)
			(xy 448.884276 -410.960317) (xy 448.828542 -410.95828) (xy 448.773699 -410.94815) (xy 448.720915 -410.930143)
			(xy 448.671315 -410.904642) (xy 448.625957 -410.872191) (xy 448.585808 -410.833482) (xy 448.551722 -410.789339)
			(xy 448.524426 -410.740704) (xy 448.504503 -410.688613) (xy 448.492377 -410.634176) (xy 448.488306 -410.578554)
			(xy 448.362832 -410.578554) (xy 448.362323 -410.60644) (xy 448.354203 -410.661616) (xy 448.338135 -410.715023)
			(xy 448.314463 -410.76552) (xy 448.28369 -410.812033) (xy 448.246473 -410.85357) (xy 448.203605 -410.889245)
			(xy 448.155999 -410.918299) (xy 448.10467 -410.940111) (xy 448.050713 -410.954217) (xy 447.995276 -410.960317)
			(xy 447.939542 -410.95828) (xy 447.884699 -410.94815) (xy 447.831915 -410.930143) (xy 447.782315 -410.904642)
			(xy 447.736957 -410.872191) (xy 447.696808 -410.833482) (xy 447.662722 -410.789339) (xy 447.635426 -410.740704)
			(xy 447.615503 -410.688613) (xy 447.603377 -410.634176) (xy 447.599306 -410.578554) (xy 447.473832 -410.578554)
			(xy 447.473323 -410.60644) (xy 447.465203 -410.661616) (xy 447.449135 -410.715023) (xy 447.425463 -410.76552)
			(xy 447.39469 -410.812033) (xy 447.357473 -410.85357) (xy 447.314605 -410.889245) (xy 447.266999 -410.918299)
			(xy 447.21567 -410.940111) (xy 447.161713 -410.954217) (xy 447.106276 -410.960317) (xy 447.050542 -410.95828)
			(xy 446.995699 -410.94815) (xy 446.942915 -410.930143) (xy 446.893315 -410.904642) (xy 446.847957 -410.872191)
			(xy 446.807808 -410.833482) (xy 446.773722 -410.789339) (xy 446.746426 -410.740704) (xy 446.726503 -410.688613)
			(xy 446.714377 -410.634176) (xy 446.710306 -410.578554) (xy 445.801496 -410.578554) (xy 445.801496 -414.046162)
			(xy 445.801045 -414.067586) (xy 445.79384 -414.109823) (xy 445.779661 -414.150257) (xy 445.758908 -414.187744)
			(xy 445.732169 -414.221224) (xy 445.700198 -414.249752) (xy 445.663901 -414.27252) (xy 445.64427 -414.281112)
			(xy 443.553107 -415.147252) (xy 449.363338 -415.147252) (xy 449.363825 -415.119882) (xy 449.371637 -415.065704)
			(xy 449.38712 -415.013201) (xy 449.409957 -414.963453) (xy 449.439678 -414.917486) (xy 449.457318 -414.896554)
			(xy 449.463414 -414.889442) (xy 449.469764 -414.872424) (xy 449.469764 -414.78708) (xy 449.463414 -414.770062)
			(xy 449.457318 -414.76295) (xy 449.439692 -414.742008) (xy 449.409977 -414.696038) (xy 449.387139 -414.646293)
			(xy 449.371645 -414.593795) (xy 449.363813 -414.539621) (xy 449.363338 -414.512252) (xy 449.363733 -414.484997)
			(xy 449.371498 -414.431044) (xy 449.386861 -414.378745) (xy 449.409511 -414.329164) (xy 449.438987 -414.283312)
			(xy 449.474688 -414.242121) (xy 449.515887 -414.20643) (xy 449.561747 -414.176966) (xy 449.611333 -414.154328)
			(xy 449.663636 -414.138978) (xy 449.717591 -414.131227) (xy 449.744846 -414.130744) (xy 449.774968 -414.13135)
			(xy 449.834463 -414.140823) (xy 449.89173 -414.159526) (xy 449.945348 -414.186993) (xy 449.993984 -414.222544)
			(xy 450.01561 -414.24352) (xy 450.022722 -414.250886) (xy 450.041518 -414.258506) (xy 450.133974 -414.258506)
			(xy 450.15277 -414.250886) (xy 450.159882 -414.24352) (xy 450.181495 -414.222527) (xy 450.230127 -414.186959)
			(xy 450.283746 -414.159481) (xy 450.341019 -414.140776) (xy 450.400521 -414.13131) (xy 450.430646 -414.130744)
			(xy 450.457896 -414.131235) (xy 450.511841 -414.138996) (xy 450.564133 -414.154355) (xy 450.613707 -414.176998)
			(xy 450.659555 -414.206465) (xy 450.700743 -414.242155) (xy 450.736434 -414.283343) (xy 450.765901 -414.329191)
			(xy 450.788544 -414.378765) (xy 450.803903 -414.431057) (xy 450.811665 -414.485002) (xy 450.812154 -414.512252)
			(xy 450.811597 -414.541729) (xy 450.802533 -414.599982) (xy 450.784616 -414.656147) (xy 450.75827 -414.708887)
			(xy 450.724123 -414.756945) (xy 450.70395 -414.778444) (xy 450.697396 -414.785764) (xy 450.689964 -414.803936)
			(xy 450.689472 -414.81375) (xy 450.689472 -414.86709) (xy 450.702426 -414.879536) (xy 450.710329 -414.886933)
			(xy 450.730463 -414.894828) (xy 450.741288 -414.894776) (xy 450.7738 -414.892998) (xy 450.784574 -414.891856)
			(xy 450.803779 -414.881872) (xy 450.810884 -414.873694) (xy 450.829064 -414.851551) (xy 450.870964 -414.812479)
			(xy 450.918237 -414.780112) (xy 450.969818 -414.755179) (xy 451.024548 -414.738242) (xy 451.081196 -414.729679)
			(xy 451.109842 -414.729168) (xy 451.139964 -414.72977) (xy 451.199459 -414.739243) (xy 451.256727 -414.757946)
			(xy 451.310345 -414.785415) (xy 451.35898 -414.820968) (xy 451.380606 -414.841944) (xy 451.387718 -414.84931)
			(xy 451.406514 -414.85693) (xy 451.49897 -414.85693) (xy 451.517766 -414.84931) (xy 451.524878 -414.841944)
			(xy 451.546497 -414.820957) (xy 451.595126 -414.785388) (xy 451.648744 -414.757908) (xy 451.706016 -414.739202)
			(xy 451.765517 -414.729734) (xy 451.795642 -414.729168) (xy 451.821941 -414.729585) (xy 451.87404 -414.73681)
			(xy 451.92465 -414.751129) (xy 451.972811 -414.772271) (xy 452.017608 -414.799834) (xy 452.058189 -414.833295)
			(xy 452.076312 -414.852358) (xy 452.083424 -414.859978) (xy 452.101712 -414.86836) (xy 452.194168 -414.871662)
			(xy 452.213218 -414.864804) (xy 452.220584 -414.857692) (xy 452.241902 -414.838411) (xy 452.289266 -414.805844)
			(xy 452.340979 -414.780753) (xy 452.395873 -414.763705) (xy 452.452702 -414.755087) (xy 452.481442 -414.754568)
			(xy 452.510242 -414.755066) (xy 452.567191 -414.763698) (xy 452.622196 -414.78079) (xy 452.674009 -414.805954)
			(xy 452.721451 -414.838618) (xy 452.742808 -414.857946) (xy 452.74992 -414.864804) (xy 452.767954 -414.871916)
			(xy 452.85787 -414.871154) (xy 452.875904 -414.864042) (xy 452.883016 -414.857184) (xy 452.904484 -414.837172)
			(xy 452.9524 -414.803287) (xy 453.004938 -414.777135) (xy 453.060861 -414.759334) (xy 453.118849 -414.750304)
			(xy 453.148192 -414.749742) (xy 453.17451 -414.750141) (xy 453.226647 -414.75737) (xy 453.277297 -414.771693)
			(xy 453.325499 -414.792837) (xy 453.370339 -414.820403) (xy 453.410968 -414.853867) (xy 453.429116 -414.872932)
			(xy 453.43626 -414.879989) (xy 453.454426 -414.888492) (xy 453.464422 -414.889442) (xy 453.51827 -414.891474)
			(xy 453.52462 -414.885124) (xy 453.531732 -414.878012) (xy 453.539352 -414.859724) (xy 453.540368 -414.76803)
			(xy 453.533002 -414.749742) (xy 453.52589 -414.742376) (xy 453.505877 -414.720922) (xy 453.472052 -414.672985)
			(xy 453.44596 -414.620436) (xy 453.428217 -414.564514) (xy 453.419239 -414.506535) (xy 453.418702 -414.4772)
			(xy 453.419188 -414.449949) (xy 453.426944 -414.396001) (xy 453.442299 -414.343706) (xy 453.464941 -414.294129)
			(xy 453.494407 -414.248279) (xy 453.530098 -414.207088) (xy 453.571289 -414.171397) (xy 453.617139 -414.141931)
			(xy 453.666716 -414.119289) (xy 453.719011 -414.103934) (xy 453.772959 -414.096178) (xy 453.827461 -414.096178)
			(xy 453.881409 -414.103934) (xy 453.933704 -414.119289) (xy 453.983281 -414.141931) (xy 454.029131 -414.171397)
			(xy 454.070322 -414.207088) (xy 454.106013 -414.248279) (xy 454.135479 -414.294129) (xy 454.158121 -414.343706)
			(xy 454.173476 -414.396001) (xy 454.181232 -414.449949) (xy 454.181718 -414.4772) (xy 454.181157 -414.507324)
			(xy 454.171675 -414.566821) (xy 454.152962 -414.62409) (xy 454.125484 -414.677707) (xy 454.089923 -414.72634)
			(xy 454.068942 -414.747964) (xy 454.06183 -414.755076) (xy 454.05421 -414.773364) (xy 454.053194 -414.865058)
			(xy 454.06056 -414.883346) (xy 454.067672 -414.890712) (xy 454.087673 -414.912177) (xy 454.121501 -414.960111)
			(xy 454.147596 -415.012656) (xy 454.165342 -415.068577) (xy 454.174322 -415.126554) (xy 454.17486 -415.155888)
			(xy 454.174371 -415.183386) (xy 454.166481 -415.237812) (xy 454.150863 -415.290544) (xy 454.12784 -415.340488)
			(xy 454.097888 -415.386612) (xy 454.080118 -415.407602) (xy 454.073768 -415.414714) (xy 454.067418 -415.43224)
			(xy 454.068688 -415.519362) (xy 454.075546 -415.536634) (xy 454.081896 -415.543746) (xy 454.100923 -415.565062)
			(xy 454.133149 -415.612242) (xy 454.157985 -415.663697) (xy 454.174875 -415.718278) (xy 454.183443 -415.774767)
			(xy 454.184004 -415.803334) (xy 454.183554 -415.830586) (xy 454.175793 -415.884535) (xy 454.160433 -415.936831)
			(xy 454.137788 -415.986409) (xy 454.108317 -416.032259) (xy 454.072622 -416.073449) (xy 454.031429 -416.10914)
			(xy 453.985575 -416.138606) (xy 453.935995 -416.161246) (xy 453.883698 -416.176601) (xy 453.829748 -416.184357)
			(xy 453.802496 -416.184842) (xy 453.776975 -416.18445) (xy 453.726387 -416.177654) (xy 453.677158 -416.164171)
			(xy 453.630167 -416.144242) (xy 453.586254 -416.118222) (xy 453.546205 -416.086578) (xy 453.528176 -416.06851)
			(xy 453.521572 -416.061652) (xy 453.5043 -416.053778) (xy 453.416162 -416.048698) (xy 453.398128 -416.05454)
			(xy 453.390762 -416.06089) (xy 453.37018 -416.077259) (xy 453.325366 -416.104777) (xy 453.277195 -416.125875)
			(xy 453.226582 -416.140152) (xy 453.174487 -416.147338) (xy 453.148192 -416.147758) (xy 453.119392 -416.14726)
			(xy 453.062442 -416.138631) (xy 453.007436 -416.12154) (xy 452.955623 -416.096376) (xy 452.908182 -416.06371)
			(xy 452.886826 -416.04438) (xy 452.879714 -416.037522) (xy 452.86168 -416.03041) (xy 452.771764 -416.031172)
			(xy 452.75373 -416.038284) (xy 452.746618 -416.045142) (xy 452.725182 -416.06519) (xy 452.677257 -416.099069)
			(xy 452.62471 -416.125214) (xy 452.568781 -416.143006) (xy 452.510787 -416.152027) (xy 452.481442 -416.152584)
			(xy 452.45132 -416.151977) (xy 452.391826 -416.142503) (xy 452.334559 -416.1238) (xy 452.280941 -416.096333)
			(xy 452.232305 -416.060783) (xy 452.210678 -416.039808) (xy 452.203566 -416.032442) (xy 452.18477 -416.024822)
			(xy 452.092314 -416.024822) (xy 452.073518 -416.032442) (xy 452.066406 -416.039808) (xy 452.046782 -416.05891)
			(xy 452.003043 -416.091863) (xy 451.955042 -416.118223) (xy 451.903764 -416.137449) (xy 451.850264 -416.149145)
			(xy 451.795642 -416.15307) (xy 451.74102 -416.149145) (xy 451.68752 -416.137449) (xy 451.636242 -416.118223)
			(xy 451.588241 -416.091863) (xy 451.544502 -416.05891) (xy 451.524878 -416.039808) (xy 451.517766 -416.032442)
			(xy 451.49897 -416.024822) (xy 451.406514 -416.024822) (xy 451.387718 -416.032442) (xy 451.380606 -416.039808)
			(xy 451.359003 -416.060812) (xy 451.310368 -416.096377) (xy 451.256746 -416.123852) (xy 451.199471 -416.142555)
			(xy 451.139968 -416.152019) (xy 451.109842 -416.152584) (xy 451.080711 -416.152045) (xy 451.023129 -416.14317)
			(xy 450.967568 -416.125637) (xy 450.915322 -416.099853) (xy 450.867607 -416.06642) (xy 450.84619 -416.046666)
			(xy 450.838824 -416.039808) (xy 450.820282 -416.032442) (xy 450.728588 -416.033966) (xy 450.710554 -416.04184)
			(xy 450.703188 -416.049206) (xy 450.681532 -416.070516) (xy 450.632677 -416.106631) (xy 450.578715 -416.134546)
			(xy 450.521011 -416.153554) (xy 450.461023 -416.163175) (xy 450.430646 -416.16376) (xy 450.403392 -416.163302)
			(xy 450.349438 -416.15555) (xy 450.297138 -416.140197) (xy 450.247554 -416.117557) (xy 450.201699 -416.088089)
			(xy 450.160504 -416.052394) (xy 450.12481 -416.0112) (xy 450.095343 -415.965344) (xy 450.072702 -415.915761)
			(xy 450.05735 -415.86346) (xy 450.049598 -415.809506) (xy 450.049138 -415.782252) (xy 450.0497 -415.752775)
			(xy 450.058762 -415.694522) (xy 450.076679 -415.638357) (xy 450.103024 -415.585618) (xy 450.137169 -415.537559)
			(xy 450.157342 -415.51606) (xy 450.163893 -415.508738) (xy 450.171327 -415.490568) (xy 450.17182 -415.480754)
			(xy 450.17182 -415.427414) (xy 450.159882 -415.415984) (xy 450.15277 -415.408618) (xy 450.133974 -415.400998)
			(xy 450.041518 -415.400998) (xy 450.022722 -415.408618) (xy 450.01561 -415.415984) (xy 449.994001 -415.436982)
			(xy 449.945368 -415.472548) (xy 449.891748 -415.500026) (xy 449.834474 -415.51873) (xy 449.774971 -415.528195)
			(xy 449.744846 -415.52876) (xy 449.717592 -415.528302) (xy 449.663638 -415.52055) (xy 449.611338 -415.505197)
			(xy 449.561754 -415.482557) (xy 449.515899 -415.453089) (xy 449.474704 -415.417394) (xy 449.43901 -415.3762)
			(xy 449.409543 -415.330344) (xy 449.386902 -415.280761) (xy 449.37155 -415.22846) (xy 449.363798 -415.174506)
			(xy 449.363338 -415.147252) (xy 443.553107 -415.147252) (xy 442.97727 -415.385758) (xy 442.972697 -415.38775)
			(xy 442.964378 -415.393248) (xy 442.96076 -415.39668) (xy 441.969398 -416.388042) (xy 441.962547 -416.395433)
			(xy 441.954834 -416.414039) (xy 441.954412 -416.42411) (xy 441.954412 -418.199824) (xy 448.144898 -418.199824)
			(xy 448.148969 -418.144202) (xy 448.161095 -418.089765) (xy 448.181018 -418.037674) (xy 448.208314 -417.989039)
			(xy 448.2424 -417.944896) (xy 448.282549 -417.906187) (xy 448.327907 -417.873736) (xy 448.377507 -417.848235)
			(xy 448.430291 -417.830228) (xy 448.485134 -417.820098) (xy 448.540868 -417.818061) (xy 448.596305 -417.824161)
			(xy 448.650262 -417.838267) (xy 448.701591 -417.860079) (xy 448.749197 -417.889133) (xy 448.792065 -417.924808)
			(xy 448.829282 -417.966345) (xy 448.860055 -418.012858) (xy 448.883727 -418.063355) (xy 448.899795 -418.116762)
			(xy 448.907915 -418.171938) (xy 448.908424 -418.199824) (xy 448.907915 -418.22771) (xy 448.899795 -418.282886)
			(xy 448.883727 -418.336293) (xy 448.860055 -418.38679) (xy 448.829282 -418.433303) (xy 448.792065 -418.47484)
			(xy 448.749197 -418.510515) (xy 448.701591 -418.539569) (xy 448.650262 -418.561381) (xy 448.596305 -418.575487)
			(xy 448.540868 -418.581587) (xy 448.485134 -418.57955) (xy 448.430291 -418.56942) (xy 448.377507 -418.551413)
			(xy 448.327907 -418.525912) (xy 448.282549 -418.493461) (xy 448.2424 -418.454752) (xy 448.208314 -418.410609)
			(xy 448.181018 -418.361974) (xy 448.161095 -418.309883) (xy 448.148969 -418.255446) (xy 448.144898 -418.199824)
			(xy 441.954412 -418.199824) (xy 441.954412 -419.412166) (xy 442.711584 -419.412166) (xy 442.715655 -419.356544)
			(xy 442.727781 -419.302107) (xy 442.747704 -419.250016) (xy 442.775 -419.201381) (xy 442.809086 -419.157238)
			(xy 442.849235 -419.118529) (xy 442.894593 -419.086078) (xy 442.944193 -419.060577) (xy 442.996977 -419.04257)
			(xy 443.05182 -419.03244) (xy 443.107554 -419.030403) (xy 443.162991 -419.036503) (xy 443.216948 -419.050609)
			(xy 443.268277 -419.072421) (xy 443.315883 -419.101475) (xy 443.358751 -419.13715) (xy 443.395968 -419.178687)
			(xy 443.426741 -419.2252) (xy 443.450413 -419.275697) (xy 443.466481 -419.329104) (xy 443.474601 -419.38428)
			(xy 443.47511 -419.412166) (xy 443.474601 -419.440052) (xy 443.466481 -419.495228) (xy 443.450413 -419.548635)
			(xy 443.427823 -419.596824) (xy 448.925948 -419.596824) (xy 448.930019 -419.541202) (xy 448.942145 -419.486765)
			(xy 448.962068 -419.434674) (xy 448.989364 -419.386039) (xy 449.02345 -419.341896) (xy 449.063599 -419.303187)
			(xy 449.108957 -419.270736) (xy 449.158557 -419.245235) (xy 449.211341 -419.227228) (xy 449.266184 -419.217098)
			(xy 449.321918 -419.215061) (xy 449.377355 -419.221161) (xy 449.431312 -419.235267) (xy 449.482641 -419.257079)
			(xy 449.530247 -419.286133) (xy 449.573115 -419.321808) (xy 449.610332 -419.363345) (xy 449.641105 -419.409858)
			(xy 449.664777 -419.460355) (xy 449.680845 -419.513762) (xy 449.688965 -419.568938) (xy 449.689474 -419.596824)
			(xy 449.688965 -419.62471) (xy 449.680845 -419.679886) (xy 449.664777 -419.733293) (xy 449.641105 -419.78379)
			(xy 449.610332 -419.830303) (xy 449.573115 -419.87184) (xy 449.530247 -419.907515) (xy 449.482641 -419.936569)
			(xy 449.431312 -419.958381) (xy 449.377355 -419.972487) (xy 449.321918 -419.978587) (xy 449.266184 -419.97655)
			(xy 449.211341 -419.96642) (xy 449.158557 -419.948413) (xy 449.108957 -419.922912) (xy 449.063599 -419.890461)
			(xy 449.02345 -419.851752) (xy 448.989364 -419.807609) (xy 448.962068 -419.758974) (xy 448.942145 -419.706883)
			(xy 448.930019 -419.652446) (xy 448.925948 -419.596824) (xy 443.427823 -419.596824) (xy 443.426741 -419.599132)
			(xy 443.395968 -419.645645) (xy 443.358751 -419.687182) (xy 443.315883 -419.722857) (xy 443.268277 -419.751911)
			(xy 443.216948 -419.773723) (xy 443.162991 -419.787829) (xy 443.107554 -419.793929) (xy 443.05182 -419.791892)
			(xy 442.996977 -419.781762) (xy 442.944193 -419.763755) (xy 442.894593 -419.738254) (xy 442.849235 -419.705803)
			(xy 442.809086 -419.667094) (xy 442.775 -419.622951) (xy 442.747704 -419.574316) (xy 442.727781 -419.522225)
			(xy 442.715655 -419.467788) (xy 442.711584 -419.412166) (xy 441.954412 -419.412166) (xy 441.954412 -420.23411)
			(xy 444.235584 -420.23411) (xy 444.239655 -420.178488) (xy 444.251781 -420.124051) (xy 444.271704 -420.07196)
			(xy 444.299 -420.023325) (xy 444.333086 -419.979182) (xy 444.373235 -419.940473) (xy 444.418593 -419.908022)
			(xy 444.468193 -419.882521) (xy 444.520977 -419.864514) (xy 444.57582 -419.854384) (xy 444.631554 -419.852347)
			(xy 444.686991 -419.858447) (xy 444.740948 -419.872553) (xy 444.792277 -419.894365) (xy 444.839883 -419.923419)
			(xy 444.882751 -419.959094) (xy 444.919968 -420.000631) (xy 444.950741 -420.047144) (xy 444.974413 -420.097641)
			(xy 444.990481 -420.151048) (xy 444.998601 -420.206224) (xy 444.99911 -420.23411) (xy 445.505584 -420.23411)
			(xy 445.509655 -420.178488) (xy 445.521781 -420.124051) (xy 445.541704 -420.07196) (xy 445.569 -420.023325)
			(xy 445.603086 -419.979182) (xy 445.643235 -419.940473) (xy 445.688593 -419.908022) (xy 445.738193 -419.882521)
			(xy 445.790977 -419.864514) (xy 445.84582 -419.854384) (xy 445.901554 -419.852347) (xy 445.956991 -419.858447)
			(xy 446.010948 -419.872553) (xy 446.062277 -419.894365) (xy 446.109883 -419.923419) (xy 446.152751 -419.959094)
			(xy 446.189968 -420.000631) (xy 446.220741 -420.047144) (xy 446.244413 -420.097641) (xy 446.260481 -420.151048)
			(xy 446.268601 -420.206224) (xy 446.26911 -420.23411) (xy 446.268601 -420.261996) (xy 446.260481 -420.317172)
			(xy 446.244413 -420.370579) (xy 446.220741 -420.421076) (xy 446.189968 -420.467589) (xy 446.152751 -420.509126)
			(xy 446.109883 -420.544801) (xy 446.062277 -420.573855) (xy 446.010948 -420.595667) (xy 445.956991 -420.609773)
			(xy 445.901554 -420.615873) (xy 445.84582 -420.613836) (xy 445.790977 -420.603706) (xy 445.738193 -420.585699)
			(xy 445.688593 -420.560198) (xy 445.643235 -420.527747) (xy 445.603086 -420.489038) (xy 445.569 -420.444895)
			(xy 445.541704 -420.39626) (xy 445.521781 -420.344169) (xy 445.509655 -420.289732) (xy 445.505584 -420.23411)
			(xy 444.99911 -420.23411) (xy 444.998601 -420.261996) (xy 444.990481 -420.317172) (xy 444.974413 -420.370579)
			(xy 444.950741 -420.421076) (xy 444.919968 -420.467589) (xy 444.882751 -420.509126) (xy 444.839883 -420.544801)
			(xy 444.792277 -420.573855) (xy 444.740948 -420.595667) (xy 444.686991 -420.609773) (xy 444.631554 -420.615873)
			(xy 444.57582 -420.613836) (xy 444.520977 -420.603706) (xy 444.468193 -420.585699) (xy 444.418593 -420.560198)
			(xy 444.373235 -420.527747) (xy 444.333086 -420.489038) (xy 444.299 -420.444895) (xy 444.271704 -420.39626)
			(xy 444.251781 -420.344169) (xy 444.239655 -420.289732) (xy 444.235584 -420.23411) (xy 441.954412 -420.23411)
			(xy 441.954412 -420.74211) (xy 442.838584 -420.74211) (xy 442.842655 -420.686488) (xy 442.854781 -420.632051)
			(xy 442.874704 -420.57996) (xy 442.902 -420.531325) (xy 442.936086 -420.487182) (xy 442.976235 -420.448473)
			(xy 443.021593 -420.416022) (xy 443.071193 -420.390521) (xy 443.123977 -420.372514) (xy 443.17882 -420.362384)
			(xy 443.234554 -420.360347) (xy 443.289991 -420.366447) (xy 443.343948 -420.380553) (xy 443.395277 -420.402365)
			(xy 443.442883 -420.431419) (xy 443.485751 -420.467094) (xy 443.522968 -420.508631) (xy 443.553741 -420.555144)
			(xy 443.577413 -420.605641) (xy 443.593481 -420.659048) (xy 443.601601 -420.714224) (xy 443.60211 -420.74211)
			(xy 443.601601 -420.769996) (xy 443.593481 -420.825172) (xy 443.577413 -420.878579) (xy 443.553741 -420.929076)
			(xy 443.522968 -420.975589) (xy 443.504581 -420.99611) (xy 450.196458 -420.99611) (xy 450.196941 -420.968612)
			(xy 450.204832 -420.914185) (xy 450.220451 -420.861453) (xy 450.243476 -420.811509) (xy 450.27343 -420.765386)
			(xy 450.2912 -420.744396) (xy 450.29755 -420.737284) (xy 450.3039 -420.720266) (xy 450.3039 -420.634668)
			(xy 450.29755 -420.61765) (xy 450.2912 -420.610538) (xy 450.273442 -420.589537) (xy 450.243486 -420.543417)
			(xy 450.220458 -420.493476) (xy 450.204835 -420.440747) (xy 450.19694 -420.386321) (xy 450.196458 -420.358824)
			(xy 450.196944 -420.331573) (xy 450.2047 -420.277625) (xy 450.220055 -420.22533) (xy 450.242697 -420.175753)
			(xy 450.272163 -420.129903) (xy 450.307854 -420.088712) (xy 450.349045 -420.053021) (xy 450.394895 -420.023555)
			(xy 450.444472 -420.000913) (xy 450.496767 -419.985558) (xy 450.550715 -419.977802) (xy 450.605217 -419.977802)
			(xy 450.659165 -419.985558) (xy 450.71146 -420.000913) (xy 450.761037 -420.023555) (xy 450.806887 -420.053021)
			(xy 450.848078 -420.088712) (xy 450.883769 -420.129903) (xy 450.913235 -420.175753) (xy 450.935877 -420.22533)
			(xy 450.951232 -420.277625) (xy 450.958988 -420.331573) (xy 450.959474 -420.358824) (xy 450.959003 -420.386322)
			(xy 450.951108 -420.44075) (xy 450.935486 -420.493481) (xy 450.912458 -420.543425) (xy 450.882503 -420.589548)
			(xy 450.864732 -420.610538) (xy 450.858382 -420.61765) (xy 450.852032 -420.634668) (xy 450.852032 -420.720266)
			(xy 450.858382 -420.737284) (xy 450.864732 -420.744396) (xy 450.882511 -420.76538) (xy 450.912463 -420.811505)
			(xy 450.935486 -420.861451) (xy 450.951105 -420.914183) (xy 450.958995 -420.968611) (xy 450.959474 -420.99611)
			(xy 450.958988 -421.023361) (xy 450.951232 -421.077309) (xy 450.935877 -421.129604) (xy 450.913235 -421.179181)
			(xy 450.883769 -421.225031) (xy 450.848078 -421.266222) (xy 450.806887 -421.301913) (xy 450.761037 -421.331379)
			(xy 450.71146 -421.354021) (xy 450.659165 -421.369376) (xy 450.605217 -421.377132) (xy 450.550715 -421.377132)
			(xy 450.496767 -421.369376) (xy 450.444472 -421.354021) (xy 450.394895 -421.331379) (xy 450.349045 -421.301913)
			(xy 450.307854 -421.266222) (xy 450.272163 -421.225031) (xy 450.242697 -421.179181) (xy 450.220055 -421.129604)
			(xy 450.2047 -421.077309) (xy 450.196944 -421.023361) (xy 450.196458 -420.99611) (xy 443.504581 -420.99611)
			(xy 443.485751 -421.017126) (xy 443.442883 -421.052801) (xy 443.395277 -421.081855) (xy 443.343948 -421.103667)
			(xy 443.289991 -421.117773) (xy 443.234554 -421.123873) (xy 443.17882 -421.121836) (xy 443.123977 -421.111706)
			(xy 443.071193 -421.093699) (xy 443.021593 -421.068198) (xy 442.976235 -421.035747) (xy 442.936086 -420.997038)
			(xy 442.902 -420.952895) (xy 442.874704 -420.90426) (xy 442.854781 -420.852169) (xy 442.842655 -420.797732)
			(xy 442.838584 -420.74211) (xy 441.954412 -420.74211) (xy 441.954412 -422.77411) (xy 448.661534 -422.77411)
			(xy 448.665605 -422.718488) (xy 448.677731 -422.664051) (xy 448.697654 -422.61196) (xy 448.72495 -422.563325)
			(xy 448.759036 -422.519182) (xy 448.799185 -422.480473) (xy 448.844543 -422.448022) (xy 448.894143 -422.422521)
			(xy 448.946927 -422.404514) (xy 449.00177 -422.394384) (xy 449.057504 -422.392347) (xy 449.112941 -422.398447)
			(xy 449.166898 -422.412553) (xy 449.218227 -422.434365) (xy 449.265833 -422.463419) (xy 449.308701 -422.499094)
			(xy 449.345918 -422.540631) (xy 449.376691 -422.587144) (xy 449.400363 -422.637641) (xy 449.416431 -422.691048)
			(xy 449.424551 -422.746224) (xy 449.42506 -422.77411) (xy 449.424551 -422.801996) (xy 449.416431 -422.857172)
			(xy 449.400363 -422.910579) (xy 449.376691 -422.961076) (xy 449.345918 -423.007589) (xy 449.308701 -423.049126)
			(xy 449.265833 -423.084801) (xy 449.218227 -423.113855) (xy 449.166898 -423.135667) (xy 449.112941 -423.149773)
			(xy 449.057504 -423.155873) (xy 449.00177 -423.153836) (xy 448.946927 -423.143706) (xy 448.894143 -423.125699)
			(xy 448.844543 -423.100198) (xy 448.799185 -423.067747) (xy 448.759036 -423.029038) (xy 448.72495 -422.984895)
			(xy 448.697654 -422.93626) (xy 448.677731 -422.884169) (xy 448.665605 -422.829732) (xy 448.661534 -422.77411)
			(xy 441.954412 -422.77411) (xy 441.954412 -423.556738) (xy 456.285335 -423.556738) (xy 456.285335 -423.427598)
			(xy 456.293285 -423.298703) (xy 456.309155 -423.170543) (xy 456.332884 -423.043602) (xy 456.364383 -422.918363)
			(xy 456.403532 -422.7953) (xy 456.450183 -422.674881) (xy 456.504158 -422.557562) (xy 456.565253 -422.443788)
			(xy 456.633236 -422.333991) (xy 456.70785 -422.228588) (xy 456.788811 -422.127978) (xy 456.875811 -422.032543)
			(xy 456.968522 -421.942644) (xy 457.066592 -421.858623) (xy 457.169647 -421.780799) (xy 457.277298 -421.709467)
			(xy 457.389137 -421.644897) (xy 457.504738 -421.587335) (xy 457.623663 -421.536998) (xy 457.745462 -421.494078)
			(xy 457.869672 -421.458737) (xy 457.995821 -421.43111) (xy 458.123433 -421.411301) (xy 458.252022 -421.399385)
			(xy 458.3811 -421.395409) (xy 458.510178 -421.399385) (xy 458.638767 -421.411301) (xy 458.766379 -421.43111)
			(xy 458.892528 -421.458737) (xy 459.016738 -421.494078) (xy 459.138537 -421.536998) (xy 459.257462 -421.587335)
			(xy 459.373063 -421.644897) (xy 459.484902 -421.709467) (xy 459.592553 -421.780799) (xy 459.695608 -421.858623)
			(xy 459.793678 -421.942644) (xy 459.886389 -422.032543) (xy 459.973389 -422.127978) (xy 460.05435 -422.228588)
			(xy 460.128964 -422.333991) (xy 460.196947 -422.443788) (xy 460.258042 -422.557562) (xy 460.312017 -422.674881)
			(xy 460.358668 -422.7953) (xy 460.397817 -422.918363) (xy 460.429316 -423.043602) (xy 460.453045 -423.170543)
			(xy 460.468915 -423.298703) (xy 460.476865 -423.427598) (xy 460.477362 -423.492168) (xy 460.476865 -423.556738)
			(xy 460.468915 -423.685633) (xy 460.453045 -423.813793) (xy 460.429316 -423.940734) (xy 460.397817 -424.065973)
			(xy 460.358668 -424.189036) (xy 460.312017 -424.309455) (xy 460.258042 -424.426774) (xy 460.196947 -424.540548)
			(xy 460.128964 -424.650345) (xy 460.05435 -424.755748) (xy 459.973389 -424.856358) (xy 459.886389 -424.951793)
			(xy 459.793678 -425.041692) (xy 459.695608 -425.125713) (xy 459.592553 -425.203537) (xy 459.484902 -425.274869)
			(xy 459.373063 -425.339439) (xy 459.257462 -425.397001) (xy 459.138537 -425.447338) (xy 459.016738 -425.490258)
			(xy 458.892528 -425.525599) (xy 458.766379 -425.553226) (xy 458.638767 -425.573035) (xy 458.510178 -425.584951)
			(xy 458.3811 -425.588928) (xy 458.252022 -425.584951) (xy 458.123433 -425.573035) (xy 457.995821 -425.553226)
			(xy 457.869672 -425.525599) (xy 457.745462 -425.490258) (xy 457.623663 -425.447338) (xy 457.504738 -425.397001)
			(xy 457.389137 -425.339439) (xy 457.277298 -425.274869) (xy 457.169647 -425.203537) (xy 457.066592 -425.125713)
			(xy 456.968522 -425.041692) (xy 456.875811 -424.951793) (xy 456.788811 -424.856358) (xy 456.70785 -424.755748)
			(xy 456.633236 -424.650345) (xy 456.565253 -424.540548) (xy 456.504158 -424.426774) (xy 456.450183 -424.309455)
			(xy 456.403532 -424.189036) (xy 456.364383 -424.065973) (xy 456.332884 -423.940734) (xy 456.309155 -423.813793)
			(xy 456.293285 -423.685633) (xy 456.285335 -423.556738) (xy 441.954412 -423.556738) (xy 441.954412 -424.655552)
			(xy 447.233765 -424.655552) (xy 447.233765 -424.601048) (xy 447.241522 -424.547098) (xy 447.256878 -424.494801)
			(xy 447.27952 -424.445222) (xy 447.308987 -424.39937) (xy 447.34468 -424.358179) (xy 447.385872 -424.322486)
			(xy 447.431724 -424.293019) (xy 447.481303 -424.270377) (xy 447.5336 -424.255022) (xy 447.58755 -424.247265)
			(xy 447.614802 -424.246802) (xy 447.642246 -424.247291) (xy 447.696568 -424.255158) (xy 447.749197 -424.270743)
			(xy 447.799044 -424.293723) (xy 447.82232 -424.30827) (xy 447.834456 -424.315613) (xy 447.861559 -424.323945)
			(xy 447.889908 -424.324497) (xy 447.917314 -424.317226) (xy 447.941661 -424.302693) (xy 447.961068 -424.282021)
			(xy 447.974037 -424.256806) (xy 447.97726 -424.242992) (xy 447.983544 -424.214555) (xy 448.003543 -424.159862)
			(xy 448.031619 -424.108841) (xy 448.067119 -424.062677) (xy 448.10922 -424.022442) (xy 448.156944 -423.989069)
			(xy 448.209184 -423.963333) (xy 448.264727 -423.945832) (xy 448.322285 -423.936971) (xy 448.351402 -423.936414)
			(xy 448.378655 -423.936856) (xy 448.432605 -423.944613) (xy 448.484903 -423.959969) (xy 448.534483 -423.982612)
			(xy 448.580336 -424.01208) (xy 448.621528 -424.047774) (xy 448.657221 -424.088966) (xy 448.686689 -424.134819)
			(xy 448.709331 -424.184399) (xy 448.724687 -424.236697) (xy 448.732444 -424.290647) (xy 448.732444 -424.345153)
			(xy 448.724687 -424.399103) (xy 448.709331 -424.451401) (xy 448.686689 -424.500981) (xy 448.657221 -424.546834)
			(xy 448.621528 -424.588026) (xy 448.580336 -424.62372) (xy 448.534483 -424.653188) (xy 448.484903 -424.675831)
			(xy 448.432605 -424.691187) (xy 448.378655 -424.698944) (xy 448.351402 -424.69943) (xy 448.323958 -424.698934)
			(xy 448.269637 -424.691069) (xy 448.217008 -424.675486) (xy 448.167161 -424.652508) (xy 448.143884 -424.637962)
			(xy 448.131723 -424.630667) (xy 448.104631 -424.622343) (xy 448.076293 -424.621793) (xy 448.048898 -424.629059)
			(xy 448.024558 -424.64358) (xy 448.005151 -424.664236) (xy 447.992174 -424.689434) (xy 447.988944 -424.70324)
			(xy 447.982701 -424.731688) (xy 447.962704 -424.786389) (xy 447.934628 -424.837415) (xy 447.899125 -424.883583)
			(xy 447.857018 -424.923821) (xy 447.809287 -424.957193) (xy 447.757038 -424.982924) (xy 447.701487 -425.000418)
			(xy 447.643922 -425.009268) (xy 447.614802 -425.009818) (xy 447.58755 -425.009335) (xy 447.5336 -425.001578)
			(xy 447.481303 -424.986223) (xy 447.431724 -424.963581) (xy 447.385872 -424.934114) (xy 447.34468 -424.898421)
			(xy 447.308987 -424.85723) (xy 447.27952 -424.811378) (xy 447.256878 -424.761799) (xy 447.241522 -424.709502)
			(xy 447.233765 -424.655552) (xy 441.954412 -424.655552) (xy 441.954412 -425.482258) (xy 441.954856 -425.492325)
			(xy 441.962563 -425.510923) (xy 441.969398 -425.518326) (xy 442.476128 -426.025056) (xy 442.483607 -426.031752)
			(xy 442.502168 -426.03934) (xy 442.512196 -426.039788) (xy 443.19571 -426.039788) (xy 443.220708 -426.040399)
			(xy 443.269732 -426.050208) (xy 443.315903 -426.069389) (xy 443.325941 -426.07611) (xy 448.045584 -426.07611)
			(xy 448.049655 -426.020488) (xy 448.061781 -425.966051) (xy 448.081704 -425.91396) (xy 448.109 -425.865325)
			(xy 448.143086 -425.821182) (xy 448.183235 -425.782473) (xy 448.228593 -425.750022) (xy 448.278193 -425.724521)
			(xy 448.330977 -425.706514) (xy 448.38582 -425.696384) (xy 448.441554 -425.694347) (xy 448.496991 -425.700447)
			(xy 448.550948 -425.714553) (xy 448.602277 -425.736365) (xy 448.649883 -425.765419) (xy 448.692751 -425.801094)
			(xy 448.729968 -425.842631) (xy 448.760741 -425.889144) (xy 448.776945 -425.92371) (xy 450.299834 -425.92371)
			(xy 450.303905 -425.868088) (xy 450.316031 -425.813651) (xy 450.335954 -425.76156) (xy 450.36325 -425.712925)
			(xy 450.397336 -425.668782) (xy 450.437485 -425.630073) (xy 450.482843 -425.597622) (xy 450.532443 -425.572121)
			(xy 450.585227 -425.554114) (xy 450.64007 -425.543984) (xy 450.695804 -425.541947) (xy 450.751241 -425.548047)
			(xy 450.805198 -425.562153) (xy 450.856527 -425.583965) (xy 450.904133 -425.613019) (xy 450.947001 -425.648694)
			(xy 450.984218 -425.690231) (xy 451.014991 -425.736744) (xy 451.038663 -425.787241) (xy 451.054731 -425.840648)
			(xy 451.062851 -425.895824) (xy 451.06336 -425.92371) (xy 451.062851 -425.951596) (xy 451.054731 -426.006772)
			(xy 451.038663 -426.060179) (xy 451.014991 -426.110676) (xy 450.984218 -426.157189) (xy 450.947001 -426.198726)
			(xy 450.904133 -426.234401) (xy 450.856527 -426.263455) (xy 450.805198 -426.285267) (xy 450.751241 -426.299373)
			(xy 450.695804 -426.305473) (xy 450.64007 -426.303436) (xy 450.585227 -426.293306) (xy 450.532443 -426.275299)
			(xy 450.482843 -426.249798) (xy 450.437485 -426.217347) (xy 450.397336 -426.178638) (xy 450.36325 -426.134495)
			(xy 450.335954 -426.08586) (xy 450.316031 -426.033769) (xy 450.303905 -425.979332) (xy 450.299834 -425.92371)
			(xy 448.776945 -425.92371) (xy 448.784413 -425.939641) (xy 448.800481 -425.993048) (xy 448.808601 -426.048224)
			(xy 448.80911 -426.07611) (xy 448.808601 -426.103996) (xy 448.800481 -426.159172) (xy 448.784413 -426.212579)
			(xy 448.760741 -426.263076) (xy 448.729968 -426.309589) (xy 448.692751 -426.351126) (xy 448.649883 -426.386801)
			(xy 448.602277 -426.415855) (xy 448.550948 -426.437667) (xy 448.496991 -426.451773) (xy 448.441554 -426.457873)
			(xy 448.38582 -426.455836) (xy 448.330977 -426.445706) (xy 448.278193 -426.427699) (xy 448.228593 -426.402198)
			(xy 448.183235 -426.369747) (xy 448.143086 -426.331038) (xy 448.109 -426.286895) (xy 448.081704 -426.23826)
			(xy 448.061781 -426.186169) (xy 448.049655 -426.131732) (xy 448.045584 -426.07611) (xy 443.325941 -426.07611)
			(xy 443.357448 -426.097205) (xy 443.375542 -426.114464) (xy 444.861188 -427.60011) (xy 447.029584 -427.60011)
			(xy 447.033655 -427.544488) (xy 447.045781 -427.490051) (xy 447.065704 -427.43796) (xy 447.093 -427.389325)
			(xy 447.127086 -427.345182) (xy 447.167235 -427.306473) (xy 447.212593 -427.274022) (xy 447.262193 -427.248521)
			(xy 447.314977 -427.230514) (xy 447.36982 -427.220384) (xy 447.425554 -427.218347) (xy 447.480991 -427.224447)
			(xy 447.534948 -427.238553) (xy 447.586277 -427.260365) (xy 447.633883 -427.289419) (xy 447.676751 -427.325094)
			(xy 447.713968 -427.366631) (xy 447.744741 -427.413144) (xy 447.768413 -427.463641) (xy 447.784481 -427.517048)
			(xy 447.792601 -427.572224) (xy 447.79311 -427.60011) (xy 447.792601 -427.627996) (xy 447.784481 -427.683172)
			(xy 447.768413 -427.736579) (xy 447.744741 -427.787076) (xy 447.713968 -427.833589) (xy 447.676751 -427.875126)
			(xy 447.633883 -427.910801) (xy 447.586277 -427.939855) (xy 447.534948 -427.961667) (xy 447.480991 -427.975773)
			(xy 447.425554 -427.981873) (xy 447.36982 -427.979836) (xy 447.314977 -427.969706) (xy 447.262193 -427.951699)
			(xy 447.212593 -427.926198) (xy 447.167235 -427.893747) (xy 447.127086 -427.855038) (xy 447.093 -427.810895)
			(xy 447.065704 -427.76226) (xy 447.045781 -427.710169) (xy 447.033655 -427.655732) (xy 447.029584 -427.60011)
			(xy 444.861188 -427.60011) (xy 445.020192 -427.759114) (xy 445.037446 -427.777211) (xy 445.065257 -427.818755)
			(xy 445.084431 -427.864926) (xy 445.094231 -427.91395) (xy 445.094868 -427.938946) (xy 445.094868 -427.98365)
			(xy 445.102488 -428.002192) (xy 445.1096 -428.009304) (xy 445.130516 -428.030892) (xy 445.165924 -428.079464)
			(xy 445.193274 -428.132989) (xy 445.21189 -428.190141) (xy 445.221309 -428.249506) (xy 445.221868 -428.27956)
			(xy 445.221407 -428.306814) (xy 445.213655 -428.360767) (xy 445.198302 -428.413067) (xy 445.175661 -428.46265)
			(xy 445.146194 -428.508505) (xy 445.110499 -428.549699) (xy 445.069305 -428.585394) (xy 445.02345 -428.614861)
			(xy 444.973867 -428.637502) (xy 444.921567 -428.652855) (xy 444.867614 -428.660607) (xy 444.84036 -428.661068)
			(xy 444.811511 -428.660536) (xy 444.754467 -428.651868) (xy 444.69938 -428.634706) (xy 444.647508 -428.609441)
			(xy 444.600033 -428.57665) (xy 444.55804 -428.537081) (xy 444.522487 -428.491638) (xy 444.507874 -428.466758)
			(xy 444.501016 -428.454566) (xy 444.476886 -428.440596) (xy 444.358776 -428.44339) (xy 444.335154 -428.458122)
			(xy 444.328804 -428.470822) (xy 444.316553 -428.494094) (xy 444.286602 -428.537325) (xy 444.250993 -428.576029)
			(xy 444.210404 -428.609472) (xy 444.165604 -428.63702) (xy 444.117443 -428.65815) (xy 444.066835 -428.672461)
			(xy 444.01474 -428.679681) (xy 443.988444 -428.680118) (xy 443.96222 -428.679697) (xy 443.91027 -428.672494)
			(xy 443.859795 -428.658245) (xy 443.811747 -428.637219) (xy 443.767031 -428.609811) (xy 443.726489 -428.576538)
			(xy 443.690885 -428.538027) (xy 443.66089 -428.495003) (xy 443.648592 -428.471838) (xy 443.641988 -428.458884)
			(xy 443.617604 -428.444152) (xy 437.768746 -428.444152) (xy 437.743751 -428.443495) (xy 437.694729 -428.433699)
			(xy 437.648558 -428.414531) (xy 437.607011 -428.386729) (xy 437.588914 -428.369476) (xy 435.903116 -426.683678)
			(xy 435.885859 -426.665583) (xy 435.858048 -426.624038) (xy 435.838875 -426.577867) (xy 435.829076 -426.528842)
			(xy 435.82844 -426.503846) (xy 432.30673 -426.503846) (xy 432.30673 -429.658272) (xy 432.963826 -429.658272)
			(xy 432.967897 -429.60265) (xy 432.980023 -429.548213) (xy 432.999946 -429.496122) (xy 433.027242 -429.447487)
			(xy 433.061328 -429.403344) (xy 433.101477 -429.364635) (xy 433.146835 -429.332184) (xy 433.196435 -429.306683)
			(xy 433.249219 -429.288676) (xy 433.304062 -429.278546) (xy 433.359796 -429.276509) (xy 433.415233 -429.282609)
			(xy 433.46919 -429.296715) (xy 433.481415 -429.30191) (xy 439.529726 -429.30191) (xy 439.533797 -429.246288)
			(xy 439.545923 -429.191851) (xy 439.565846 -429.13976) (xy 439.593142 -429.091125) (xy 439.627228 -429.046982)
			(xy 439.667377 -429.008273) (xy 439.712735 -428.975822) (xy 439.762335 -428.950321) (xy 439.815119 -428.932314)
			(xy 439.869962 -428.922184) (xy 439.925696 -428.920147) (xy 439.981133 -428.926247) (xy 440.03509 -428.940353)
			(xy 440.086419 -428.962165) (xy 440.134025 -428.991219) (xy 440.176893 -429.026894) (xy 440.21411 -429.068431)
			(xy 440.244883 -429.114944) (xy 440.268555 -429.165441) (xy 440.284623 -429.218848) (xy 440.292743 -429.274024)
			(xy 440.293252 -429.30191) (xy 440.292743 -429.329796) (xy 440.284623 -429.384972) (xy 440.268555 -429.438379)
			(xy 440.244883 -429.488876) (xy 440.21411 -429.535389) (xy 440.176893 -429.576926) (xy 440.134025 -429.612601)
			(xy 440.086419 -429.641655) (xy 440.03509 -429.663467) (xy 439.981133 -429.677573) (xy 439.925696 -429.683673)
			(xy 439.869962 -429.681636) (xy 439.815119 -429.671506) (xy 439.762335 -429.653499) (xy 439.712735 -429.627998)
			(xy 439.667377 -429.595547) (xy 439.627228 -429.556838) (xy 439.593142 -429.512695) (xy 439.565846 -429.46406)
			(xy 439.545923 -429.411969) (xy 439.533797 -429.357532) (xy 439.529726 -429.30191) (xy 433.481415 -429.30191)
			(xy 433.520519 -429.318527) (xy 433.568125 -429.347581) (xy 433.610993 -429.383256) (xy 433.64821 -429.424793)
			(xy 433.678983 -429.471306) (xy 433.702655 -429.521803) (xy 433.718723 -429.57521) (xy 433.726843 -429.630386)
			(xy 433.727352 -429.658272) (xy 433.726843 -429.686158) (xy 433.718723 -429.741334) (xy 433.702655 -429.794741)
			(xy 433.678983 -429.845238) (xy 433.64821 -429.891751) (xy 433.610993 -429.933288) (xy 433.609388 -429.934624)
			(xy 437.875424 -429.934624) (xy 437.879495 -429.879002) (xy 437.891621 -429.824565) (xy 437.911544 -429.772474)
			(xy 437.93884 -429.723839) (xy 437.972926 -429.679696) (xy 438.013075 -429.640987) (xy 438.058433 -429.608536)
			(xy 438.108033 -429.583035) (xy 438.160817 -429.565028) (xy 438.21566 -429.554898) (xy 438.271394 -429.552861)
			(xy 438.326831 -429.558961) (xy 438.380788 -429.573067) (xy 438.432117 -429.594879) (xy 438.479723 -429.623933)
			(xy 438.522591 -429.659608) (xy 438.559808 -429.701145) (xy 438.590581 -429.747658) (xy 438.614253 -429.798155)
			(xy 438.630321 -429.851562) (xy 438.638441 -429.906738) (xy 438.63895 -429.934624) (xy 438.638441 -429.96251)
			(xy 438.631331 -430.010824) (xy 449.461634 -430.010824) (xy 449.465705 -429.955202) (xy 449.477831 -429.900765)
			(xy 449.497754 -429.848674) (xy 449.52505 -429.800039) (xy 449.559136 -429.755896) (xy 449.599285 -429.717187)
			(xy 449.644643 -429.684736) (xy 449.694243 -429.659235) (xy 449.747027 -429.641228) (xy 449.80187 -429.631098)
			(xy 449.857604 -429.629061) (xy 449.913041 -429.635161) (xy 449.966998 -429.649267) (xy 450.018327 -429.671079)
			(xy 450.065933 -429.700133) (xy 450.108801 -429.735808) (xy 450.146018 -429.777345) (xy 450.176791 -429.823858)
			(xy 450.200463 -429.874355) (xy 450.216531 -429.927762) (xy 450.224651 -429.982938) (xy 450.22516 -430.010824)
			(xy 450.224651 -430.03871) (xy 450.216531 -430.093886) (xy 450.200463 -430.147293) (xy 450.176791 -430.19779)
			(xy 450.146018 -430.244303) (xy 450.108801 -430.28584) (xy 450.065933 -430.321515) (xy 450.018327 -430.350569)
			(xy 449.966998 -430.372381) (xy 449.913041 -430.386487) (xy 449.857604 -430.392587) (xy 449.80187 -430.39055)
			(xy 449.747027 -430.38042) (xy 449.694243 -430.362413) (xy 449.644643 -430.336912) (xy 449.599285 -430.304461)
			(xy 449.559136 -430.265752) (xy 449.52505 -430.221609) (xy 449.497754 -430.172974) (xy 449.477831 -430.120883)
			(xy 449.465705 -430.066446) (xy 449.461634 -430.010824) (xy 438.631331 -430.010824) (xy 438.630321 -430.017686)
			(xy 438.614253 -430.071093) (xy 438.590581 -430.12159) (xy 438.559808 -430.168103) (xy 438.522591 -430.20964)
			(xy 438.479723 -430.245315) (xy 438.432117 -430.274369) (xy 438.380788 -430.296181) (xy 438.326831 -430.310287)
			(xy 438.271394 -430.316387) (xy 438.21566 -430.31435) (xy 438.160817 -430.30422) (xy 438.108033 -430.286213)
			(xy 438.058433 -430.260712) (xy 438.013075 -430.228261) (xy 437.972926 -430.189552) (xy 437.93884 -430.145409)
			(xy 437.911544 -430.096774) (xy 437.891621 -430.044683) (xy 437.879495 -429.990246) (xy 437.875424 -429.934624)
			(xy 433.609388 -429.934624) (xy 433.568125 -429.968963) (xy 433.520519 -429.998017) (xy 433.46919 -430.019829)
			(xy 433.415233 -430.033935) (xy 433.359796 -430.040035) (xy 433.304062 -430.037998) (xy 433.249219 -430.027868)
			(xy 433.196435 -430.009861) (xy 433.146835 -429.98436) (xy 433.101477 -429.951909) (xy 433.061328 -429.9132)
			(xy 433.027242 -429.869057) (xy 432.999946 -429.820422) (xy 432.980023 -429.768331) (xy 432.967897 -429.713894)
			(xy 432.963826 -429.658272) (xy 432.30673 -429.658272) (xy 432.30673 -430.035462) (xy 432.307165 -430.045527)
			(xy 432.314899 -430.064112) (xy 432.321716 -430.07153) (xy 432.644296 -430.39411) (xy 440.425584 -430.39411)
			(xy 440.429655 -430.338488) (xy 440.441781 -430.284051) (xy 440.461704 -430.23196) (xy 440.489 -430.183325)
			(xy 440.523086 -430.139182) (xy 440.563235 -430.100473) (xy 440.608593 -430.068022) (xy 440.658193 -430.042521)
			(xy 440.710977 -430.024514) (xy 440.76582 -430.014384) (xy 440.821554 -430.012347) (xy 440.876991 -430.018447)
			(xy 440.930948 -430.032553) (xy 440.982277 -430.054365) (xy 441.029883 -430.083419) (xy 441.072751 -430.119094)
			(xy 441.109968 -430.160631) (xy 441.140741 -430.207144) (xy 441.164413 -430.257641) (xy 441.180481 -430.311048)
			(xy 441.188601 -430.366224) (xy 441.18911 -430.39411) (xy 441.188601 -430.421996) (xy 441.180481 -430.477172)
			(xy 441.164413 -430.530579) (xy 441.140741 -430.581076) (xy 441.109968 -430.627589) (xy 441.072751 -430.669126)
			(xy 441.029883 -430.704801) (xy 440.982277 -430.733855) (xy 440.930948 -430.755667) (xy 440.876991 -430.769773)
			(xy 440.821554 -430.775873) (xy 440.76582 -430.773836) (xy 440.710977 -430.763706) (xy 440.658193 -430.745699)
			(xy 440.608593 -430.720198) (xy 440.563235 -430.687747) (xy 440.523086 -430.649038) (xy 440.489 -430.604895)
			(xy 440.461704 -430.55626) (xy 440.441781 -430.504169) (xy 440.429655 -430.449732) (xy 440.425584 -430.39411)
			(xy 432.644296 -430.39411) (xy 433.453794 -431.203608) (xy 433.461193 -431.210455) (xy 433.47979 -431.21819)
			(xy 433.489862 -431.218594) (xy 444.244984 -431.218594) (xy 444.255048 -431.219032) (xy 444.273631 -431.226767)
			(xy 444.281052 -431.23358) (xy 445.074294 -432.026822) (xy 445.081138 -432.034222) (xy 445.088865 -432.05282)
			(xy 445.08928 -432.06289) (xy 445.08928 -435.677116) (xy 445.799708 -435.677116) (xy 445.799708 -435.522564)
			(xy 445.807664 -435.368217) (xy 445.823555 -435.214484) (xy 445.847339 -435.061773) (xy 445.878953 -434.910489)
			(xy 445.918313 -434.761033) (xy 445.965314 -434.613801) (xy 446.019833 -434.469184) (xy 446.081724 -434.327565)
			(xy 446.150823 -434.189321) (xy 446.226947 -434.054816) (xy 446.309895 -433.924409) (xy 446.399446 -433.798445)
			(xy 446.495362 -433.677257) (xy 446.59739 -433.561169) (xy 446.705259 -433.450486) (xy 446.818682 -433.345503)
			(xy 446.93736 -433.246498) (xy 447.060976 -433.153733) (xy 447.189205 -433.067456) (xy 447.321704 -432.987893)
			(xy 447.458124 -432.915258) (xy 447.598102 -432.849741) (xy 447.741268 -432.791517) (xy 447.88724 -432.74074)
			(xy 448.035633 -432.697545) (xy 448.186053 -432.662046) (xy 448.338101 -432.634338) (xy 448.491374 -432.614494)
			(xy 448.645465 -432.602566) (xy 448.799966 -432.598587) (xy 448.954467 -432.602566) (xy 449.108558 -432.614494)
			(xy 449.261831 -432.634338) (xy 449.413879 -432.662046) (xy 449.564299 -432.697545) (xy 449.712692 -432.74074)
			(xy 449.858664 -432.791517) (xy 450.00183 -432.849741) (xy 450.141808 -432.915258) (xy 450.278228 -432.987893)
			(xy 450.410727 -433.067456) (xy 450.538956 -433.153733) (xy 450.662572 -433.246498) (xy 450.78125 -433.345503)
			(xy 450.894673 -433.450486) (xy 451.002542 -433.561169) (xy 451.10457 -433.677257) (xy 451.200486 -433.798445)
			(xy 451.290037 -433.924409) (xy 451.372985 -434.054816) (xy 451.449109 -434.189321) (xy 451.518208 -434.327565)
			(xy 451.580099 -434.469184) (xy 451.634618 -434.613801) (xy 451.681619 -434.761033) (xy 451.720979 -434.910489)
			(xy 451.752593 -435.061773) (xy 451.776377 -435.214484) (xy 451.792268 -435.368217) (xy 451.800224 -435.522564)
			(xy 451.800722 -435.59984) (xy 451.800224 -435.677116) (xy 451.792268 -435.831463) (xy 451.776377 -435.985196)
			(xy 451.752593 -436.137907) (xy 451.720979 -436.289191) (xy 451.681619 -436.438647) (xy 451.634618 -436.585879)
			(xy 451.580099 -436.730496) (xy 451.518208 -436.872115) (xy 451.449109 -437.010359) (xy 451.372985 -437.144864)
			(xy 451.290037 -437.275271) (xy 451.200486 -437.401235) (xy 451.10457 -437.522423) (xy 451.002542 -437.638511)
			(xy 450.894673 -437.749194) (xy 450.78125 -437.854177) (xy 450.662572 -437.953182) (xy 450.538956 -438.045947)
			(xy 450.410727 -438.132224) (xy 450.278228 -438.211787) (xy 450.141808 -438.284422) (xy 450.00183 -438.349939)
			(xy 449.858664 -438.408163) (xy 449.712692 -438.45894) (xy 449.564299 -438.502135) (xy 449.413879 -438.537634)
			(xy 449.261831 -438.565342) (xy 449.108558 -438.585186) (xy 448.954467 -438.597114) (xy 448.799966 -438.601094)
			(xy 448.645465 -438.597114) (xy 448.491374 -438.585186) (xy 448.338101 -438.565342) (xy 448.186053 -438.537634)
			(xy 448.035633 -438.502135) (xy 447.88724 -438.45894) (xy 447.741268 -438.408163) (xy 447.598102 -438.349939)
			(xy 447.458124 -438.284422) (xy 447.321704 -438.211787) (xy 447.189205 -438.132224) (xy 447.060976 -438.045947)
			(xy 446.93736 -437.953182) (xy 446.818682 -437.854177) (xy 446.705259 -437.749194) (xy 446.59739 -437.638511)
			(xy 446.495362 -437.522423) (xy 446.399446 -437.401235) (xy 446.309895 -437.275271) (xy 446.226947 -437.144864)
			(xy 446.150823 -437.010359) (xy 446.081724 -436.872115) (xy 446.019833 -436.730496) (xy 445.965314 -436.585879)
			(xy 445.918313 -436.438647) (xy 445.878953 -436.289191) (xy 445.847339 -436.137907) (xy 445.823555 -435.985196)
			(xy 445.807664 -435.831463) (xy 445.799708 -435.677116) (xy 445.08928 -435.677116) (xy 445.08928 -440.362848)
			(xy 445.089711 -440.372915) (xy 445.097436 -440.391509) (xy 445.104266 -440.398916) (xy 445.205358 -440.500008)
			(xy 445.21276 -440.506844) (xy 445.231358 -440.514557) (xy 445.241426 -440.514994) (xy 456.412346 -440.514994)
		)
		(stroke
			(width 0)
			(type solid)
		)
		(fill yes)
		(layer "In4.Cu")
		(net "GND")
	)
	(gr_poly
		(pts
			(xy 100.7872 -265.641074) (xy 100.797034 -265.640532) (xy 100.815185 -265.632935) (xy 100.822506 -265.626342)
			(xy 101.915722 -264.533126) (xy 101.922407 -264.525837) (xy 101.93011 -264.507641) (xy 101.930331 -264.487883)
			(xy 101.927152 -264.478516) (xy 101.927152 -264.478262) (xy 101.917215 -264.451265) (xy 101.906474 -264.394755)
			(xy 101.905816 -264.365994) (xy 101.905816 -264.36193) (xy 101.906603 -264.338159) (xy 101.914634 -264.291283)
			(xy 101.929836 -264.246218) (xy 101.951842 -264.204057) (xy 101.98012 -264.165817) (xy 102.013985 -264.132425)
			(xy 102.052619 -264.104688) (xy 102.095086 -264.083276) (xy 102.14036 -264.068709) (xy 102.187344 -264.061338)
			(xy 102.211124 -264.06094) (xy 102.211378 -264.06094) (xy 102.240013 -264.061614) (xy 102.296266 -264.072361)
			(xy 102.323138 -264.082276) (xy 102.323392 -264.082276) (xy 102.332757 -264.085456) (xy 102.352513 -264.085207)
			(xy 102.370722 -264.077537) (xy 102.378002 -264.070846) (xy 102.502208 -263.94664) (xy 102.50833 -263.940075)
			(xy 102.515883 -263.923804) (xy 102.51694 -263.91489) (xy 102.517194 -263.91108) (xy 102.511606 -263.822688)
			(xy 102.5017 -263.803638) (xy 102.49281 -263.79678) (xy 102.474896 -263.782209) (xy 102.443246 -263.748587)
			(xy 102.417017 -263.710584) (xy 102.396806 -263.669067) (xy 102.383074 -263.624981) (xy 102.376133 -263.57933)
			(xy 102.375716 -263.556242) (xy 102.376186 -263.532007) (xy 102.383852 -263.484146) (xy 102.398981 -263.438097)
			(xy 102.421195 -263.395016) (xy 102.449936 -263.355985) (xy 102.484481 -263.321984) (xy 102.523963 -263.293867)
			(xy 102.567392 -263.27234) (xy 102.613675 -263.257943) (xy 102.63759 -263.253982) (xy 102.650798 -263.252204)
			(xy 102.681024 -263.25068) (xy 102.704143 -263.251099) (xy 102.749856 -263.258053) (xy 102.793999 -263.271814)
			(xy 102.835566 -263.292067) (xy 102.873607 -263.318351) (xy 102.907255 -263.350066) (xy 102.921816 -263.368028)
			(xy 102.928674 -263.376664) (xy 102.947724 -263.386824) (xy 103.032306 -263.392158) (xy 103.043148 -263.392376)
			(xy 103.063426 -263.38475) (xy 103.071422 -263.377426) (xy 103.224076 -263.224772) (xy 103.230883 -263.217344)
			(xy 103.238549 -263.198728) (xy 103.238494 -263.178595) (xy 103.234998 -263.169146) (xy 103.199438 -263.084564)
			(xy 103.19606 -263.077381) (xy 103.185718 -263.065351) (xy 103.179118 -263.060942) (xy 103.166926 -263.053576)
			(xy 103.147876 -263.053576) (xy 103.123059 -263.053088) (xy 103.074079 -263.045055) (xy 103.027043 -263.029203)
			(xy 102.983192 -263.005951) (xy 102.94368 -262.975912) (xy 102.909548 -262.939876) (xy 102.881695 -262.898793)
			(xy 102.860856 -262.853745) (xy 102.847578 -262.805919) (xy 102.842213 -262.756575) (xy 102.844901 -262.707013)
			(xy 102.855571 -262.658539) (xy 102.873943 -262.61243) (xy 102.899532 -262.5699) (xy 102.931665 -262.53207)
			(xy 102.969494 -262.499937) (xy 103.012023 -262.474347) (xy 103.058132 -262.455974) (xy 103.106605 -262.445302)
			(xy 103.156167 -262.442613) (xy 103.205511 -262.447977) (xy 103.253337 -262.461253) (xy 103.298386 -262.482091)
			(xy 103.339469 -262.509943) (xy 103.375506 -262.544074) (xy 103.405547 -262.583585) (xy 103.4288 -262.627436)
			(xy 103.444653 -262.674471) (xy 103.452688 -262.723451) (xy 103.453184 -262.748268) (xy 103.453184 -262.753094)
			(xy 103.453426 -262.760044) (xy 103.457165 -262.773434) (xy 103.46055 -262.77951) (xy 103.464903 -262.78616)
			(xy 103.476945 -262.796523) (xy 103.484172 -262.79983) (xy 103.568754 -262.83539) (xy 103.578197 -262.838929)
			(xy 103.598347 -262.839021) (xy 103.616958 -262.831298) (xy 103.62438 -262.824468) (xy 103.798624 -262.650224)
			(xy 103.802434 -262.640064) (xy 103.812106 -262.616084) (xy 103.838317 -262.571518) (xy 103.871661 -262.532004)
			(xy 103.911184 -262.498671) (xy 103.955756 -262.472472) (xy 103.979726 -262.462772) (xy 103.989886 -262.458962)
			(xy 104.619552 -261.829296) (xy 104.626792 -261.822588) (xy 104.644997 -261.815008) (xy 104.654858 -261.814564)
			(xy 105.62971 -261.814564) (xy 105.639554 -261.814041) (xy 105.657736 -261.806476) (xy 105.665016 -261.799832)
			(xy 105.940352 -261.524496) (xy 105.947592 -261.517788) (xy 105.965797 -261.510208) (xy 105.975658 -261.509764)
			(xy 105.999026 -261.509764) (xy 106.011765 -261.509072) (xy 106.034174 -261.49695) (xy 106.041698 -261.48665)
			(xy 106.08691 -261.417308) (xy 106.090225 -261.411855) (xy 106.094332 -261.399775) (xy 106.095038 -261.393432)
			(xy 106.096054 -261.380986) (xy 106.090974 -261.369048) (xy 106.09072 -261.368794) (xy 106.081764 -261.34748)
			(xy 106.06902 -261.303038) (xy 106.062373 -261.257286) (xy 106.061764 -261.234174) (xy 106.061764 -261.229094)
			(xy 106.062334 -261.203457) (xy 106.070146 -261.152778) (xy 106.085407 -261.103825) (xy 106.107778 -261.057684)
			(xy 106.13676 -261.015383) (xy 106.17171 -260.977862) (xy 106.211851 -260.945955) (xy 106.25629 -260.920371)
			(xy 106.30404 -260.901679) (xy 106.354037 -260.890295) (xy 106.405172 -260.886472) (xy 106.456307 -260.890295)
			(xy 106.506304 -260.901679) (xy 106.554054 -260.920371) (xy 106.598493 -260.945955) (xy 106.638634 -260.977862)
			(xy 106.673584 -261.015383) (xy 106.702566 -261.057684) (xy 106.724937 -261.103825) (xy 106.740198 -261.152778)
			(xy 106.74801 -261.203457) (xy 106.74858 -261.229094) (xy 106.74858 -261.231126) (xy 106.748174 -261.254751)
			(xy 106.741662 -261.301551) (xy 106.728777 -261.347011) (xy 106.719624 -261.368794) (xy 106.71937 -261.369048)
			(xy 106.719116 -261.369556) (xy 106.716883 -261.37525) (xy 106.714961 -261.387325) (xy 106.715306 -261.393432)
			(xy 106.716322 -261.406386) (xy 106.768646 -261.48665) (xy 106.773507 -261.493583) (xy 106.786843 -261.504)
			(xy 106.802855 -261.509474) (xy 106.811318 -261.509764) (xy 107.212638 -261.509764) (xy 107.223922 -261.509151)
			(xy 107.244334 -261.49952) (xy 107.252008 -261.491222) (xy 107.307888 -261.42315) (xy 107.313476 -261.401306)
			(xy 107.31119 -261.389876) (xy 107.308107 -261.373348) (xy 107.304798 -261.339886) (xy 107.304586 -261.323074)
			(xy 107.305117 -261.29609) (xy 107.313563 -261.242787) (xy 107.330243 -261.191461) (xy 107.354746 -261.143377)
			(xy 107.38647 -261.099717) (xy 107.424632 -261.061557) (xy 107.468294 -261.029836) (xy 107.51638 -261.005335)
			(xy 107.567706 -260.988659) (xy 107.62101 -260.980216) (xy 107.647994 -260.979666) (xy 107.674828 -260.980183)
			(xy 107.727843 -260.98853) (xy 107.778914 -261.005022) (xy 107.826798 -261.029258) (xy 107.87033 -261.060647)
			(xy 107.908448 -261.098426) (xy 107.940227 -261.141674) (xy 107.964891 -261.189338) (xy 107.98184 -261.24026)
			(xy 107.990663 -261.293198) (xy 107.991402 -261.320026) (xy 107.991402 -261.323836) (xy 107.990719 -261.35388)
			(xy 107.980119 -261.413029) (xy 107.97032 -261.441438) (xy 107.966764 -261.450836) (xy 107.967272 -261.46125)
			(xy 107.968138 -261.470955) (xy 107.976187 -261.488679) (xy 107.990264 -261.502126) (xy 108.008338 -261.509357)
			(xy 108.018072 -261.509764) (xy 108.03509 -261.509764) (xy 108.044927 -261.509226) (xy 108.063089 -261.501641)
			(xy 108.070396 -261.495032) (xy 108.218732 -261.346696) (xy 108.225444 -261.339457) (xy 108.233038 -261.321253)
			(xy 108.233464 -261.31139) (xy 108.233464 -258.133342) (xy 108.23313 -258.124509) (xy 108.227202 -258.107871)
			(xy 108.215969 -258.09424) (xy 108.208572 -258.0894) (xy 108.123228 -258.039108) (xy 108.096558 -258.038854)
			(xy 108.08462 -258.045458) (xy 108.058916 -258.059019) (xy 108.004083 -258.078258) (xy 107.946797 -258.088012)
			(xy 107.917742 -258.088638) (xy 107.890752 -258.088139) (xy 107.837435 -258.079701) (xy 107.786094 -258.063026)
			(xy 107.737995 -258.038525) (xy 107.69432 -258.006801) (xy 107.656146 -257.968635) (xy 107.624413 -257.924967)
			(xy 107.599901 -257.876872) (xy 107.583216 -257.825535) (xy 107.574766 -257.77222) (xy 107.574334 -257.74523)
			(xy 107.574816 -257.719051) (xy 107.582743 -257.667296) (xy 107.598434 -257.617343) (xy 107.621524 -257.570351)
			(xy 107.651479 -257.527408) (xy 107.687605 -257.489509) (xy 107.729065 -257.457532) (xy 107.774897 -257.432218)
			(xy 107.824041 -257.414153) (xy 107.875357 -257.403757) (xy 107.901486 -257.402076) (xy 107.90174 -257.402076)
			(xy 107.911508 -257.401207) (xy 107.929327 -257.393061) (xy 107.942761 -257.378799) (xy 107.946698 -257.369818)
			(xy 107.979464 -257.28549) (xy 107.982636 -257.276169) (xy 107.982374 -257.256501) (xy 107.974684 -257.238396)
			(xy 107.968034 -257.231134) (xy 107.86745 -257.13055) (xy 107.860338 -257.123184) (xy 107.841542 -257.115564)
			(xy 106.793538 -257.115564) (xy 106.792522 -257.115564) (xy 106.780446 -257.116491) (xy 106.759107 -257.127882)
			(xy 106.751628 -257.137408) (xy 106.74985 -257.140456) (xy 106.706416 -257.213862) (xy 106.702284 -257.22164)
			(xy 106.699061 -257.238942) (xy 106.701905 -257.25631) (xy 106.705908 -257.264154) (xy 106.705908 -257.264408)
			(xy 106.719327 -257.289974) (xy 106.738359 -257.344481) (xy 106.748013 -257.401403) (xy 106.74858 -257.43027)
			(xy 106.7481 -257.455969) (xy 106.740439 -257.506793) (xy 106.72529 -257.555907) (xy 106.702989 -257.602215)
			(xy 106.674036 -257.644682) (xy 106.639076 -257.682359) (xy 106.598892 -257.714405) (xy 106.55438 -257.740104)
			(xy 106.506535 -257.758881) (xy 106.456426 -257.770319) (xy 106.405172 -257.77416) (xy 106.353918 -257.770319)
			(xy 106.303809 -257.758881) (xy 106.255964 -257.740104) (xy 106.211452 -257.714405) (xy 106.171268 -257.682359)
			(xy 106.136308 -257.644682) (xy 106.107355 -257.602215) (xy 106.085054 -257.555907) (xy 106.069905 -257.506793)
			(xy 106.062244 -257.455969) (xy 106.061764 -257.43027) (xy 106.062357 -257.401404) (xy 106.072006 -257.344485)
			(xy 106.091029 -257.289978) (xy 106.104436 -257.264408) (xy 106.104436 -257.264154) (xy 106.10836 -257.256286)
			(xy 106.111171 -257.238943) (xy 106.107985 -257.221664) (xy 106.103928 -257.213862) (xy 106.060494 -257.140456)
			(xy 106.058716 -257.137408) (xy 106.051284 -257.12782) (xy 106.029923 -257.116403) (xy 106.017822 -257.115564)
			(xy 100.971858 -257.115564) (xy 100.962017 -257.115035) (xy 100.943842 -257.107462) (xy 100.936552 -257.100832)
			(xy 100.20427 -256.36855) (xy 100.197158 -256.361184) (xy 100.178362 -256.353564) (xy 99.454208 -256.353564)
			(xy 99.445572 -256.353908) (xy 99.42929 -256.359667) (xy 99.415861 -256.370528) (xy 99.411028 -256.377694)
			(xy 99.35972 -256.460498) (xy 99.35845 -256.48666) (xy 99.364292 -256.498598) (xy 99.374385 -256.519814)
			(xy 99.388647 -256.564577) (xy 99.395873 -256.610998) (xy 99.396296 -256.634488) (xy 99.395851 -256.658481)
			(xy 99.388345 -256.705878) (xy 99.373518 -256.751516) (xy 99.351733 -256.794273) (xy 99.323527 -256.833095)
			(xy 99.289595 -256.867027) (xy 99.250773 -256.895233) (xy 99.208016 -256.917018) (xy 99.162378 -256.931845)
			(xy 99.114981 -256.939351) (xy 99.090988 -256.939796) (xy 99.078225 -256.939659) (xy 99.052791 -256.937498)
			(xy 99.040188 -256.935478) (xy 99.040188 -256.935732) (xy 99.016506 -256.931288) (xy 98.970838 -256.91593)
			(xy 98.928151 -256.893586) (xy 98.889506 -256.864812) (xy 98.855862 -256.830322) (xy 98.828056 -256.790974)
			(xy 98.806778 -256.747745) (xy 98.792559 -256.70171) (xy 98.788728 -256.677922) (xy 98.78695 -256.665222)
			(xy 98.785426 -256.634996) (xy 98.785426 -256.634488) (xy 98.785873 -256.610999) (xy 98.793095 -256.564579)
			(xy 98.807336 -256.519812) (xy 98.81743 -256.498598) (xy 98.81743 -256.498344) (xy 98.817684 -256.497836)
			(xy 98.821094 -256.489984) (xy 98.823039 -256.472987) (xy 98.81932 -256.456288) (xy 98.815144 -256.448814)
			(xy 98.770948 -256.37744) (xy 98.766111 -256.3703) (xy 98.75266 -256.359527) (xy 98.736386 -256.353855)
			(xy 98.727768 -256.353564) (xy 97.574354 -256.353564) (xy 97.565714 -256.353901) (xy 97.54942 -256.35965)
			(xy 97.535979 -256.370507) (xy 97.531174 -256.377694) (xy 97.479866 -256.460498) (xy 97.478596 -256.48666)
			(xy 97.484438 -256.498598) (xy 97.494529 -256.519814) (xy 97.50879 -256.564577) (xy 97.516014 -256.610998)
			(xy 97.516442 -256.634488) (xy 97.515972 -256.658481) (xy 97.508468 -256.705876) (xy 97.493642 -256.751514)
			(xy 97.47186 -256.794271) (xy 97.443657 -256.833094) (xy 97.409729 -256.867027) (xy 97.37091 -256.895236)
			(xy 97.328156 -256.917024) (xy 97.282521 -256.931857) (xy 97.235127 -256.939369) (xy 97.211134 -256.939796)
			(xy 97.198371 -256.939656) (xy 97.172938 -256.937491) (xy 97.160334 -256.935478) (xy 97.160334 -256.935732)
			(xy 97.136655 -256.931285) (xy 97.090994 -256.915921) (xy 97.048313 -256.893573) (xy 97.009675 -256.864797)
			(xy 96.976037 -256.830307) (xy 96.948237 -256.79096) (xy 96.926964 -256.747734) (xy 96.912748 -256.701702)
			(xy 96.908874 -256.677922) (xy 96.907096 -256.665222) (xy 96.905572 -256.634996) (xy 96.905572 -256.634488)
			(xy 96.906018 -256.610999) (xy 96.913239 -256.564579) (xy 96.927479 -256.51981) (xy 96.937576 -256.498598)
			(xy 96.937576 -256.498344) (xy 96.93783 -256.497836) (xy 96.941242 -256.489985) (xy 96.943189 -256.472987)
			(xy 96.939467 -256.456288) (xy 96.93529 -256.448814) (xy 96.891094 -256.37744) (xy 96.886255 -256.370307)
			(xy 96.872801 -256.359547) (xy 96.856529 -256.353893) (xy 96.847914 -256.353564) (xy 96.463358 -256.353564)
			(xy 96.453517 -256.353035) (xy 96.435342 -256.345462) (xy 96.428052 -256.338832) (xy 96.168718 -256.079498)
			(xy 96.161606 -256.072386) (xy 96.072198 -256.034794) (xy 96.065272 -256.032186) (xy 96.05056 -256.03064)
			(xy 96.043242 -256.031746) (xy 96.038162 -256.032762) (xy 96.020031 -256.05259) (xy 95.978262 -256.08638)
			(xy 95.93138 -256.112619) (xy 95.880736 -256.13055) (xy 95.827788 -256.139658) (xy 95.800926 -256.140204)
			(xy 95.776115 -256.139745) (xy 95.727102 -256.131986) (xy 95.679907 -256.116654) (xy 95.635691 -256.094129)
			(xy 95.595544 -256.064963) (xy 95.560454 -256.029876) (xy 95.531285 -255.989731) (xy 95.508756 -255.945517)
			(xy 95.493421 -255.898323) (xy 95.485657 -255.849311) (xy 95.485657 -255.799689) (xy 95.493421 -255.750677)
			(xy 95.508756 -255.703483) (xy 95.531285 -255.659269) (xy 95.560454 -255.619124) (xy 95.595544 -255.584037)
			(xy 95.635691 -255.554871) (xy 95.679907 -255.532346) (xy 95.727102 -255.517014) (xy 95.776115 -255.509255)
			(xy 95.800926 -255.50876) (xy 95.825637 -255.509264) (xy 95.874448 -255.517012) (xy 95.921457 -255.532269)
			(xy 95.965516 -255.554662) (xy 96.005549 -255.583644) (xy 96.02343 -255.600708) (xy 96.034352 -255.61163)
			(xy 96.064578 -255.617472) (xy 96.152462 -255.580388) (xy 96.161452 -255.576087) (xy 96.175503 -255.56198)
			(xy 96.183167 -255.543604) (xy 96.183704 -255.533652) (xy 96.183704 -255.32715) (xy 96.16694 -255.30175)
			(xy 96.152716 -255.295908) (xy 96.129332 -255.285507) (xy 96.086131 -255.258075) (xy 96.048108 -255.223825)
			(xy 96.016327 -255.183714) (xy 95.99168 -255.138866) (xy 95.974855 -255.090537) (xy 95.966324 -255.040078)
			(xy 95.966326 -254.988903) (xy 95.97486 -254.938445) (xy 95.991688 -254.890117) (xy 96.016338 -254.84527)
			(xy 96.04812 -254.805161) (xy 96.086146 -254.770913) (xy 96.129349 -254.743485) (xy 96.152716 -254.733044)
			(xy 96.16694 -254.727202) (xy 96.183704 -254.701802) (xy 96.183704 -254.4953) (xy 96.183228 -254.485366)
			(xy 96.175664 -254.466993) (xy 96.161676 -254.452883) (xy 96.152716 -254.448564) (xy 96.064578 -254.41148)
			(xy 96.034352 -254.417322) (xy 96.02343 -254.428244) (xy 96.005577 -254.445339) (xy 95.96554 -254.474321)
			(xy 95.921474 -254.496707) (xy 95.874457 -254.511949) (xy 95.825639 -254.519675) (xy 95.800926 -254.520192)
			(xy 95.776115 -254.519733) (xy 95.727105 -254.511974) (xy 95.679911 -254.496643) (xy 95.635698 -254.474118)
			(xy 95.595552 -254.444954) (xy 95.560463 -254.409868) (xy 95.531295 -254.369725) (xy 95.508767 -254.325513)
			(xy 95.493432 -254.278321) (xy 95.485669 -254.22931) (xy 95.485669 -254.17969) (xy 95.493432 -254.130679)
			(xy 95.508767 -254.083487) (xy 95.531295 -254.039275) (xy 95.560463 -253.999132) (xy 95.595552 -253.964046)
			(xy 95.635698 -253.934882) (xy 95.679911 -253.912357) (xy 95.727105 -253.897026) (xy 95.776115 -253.889267)
			(xy 95.800926 -253.888748) (xy 95.825637 -253.889252) (xy 95.874449 -253.897) (xy 95.921458 -253.912256)
			(xy 95.965517 -253.934649) (xy 96.005551 -253.96363) (xy 96.02343 -253.980696) (xy 96.034352 -253.991618)
			(xy 96.064578 -253.99746) (xy 96.152462 -253.960376) (xy 96.161451 -253.956074) (xy 96.175498 -253.941967)
			(xy 96.183158 -253.923591) (xy 96.183704 -253.91364) (xy 96.183704 -253.707138) (xy 96.16694 -253.681738)
			(xy 96.152716 -253.675896) (xy 96.129333 -253.665495) (xy 96.086134 -253.638064) (xy 96.048113 -253.603814)
			(xy 96.016334 -253.563704) (xy 95.991688 -253.518858) (xy 95.974865 -253.470529) (xy 95.966335 -253.420072)
			(xy 95.966337 -253.3689) (xy 95.974872 -253.318444) (xy 95.9917 -253.270117) (xy 96.01635 -253.225272)
			(xy 96.048132 -253.185165) (xy 96.086156 -253.150919) (xy 96.129358 -253.123492) (xy 96.152716 -253.113032)
			(xy 96.16694 -253.10719) (xy 96.183704 -253.08179) (xy 96.183704 -252.875288) (xy 96.183225 -252.865355)
			(xy 96.175659 -252.846986) (xy 96.161671 -252.83288) (xy 96.152716 -252.828552) (xy 96.064578 -252.791468)
			(xy 96.034352 -252.79731) (xy 96.02343 -252.808232) (xy 96.005578 -252.825328) (xy 95.965541 -252.854311)
			(xy 95.921475 -252.876698) (xy 95.874458 -252.89194) (xy 95.825639 -252.899666) (xy 95.800926 -252.90018)
			(xy 95.776116 -252.899721) (xy 95.727108 -252.891962) (xy 95.679916 -252.876632) (xy 95.635704 -252.854108)
			(xy 95.59556 -252.824945) (xy 95.560472 -252.78986) (xy 95.531305 -252.749718) (xy 95.508778 -252.705508)
			(xy 95.493444 -252.658318) (xy 95.485681 -252.60931) (xy 95.485681 -252.55969) (xy 95.493444 -252.510682)
			(xy 95.508778 -252.463492) (xy 95.531305 -252.419282) (xy 95.560472 -252.37914) (xy 95.59556 -252.344055)
			(xy 95.635704 -252.314892) (xy 95.679916 -252.292368) (xy 95.727108 -252.277038) (xy 95.776116 -252.269279)
			(xy 95.800926 -252.268736) (xy 95.825637 -252.26924) (xy 95.874449 -252.276988) (xy 95.921458 -252.292244)
			(xy 95.965518 -252.314635) (xy 96.005553 -252.343616) (xy 96.02343 -252.360684) (xy 96.034352 -252.371606)
			(xy 96.064578 -252.377448) (xy 96.152462 -252.340364) (xy 96.16145 -252.336062) (xy 96.175494 -252.321954)
			(xy 96.18315 -252.303578) (xy 96.183704 -252.293628) (xy 96.183704 -252.087126) (xy 96.16694 -252.061726)
			(xy 96.152716 -252.055884) (xy 96.129334 -252.045483) (xy 96.086137 -252.018052) (xy 96.048117 -251.983803)
			(xy 96.016341 -251.943694) (xy 95.991696 -251.898849) (xy 95.974874 -251.850522) (xy 95.966345 -251.800067)
			(xy 95.966348 -251.748896) (xy 95.974884 -251.698442) (xy 95.991712 -251.650117) (xy 96.016361 -251.605274)
			(xy 96.048143 -251.56517) (xy 96.086166 -251.530925) (xy 96.129367 -251.5035) (xy 96.152716 -251.49302)
			(xy 96.16694 -251.487178) (xy 96.183704 -251.461778) (xy 96.183704 -251.255276) (xy 96.183241 -251.245333)
			(xy 96.175693 -251.226938) (xy 96.161707 -251.212804) (xy 96.152716 -251.20854) (xy 96.064578 -251.171456)
			(xy 96.034352 -251.177298) (xy 96.02343 -251.18822) (xy 96.005578 -251.205316) (xy 95.965542 -251.234301)
			(xy 95.921476 -251.256688) (xy 95.874458 -251.271932) (xy 95.825639 -251.279658) (xy 95.800926 -251.280168)
			(xy 95.77611 -251.279708) (xy 95.727087 -251.271948) (xy 95.679882 -251.256613) (xy 95.635658 -251.234083)
			(xy 95.595502 -251.204912) (xy 95.560405 -251.169817) (xy 95.53123 -251.129664) (xy 95.508696 -251.085442)
			(xy 95.493358 -251.038238) (xy 95.485594 -250.989216) (xy 95.485594 -250.939584) (xy 95.493358 -250.890562)
			(xy 95.508696 -250.843358) (xy 95.53123 -250.799136) (xy 95.560405 -250.758983) (xy 95.595502 -250.723888)
			(xy 95.635658 -250.694717) (xy 95.679882 -250.672187) (xy 95.727087 -250.656852) (xy 95.77611 -250.649092)
			(xy 95.800926 -250.648724) (xy 95.825637 -250.649228) (xy 95.874449 -250.656975) (xy 95.921459 -250.672231)
			(xy 95.965519 -250.694622) (xy 96.005555 -250.723602) (xy 96.02343 -250.740672) (xy 96.034352 -250.751594)
			(xy 96.064578 -250.757436) (xy 96.152462 -250.720352) (xy 96.161449 -250.71605) (xy 96.175489 -250.70194)
			(xy 96.183141 -250.683565) (xy 96.183704 -250.673616) (xy 96.183704 -250.467114) (xy 96.16694 -250.441714)
			(xy 96.152716 -250.435872) (xy 96.129327 -250.42547) (xy 96.086115 -250.398037) (xy 96.048082 -250.363784)
			(xy 96.016292 -250.323668) (xy 95.991636 -250.278813) (xy 95.974804 -250.230475) (xy 95.966267 -250.180008)
			(xy 95.966265 -250.128823) (xy 95.974796 -250.078355) (xy 95.991624 -250.030015) (xy 96.016275 -249.985158)
			(xy 96.04806 -249.945039) (xy 96.08609 -249.910781) (xy 96.1293 -249.883344) (xy 96.152716 -249.873008)
			(xy 96.16694 -249.867166) (xy 96.183704 -249.841766) (xy 96.183704 -249.635264) (xy 96.183239 -249.625323)
			(xy 96.175689 -249.606931) (xy 96.161702 -249.592801) (xy 96.152716 -249.588528) (xy 96.064578 -249.551444)
			(xy 96.034352 -249.557286) (xy 96.02343 -249.568208) (xy 96.005578 -249.585305) (xy 95.965542 -249.61429)
			(xy 95.921476 -249.636679) (xy 95.874459 -249.651923) (xy 95.825639 -249.659649) (xy 95.800926 -249.660156)
			(xy 95.77611 -249.659696) (xy 95.72709 -249.651936) (xy 95.679887 -249.636602) (xy 95.635664 -249.614073)
			(xy 95.59551 -249.584903) (xy 95.560414 -249.54981) (xy 95.531241 -249.509658) (xy 95.508708 -249.465437)
			(xy 95.49337 -249.418235) (xy 95.485606 -249.369216) (xy 95.485606 -249.319584) (xy 95.49337 -249.270565)
			(xy 95.508708 -249.223363) (xy 95.531241 -249.179142) (xy 95.560414 -249.13899) (xy 95.59551 -249.103897)
			(xy 95.635664 -249.074727) (xy 95.679887 -249.052198) (xy 95.72709 -249.036864) (xy 95.77611 -249.029104)
			(xy 95.800926 -249.028712) (xy 95.82659 -249.029216) (xy 95.87724 -249.037524) (xy 95.92588 -249.053916)
			(xy 95.971227 -249.077961) (xy 96.012086 -249.109026) (xy 96.047382 -249.146291) (xy 96.076185 -249.188775)
			(xy 96.087438 -249.211846) (xy 96.091771 -249.220252) (xy 96.105411 -249.233336) (xy 96.122863 -249.240593)
			(xy 96.141758 -249.241038) (xy 96.159532 -249.234613) (xy 96.173774 -249.222188) (xy 96.182551 -249.205449)
			(xy 96.183958 -249.196098) (xy 96.185212 -249.187616) (xy 96.192605 -249.172158) (xy 96.198436 -249.165872)
			(xy 96.35363 -249.010678) (xy 96.360497 -249.003173) (xy 96.368173 -248.984353) (xy 96.367968 -248.964029)
			(xy 96.364298 -248.954544) (xy 96.321626 -248.855738) (xy 96.29521 -248.839228) (xy 96.279716 -248.839736)
			(xy 96.27108 -248.839736) (xy 96.245823 -248.839213) (xy 96.196 -248.830896) (xy 96.148224 -248.814492)
			(xy 96.1038 -248.790448) (xy 96.06394 -248.759421) (xy 96.029729 -248.722256) (xy 96.002102 -248.679967)
			(xy 95.981812 -248.633708) (xy 95.969412 -248.584741) (xy 95.965241 -248.5344) (xy 95.969412 -248.484059)
			(xy 95.981812 -248.435092) (xy 96.002102 -248.388833) (xy 96.029729 -248.346544) (xy 96.06394 -248.309379)
			(xy 96.1038 -248.278352) (xy 96.148224 -248.254308) (xy 96.196 -248.237904) (xy 96.245823 -248.229587)
			(xy 96.27108 -248.22912) (xy 96.296673 -248.22962) (xy 96.347149 -248.238106) (xy 96.395508 -248.254878)
			(xy 96.440399 -248.279468) (xy 96.460818 -248.294906) (xy 96.472248 -248.304304) (xy 96.50095 -248.307352)
			(xy 96.594422 -248.26214) (xy 96.602822 -248.25764) (xy 96.61576 -248.243669) (xy 96.622711 -248.225941)
			(xy 96.623124 -248.21642) (xy 96.623124 -248.023888) (xy 96.6089 -248.000012) (xy 96.596454 -247.993408)
			(xy 96.574375 -247.980978) (xy 96.534314 -247.949959) (xy 96.499921 -247.912754) (xy 96.472141 -247.870384)
			(xy 96.451735 -247.824009) (xy 96.439262 -247.774902) (xy 96.435065 -247.72441) (xy 96.439259 -247.673918)
			(xy 96.451728 -247.624811) (xy 96.472131 -247.578435) (xy 96.499909 -247.536062) (xy 96.534298 -247.498855)
			(xy 96.574357 -247.467833) (xy 96.596454 -247.455436) (xy 96.6089 -247.448832) (xy 96.623124 -247.424956)
			(xy 96.623124 -246.403876) (xy 96.6089 -246.38) (xy 96.596454 -246.373396) (xy 96.574376 -246.360966)
			(xy 96.534317 -246.329948) (xy 96.499926 -246.292743) (xy 96.472148 -246.250374) (xy 96.451743 -246.204)
			(xy 96.439271 -246.154895) (xy 96.435075 -246.104405) (xy 96.43927 -246.053915) (xy 96.45174 -246.004809)
			(xy 96.472143 -245.958435) (xy 96.49992 -245.916064) (xy 96.53431 -245.878859) (xy 96.574368 -245.847839)
			(xy 96.596454 -245.835424) (xy 96.6089 -245.82882) (xy 96.623124 -245.804944) (xy 96.623124 -245.612412)
			(xy 96.62273 -245.602889) (xy 96.615776 -245.585158) (xy 96.602824 -245.571193) (xy 96.594422 -245.566692)
			(xy 96.50095 -245.52148) (xy 96.472248 -245.524528) (xy 96.460818 -245.533926) (xy 96.440408 -245.549375)
			(xy 96.395512 -245.573957) (xy 96.34715 -245.590722) (xy 96.296673 -245.599205) (xy 96.27108 -245.599712)
			(xy 96.245825 -245.599189) (xy 96.196006 -245.590872) (xy 96.148234 -245.57447) (xy 96.103814 -245.550428)
			(xy 96.063956 -245.519403) (xy 96.029748 -245.482241) (xy 96.002123 -245.439956) (xy 95.981835 -245.3937)
			(xy 95.969436 -245.344737) (xy 95.965265 -245.2944) (xy 95.969436 -245.244063) (xy 95.981835 -245.1951)
			(xy 96.002123 -245.148844) (xy 96.029748 -245.106559) (xy 96.063956 -245.069397) (xy 96.103814 -245.038372)
			(xy 96.148234 -245.01433) (xy 96.196006 -244.997928) (xy 96.245825 -244.989611) (xy 96.27108 -244.989096)
			(xy 96.296672 -244.989596) (xy 96.347147 -244.998084) (xy 96.395504 -245.01486) (xy 96.440391 -245.039455)
			(xy 96.460818 -245.054882) (xy 96.472248 -245.06428) (xy 96.50095 -245.067328) (xy 96.594422 -245.022116)
			(xy 96.60283 -245.01762) (xy 96.615789 -245.003652) (xy 96.622767 -244.985922) (xy 96.623124 -244.976396)
			(xy 96.623124 -244.783864) (xy 96.6089 -244.759988) (xy 96.596454 -244.753384) (xy 96.574377 -244.740954)
			(xy 96.53432 -244.709936) (xy 96.499931 -244.672732) (xy 96.472154 -244.630363) (xy 96.451751 -244.583991)
			(xy 96.439281 -244.534887) (xy 96.435086 -244.484399) (xy 96.439281 -244.433911) (xy 96.451752 -244.384807)
			(xy 96.472155 -244.338435) (xy 96.499932 -244.296066) (xy 96.534321 -244.258863) (xy 96.574378 -244.227845)
			(xy 96.596454 -244.215412) (xy 96.6089 -244.208808) (xy 96.623124 -244.184932) (xy 96.623124 -243.163852)
			(xy 96.6089 -243.139976) (xy 96.596454 -243.133372) (xy 96.574378 -243.120942) (xy 96.534322 -243.089924)
			(xy 96.499936 -243.052721) (xy 96.472161 -243.010353) (xy 96.451759 -242.963982) (xy 96.43929 -242.91488)
			(xy 96.435097 -242.864393) (xy 96.439293 -242.813907) (xy 96.451764 -242.764805) (xy 96.472167 -242.718435)
			(xy 96.499944 -242.676068) (xy 96.534332 -242.638867) (xy 96.574389 -242.607851) (xy 96.596454 -242.5954)
			(xy 96.6089 -242.588796) (xy 96.623124 -242.56492) (xy 96.623124 -242.372388) (xy 96.622726 -242.362867)
			(xy 96.615767 -242.345143) (xy 96.602814 -242.331186) (xy 96.594422 -242.326668) (xy 96.50095 -242.281456)
			(xy 96.472248 -242.284504) (xy 96.460818 -242.293902) (xy 96.440408 -242.309352) (xy 96.395513 -242.333936)
			(xy 96.347151 -242.350703) (xy 96.296673 -242.359186) (xy 96.27108 -242.359688) (xy 96.245827 -242.359165)
			(xy 96.196011 -242.350849) (xy 96.148244 -242.334448) (xy 96.103827 -242.310408) (xy 96.063972 -242.279385)
			(xy 96.029767 -242.242226) (xy 96.002144 -242.199944) (xy 95.981857 -242.153693) (xy 95.96946 -242.104733)
			(xy 95.965289 -242.0544) (xy 95.96946 -242.004067) (xy 95.981857 -241.955107) (xy 96.002144 -241.908856)
			(xy 96.029767 -241.866574) (xy 96.063972 -241.829415) (xy 96.103827 -241.798392) (xy 96.148244 -241.774352)
			(xy 96.196011 -241.757951) (xy 96.245827 -241.749635) (xy 96.27108 -241.749072) (xy 96.296672 -241.749572)
			(xy 96.347148 -241.75806) (xy 96.395505 -241.774834) (xy 96.440394 -241.799427) (xy 96.460818 -241.814858)
			(xy 96.472248 -241.824256) (xy 96.50095 -241.827304) (xy 96.594422 -241.782092) (xy 96.602828 -241.777595)
			(xy 96.61578 -241.763626) (xy 96.622749 -241.745896) (xy 96.623124 -241.736372) (xy 96.623124 -241.54384)
			(xy 96.6089 -241.519964) (xy 96.596454 -241.51336) (xy 96.574379 -241.50093) (xy 96.534325 -241.469913)
			(xy 96.499941 -241.43271) (xy 96.472167 -241.390343) (xy 96.451767 -241.343974) (xy 96.4393 -241.294873)
			(xy 96.435107 -241.244388) (xy 96.439304 -241.193903) (xy 96.451775 -241.144803) (xy 96.472179 -241.098435)
			(xy 96.499956 -241.05607) (xy 96.534344 -241.018871) (xy 96.574399 -240.987856) (xy 96.596454 -240.975388)
			(xy 96.6089 -240.968784) (xy 96.623124 -240.944908) (xy 96.623124 -239.923828) (xy 96.6089 -239.899952)
			(xy 96.596454 -239.893348) (xy 96.574379 -239.880918) (xy 96.534328 -239.849901) (xy 96.499946 -239.812699)
			(xy 96.472174 -239.770333) (xy 96.451775 -239.723965) (xy 96.439309 -239.674865) (xy 96.435118 -239.624382)
			(xy 96.439315 -239.573899) (xy 96.451787 -239.524801) (xy 96.472191 -239.478435) (xy 96.499968 -239.436072)
			(xy 96.534355 -239.398874) (xy 96.57441 -239.367862) (xy 96.596454 -239.355376) (xy 96.6089 -239.348772)
			(xy 96.623124 -239.324896) (xy 96.623124 -239.132364) (xy 96.622739 -239.122836) (xy 96.615796 -239.10509)
			(xy 96.602846 -239.09111) (xy 96.594422 -239.086644) (xy 96.50095 -239.041432) (xy 96.472248 -239.04448)
			(xy 96.460818 -239.053878) (xy 96.440409 -239.069329) (xy 96.395513 -239.093915) (xy 96.347152 -239.110683)
			(xy 96.296674 -239.119167) (xy 96.27108 -239.119664) (xy 96.245829 -239.119141) (xy 96.196017 -239.110826)
			(xy 96.148253 -239.094426) (xy 96.10384 -239.070388) (xy 96.063988 -239.039368) (xy 96.029786 -239.002212)
			(xy 96.002165 -238.959933) (xy 95.98188 -238.913685) (xy 95.969483 -238.864729) (xy 95.965313 -238.8144)
			(xy 95.969483 -238.764071) (xy 95.98188 -238.715115) (xy 96.002165 -238.668867) (xy 96.029786 -238.626588)
			(xy 96.063988 -238.589432) (xy 96.10384 -238.558412) (xy 96.148253 -238.534374) (xy 96.196017 -238.517974)
			(xy 96.245829 -238.509659) (xy 96.27108 -238.509048) (xy 96.296673 -238.509548) (xy 96.347148 -238.518035)
			(xy 96.395506 -238.534808) (xy 96.440396 -238.5594) (xy 96.460818 -238.574834) (xy 96.472248 -238.584232)
			(xy 96.50095 -238.58728) (xy 96.59493 -238.541814) (xy 96.601788 -238.538512) (xy 96.61271 -238.528606)
			(xy 96.622108 -238.512858) (xy 96.629474 -238.503714) (xy 97.449132 -237.684056) (xy 97.455838 -237.676815)
			(xy 97.463417 -237.65861) (xy 97.463864 -237.64875) (xy 97.463864 -237.570264) (xy 97.463227 -237.557753)
			(xy 97.451516 -237.535639) (xy 97.441512 -237.5281) (xy 97.362772 -237.475268) (xy 97.33788 -237.472728)
			(xy 97.326196 -237.477554) (xy 97.298757 -237.487878) (xy 97.241205 -237.49901) (xy 97.211896 -237.499652)
			(xy 97.211134 -237.499652) (xy 97.18714 -237.499184) (xy 97.139741 -237.491682) (xy 97.0941 -237.476859)
			(xy 97.051339 -237.455077) (xy 97.012513 -237.426875) (xy 96.978575 -237.392947) (xy 96.950363 -237.354127)
			(xy 96.928571 -237.311372) (xy 96.913736 -237.265735) (xy 96.906222 -237.218338) (xy 96.905826 -237.194344)
			(xy 96.905845 -237.183515) (xy 96.90724 -237.161904) (xy 96.90862 -237.151164) (xy 96.910398 -237.13821)
			(xy 96.89719 -237.104174) (xy 96.891094 -237.097316) (xy 96.861535 -237.063866) (xy 96.807504 -236.992801)
			(xy 96.759617 -236.917458) (xy 96.718211 -236.838368) (xy 96.683578 -236.756087) (xy 96.669352 -236.713776)
			(xy 96.665796 -236.702854) (xy 96.63557 -236.671104) (xy 96.62541 -236.66704) (xy 96.603287 -236.657491)
			(xy 96.562118 -236.632459) (xy 96.525388 -236.601275) (xy 96.494007 -236.564713) (xy 96.468754 -236.523678)
			(xy 96.450254 -236.479189) (xy 96.438967 -236.432347) (xy 96.435172 -236.384314) (xy 96.438963 -236.336281)
			(xy 96.450246 -236.289439) (xy 96.468741 -236.244947) (xy 96.49399 -236.203911) (xy 96.525367 -236.167345)
			(xy 96.562094 -236.136158) (xy 96.603262 -236.111122) (xy 96.62541 -236.101636) (xy 96.63557 -236.097572)
			(xy 96.665796 -236.065822) (xy 96.669352 -236.0549) (xy 96.683594 -236.012595) (xy 96.718226 -235.930314)
			(xy 96.759629 -235.851224) (xy 96.807513 -235.775881) (xy 96.861541 -235.704815) (xy 96.891094 -235.67136)
			(xy 96.89719 -235.664502) (xy 96.910398 -235.630466) (xy 96.90862 -235.617512) (xy 96.907265 -235.606833)
			(xy 96.905868 -235.58535) (xy 96.905826 -235.574586) (xy 96.905826 -235.574078) (xy 96.905854 -235.563313)
			(xy 96.907252 -235.54183) (xy 96.90862 -235.531152) (xy 96.910398 -235.518198) (xy 96.89719 -235.484162)
			(xy 96.891094 -235.477304) (xy 96.861535 -235.443854) (xy 96.807505 -235.372788) (xy 96.759619 -235.297445)
			(xy 96.718214 -235.218355) (xy 96.683581 -235.136074) (xy 96.669352 -235.093764) (xy 96.665796 -235.082842)
			(xy 96.63557 -235.051092) (xy 96.62541 -235.047028) (xy 96.60173 -235.036745) (xy 96.55793 -235.009426)
			(xy 96.519342 -234.975138) (xy 96.487061 -234.934855) (xy 96.462007 -234.889721) (xy 96.44489 -234.84102)
			(xy 96.436198 -234.790136) (xy 96.435672 -234.764326) (xy 96.436159 -234.739464) (xy 96.444212 -234.690395)
			(xy 96.46011 -234.64328) (xy 96.483432 -234.599364) (xy 96.513563 -234.559808) (xy 96.549704 -234.525656)
			(xy 96.570038 -234.511342) (xy 96.574864 -234.508294) (xy 96.578928 -234.503722) (xy 96.586294 -234.493562)
			(xy 96.594676 -234.478576) (xy 96.59921 -234.469487) (xy 96.60145 -234.449315) (xy 96.598994 -234.43946)
			(xy 96.59874 -234.438952) (xy 96.59874 -234.438698) (xy 96.592128 -234.417321) (xy 96.579935 -234.374262)
			(xy 96.574356 -234.352592) (xy 96.574356 -234.352338) (xy 96.572578 -234.34548) (xy 96.558608 -234.321096)
			(xy 96.553274 -234.316016) (xy 96.534861 -234.298165) (xy 96.49904 -234.261456) (xy 96.481646 -234.24261)
			(xy 96.474534 -234.234736) (xy 96.44253 -234.220512) (xy 96.41967 -234.221274) (xy 96.409256 -234.226608)
			(xy 96.387722 -234.237009) (xy 96.342225 -234.251728) (xy 96.29499 -234.259177) (xy 96.27108 -234.259628)
			(xy 96.247089 -234.259156) (xy 96.199699 -234.251647) (xy 96.154066 -234.236819) (xy 96.111315 -234.215034)
			(xy 96.072497 -234.186831) (xy 96.038569 -234.152903) (xy 96.010366 -234.114085) (xy 95.988581 -234.071334)
			(xy 95.973753 -234.025701) (xy 95.966244 -233.978311) (xy 95.965772 -233.95432) (xy 95.966258 -233.92949)
			(xy 95.974296 -233.880484) (xy 95.990165 -233.833427) (xy 96.013444 -233.789561) (xy 96.04352 -233.750043)
			(xy 96.079598 -233.715918) (xy 96.099884 -233.70159) (xy 96.100138 -233.701336) (xy 96.105218 -233.69778)
			(xy 96.108774 -233.69397) (xy 96.116394 -233.683556) (xy 96.129602 -233.659426) (xy 96.131634 -233.639106)
			(xy 96.128586 -233.6292) (xy 96.121958 -233.607572) (xy 96.109764 -233.564005) (xy 96.104202 -233.542078)
			(xy 96.102424 -233.534966) (xy 96.0882 -233.510836) (xy 96.08312 -233.50601) (xy 96.064773 -233.48822)
			(xy 96.02908 -233.451636) (xy 96.011746 -233.432858) (xy 96.003703 -233.424998) (xy 95.982902 -233.416522)
			(xy 95.96047 -233.417688) (xy 95.950278 -233.422444) (xy 95.927176 -233.434267) (xy 95.878065 -233.451028)
			(xy 95.826872 -233.459525) (xy 95.800926 -233.460036) (xy 95.776113 -233.459577) (xy 95.727097 -233.451817)
			(xy 95.679898 -233.436485) (xy 95.635679 -233.413958) (xy 95.595528 -233.384791) (xy 95.560435 -233.349702)
			(xy 95.531262 -233.309555) (xy 95.50873 -233.265339) (xy 95.493392 -233.218142) (xy 95.485627 -233.169127)
			(xy 95.485204 -233.144314) (xy 95.485761 -233.117442) (xy 95.494894 -233.06448) (xy 95.512864 -233.013829)
			(xy 95.539153 -232.966954) (xy 95.573001 -232.925207) (xy 95.613429 -232.889796) (xy 95.63608 -232.875328)
			(xy 95.645321 -232.868911) (xy 95.657578 -232.850076) (xy 95.660675 -232.827818) (xy 95.657924 -232.816908)
			(xy 95.651448 -232.795781) (xy 95.639507 -232.75323) (xy 95.634048 -232.731818) (xy 95.634048 -232.731564)
			(xy 95.63227 -232.724706) (xy 95.6183 -232.700322) (xy 95.612966 -232.695242) (xy 95.594754 -232.677571)
			(xy 95.559314 -232.641242) (xy 95.5421 -232.622598) (xy 95.534988 -232.614724) (xy 95.507048 -232.602532)
			(xy 95.496888 -232.602786) (xy 95.47175 -232.617504) (xy 95.41741 -232.638468) (xy 95.360148 -232.649114)
			(xy 95.331026 -232.649776) (xy 95.306229 -232.649292) (xy 95.257245 -232.641541) (xy 95.210075 -232.626225)
			(xy 95.165881 -232.603721) (xy 95.12575 -232.574583) (xy 95.090669 -232.539528) (xy 95.061501 -232.499418)
			(xy 95.038965 -232.455241) (xy 95.023614 -232.408083) (xy 95.015826 -232.359105) (xy 95.015304 -232.334308)
			(xy 95.015846 -232.307417) (xy 95.024959 -232.254413) (xy 95.042923 -232.203721) (xy 95.069218 -232.156806)
			(xy 95.103083 -232.115025) (xy 95.14354 -232.079589) (xy 95.16618 -232.065068) (xy 95.175509 -232.058713)
			(xy 95.187929 -232.039898) (xy 95.191095 -232.017577) (xy 95.188278 -232.006648) (xy 95.177295 -231.970788)
			(xy 95.158239 -231.898242) (xy 95.150178 -231.861614) (xy 95.147638 -231.849676) (xy 95.132906 -231.831134)
			(xy 95.039434 -231.787446) (xy 95.015812 -231.788208) (xy 95.005144 -231.793796) (xy 94.982852 -231.805144)
			(xy 94.935487 -231.821224) (xy 94.886136 -231.829374) (xy 94.861126 -231.829864) (xy 94.85122 -231.829864)
			(xy 94.837504 -231.828594) (xy 94.812279 -231.82613) (xy 94.763094 -231.813912) (xy 94.7166 -231.793741)
			(xy 94.674074 -231.766173) (xy 94.636681 -231.731963) (xy 94.605449 -231.69205) (xy 94.581234 -231.647529)
			(xy 94.5647 -231.599621) (xy 94.556301 -231.549642) (xy 94.555818 -231.524302) (xy 94.556283 -231.500064)
			(xy 94.563941 -231.452196) (xy 94.579066 -231.406139) (xy 94.601276 -231.36305) (xy 94.630016 -231.324012)
			(xy 94.664561 -231.290003) (xy 94.704046 -231.26188) (xy 94.747478 -231.240348) (xy 94.793766 -231.225947)
			(xy 94.817692 -231.222042) (xy 94.829884 -231.220264) (xy 94.861126 -231.21874) (xy 94.886093 -231.219255)
			(xy 94.935358 -231.227411) (xy 94.982641 -231.243468) (xy 95.00489 -231.254808) (xy 95.005398 -231.254808)
			(xy 95.005398 -231.255062) (xy 95.016114 -231.260003) (xy 95.039677 -231.260522) (xy 95.05061 -231.256078)
			(xy 95.132906 -231.21747) (xy 95.147638 -231.198928) (xy 95.150178 -231.18699) (xy 95.158167 -231.150363)
			(xy 95.1771 -231.077817) (xy 95.188024 -231.041956) (xy 95.190845 -231.031047) (xy 95.187784 -231.008753)
			(xy 95.175464 -230.989922) (xy 95.16618 -230.983536) (xy 95.143547 -230.969044) (xy 95.103126 -230.93363)
			(xy 95.069281 -230.891886) (xy 95.042988 -230.845017) (xy 95.025006 -230.794375) (xy 95.015853 -230.74142)
			(xy 95.015304 -230.71455) (xy 95.015795 -230.689744) (xy 95.023563 -230.640743) (xy 95.038901 -230.593561)
			(xy 95.061431 -230.549359) (xy 95.090597 -230.509225) (xy 95.125683 -230.474148) (xy 95.165824 -230.444991)
			(xy 95.210031 -230.422472) (xy 95.257217 -230.407145) (xy 95.30622 -230.399389) (xy 95.331026 -230.398828)
			(xy 95.356971 -230.399356) (xy 95.408161 -230.407852) (xy 95.45727 -230.424611) (xy 95.480378 -230.43642)
			(xy 95.490554 -230.441261) (xy 95.513028 -230.442482) (xy 95.533853 -230.433947) (xy 95.541846 -230.426006)
			(xy 95.559123 -230.407297) (xy 95.594689 -230.370841) (xy 95.612966 -230.353108) (xy 95.618046 -230.348282)
			(xy 95.628714 -230.329994) (xy 95.630516 -230.326811) (xy 95.633318 -230.320055) (xy 95.634302 -230.316532)
			(xy 95.639767 -230.295184) (xy 95.651705 -230.25276) (xy 95.658178 -230.231696) (xy 95.660856 -230.220802)
			(xy 95.657622 -230.19863) (xy 95.64531 -230.179908) (xy 95.63608 -230.17353) (xy 95.61343 -230.159025)
			(xy 95.572982 -230.123578) (xy 95.539123 -230.081792) (xy 95.512829 -230.034875) (xy 95.494861 -229.984184)
			(xy 95.485737 -229.931181) (xy 95.485204 -229.90429) (xy 95.485763 -229.877419) (xy 95.494899 -229.824459)
			(xy 95.512872 -229.773812) (xy 95.539163 -229.726939) (xy 95.573011 -229.685196) (xy 95.61344 -229.649788)
			(xy 95.63608 -229.635304) (xy 95.645317 -229.628886) (xy 95.657565 -229.610052) (xy 95.660653 -229.587799)
			(xy 95.657924 -229.576884) (xy 95.647005 -229.541021) (xy 95.628073 -229.468476) (xy 95.620078 -229.43185)
			(xy 95.617538 -229.419912) (xy 95.602806 -229.40137) (xy 95.52051 -229.362762) (xy 95.496126 -229.363778)
			(xy 95.485458 -229.369874) (xy 95.461722 -229.382576) (xy 95.410992 -229.400586) (xy 95.357942 -229.409725)
			(xy 95.331026 -229.41026) (xy 95.30621 -229.4098) (xy 95.257189 -229.40204) (xy 95.209985 -229.386706)
			(xy 95.165762 -229.364176) (xy 95.125608 -229.335006) (xy 95.090511 -229.299912) (xy 95.061337 -229.25976)
			(xy 95.038804 -229.215539) (xy 95.023466 -229.168336) (xy 95.015702 -229.119316) (xy 95.015702 -229.069684)
			(xy 95.023466 -229.020664) (xy 95.038804 -228.973461) (xy 95.061337 -228.92924) (xy 95.090511 -228.889088)
			(xy 95.125608 -228.853994) (xy 95.165762 -228.824824) (xy 95.209985 -228.802294) (xy 95.257189 -228.78696)
			(xy 95.30621 -228.7792) (xy 95.331026 -228.778816) (xy 95.357941 -228.779364) (xy 95.410989 -228.788502)
			(xy 95.461718 -228.806509) (xy 95.485458 -228.819202) (xy 95.496126 -228.825298) (xy 95.52051 -228.826314)
			(xy 95.591884 -228.79304) (xy 95.602272 -228.787485) (xy 95.61695 -228.769092) (xy 95.620078 -228.757734)
			(xy 95.620078 -228.75748) (xy 95.628059 -228.720725) (xy 95.64699 -228.647925) (xy 95.657924 -228.611938)
			(xy 95.660741 -228.601031) (xy 95.657674 -228.578743) (xy 95.645352 -228.559918) (xy 95.63608 -228.553518)
			(xy 95.613447 -228.539026) (xy 95.573029 -228.503611) (xy 95.539186 -228.461867) (xy 95.512896 -228.414998)
			(xy 95.494916 -228.364355) (xy 95.485767 -228.311401) (xy 95.485204 -228.284532) (xy 95.485767 -228.257664)
			(xy 95.494912 -228.20471) (xy 95.512891 -228.154069) (xy 95.539186 -228.107205) (xy 95.573037 -228.065469)
			(xy 95.613467 -228.030069) (xy 95.63608 -228.015546) (xy 95.645324 -228.009129) (xy 95.657588 -227.990294)
			(xy 95.660692 -227.968033) (xy 95.657924 -227.957126) (xy 95.646995 -227.921138) (xy 95.628062 -227.848338)
			(xy 95.620078 -227.811584) (xy 95.620078 -227.81133) (xy 95.617039 -227.799923) (xy 95.602346 -227.781486)
			(xy 95.591884 -227.776024) (xy 95.52051 -227.74275) (xy 95.496126 -227.743766) (xy 95.485458 -227.749862)
			(xy 95.461722 -227.762565) (xy 95.410992 -227.780575) (xy 95.357942 -227.789714) (xy 95.331026 -227.790248)
			(xy 95.306211 -227.789789) (xy 95.257192 -227.782028) (xy 95.20999 -227.766695) (xy 95.165768 -227.744166)
			(xy 95.125615 -227.714996) (xy 95.09052 -227.679904) (xy 95.061348 -227.639754) (xy 95.038815 -227.595534)
			(xy 95.023478 -227.548334) (xy 95.015714 -227.499315) (xy 95.015714 -227.449685) (xy 95.023478 -227.400666)
			(xy 95.038815 -227.353466) (xy 95.061348 -227.309246) (xy 95.09052 -227.269096) (xy 95.125615 -227.234004)
			(xy 95.165768 -227.204834) (xy 95.20999 -227.182305) (xy 95.257192 -227.166972) (xy 95.306211 -227.159211)
			(xy 95.331026 -227.158804) (xy 95.35794 -227.159352) (xy 95.410988 -227.168493) (xy 95.461714 -227.186504)
			(xy 95.485458 -227.19919) (xy 95.496126 -227.205286) (xy 95.52051 -227.206048) (xy 95.602806 -227.167694)
			(xy 95.617538 -227.149152) (xy 95.620078 -227.137468) (xy 95.624142 -227.11918) (xy 95.625412 -227.113846)
			(xy 95.625412 -227.108004) (xy 95.624925 -227.097995) (xy 95.617266 -227.0795) (xy 95.603114 -227.065343)
			(xy 95.584621 -227.057679) (xy 95.574612 -227.057204) (xy 93.151198 -227.057204) (xy 93.141363 -227.057746)
			(xy 93.123211 -227.065341) (xy 93.115892 -227.071936) (xy 93.021404 -227.166424) (xy 93.014246 -227.174298)
			(xy 93.00653 -227.194103) (xy 93.007513 -227.215335) (xy 93.011752 -227.225098) (xy 93.025758 -227.254236)
			(xy 93.047726 -227.315042) (xy 93.062531 -227.377977) (xy 93.069977 -227.4422) (xy 93.070426 -227.474526)
			(xy 94.074737 -227.474526) (xy 94.078832 -227.423798) (xy 94.091011 -227.374384) (xy 94.110959 -227.327564)
			(xy 94.13816 -227.28455) (xy 94.171908 -227.246456) (xy 94.21133 -227.214269) (xy 94.255404 -227.188823)
			(xy 94.30299 -227.170776) (xy 94.352854 -227.160596) (xy 94.403706 -227.158547) (xy 94.454227 -227.164681)
			(xy 94.503111 -227.178841) (xy 94.54909 -227.200658) (xy 94.590974 -227.229568) (xy 94.627678 -227.264823)
			(xy 94.658251 -227.305509) (xy 94.681902 -227.350572) (xy 94.698018 -227.398846) (xy 94.706182 -227.44908)
			(xy 94.706694 -227.474526) (xy 94.706182 -227.499972) (xy 94.698018 -227.550206) (xy 94.681902 -227.59848)
			(xy 94.658251 -227.643543) (xy 94.627678 -227.684229) (xy 94.590974 -227.719484) (xy 94.54909 -227.748394)
			(xy 94.503111 -227.770211) (xy 94.454227 -227.784371) (xy 94.403706 -227.790505) (xy 94.352854 -227.788456)
			(xy 94.30299 -227.778276) (xy 94.255404 -227.760229) (xy 94.21133 -227.734783) (xy 94.171908 -227.702596)
			(xy 94.13816 -227.664502) (xy 94.110959 -227.621488) (xy 94.091011 -227.574668) (xy 94.078832 -227.525254)
			(xy 94.074737 -227.474526) (xy 93.070426 -227.474526) (xy 93.069839 -227.511331) (xy 93.060178 -227.584306)
			(xy 93.041026 -227.655382) (xy 93.012715 -227.723331) (xy 92.994734 -227.75545) (xy 92.95003 -227.832412)
			(xy 92.944241 -227.843625) (xy 92.943298 -227.868813) (xy 92.948252 -227.880418) (xy 92.984574 -227.954078)
			(xy 92.990627 -227.965038) (xy 93.010878 -227.979709) (xy 93.023182 -227.982018) (xy 93.04719 -227.985862)
			(xy 93.093661 -228.000156) (xy 93.137282 -228.021627) (xy 93.176955 -228.049733) (xy 93.211677 -228.083765)
			(xy 93.240574 -228.122865) (xy 93.262917 -228.166047) (xy 93.278142 -228.212221) (xy 93.285866 -228.260223)
			(xy 93.286326 -228.284532) (xy 93.604837 -228.284532) (xy 93.608932 -228.233804) (xy 93.621111 -228.18439)
			(xy 93.641059 -228.13757) (xy 93.66826 -228.094556) (xy 93.702008 -228.056462) (xy 93.74143 -228.024275)
			(xy 93.785504 -227.998829) (xy 93.83309 -227.980782) (xy 93.882954 -227.970602) (xy 93.933806 -227.968553)
			(xy 93.984327 -227.974687) (xy 94.033211 -227.988847) (xy 94.07919 -228.010664) (xy 94.121074 -228.039574)
			(xy 94.157778 -228.074829) (xy 94.188351 -228.115515) (xy 94.212002 -228.160578) (xy 94.228118 -228.208852)
			(xy 94.236282 -228.259086) (xy 94.236794 -228.284532) (xy 94.555322 -228.284532) (xy 94.559282 -228.235478)
			(xy 94.571059 -228.187694) (xy 94.59035 -228.142418) (xy 94.616653 -228.100822) (xy 94.649288 -228.063985)
			(xy 94.687409 -228.03286) (xy 94.73003 -228.008253) (xy 94.776046 -227.990801) (xy 94.824265 -227.980957)
			(xy 94.87344 -227.978976) (xy 94.922295 -227.984908) (xy 94.969566 -227.9986) (xy 95.014028 -228.019698)
			(xy 95.054531 -228.047654) (xy 95.090024 -228.081746) (xy 95.119589 -228.12109) (xy 95.14246 -228.164667)
			(xy 95.158044 -228.211348) (xy 95.165939 -228.259925) (xy 95.166434 -228.284532) (xy 95.165939 -228.309139)
			(xy 95.158044 -228.357716) (xy 95.14246 -228.404397) (xy 95.119589 -228.447974) (xy 95.090024 -228.487318)
			(xy 95.054531 -228.52141) (xy 95.014028 -228.549366) (xy 94.969566 -228.570464) (xy 94.922295 -228.584156)
			(xy 94.87344 -228.590088) (xy 94.824265 -228.588107) (xy 94.776046 -228.578263) (xy 94.73003 -228.560811)
			(xy 94.687409 -228.536204) (xy 94.649288 -228.505079) (xy 94.616653 -228.468242) (xy 94.59035 -228.426646)
			(xy 94.571059 -228.38137) (xy 94.559282 -228.333586) (xy 94.555322 -228.284532) (xy 94.236794 -228.284532)
			(xy 94.236282 -228.309978) (xy 94.228118 -228.360212) (xy 94.212002 -228.408486) (xy 94.188351 -228.453549)
			(xy 94.157778 -228.494235) (xy 94.121074 -228.52949) (xy 94.07919 -228.5584) (xy 94.033211 -228.580217)
			(xy 93.984327 -228.594377) (xy 93.933806 -228.600511) (xy 93.882954 -228.598462) (xy 93.83309 -228.588282)
			(xy 93.785504 -228.570235) (xy 93.74143 -228.544789) (xy 93.702008 -228.512602) (xy 93.66826 -228.474508)
			(xy 93.641059 -228.431494) (xy 93.621111 -228.384674) (xy 93.608932 -228.33526) (xy 93.604837 -228.284532)
			(xy 93.286326 -228.284532) (xy 93.285863 -228.309141) (xy 93.277977 -228.357721) (xy 93.262398 -228.404408)
			(xy 93.239531 -228.447989) (xy 93.209967 -228.487337) (xy 93.174473 -228.521432) (xy 93.133968 -228.54939)
			(xy 93.089502 -228.570487) (xy 93.042227 -228.584176) (xy 93.017848 -228.587554) (xy 93.003878 -228.589332)
			(xy 92.982288 -228.605842) (xy 92.9386 -228.710998) (xy 92.94241 -228.73843) (xy 92.951046 -228.749098)
			(xy 92.975518 -228.781578) (xy 93.015809 -228.852217) (xy 93.03131 -228.889814) (xy 93.03639 -228.902768)
			(xy 93.05798 -228.919786) (xy 93.171772 -228.934772) (xy 93.197172 -228.92385) (xy 93.205554 -228.912928)
			(xy 93.220056 -228.894097) (xy 93.253908 -228.860737) (xy 93.292521 -228.833025) (xy 93.334961 -228.81163)
			(xy 93.380203 -228.797069) (xy 93.427154 -228.789693) (xy 93.450918 -228.78923) (xy 93.474909 -228.789678)
			(xy 93.5223 -228.797187) (xy 93.567933 -228.812017) (xy 93.610684 -228.833804) (xy 93.6495 -228.862011)
			(xy 93.683426 -228.895943) (xy 93.711625 -228.934764) (xy 93.733404 -228.977519) (xy 93.748226 -229.023154)
			(xy 93.755727 -229.070547) (xy 93.756226 -229.094538) (xy 94.074737 -229.094538) (xy 94.078832 -229.04381)
			(xy 94.091011 -228.994396) (xy 94.110959 -228.947576) (xy 94.13816 -228.904562) (xy 94.171908 -228.866468)
			(xy 94.21133 -228.834281) (xy 94.255404 -228.808835) (xy 94.30299 -228.790788) (xy 94.352854 -228.780608)
			(xy 94.403706 -228.778559) (xy 94.454227 -228.784693) (xy 94.503111 -228.798853) (xy 94.54909 -228.82067)
			(xy 94.590974 -228.84958) (xy 94.627678 -228.884835) (xy 94.658251 -228.925521) (xy 94.681902 -228.970584)
			(xy 94.698018 -229.018858) (xy 94.706182 -229.069092) (xy 94.706694 -229.094538) (xy 94.706182 -229.119984)
			(xy 94.698018 -229.170218) (xy 94.681902 -229.218492) (xy 94.658251 -229.263555) (xy 94.627678 -229.304241)
			(xy 94.590974 -229.339496) (xy 94.54909 -229.368406) (xy 94.503111 -229.390223) (xy 94.454227 -229.404383)
			(xy 94.403706 -229.410517) (xy 94.352854 -229.408468) (xy 94.30299 -229.398288) (xy 94.255404 -229.380241)
			(xy 94.21133 -229.354795) (xy 94.171908 -229.322608) (xy 94.13816 -229.284514) (xy 94.110959 -229.2415)
			(xy 94.091011 -229.19468) (xy 94.078832 -229.145266) (xy 94.074737 -229.094538) (xy 93.756226 -229.094538)
			(xy 93.755758 -229.118775) (xy 93.748095 -229.166641) (xy 93.732968 -229.212695) (xy 93.710756 -229.255781)
			(xy 93.682017 -229.294818) (xy 93.647473 -229.328826) (xy 93.607991 -229.35695) (xy 93.564562 -229.378484)
			(xy 93.518276 -229.392889) (xy 93.494352 -229.396798) (xy 93.481906 -229.398576) (xy 93.450918 -229.4001)
			(xy 93.427135 -229.399649) (xy 93.380144 -229.392282) (xy 93.334862 -229.377723) (xy 93.292382 -229.356325)
			(xy 93.25373 -229.328603) (xy 93.21984 -229.295228) (xy 93.2053 -229.276402) (xy 93.196918 -229.265226)
			(xy 93.171518 -229.254304) (xy 93.05798 -229.26929) (xy 93.03639 -229.286308) (xy 93.03131 -229.299262)
			(xy 93.023437 -229.318897) (xy 93.005128 -229.357037) (xy 92.994734 -229.375462) (xy 92.84589 -229.631748)
			(xy 92.826206 -229.664197) (xy 92.779436 -229.723966) (xy 92.752672 -229.750874) (xy 92.75191 -229.751636)
			(xy 92.747084 -229.756716) (xy 92.73286 -229.780592) (xy 92.731082 -229.787704) (xy 92.720978 -229.824622)
			(xy 92.692042 -229.895484) (xy 92.68714 -229.90429) (xy 93.604837 -229.90429) (xy 93.608932 -229.853562)
			(xy 93.621111 -229.804148) (xy 93.641059 -229.757328) (xy 93.66826 -229.714314) (xy 93.702008 -229.67622)
			(xy 93.74143 -229.644033) (xy 93.785504 -229.618587) (xy 93.83309 -229.60054) (xy 93.882954 -229.59036)
			(xy 93.933806 -229.588311) (xy 93.984327 -229.594445) (xy 94.033211 -229.608605) (xy 94.07919 -229.630422)
			(xy 94.121074 -229.659332) (xy 94.157778 -229.694587) (xy 94.188351 -229.735273) (xy 94.212002 -229.780336)
			(xy 94.228118 -229.82861) (xy 94.236282 -229.878844) (xy 94.236794 -229.90429) (xy 94.555322 -229.90429)
			(xy 94.559282 -229.855236) (xy 94.571059 -229.807452) (xy 94.59035 -229.762176) (xy 94.616653 -229.72058)
			(xy 94.649288 -229.683743) (xy 94.687409 -229.652618) (xy 94.73003 -229.628011) (xy 94.776046 -229.610559)
			(xy 94.824265 -229.600715) (xy 94.87344 -229.598734) (xy 94.922295 -229.604666) (xy 94.969566 -229.618358)
			(xy 95.014028 -229.639456) (xy 95.054531 -229.667412) (xy 95.090024 -229.701504) (xy 95.119589 -229.740848)
			(xy 95.14246 -229.784425) (xy 95.158044 -229.831106) (xy 95.165939 -229.879683) (xy 95.166434 -229.90429)
			(xy 95.165939 -229.928897) (xy 95.158044 -229.977474) (xy 95.14246 -230.024155) (xy 95.119589 -230.067732)
			(xy 95.090024 -230.107076) (xy 95.054531 -230.141168) (xy 95.014028 -230.169124) (xy 94.969566 -230.190222)
			(xy 94.922295 -230.203914) (xy 94.87344 -230.209846) (xy 94.824265 -230.207865) (xy 94.776046 -230.198021)
			(xy 94.73003 -230.180569) (xy 94.687409 -230.155962) (xy 94.649288 -230.124837) (xy 94.616653 -230.088)
			(xy 94.59035 -230.046404) (xy 94.571059 -230.001128) (xy 94.559282 -229.953344) (xy 94.555322 -229.90429)
			(xy 94.236794 -229.90429) (xy 94.236282 -229.929736) (xy 94.228118 -229.97997) (xy 94.212002 -230.028244)
			(xy 94.188351 -230.073307) (xy 94.157778 -230.113993) (xy 94.121074 -230.149248) (xy 94.07919 -230.178158)
			(xy 94.033211 -230.199975) (xy 93.984327 -230.214135) (xy 93.933806 -230.220269) (xy 93.882954 -230.21822)
			(xy 93.83309 -230.20804) (xy 93.785504 -230.189993) (xy 93.74143 -230.164547) (xy 93.702008 -230.13236)
			(xy 93.66826 -230.094266) (xy 93.641059 -230.051252) (xy 93.621111 -230.004432) (xy 93.608932 -229.955018)
			(xy 93.604837 -229.90429) (xy 92.68714 -229.90429) (xy 92.673424 -229.928928) (xy 92.593922 -230.065834)
			(xy 92.59078 -230.071711) (xy 92.587306 -230.084574) (xy 92.587064 -230.091234) (xy 92.587064 -230.117904)
			(xy 92.587411 -230.126595) (xy 92.593259 -230.142962) (xy 92.598494 -230.149908) (xy 92.604082 -230.156766)
			(xy 92.618814 -230.16591) (xy 92.62745 -230.167688) (xy 92.661067 -230.175354) (xy 92.726239 -230.197875)
			(xy 92.788144 -230.228244) (xy 92.845842 -230.265998) (xy 92.898457 -230.310564) (xy 92.945189 -230.361266)
			(xy 92.985328 -230.417331) (xy 93.018264 -230.47791) (xy 93.03131 -230.509826) (xy 93.03639 -230.52278)
			(xy 93.058234 -230.539798) (xy 93.171772 -230.554784) (xy 93.197172 -230.543862) (xy 93.205554 -230.532686)
			(xy 93.220058 -230.513857) (xy 93.253914 -230.4805) (xy 93.292527 -230.452789) (xy 93.334965 -230.431391)
			(xy 93.380205 -230.416822) (xy 93.427154 -230.409435) (xy 93.450918 -230.408988) (xy 93.474908 -230.40946)
			(xy 93.522298 -230.416968) (xy 93.56793 -230.431797) (xy 93.61068 -230.453582) (xy 93.649497 -230.481785)
			(xy 93.683424 -230.515714) (xy 93.711626 -230.554531) (xy 93.733408 -230.597283) (xy 93.748235 -230.642915)
			(xy 93.755741 -230.690306) (xy 93.756226 -230.714296) (xy 93.756226 -230.71455) (xy 94.074737 -230.71455)
			(xy 94.078832 -230.663822) (xy 94.091011 -230.614408) (xy 94.110959 -230.567588) (xy 94.13816 -230.524574)
			(xy 94.171908 -230.48648) (xy 94.21133 -230.454293) (xy 94.255404 -230.428847) (xy 94.30299 -230.4108)
			(xy 94.352854 -230.40062) (xy 94.403706 -230.398571) (xy 94.454227 -230.404705) (xy 94.503111 -230.418865)
			(xy 94.54909 -230.440682) (xy 94.590974 -230.469592) (xy 94.627678 -230.504847) (xy 94.658251 -230.545533)
			(xy 94.681902 -230.590596) (xy 94.698018 -230.63887) (xy 94.706182 -230.689104) (xy 94.706694 -230.71455)
			(xy 94.706182 -230.739996) (xy 94.698018 -230.79023) (xy 94.681902 -230.838504) (xy 94.658251 -230.883567)
			(xy 94.627678 -230.924253) (xy 94.590974 -230.959508) (xy 94.54909 -230.988418) (xy 94.503111 -231.010235)
			(xy 94.454227 -231.024395) (xy 94.403706 -231.030529) (xy 94.352854 -231.02848) (xy 94.30299 -231.0183)
			(xy 94.255404 -231.000253) (xy 94.21133 -230.974807) (xy 94.171908 -230.94262) (xy 94.13816 -230.904526)
			(xy 94.110959 -230.861512) (xy 94.091011 -230.814692) (xy 94.078832 -230.765278) (xy 94.074737 -230.71455)
			(xy 93.756226 -230.71455) (xy 93.755752 -230.738539) (xy 93.748239 -230.785926) (xy 93.733408 -230.831554)
			(xy 93.711622 -230.874301) (xy 93.683418 -230.913115) (xy 93.64949 -230.947039) (xy 93.610674 -230.975239)
			(xy 93.567925 -230.99702) (xy 93.522295 -231.011847) (xy 93.474907 -231.019354) (xy 93.450918 -231.019858)
			(xy 93.427156 -231.019386) (xy 93.380209 -231.011992) (xy 93.334971 -230.997425) (xy 93.292531 -230.976036)
			(xy 93.253909 -230.94834) (xy 93.220037 -230.915004) (xy 93.205554 -230.89616) (xy 93.197172 -230.885238)
			(xy 93.171772 -230.874316) (xy 93.05798 -230.889302) (xy 93.03639 -230.90632) (xy 93.03131 -230.919274)
			(xy 93.023436 -230.938909) (xy 93.005127 -230.977049) (xy 92.994734 -230.995474) (xy 92.950284 -231.07142)
			(xy 92.950284 -231.071928) (xy 92.94368 -231.08285) (xy 92.942664 -231.10825) (xy 92.984574 -231.193848)
			(xy 92.990623 -231.204813) (xy 93.010874 -231.219492) (xy 93.023182 -231.221788) (xy 93.047191 -231.225632)
			(xy 93.093664 -231.239926) (xy 93.137288 -231.261396) (xy 93.176963 -231.289502) (xy 93.211688 -231.323533)
			(xy 93.240589 -231.362633) (xy 93.262936 -231.405814) (xy 93.278165 -231.451989) (xy 93.285893 -231.499992)
			(xy 93.286326 -231.524302) (xy 93.604837 -231.524302) (xy 93.608932 -231.473574) (xy 93.621111 -231.42416)
			(xy 93.641059 -231.37734) (xy 93.66826 -231.334326) (xy 93.702008 -231.296232) (xy 93.74143 -231.264045)
			(xy 93.785504 -231.238599) (xy 93.83309 -231.220552) (xy 93.882954 -231.210372) (xy 93.933806 -231.208323)
			(xy 93.984327 -231.214457) (xy 94.033211 -231.228617) (xy 94.07919 -231.250434) (xy 94.121074 -231.279344)
			(xy 94.157778 -231.314599) (xy 94.188351 -231.355285) (xy 94.212002 -231.400348) (xy 94.228118 -231.448622)
			(xy 94.236282 -231.498856) (xy 94.236794 -231.524302) (xy 94.236282 -231.549748) (xy 94.228118 -231.599982)
			(xy 94.212002 -231.648256) (xy 94.188351 -231.693319) (xy 94.157778 -231.734005) (xy 94.121074 -231.76926)
			(xy 94.07919 -231.79817) (xy 94.033211 -231.819987) (xy 93.984327 -231.834147) (xy 93.933806 -231.840281)
			(xy 93.882954 -231.838232) (xy 93.83309 -231.828052) (xy 93.785504 -231.810005) (xy 93.74143 -231.784559)
			(xy 93.702008 -231.752372) (xy 93.66826 -231.714278) (xy 93.641059 -231.671264) (xy 93.621111 -231.624444)
			(xy 93.608932 -231.57503) (xy 93.604837 -231.524302) (xy 93.286326 -231.524302) (xy 93.285857 -231.548907)
			(xy 93.277962 -231.59748) (xy 93.262377 -231.644156) (xy 93.239506 -231.687728) (xy 93.209941 -231.727067)
			(xy 93.174447 -231.761153) (xy 93.133946 -231.789103) (xy 93.089484 -231.810194) (xy 93.042215 -231.823879)
			(xy 93.017848 -231.827324) (xy 93.003878 -231.829102) (xy 92.982288 -231.845612) (xy 92.943934 -231.938068)
			(xy 92.940844 -231.946521) (xy 92.940171 -231.964496) (xy 92.945741 -231.981598) (xy 92.951046 -231.988868)
			(xy 92.969874 -232.013542) (xy 93.002553 -232.066312) (xy 93.029194 -232.122374) (xy 93.049468 -232.181039)
			(xy 93.063128 -232.241586) (xy 93.070005 -232.303273) (xy 93.070426 -232.334308) (xy 94.074737 -232.334308)
			(xy 94.078832 -232.28358) (xy 94.091011 -232.234166) (xy 94.110959 -232.187346) (xy 94.13816 -232.144332)
			(xy 94.171908 -232.106238) (xy 94.21133 -232.074051) (xy 94.255404 -232.048605) (xy 94.30299 -232.030558)
			(xy 94.352854 -232.020378) (xy 94.403706 -232.018329) (xy 94.454227 -232.024463) (xy 94.503111 -232.038623)
			(xy 94.54909 -232.06044) (xy 94.590974 -232.08935) (xy 94.627678 -232.124605) (xy 94.658251 -232.165291)
			(xy 94.681902 -232.210354) (xy 94.698018 -232.258628) (xy 94.706182 -232.308862) (xy 94.706694 -232.334308)
			(xy 94.706182 -232.359754) (xy 94.698018 -232.409988) (xy 94.681902 -232.458262) (xy 94.658251 -232.503325)
			(xy 94.627678 -232.544011) (xy 94.590974 -232.579266) (xy 94.54909 -232.608176) (xy 94.503111 -232.629993)
			(xy 94.454227 -232.644153) (xy 94.403706 -232.650287) (xy 94.352854 -232.648238) (xy 94.30299 -232.638058)
			(xy 94.255404 -232.620011) (xy 94.21133 -232.594565) (xy 94.171908 -232.562378) (xy 94.13816 -232.524284)
			(xy 94.110959 -232.48127) (xy 94.091011 -232.43445) (xy 94.078832 -232.385036) (xy 94.074737 -232.334308)
			(xy 93.070426 -232.334308) (xy 93.06984 -232.371114) (xy 93.060181 -232.444089) (xy 93.041032 -232.515166)
			(xy 93.012722 -232.583116) (xy 92.994734 -232.615232) (xy 92.95003 -232.692194) (xy 92.944236 -232.703407)
			(xy 92.943285 -232.728599) (xy 92.948252 -232.7402) (xy 92.984574 -232.81386) (xy 92.990625 -232.824823)
			(xy 93.010875 -232.839499) (xy 93.023182 -232.8418) (xy 93.047191 -232.845644) (xy 93.093663 -232.859938)
			(xy 93.137286 -232.881409) (xy 93.17696 -232.909514) (xy 93.211684 -232.943546) (xy 93.240583 -232.982646)
			(xy 93.262928 -233.025827) (xy 93.278156 -233.072001) (xy 93.285882 -233.120004) (xy 93.286326 -233.144314)
			(xy 93.604837 -233.144314) (xy 93.608932 -233.093586) (xy 93.621111 -233.044172) (xy 93.641059 -232.997352)
			(xy 93.66826 -232.954338) (xy 93.702008 -232.916244) (xy 93.74143 -232.884057) (xy 93.785504 -232.858611)
			(xy 93.83309 -232.840564) (xy 93.882954 -232.830384) (xy 93.933806 -232.828335) (xy 93.984327 -232.834469)
			(xy 94.033211 -232.848629) (xy 94.07919 -232.870446) (xy 94.121074 -232.899356) (xy 94.157778 -232.934611)
			(xy 94.188351 -232.975297) (xy 94.212002 -233.02036) (xy 94.228118 -233.068634) (xy 94.236282 -233.118868)
			(xy 94.236794 -233.144314) (xy 94.555322 -233.144314) (xy 94.559282 -233.09526) (xy 94.571059 -233.047476)
			(xy 94.59035 -233.0022) (xy 94.616653 -232.960604) (xy 94.649288 -232.923767) (xy 94.687409 -232.892642)
			(xy 94.73003 -232.868035) (xy 94.776046 -232.850583) (xy 94.824265 -232.840739) (xy 94.87344 -232.838758)
			(xy 94.922295 -232.84469) (xy 94.969566 -232.858382) (xy 95.014028 -232.87948) (xy 95.054531 -232.907436)
			(xy 95.090024 -232.941528) (xy 95.119589 -232.980872) (xy 95.14246 -233.024449) (xy 95.158044 -233.07113)
			(xy 95.165939 -233.119707) (xy 95.166434 -233.144314) (xy 95.165939 -233.168921) (xy 95.158044 -233.217498)
			(xy 95.14246 -233.264179) (xy 95.119589 -233.307756) (xy 95.090024 -233.3471) (xy 95.054531 -233.381192)
			(xy 95.014028 -233.409148) (xy 94.969566 -233.430246) (xy 94.922295 -233.443938) (xy 94.87344 -233.44987)
			(xy 94.824265 -233.447889) (xy 94.776046 -233.438045) (xy 94.73003 -233.420593) (xy 94.687409 -233.395986)
			(xy 94.649288 -233.364861) (xy 94.616653 -233.328024) (xy 94.59035 -233.286428) (xy 94.571059 -233.241152)
			(xy 94.559282 -233.193368) (xy 94.555322 -233.144314) (xy 94.236794 -233.144314) (xy 94.236282 -233.16976)
			(xy 94.228118 -233.219994) (xy 94.212002 -233.268268) (xy 94.188351 -233.313331) (xy 94.157778 -233.354017)
			(xy 94.121074 -233.389272) (xy 94.07919 -233.418182) (xy 94.033211 -233.439999) (xy 93.984327 -233.454159)
			(xy 93.933806 -233.460293) (xy 93.882954 -233.458244) (xy 93.83309 -233.448064) (xy 93.785504 -233.430017)
			(xy 93.74143 -233.404571) (xy 93.702008 -233.372384) (xy 93.66826 -233.33429) (xy 93.641059 -233.291276)
			(xy 93.621111 -233.244456) (xy 93.608932 -233.195042) (xy 93.604837 -233.144314) (xy 93.286326 -233.144314)
			(xy 93.285864 -233.168923) (xy 93.27798 -233.217506) (xy 93.262403 -233.264195) (xy 93.239537 -233.307779)
			(xy 93.209973 -233.34713) (xy 93.174479 -233.381227) (xy 93.133973 -233.409187) (xy 93.089506 -233.430286)
			(xy 93.04223 -233.443976) (xy 93.017848 -233.447336) (xy 93.003878 -233.449114) (xy 92.982288 -233.465624)
			(xy 92.9386 -233.57078) (xy 92.94241 -233.598212) (xy 92.951046 -233.60888) (xy 92.975519 -233.64136)
			(xy 93.015812 -233.711997) (xy 93.03131 -233.749596) (xy 93.03639 -233.76255) (xy 93.05798 -233.779568)
			(xy 93.171772 -233.794554) (xy 93.197172 -233.783632) (xy 93.205554 -233.77271) (xy 93.220056 -233.753879)
			(xy 93.25391 -233.720522) (xy 93.292523 -233.692812) (xy 93.334962 -233.671418) (xy 93.380204 -233.656858)
			(xy 93.427155 -233.649482) (xy 93.450918 -233.649012) (xy 93.47491 -233.64946) (xy 93.522302 -233.656969)
			(xy 93.567936 -233.671799) (xy 93.610688 -233.693586) (xy 93.649506 -233.721792) (xy 93.683433 -233.755723)
			(xy 93.711634 -233.794545) (xy 93.733416 -233.837299) (xy 93.74824 -233.882935) (xy 93.755743 -233.930328)
			(xy 93.756226 -233.95432) (xy 94.074737 -233.95432) (xy 94.078832 -233.903592) (xy 94.091011 -233.854178)
			(xy 94.110959 -233.807358) (xy 94.13816 -233.764344) (xy 94.171908 -233.72625) (xy 94.21133 -233.694063)
			(xy 94.255404 -233.668617) (xy 94.30299 -233.65057) (xy 94.352854 -233.64039) (xy 94.403706 -233.638341)
			(xy 94.454227 -233.644475) (xy 94.503111 -233.658635) (xy 94.54909 -233.680452) (xy 94.590974 -233.709362)
			(xy 94.627678 -233.744617) (xy 94.658251 -233.785303) (xy 94.681902 -233.830366) (xy 94.698018 -233.87864)
			(xy 94.706182 -233.928874) (xy 94.706694 -233.95432) (xy 95.014791 -233.95432) (xy 95.018886 -233.903592)
			(xy 95.031065 -233.854178) (xy 95.051013 -233.807358) (xy 95.078214 -233.764344) (xy 95.111962 -233.72625)
			(xy 95.151384 -233.694063) (xy 95.195458 -233.668617) (xy 95.243044 -233.65057) (xy 95.292908 -233.64039)
			(xy 95.34376 -233.638341) (xy 95.394281 -233.644475) (xy 95.443165 -233.658635) (xy 95.489144 -233.680452)
			(xy 95.531028 -233.709362) (xy 95.567732 -233.744617) (xy 95.598305 -233.785303) (xy 95.621956 -233.830366)
			(xy 95.638072 -233.87864) (xy 95.646236 -233.928874) (xy 95.646748 -233.95432) (xy 95.646236 -233.979766)
			(xy 95.638072 -234.03) (xy 95.621956 -234.078274) (xy 95.598305 -234.123337) (xy 95.567732 -234.164023)
			(xy 95.531028 -234.199278) (xy 95.489144 -234.228188) (xy 95.443165 -234.250005) (xy 95.394281 -234.264165)
			(xy 95.34376 -234.270299) (xy 95.292908 -234.26825) (xy 95.243044 -234.25807) (xy 95.195458 -234.240023)
			(xy 95.151384 -234.214577) (xy 95.111962 -234.18239) (xy 95.078214 -234.144296) (xy 95.051013 -234.101282)
			(xy 95.031065 -234.054462) (xy 95.018886 -234.005048) (xy 95.014791 -233.95432) (xy 94.706694 -233.95432)
			(xy 94.706182 -233.979766) (xy 94.698018 -234.03) (xy 94.681902 -234.078274) (xy 94.658251 -234.123337)
			(xy 94.627678 -234.164023) (xy 94.590974 -234.199278) (xy 94.54909 -234.228188) (xy 94.503111 -234.250005)
			(xy 94.454227 -234.264165) (xy 94.403706 -234.270299) (xy 94.352854 -234.26825) (xy 94.30299 -234.25807)
			(xy 94.255404 -234.240023) (xy 94.21133 -234.214577) (xy 94.171908 -234.18239) (xy 94.13816 -234.144296)
			(xy 94.110959 -234.101282) (xy 94.091011 -234.054462) (xy 94.078832 -234.005048) (xy 94.074737 -233.95432)
			(xy 93.756226 -233.95432) (xy 93.75576 -233.978558) (xy 93.748099 -234.026426) (xy 93.732973 -234.072482)
			(xy 93.710763 -234.115571) (xy 93.682024 -234.154611) (xy 93.64748 -234.18862) (xy 93.607997 -234.216746)
			(xy 93.564567 -234.238282) (xy 93.51828 -234.252688) (xy 93.494352 -234.25658) (xy 93.481906 -234.258358)
			(xy 93.450918 -234.259882) (xy 93.427136 -234.25943) (xy 93.380145 -234.252063) (xy 93.334863 -234.237504)
			(xy 93.292384 -234.216105) (xy 93.253733 -234.188383) (xy 93.219845 -234.155006) (xy 93.2053 -234.136184)
			(xy 93.196918 -234.125008) (xy 93.171518 -234.114086) (xy 93.05798 -234.129072) (xy 93.03639 -234.14609)
			(xy 93.03131 -234.159044) (xy 93.023437 -234.178679) (xy 93.00513 -234.21682) (xy 92.994734 -234.235244)
			(xy 92.84589 -234.49153) (xy 92.826206 -234.524145) (xy 92.779299 -234.584171) (xy 92.752418 -234.611164)
			(xy 92.752164 -234.611418) (xy 92.747084 -234.616498) (xy 92.733622 -234.639612) (xy 92.731844 -234.64647)
			(xy 92.721617 -234.683738) (xy 92.692308 -234.755246) (xy 92.687223 -234.764326) (xy 93.604837 -234.764326)
			(xy 93.608932 -234.713598) (xy 93.621111 -234.664184) (xy 93.641059 -234.617364) (xy 93.66826 -234.57435)
			(xy 93.702008 -234.536256) (xy 93.74143 -234.504069) (xy 93.785504 -234.478623) (xy 93.83309 -234.460576)
			(xy 93.882954 -234.450396) (xy 93.933806 -234.448347) (xy 93.984327 -234.454481) (xy 94.033211 -234.468641)
			(xy 94.07919 -234.490458) (xy 94.121074 -234.519368) (xy 94.157778 -234.554623) (xy 94.188351 -234.595309)
			(xy 94.212002 -234.640372) (xy 94.228118 -234.688646) (xy 94.236282 -234.73888) (xy 94.236794 -234.764326)
			(xy 94.555322 -234.764326) (xy 94.559282 -234.715272) (xy 94.571059 -234.667488) (xy 94.59035 -234.622212)
			(xy 94.616653 -234.580616) (xy 94.649288 -234.543779) (xy 94.687409 -234.512654) (xy 94.73003 -234.488047)
			(xy 94.776046 -234.470595) (xy 94.824265 -234.460751) (xy 94.87344 -234.45877) (xy 94.922295 -234.464702)
			(xy 94.969566 -234.478394) (xy 95.014028 -234.499492) (xy 95.054531 -234.527448) (xy 95.090024 -234.56154)
			(xy 95.119589 -234.600884) (xy 95.14246 -234.644461) (xy 95.158044 -234.691142) (xy 95.165939 -234.739719)
			(xy 95.166434 -234.764326) (xy 95.484691 -234.764326) (xy 95.488786 -234.713598) (xy 95.500965 -234.664184)
			(xy 95.520913 -234.617364) (xy 95.548114 -234.57435) (xy 95.581862 -234.536256) (xy 95.621284 -234.504069)
			(xy 95.665358 -234.478623) (xy 95.712944 -234.460576) (xy 95.762808 -234.450396) (xy 95.81366 -234.448347)
			(xy 95.864181 -234.454481) (xy 95.913065 -234.468641) (xy 95.959044 -234.490458) (xy 96.000928 -234.519368)
			(xy 96.037632 -234.554623) (xy 96.068205 -234.595309) (xy 96.091856 -234.640372) (xy 96.107972 -234.688646)
			(xy 96.116136 -234.73888) (xy 96.116648 -234.764326) (xy 96.116136 -234.789772) (xy 96.107972 -234.840006)
			(xy 96.091856 -234.88828) (xy 96.068205 -234.933343) (xy 96.037632 -234.974029) (xy 96.000928 -235.009284)
			(xy 95.959044 -235.038194) (xy 95.913065 -235.060011) (xy 95.864181 -235.074171) (xy 95.81366 -235.080305)
			(xy 95.762808 -235.078256) (xy 95.712944 -235.068076) (xy 95.665358 -235.050029) (xy 95.621284 -235.024583)
			(xy 95.581862 -234.992396) (xy 95.548114 -234.954302) (xy 95.520913 -234.911288) (xy 95.500965 -234.864468)
			(xy 95.488786 -234.815054) (xy 95.484691 -234.764326) (xy 95.166434 -234.764326) (xy 95.165939 -234.788933)
			(xy 95.158044 -234.83751) (xy 95.14246 -234.884191) (xy 95.119589 -234.927768) (xy 95.090024 -234.967112)
			(xy 95.054531 -235.001204) (xy 95.014028 -235.02916) (xy 94.969566 -235.050258) (xy 94.922295 -235.06395)
			(xy 94.87344 -235.069882) (xy 94.824265 -235.067901) (xy 94.776046 -235.058057) (xy 94.73003 -235.040605)
			(xy 94.687409 -235.015998) (xy 94.649288 -234.984873) (xy 94.616653 -234.948036) (xy 94.59035 -234.90644)
			(xy 94.571059 -234.861164) (xy 94.559282 -234.81338) (xy 94.555322 -234.764326) (xy 94.236794 -234.764326)
			(xy 94.236282 -234.789772) (xy 94.228118 -234.840006) (xy 94.212002 -234.88828) (xy 94.188351 -234.933343)
			(xy 94.157778 -234.974029) (xy 94.121074 -235.009284) (xy 94.07919 -235.038194) (xy 94.033211 -235.060011)
			(xy 93.984327 -235.074171) (xy 93.933806 -235.080305) (xy 93.882954 -235.078256) (xy 93.83309 -235.068076)
			(xy 93.785504 -235.050029) (xy 93.74143 -235.024583) (xy 93.702008 -234.992396) (xy 93.66826 -234.954302)
			(xy 93.641059 -234.911288) (xy 93.621111 -234.864468) (xy 93.608932 -234.815054) (xy 93.604837 -234.764326)
			(xy 92.687223 -234.764326) (xy 92.673424 -234.788964) (xy 92.593922 -234.92587) (xy 92.590784 -234.931748)
			(xy 92.587319 -234.944611) (xy 92.587064 -234.95127) (xy 92.587064 -234.977686) (xy 92.587408 -234.986378)
			(xy 92.593251 -235.002749) (xy 92.598494 -235.00969) (xy 92.604082 -235.016548) (xy 92.618814 -235.025692)
			(xy 92.62745 -235.02747) (xy 92.661068 -235.035136) (xy 92.72624 -235.057656) (xy 92.788146 -235.088024)
			(xy 92.845845 -235.125778) (xy 92.898462 -235.170344) (xy 92.945195 -235.221045) (xy 92.985336 -235.27711)
			(xy 93.018274 -235.337688) (xy 93.03131 -235.369608) (xy 93.03639 -235.382562) (xy 93.058234 -235.39958)
			(xy 93.171772 -235.414566) (xy 93.197172 -235.403644) (xy 93.205554 -235.392722) (xy 93.220056 -235.373891)
			(xy 93.253909 -235.340532) (xy 93.292522 -235.312821) (xy 93.334961 -235.291426) (xy 93.380203 -235.276865)
			(xy 93.427154 -235.269489) (xy 93.450918 -235.269024) (xy 93.474909 -235.269472) (xy 93.522301 -235.276981)
			(xy 93.567934 -235.291811) (xy 93.610685 -235.313598) (xy 93.649502 -235.341805) (xy 93.683428 -235.375736)
			(xy 93.711628 -235.414557) (xy 93.733408 -235.457312) (xy 93.748231 -235.502948) (xy 93.755732 -235.550341)
			(xy 93.756226 -235.574332) (xy 94.074737 -235.574332) (xy 94.078832 -235.523604) (xy 94.091011 -235.47419)
			(xy 94.110959 -235.42737) (xy 94.13816 -235.384356) (xy 94.171908 -235.346262) (xy 94.21133 -235.314075)
			(xy 94.255404 -235.288629) (xy 94.30299 -235.270582) (xy 94.352854 -235.260402) (xy 94.403706 -235.258353)
			(xy 94.454227 -235.264487) (xy 94.503111 -235.278647) (xy 94.54909 -235.300464) (xy 94.590974 -235.329374)
			(xy 94.627678 -235.364629) (xy 94.658251 -235.405315) (xy 94.681902 -235.450378) (xy 94.698018 -235.498652)
			(xy 94.706182 -235.548886) (xy 94.706694 -235.574332) (xy 95.014791 -235.574332) (xy 95.018886 -235.523604)
			(xy 95.031065 -235.47419) (xy 95.051013 -235.42737) (xy 95.078214 -235.384356) (xy 95.111962 -235.346262)
			(xy 95.151384 -235.314075) (xy 95.195458 -235.288629) (xy 95.243044 -235.270582) (xy 95.292908 -235.260402)
			(xy 95.34376 -235.258353) (xy 95.394281 -235.264487) (xy 95.443165 -235.278647) (xy 95.489144 -235.300464)
			(xy 95.531028 -235.329374) (xy 95.567732 -235.364629) (xy 95.598305 -235.405315) (xy 95.621956 -235.450378)
			(xy 95.638072 -235.498652) (xy 95.646236 -235.548886) (xy 95.646748 -235.574332) (xy 95.646236 -235.599778)
			(xy 95.638072 -235.650012) (xy 95.621956 -235.698286) (xy 95.598305 -235.743349) (xy 95.567732 -235.784035)
			(xy 95.531028 -235.81929) (xy 95.489144 -235.8482) (xy 95.443165 -235.870017) (xy 95.394281 -235.884177)
			(xy 95.34376 -235.890311) (xy 95.292908 -235.888262) (xy 95.243044 -235.878082) (xy 95.195458 -235.860035)
			(xy 95.151384 -235.834589) (xy 95.111962 -235.802402) (xy 95.078214 -235.764308) (xy 95.051013 -235.721294)
			(xy 95.031065 -235.674474) (xy 95.018886 -235.62506) (xy 95.014791 -235.574332) (xy 94.706694 -235.574332)
			(xy 94.706182 -235.599778) (xy 94.698018 -235.650012) (xy 94.681902 -235.698286) (xy 94.658251 -235.743349)
			(xy 94.627678 -235.784035) (xy 94.590974 -235.81929) (xy 94.54909 -235.8482) (xy 94.503111 -235.870017)
			(xy 94.454227 -235.884177) (xy 94.403706 -235.890311) (xy 94.352854 -235.888262) (xy 94.30299 -235.878082)
			(xy 94.255404 -235.860035) (xy 94.21133 -235.834589) (xy 94.171908 -235.802402) (xy 94.13816 -235.764308)
			(xy 94.110959 -235.721294) (xy 94.091011 -235.674474) (xy 94.078832 -235.62506) (xy 94.074737 -235.574332)
			(xy 93.756226 -235.574332) (xy 93.755759 -235.59857) (xy 93.748097 -235.646436) (xy 93.73297 -235.692491)
			(xy 93.710758 -235.735578) (xy 93.68202 -235.774616) (xy 93.647475 -235.808624) (xy 93.607993 -235.836749)
			(xy 93.564563 -235.858284) (xy 93.518278 -235.872688) (xy 93.494352 -235.876592) (xy 93.481906 -235.87837)
			(xy 93.450918 -235.879894) (xy 93.427135 -235.879443) (xy 93.380144 -235.872076) (xy 93.334862 -235.857517)
			(xy 93.292383 -235.836118) (xy 93.253731 -235.808397) (xy 93.219842 -235.775021) (xy 93.2053 -235.756196)
			(xy 93.196918 -235.74502) (xy 93.171518 -235.734098) (xy 93.05798 -235.749084) (xy 93.03639 -235.766102)
			(xy 93.03131 -235.779056) (xy 93.023437 -235.798691) (xy 93.005129 -235.836832) (xy 92.994734 -235.855256)
			(xy 92.95003 -235.932218) (xy 92.944242 -235.943431) (xy 92.943302 -235.968617) (xy 92.948252 -235.980224)
			(xy 92.984574 -236.053884) (xy 92.990628 -236.064843) (xy 93.010879 -236.079512) (xy 93.023182 -236.081824)
			(xy 93.04719 -236.085668) (xy 93.09366 -236.099963) (xy 93.137281 -236.121434) (xy 93.176953 -236.14954)
			(xy 93.211675 -236.183572) (xy 93.240571 -236.222672) (xy 93.262914 -236.265853) (xy 93.278138 -236.312027)
			(xy 93.28586 -236.360029) (xy 93.286326 -236.384338) (xy 93.604837 -236.384338) (xy 93.608932 -236.33361)
			(xy 93.621111 -236.284196) (xy 93.641059 -236.237376) (xy 93.66826 -236.194362) (xy 93.702008 -236.156268)
			(xy 93.74143 -236.124081) (xy 93.785504 -236.098635) (xy 93.83309 -236.080588) (xy 93.882954 -236.070408)
			(xy 93.933806 -236.068359) (xy 93.984327 -236.074493) (xy 94.033211 -236.088653) (xy 94.07919 -236.11047)
			(xy 94.121074 -236.13938) (xy 94.157778 -236.174635) (xy 94.188351 -236.215321) (xy 94.212002 -236.260384)
			(xy 94.228118 -236.308658) (xy 94.236282 -236.358892) (xy 94.236794 -236.384338) (xy 94.555322 -236.384338)
			(xy 94.559282 -236.335284) (xy 94.571059 -236.2875) (xy 94.59035 -236.242224) (xy 94.616653 -236.200628)
			(xy 94.649288 -236.163791) (xy 94.687409 -236.132666) (xy 94.73003 -236.108059) (xy 94.776046 -236.090607)
			(xy 94.824265 -236.080763) (xy 94.87344 -236.078782) (xy 94.922295 -236.084714) (xy 94.969566 -236.098406)
			(xy 95.014028 -236.119504) (xy 95.054531 -236.14746) (xy 95.090024 -236.181552) (xy 95.119589 -236.220896)
			(xy 95.14246 -236.264473) (xy 95.158044 -236.311154) (xy 95.165939 -236.359731) (xy 95.166434 -236.384338)
			(xy 95.484691 -236.384338) (xy 95.488786 -236.33361) (xy 95.500965 -236.284196) (xy 95.520913 -236.237376)
			(xy 95.548114 -236.194362) (xy 95.581862 -236.156268) (xy 95.621284 -236.124081) (xy 95.665358 -236.098635)
			(xy 95.712944 -236.080588) (xy 95.762808 -236.070408) (xy 95.81366 -236.068359) (xy 95.864181 -236.074493)
			(xy 95.913065 -236.088653) (xy 95.959044 -236.11047) (xy 96.000928 -236.13938) (xy 96.037632 -236.174635)
			(xy 96.068205 -236.215321) (xy 96.091856 -236.260384) (xy 96.107972 -236.308658) (xy 96.116136 -236.358892)
			(xy 96.116648 -236.384338) (xy 96.116136 -236.409784) (xy 96.107972 -236.460018) (xy 96.091856 -236.508292)
			(xy 96.068205 -236.553355) (xy 96.037632 -236.594041) (xy 96.000928 -236.629296) (xy 95.959044 -236.658206)
			(xy 95.913065 -236.680023) (xy 95.864181 -236.694183) (xy 95.81366 -236.700317) (xy 95.762808 -236.698268)
			(xy 95.712944 -236.688088) (xy 95.665358 -236.670041) (xy 95.621284 -236.644595) (xy 95.581862 -236.612408)
			(xy 95.548114 -236.574314) (xy 95.520913 -236.5313) (xy 95.500965 -236.48448) (xy 95.488786 -236.435066)
			(xy 95.484691 -236.384338) (xy 95.166434 -236.384338) (xy 95.165939 -236.408945) (xy 95.158044 -236.457522)
			(xy 95.14246 -236.504203) (xy 95.119589 -236.54778) (xy 95.090024 -236.587124) (xy 95.054531 -236.621216)
			(xy 95.014028 -236.649172) (xy 94.969566 -236.67027) (xy 94.922295 -236.683962) (xy 94.87344 -236.689894)
			(xy 94.824265 -236.687913) (xy 94.776046 -236.678069) (xy 94.73003 -236.660617) (xy 94.687409 -236.63601)
			(xy 94.649288 -236.604885) (xy 94.616653 -236.568048) (xy 94.59035 -236.526452) (xy 94.571059 -236.481176)
			(xy 94.559282 -236.433392) (xy 94.555322 -236.384338) (xy 94.236794 -236.384338) (xy 94.236282 -236.409784)
			(xy 94.228118 -236.460018) (xy 94.212002 -236.508292) (xy 94.188351 -236.553355) (xy 94.157778 -236.594041)
			(xy 94.121074 -236.629296) (xy 94.07919 -236.658206) (xy 94.033211 -236.680023) (xy 93.984327 -236.694183)
			(xy 93.933806 -236.700317) (xy 93.882954 -236.698268) (xy 93.83309 -236.688088) (xy 93.785504 -236.670041)
			(xy 93.74143 -236.644595) (xy 93.702008 -236.612408) (xy 93.66826 -236.574314) (xy 93.641059 -236.5313)
			(xy 93.621111 -236.48448) (xy 93.608932 -236.435066) (xy 93.604837 -236.384338) (xy 93.286326 -236.384338)
			(xy 93.285862 -236.408946) (xy 93.277975 -236.457526) (xy 93.262396 -236.504212) (xy 93.239528 -236.547793)
			(xy 93.209964 -236.58714) (xy 93.17447 -236.621234) (xy 93.133966 -236.649191) (xy 93.0895 -236.670288)
			(xy 93.042226 -236.683976) (xy 93.017848 -236.68736) (xy 93.003878 -236.689138) (xy 92.982288 -236.705648)
			(xy 92.943934 -236.798104) (xy 92.940851 -236.806556) (xy 92.940189 -236.824525) (xy 92.945767 -236.841618)
			(xy 92.951046 -236.848904) (xy 92.969873 -236.873579) (xy 93.002548 -236.92635) (xy 93.029185 -236.982411)
			(xy 93.049456 -237.041076) (xy 93.063112 -237.101624) (xy 93.069985 -237.16331) (xy 93.070426 -237.194344)
			(xy 94.074737 -237.194344) (xy 94.078832 -237.143616) (xy 94.091011 -237.094202) (xy 94.110959 -237.047382)
			(xy 94.13816 -237.004368) (xy 94.171908 -236.966274) (xy 94.21133 -236.934087) (xy 94.255404 -236.908641)
			(xy 94.30299 -236.890594) (xy 94.352854 -236.880414) (xy 94.403706 -236.878365) (xy 94.454227 -236.884499)
			(xy 94.503111 -236.898659) (xy 94.54909 -236.920476) (xy 94.590974 -236.949386) (xy 94.627678 -236.984641)
			(xy 94.658251 -237.025327) (xy 94.681902 -237.07039) (xy 94.698018 -237.118664) (xy 94.706182 -237.168898)
			(xy 94.706694 -237.194344) (xy 95.014791 -237.194344) (xy 95.018886 -237.143616) (xy 95.031065 -237.094202)
			(xy 95.051013 -237.047382) (xy 95.078214 -237.004368) (xy 95.111962 -236.966274) (xy 95.151384 -236.934087)
			(xy 95.195458 -236.908641) (xy 95.243044 -236.890594) (xy 95.292908 -236.880414) (xy 95.34376 -236.878365)
			(xy 95.394281 -236.884499) (xy 95.443165 -236.898659) (xy 95.489144 -236.920476) (xy 95.531028 -236.949386)
			(xy 95.567732 -236.984641) (xy 95.598305 -237.025327) (xy 95.621956 -237.07039) (xy 95.638072 -237.118664)
			(xy 95.646236 -237.168898) (xy 95.646748 -237.194344) (xy 95.965276 -237.194344) (xy 95.969236 -237.14529)
			(xy 95.981013 -237.097506) (xy 96.000304 -237.05223) (xy 96.026607 -237.010634) (xy 96.059242 -236.973797)
			(xy 96.097363 -236.942672) (xy 96.139984 -236.918065) (xy 96.186 -236.900613) (xy 96.234219 -236.890769)
			(xy 96.283394 -236.888788) (xy 96.332249 -236.89472) (xy 96.37952 -236.908412) (xy 96.423982 -236.92951)
			(xy 96.464485 -236.957466) (xy 96.499978 -236.991558) (xy 96.529543 -237.030902) (xy 96.552414 -237.074479)
			(xy 96.567998 -237.12116) (xy 96.575893 -237.169737) (xy 96.576388 -237.194344) (xy 96.575893 -237.218951)
			(xy 96.567998 -237.267528) (xy 96.552414 -237.314209) (xy 96.529543 -237.357786) (xy 96.499978 -237.39713)
			(xy 96.464485 -237.431222) (xy 96.423982 -237.459178) (xy 96.37952 -237.480276) (xy 96.332249 -237.493968)
			(xy 96.283394 -237.4999) (xy 96.234219 -237.497919) (xy 96.186 -237.488075) (xy 96.139984 -237.470623)
			(xy 96.097363 -237.446016) (xy 96.059242 -237.414891) (xy 96.026607 -237.378054) (xy 96.000304 -237.336458)
			(xy 95.981013 -237.291182) (xy 95.969236 -237.243398) (xy 95.965276 -237.194344) (xy 95.646748 -237.194344)
			(xy 95.646236 -237.21979) (xy 95.638072 -237.270024) (xy 95.621956 -237.318298) (xy 95.598305 -237.363361)
			(xy 95.567732 -237.404047) (xy 95.531028 -237.439302) (xy 95.489144 -237.468212) (xy 95.443165 -237.490029)
			(xy 95.394281 -237.504189) (xy 95.34376 -237.510323) (xy 95.292908 -237.508274) (xy 95.243044 -237.498094)
			(xy 95.195458 -237.480047) (xy 95.151384 -237.454601) (xy 95.111962 -237.422414) (xy 95.078214 -237.38432)
			(xy 95.051013 -237.341306) (xy 95.031065 -237.294486) (xy 95.018886 -237.245072) (xy 95.014791 -237.194344)
			(xy 94.706694 -237.194344) (xy 94.706182 -237.21979) (xy 94.698018 -237.270024) (xy 94.681902 -237.318298)
			(xy 94.658251 -237.363361) (xy 94.627678 -237.404047) (xy 94.590974 -237.439302) (xy 94.54909 -237.468212)
			(xy 94.503111 -237.490029) (xy 94.454227 -237.504189) (xy 94.403706 -237.510323) (xy 94.352854 -237.508274)
			(xy 94.30299 -237.498094) (xy 94.255404 -237.480047) (xy 94.21133 -237.454601) (xy 94.171908 -237.422414)
			(xy 94.13816 -237.38432) (xy 94.110959 -237.341306) (xy 94.091011 -237.294486) (xy 94.078832 -237.245072)
			(xy 94.074737 -237.194344) (xy 93.070426 -237.194344) (xy 93.069838 -237.231149) (xy 93.060175 -237.304122)
			(xy 93.041021 -237.375197) (xy 93.012708 -237.443145) (xy 92.994734 -237.475268) (xy 92.95003 -237.55223)
			(xy 92.944245 -237.563443) (xy 92.94331 -237.588627) (xy 92.948252 -237.600236) (xy 92.984574 -237.673896)
			(xy 92.990629 -237.684853) (xy 93.010881 -237.699518) (xy 93.023182 -237.701836) (xy 93.04719 -237.70568)
			(xy 93.093659 -237.719975) (xy 93.137279 -237.741446) (xy 93.17695 -237.769553) (xy 93.211671 -237.803585)
			(xy 93.240566 -237.842685) (xy 93.262906 -237.885866) (xy 93.278129 -237.93204) (xy 93.285849 -237.980041)
			(xy 93.286326 -238.00435) (xy 93.604837 -238.00435) (xy 93.608932 -237.953622) (xy 93.621111 -237.904208)
			(xy 93.641059 -237.857388) (xy 93.66826 -237.814374) (xy 93.702008 -237.77628) (xy 93.74143 -237.744093)
			(xy 93.785504 -237.718647) (xy 93.83309 -237.7006) (xy 93.882954 -237.69042) (xy 93.933806 -237.688371)
			(xy 93.984327 -237.694505) (xy 94.033211 -237.708665) (xy 94.07919 -237.730482) (xy 94.121074 -237.759392)
			(xy 94.157778 -237.794647) (xy 94.188351 -237.835333) (xy 94.212002 -237.880396) (xy 94.228118 -237.92867)
			(xy 94.236282 -237.978904) (xy 94.236794 -238.00435) (xy 94.555322 -238.00435) (xy 94.559282 -237.955296)
			(xy 94.571059 -237.907512) (xy 94.59035 -237.862236) (xy 94.616653 -237.82064) (xy 94.649288 -237.783803)
			(xy 94.687409 -237.752678) (xy 94.73003 -237.728071) (xy 94.776046 -237.710619) (xy 94.824265 -237.700775)
			(xy 94.87344 -237.698794) (xy 94.922295 -237.704726) (xy 94.969566 -237.718418) (xy 95.014028 -237.739516)
			(xy 95.054531 -237.767472) (xy 95.090024 -237.801564) (xy 95.119589 -237.840908) (xy 95.14246 -237.884485)
			(xy 95.158044 -237.931166) (xy 95.165939 -237.979743) (xy 95.166434 -238.00435) (xy 95.484691 -238.00435)
			(xy 95.488786 -237.953622) (xy 95.500965 -237.904208) (xy 95.520913 -237.857388) (xy 95.548114 -237.814374)
			(xy 95.581862 -237.77628) (xy 95.621284 -237.744093) (xy 95.665358 -237.718647) (xy 95.712944 -237.7006)
			(xy 95.762808 -237.69042) (xy 95.81366 -237.688371) (xy 95.864181 -237.694505) (xy 95.913065 -237.708665)
			(xy 95.959044 -237.730482) (xy 96.000928 -237.759392) (xy 96.037632 -237.794647) (xy 96.068205 -237.835333)
			(xy 96.091856 -237.880396) (xy 96.107972 -237.92867) (xy 96.116136 -237.978904) (xy 96.116648 -238.00435)
			(xy 96.116136 -238.029796) (xy 96.107972 -238.08003) (xy 96.091856 -238.128304) (xy 96.068205 -238.173367)
			(xy 96.037632 -238.214053) (xy 96.000928 -238.249308) (xy 95.959044 -238.278218) (xy 95.913065 -238.300035)
			(xy 95.864181 -238.314195) (xy 95.81366 -238.320329) (xy 95.762808 -238.31828) (xy 95.712944 -238.3081)
			(xy 95.665358 -238.290053) (xy 95.621284 -238.264607) (xy 95.581862 -238.23242) (xy 95.548114 -238.194326)
			(xy 95.520913 -238.151312) (xy 95.500965 -238.104492) (xy 95.488786 -238.055078) (xy 95.484691 -238.00435)
			(xy 95.166434 -238.00435) (xy 95.165939 -238.028957) (xy 95.158044 -238.077534) (xy 95.14246 -238.124215)
			(xy 95.119589 -238.167792) (xy 95.090024 -238.207136) (xy 95.054531 -238.241228) (xy 95.014028 -238.269184)
			(xy 94.969566 -238.290282) (xy 94.922295 -238.303974) (xy 94.87344 -238.309906) (xy 94.824265 -238.307925)
			(xy 94.776046 -238.298081) (xy 94.73003 -238.280629) (xy 94.687409 -238.256022) (xy 94.649288 -238.224897)
			(xy 94.616653 -238.18806) (xy 94.59035 -238.146464) (xy 94.571059 -238.101188) (xy 94.559282 -238.053404)
			(xy 94.555322 -238.00435) (xy 94.236794 -238.00435) (xy 94.236282 -238.029796) (xy 94.228118 -238.08003)
			(xy 94.212002 -238.128304) (xy 94.188351 -238.173367) (xy 94.157778 -238.214053) (xy 94.121074 -238.249308)
			(xy 94.07919 -238.278218) (xy 94.033211 -238.300035) (xy 93.984327 -238.314195) (xy 93.933806 -238.320329)
			(xy 93.882954 -238.31828) (xy 93.83309 -238.3081) (xy 93.785504 -238.290053) (xy 93.74143 -238.264607)
			(xy 93.702008 -238.23242) (xy 93.66826 -238.194326) (xy 93.641059 -238.151312) (xy 93.621111 -238.104492)
			(xy 93.608932 -238.055078) (xy 93.604837 -238.00435) (xy 93.286326 -238.00435) (xy 93.285861 -238.028958)
			(xy 93.277973 -238.077536) (xy 93.262393 -238.12422) (xy 93.239524 -238.167799) (xy 93.20996 -238.207145)
			(xy 93.174466 -238.241238) (xy 93.133962 -238.269194) (xy 93.089497 -238.290289) (xy 93.042224 -238.303977)
			(xy 93.017848 -238.307372) (xy 93.003878 -238.30915) (xy 92.982288 -238.32566) (xy 92.9386 -238.430816)
			(xy 92.94241 -238.458248) (xy 92.951046 -238.468916) (xy 92.975517 -238.501397) (xy 93.015806 -238.572036)
			(xy 93.03131 -238.609632) (xy 93.03639 -238.622586) (xy 93.05798 -238.639604) (xy 93.171772 -238.65459)
			(xy 93.197172 -238.643668) (xy 93.205554 -238.632746) (xy 93.220055 -238.613914) (xy 93.253907 -238.580552)
			(xy 93.292519 -238.552839) (xy 93.334959 -238.531443) (xy 93.380202 -238.51688) (xy 93.427154 -238.509504)
			(xy 93.450918 -238.509048) (xy 93.47491 -238.50952) (xy 93.522302 -238.517028) (xy 93.567936 -238.531856)
			(xy 93.610689 -238.55364) (xy 93.649509 -238.581843) (xy 93.68344 -238.615771) (xy 93.711646 -238.654588)
			(xy 93.733434 -238.69734) (xy 93.748266 -238.742973) (xy 93.755778 -238.790364) (xy 93.756226 -238.814356)
			(xy 94.074737 -238.814356) (xy 94.078832 -238.763628) (xy 94.091011 -238.714214) (xy 94.110959 -238.667394)
			(xy 94.13816 -238.62438) (xy 94.171908 -238.586286) (xy 94.21133 -238.554099) (xy 94.255404 -238.528653)
			(xy 94.30299 -238.510606) (xy 94.352854 -238.500426) (xy 94.403706 -238.498377) (xy 94.454227 -238.504511)
			(xy 94.503111 -238.518671) (xy 94.54909 -238.540488) (xy 94.590974 -238.569398) (xy 94.627678 -238.604653)
			(xy 94.658251 -238.645339) (xy 94.681902 -238.690402) (xy 94.698018 -238.738676) (xy 94.706182 -238.78891)
			(xy 94.706694 -238.814356) (xy 95.014791 -238.814356) (xy 95.018886 -238.763628) (xy 95.031065 -238.714214)
			(xy 95.051013 -238.667394) (xy 95.078214 -238.62438) (xy 95.111962 -238.586286) (xy 95.151384 -238.554099)
			(xy 95.195458 -238.528653) (xy 95.243044 -238.510606) (xy 95.292908 -238.500426) (xy 95.34376 -238.498377)
			(xy 95.394281 -238.504511) (xy 95.443165 -238.518671) (xy 95.489144 -238.540488) (xy 95.531028 -238.569398)
			(xy 95.567732 -238.604653) (xy 95.598305 -238.645339) (xy 95.621956 -238.690402) (xy 95.638072 -238.738676)
			(xy 95.646236 -238.78891) (xy 95.646748 -238.814356) (xy 95.646236 -238.839802) (xy 95.638072 -238.890036)
			(xy 95.621956 -238.93831) (xy 95.598305 -238.983373) (xy 95.567732 -239.024059) (xy 95.531028 -239.059314)
			(xy 95.489144 -239.088224) (xy 95.443165 -239.110041) (xy 95.394281 -239.124201) (xy 95.34376 -239.130335)
			(xy 95.292908 -239.128286) (xy 95.243044 -239.118106) (xy 95.195458 -239.100059) (xy 95.151384 -239.074613)
			(xy 95.111962 -239.042426) (xy 95.078214 -239.004332) (xy 95.051013 -238.961318) (xy 95.031065 -238.914498)
			(xy 95.018886 -238.865084) (xy 95.014791 -238.814356) (xy 94.706694 -238.814356) (xy 94.706182 -238.839802)
			(xy 94.698018 -238.890036) (xy 94.681902 -238.93831) (xy 94.658251 -238.983373) (xy 94.627678 -239.024059)
			(xy 94.590974 -239.059314) (xy 94.54909 -239.088224) (xy 94.503111 -239.110041) (xy 94.454227 -239.124201)
			(xy 94.403706 -239.130335) (xy 94.352854 -239.128286) (xy 94.30299 -239.118106) (xy 94.255404 -239.100059)
			(xy 94.21133 -239.074613) (xy 94.171908 -239.042426) (xy 94.13816 -239.004332) (xy 94.110959 -238.961318)
			(xy 94.091011 -238.914498) (xy 94.078832 -238.865084) (xy 94.074737 -238.814356) (xy 93.756226 -238.814356)
			(xy 93.755757 -238.838592) (xy 93.748092 -238.886456) (xy 93.732963 -238.932508) (xy 93.71075 -238.975592)
			(xy 93.682011 -239.014626) (xy 93.647466 -239.048631) (xy 93.607985 -239.076753) (xy 93.564557 -239.098286)
			(xy 93.518273 -239.112689) (xy 93.494352 -239.116616) (xy 93.481906 -239.118394) (xy 93.450918 -239.119918)
			(xy 93.427135 -239.119467) (xy 93.380144 -239.1121) (xy 93.334861 -239.097542) (xy 93.29238 -239.076145)
			(xy 93.253727 -239.048424) (xy 93.219835 -239.01505) (xy 93.2053 -238.99622) (xy 93.196918 -238.985044)
			(xy 93.171518 -238.974122) (xy 93.05798 -238.989108) (xy 93.03639 -239.006126) (xy 93.03131 -239.01908)
			(xy 93.023436 -239.038714) (xy 93.005127 -239.076854) (xy 92.994734 -239.09528) (xy 92.84589 -239.351566)
			(xy 92.826208 -239.384183) (xy 92.779307 -239.444214) (xy 92.752418 -239.4712) (xy 92.752164 -239.471454)
			(xy 92.747084 -239.476534) (xy 92.733622 -239.499648) (xy 92.731844 -239.506506) (xy 92.721614 -239.543773)
			(xy 92.692302 -239.615279) (xy 92.687217 -239.624362) (xy 93.604837 -239.624362) (xy 93.608932 -239.573634)
			(xy 93.621111 -239.52422) (xy 93.641059 -239.4774) (xy 93.66826 -239.434386) (xy 93.702008 -239.396292)
			(xy 93.74143 -239.364105) (xy 93.785504 -239.338659) (xy 93.83309 -239.320612) (xy 93.882954 -239.310432)
			(xy 93.933806 -239.308383) (xy 93.984327 -239.314517) (xy 94.033211 -239.328677) (xy 94.07919 -239.350494)
			(xy 94.121074 -239.379404) (xy 94.157778 -239.414659) (xy 94.188351 -239.455345) (xy 94.212002 -239.500408)
			(xy 94.228118 -239.548682) (xy 94.236282 -239.598916) (xy 94.236794 -239.624362) (xy 94.555322 -239.624362)
			(xy 94.559282 -239.575308) (xy 94.571059 -239.527524) (xy 94.59035 -239.482248) (xy 94.616653 -239.440652)
			(xy 94.649288 -239.403815) (xy 94.687409 -239.37269) (xy 94.73003 -239.348083) (xy 94.776046 -239.330631)
			(xy 94.824265 -239.320787) (xy 94.87344 -239.318806) (xy 94.922295 -239.324738) (xy 94.969566 -239.33843)
			(xy 95.014028 -239.359528) (xy 95.054531 -239.387484) (xy 95.090024 -239.421576) (xy 95.119589 -239.46092)
			(xy 95.14246 -239.504497) (xy 95.158044 -239.551178) (xy 95.165939 -239.599755) (xy 95.166434 -239.624362)
			(xy 95.484691 -239.624362) (xy 95.488786 -239.573634) (xy 95.500965 -239.52422) (xy 95.520913 -239.4774)
			(xy 95.548114 -239.434386) (xy 95.581862 -239.396292) (xy 95.621284 -239.364105) (xy 95.665358 -239.338659)
			(xy 95.712944 -239.320612) (xy 95.762808 -239.310432) (xy 95.81366 -239.308383) (xy 95.864181 -239.314517)
			(xy 95.913065 -239.328677) (xy 95.959044 -239.350494) (xy 96.000928 -239.379404) (xy 96.037632 -239.414659)
			(xy 96.068205 -239.455345) (xy 96.091856 -239.500408) (xy 96.107972 -239.548682) (xy 96.116136 -239.598916)
			(xy 96.116648 -239.624362) (xy 96.116136 -239.649808) (xy 96.107972 -239.700042) (xy 96.091856 -239.748316)
			(xy 96.068205 -239.793379) (xy 96.037632 -239.834065) (xy 96.000928 -239.86932) (xy 95.959044 -239.89823)
			(xy 95.913065 -239.920047) (xy 95.864181 -239.934207) (xy 95.81366 -239.940341) (xy 95.762808 -239.938292)
			(xy 95.712944 -239.928112) (xy 95.665358 -239.910065) (xy 95.621284 -239.884619) (xy 95.581862 -239.852432)
			(xy 95.548114 -239.814338) (xy 95.520913 -239.771324) (xy 95.500965 -239.724504) (xy 95.488786 -239.67509)
			(xy 95.484691 -239.624362) (xy 95.166434 -239.624362) (xy 95.165939 -239.648969) (xy 95.158044 -239.697546)
			(xy 95.14246 -239.744227) (xy 95.119589 -239.787804) (xy 95.090024 -239.827148) (xy 95.054531 -239.86124)
			(xy 95.014028 -239.889196) (xy 94.969566 -239.910294) (xy 94.922295 -239.923986) (xy 94.87344 -239.929918)
			(xy 94.824265 -239.927937) (xy 94.776046 -239.918093) (xy 94.73003 -239.900641) (xy 94.687409 -239.876034)
			(xy 94.649288 -239.844909) (xy 94.616653 -239.808072) (xy 94.59035 -239.766476) (xy 94.571059 -239.7212)
			(xy 94.559282 -239.673416) (xy 94.555322 -239.624362) (xy 94.236794 -239.624362) (xy 94.236282 -239.649808)
			(xy 94.228118 -239.700042) (xy 94.212002 -239.748316) (xy 94.188351 -239.793379) (xy 94.157778 -239.834065)
			(xy 94.121074 -239.86932) (xy 94.07919 -239.89823) (xy 94.033211 -239.920047) (xy 93.984327 -239.934207)
			(xy 93.933806 -239.940341) (xy 93.882954 -239.938292) (xy 93.83309 -239.928112) (xy 93.785504 -239.910065)
			(xy 93.74143 -239.884619) (xy 93.702008 -239.852432) (xy 93.66826 -239.814338) (xy 93.641059 -239.771324)
			(xy 93.621111 -239.724504) (xy 93.608932 -239.67509) (xy 93.604837 -239.624362) (xy 92.687217 -239.624362)
			(xy 92.673424 -239.649) (xy 92.593922 -239.785906) (xy 92.590776 -239.791783) (xy 92.587296 -239.804645)
			(xy 92.587064 -239.811306) (xy 92.587064 -239.837722) (xy 92.587414 -239.846412) (xy 92.593266 -239.862775)
			(xy 92.598494 -239.869726) (xy 92.604082 -239.876584) (xy 92.618814 -239.885728) (xy 92.62745 -239.887506)
			(xy 92.661067 -239.895172) (xy 92.726238 -239.917694) (xy 92.788142 -239.948063) (xy 92.845839 -239.985818)
			(xy 92.898453 -240.030385) (xy 92.945184 -240.081087) (xy 92.985321 -240.137153) (xy 93.018255 -240.197732)
			(xy 93.03131 -240.229644) (xy 93.03639 -240.242598) (xy 93.058234 -240.259616) (xy 93.171772 -240.274602)
			(xy 93.197172 -240.26368) (xy 93.205554 -240.252758) (xy 93.220055 -240.233925) (xy 93.253906 -240.200562)
			(xy 93.292518 -240.172848) (xy 93.334958 -240.151451) (xy 93.380201 -240.136888) (xy 93.427154 -240.129511)
			(xy 93.450918 -240.12906) (xy 93.474909 -240.129532) (xy 93.522301 -240.13704) (xy 93.567934 -240.151869)
			(xy 93.610687 -240.173653) (xy 93.649506 -240.201856) (xy 93.683435 -240.235784) (xy 93.71164 -240.274601)
			(xy 93.733426 -240.317353) (xy 93.748257 -240.362986) (xy 93.755767 -240.410377) (xy 93.756226 -240.434368)
			(xy 94.074737 -240.434368) (xy 94.078832 -240.38364) (xy 94.091011 -240.334226) (xy 94.110959 -240.287406)
			(xy 94.13816 -240.244392) (xy 94.171908 -240.206298) (xy 94.21133 -240.174111) (xy 94.255404 -240.148665)
			(xy 94.30299 -240.130618) (xy 94.352854 -240.120438) (xy 94.403706 -240.118389) (xy 94.454227 -240.124523)
			(xy 94.503111 -240.138683) (xy 94.54909 -240.1605) (xy 94.590974 -240.18941) (xy 94.627678 -240.224665)
			(xy 94.658251 -240.265351) (xy 94.681902 -240.310414) (xy 94.698018 -240.358688) (xy 94.706182 -240.408922)
			(xy 94.706694 -240.434368) (xy 95.014791 -240.434368) (xy 95.018886 -240.38364) (xy 95.031065 -240.334226)
			(xy 95.051013 -240.287406) (xy 95.078214 -240.244392) (xy 95.111962 -240.206298) (xy 95.151384 -240.174111)
			(xy 95.195458 -240.148665) (xy 95.243044 -240.130618) (xy 95.292908 -240.120438) (xy 95.34376 -240.118389)
			(xy 95.394281 -240.124523) (xy 95.443165 -240.138683) (xy 95.489144 -240.1605) (xy 95.531028 -240.18941)
			(xy 95.567732 -240.224665) (xy 95.598305 -240.265351) (xy 95.621956 -240.310414) (xy 95.638072 -240.358688)
			(xy 95.646236 -240.408922) (xy 95.646748 -240.434368) (xy 95.646236 -240.459814) (xy 95.638072 -240.510048)
			(xy 95.621956 -240.558322) (xy 95.598305 -240.603385) (xy 95.567732 -240.644071) (xy 95.531028 -240.679326)
			(xy 95.489144 -240.708236) (xy 95.443165 -240.730053) (xy 95.394281 -240.744213) (xy 95.34376 -240.750347)
			(xy 95.292908 -240.748298) (xy 95.243044 -240.738118) (xy 95.195458 -240.720071) (xy 95.151384 -240.694625)
			(xy 95.111962 -240.662438) (xy 95.078214 -240.624344) (xy 95.051013 -240.58133) (xy 95.031065 -240.53451)
			(xy 95.018886 -240.485096) (xy 95.014791 -240.434368) (xy 94.706694 -240.434368) (xy 94.706182 -240.459814)
			(xy 94.698018 -240.510048) (xy 94.681902 -240.558322) (xy 94.658251 -240.603385) (xy 94.627678 -240.644071)
			(xy 94.590974 -240.679326) (xy 94.54909 -240.708236) (xy 94.503111 -240.730053) (xy 94.454227 -240.744213)
			(xy 94.403706 -240.750347) (xy 94.352854 -240.748298) (xy 94.30299 -240.738118) (xy 94.255404 -240.720071)
			(xy 94.21133 -240.694625) (xy 94.171908 -240.662438) (xy 94.13816 -240.624344) (xy 94.110959 -240.58133)
			(xy 94.091011 -240.53451) (xy 94.078832 -240.485096) (xy 94.074737 -240.434368) (xy 93.756226 -240.434368)
			(xy 93.755756 -240.458604) (xy 93.748089 -240.506466) (xy 93.732959 -240.552516) (xy 93.710746 -240.595598)
			(xy 93.682006 -240.634631) (xy 93.647462 -240.668635) (xy 93.607981 -240.696756) (xy 93.564554 -240.718288)
			(xy 93.518271 -240.73269) (xy 93.494352 -240.736628) (xy 93.481906 -240.738406) (xy 93.450918 -240.73993)
			(xy 93.427135 -240.739479) (xy 93.380143 -240.732112) (xy 93.33486 -240.717555) (xy 93.292378 -240.696158)
			(xy 93.253725 -240.668438) (xy 93.219832 -240.635064) (xy 93.2053 -240.616232) (xy 93.196918 -240.605056)
			(xy 93.171518 -240.594134) (xy 93.05798 -240.60912) (xy 93.03639 -240.626138) (xy 93.03131 -240.639092)
			(xy 93.023436 -240.658726) (xy 93.005126 -240.696866) (xy 92.994734 -240.715292) (xy 92.95003 -240.792254)
			(xy 92.944251 -240.803467) (xy 92.943326 -240.828646) (xy 92.948252 -240.84026) (xy 92.984574 -240.91392)
			(xy 92.990632 -240.924873) (xy 93.010884 -240.939531) (xy 93.023182 -240.94186) (xy 93.047189 -240.945704)
			(xy 93.093657 -240.96) (xy 93.137275 -240.981471) (xy 93.176943 -241.009578) (xy 93.211662 -241.043611)
			(xy 93.240554 -241.082711) (xy 93.262891 -241.125892) (xy 93.27811 -241.172065) (xy 93.285827 -241.220066)
			(xy 93.286326 -241.244374) (xy 93.604837 -241.244374) (xy 93.608932 -241.193646) (xy 93.621111 -241.144232)
			(xy 93.641059 -241.097412) (xy 93.66826 -241.054398) (xy 93.702008 -241.016304) (xy 93.74143 -240.984117)
			(xy 93.785504 -240.958671) (xy 93.83309 -240.940624) (xy 93.882954 -240.930444) (xy 93.933806 -240.928395)
			(xy 93.984327 -240.934529) (xy 94.033211 -240.948689) (xy 94.07919 -240.970506) (xy 94.121074 -240.999416)
			(xy 94.157778 -241.034671) (xy 94.188351 -241.075357) (xy 94.212002 -241.12042) (xy 94.228118 -241.168694)
			(xy 94.236282 -241.218928) (xy 94.236794 -241.244374) (xy 94.555322 -241.244374) (xy 94.559282 -241.19532)
			(xy 94.571059 -241.147536) (xy 94.59035 -241.10226) (xy 94.616653 -241.060664) (xy 94.649288 -241.023827)
			(xy 94.687409 -240.992702) (xy 94.73003 -240.968095) (xy 94.776046 -240.950643) (xy 94.824265 -240.940799)
			(xy 94.87344 -240.938818) (xy 94.922295 -240.94475) (xy 94.969566 -240.958442) (xy 95.014028 -240.97954)
			(xy 95.054531 -241.007496) (xy 95.090024 -241.041588) (xy 95.119589 -241.080932) (xy 95.14246 -241.124509)
			(xy 95.158044 -241.17119) (xy 95.165939 -241.219767) (xy 95.166434 -241.244374) (xy 95.484691 -241.244374)
			(xy 95.488786 -241.193646) (xy 95.500965 -241.144232) (xy 95.520913 -241.097412) (xy 95.548114 -241.054398)
			(xy 95.581862 -241.016304) (xy 95.621284 -240.984117) (xy 95.665358 -240.958671) (xy 95.712944 -240.940624)
			(xy 95.762808 -240.930444) (xy 95.81366 -240.928395) (xy 95.864181 -240.934529) (xy 95.913065 -240.948689)
			(xy 95.959044 -240.970506) (xy 96.000928 -240.999416) (xy 96.037632 -241.034671) (xy 96.068205 -241.075357)
			(xy 96.091856 -241.12042) (xy 96.107972 -241.168694) (xy 96.116136 -241.218928) (xy 96.116648 -241.244374)
			(xy 96.116136 -241.26982) (xy 96.107972 -241.320054) (xy 96.091856 -241.368328) (xy 96.068205 -241.413391)
			(xy 96.037632 -241.454077) (xy 96.000928 -241.489332) (xy 95.959044 -241.518242) (xy 95.913065 -241.540059)
			(xy 95.864181 -241.554219) (xy 95.81366 -241.560353) (xy 95.762808 -241.558304) (xy 95.712944 -241.548124)
			(xy 95.665358 -241.530077) (xy 95.621284 -241.504631) (xy 95.581862 -241.472444) (xy 95.548114 -241.43435)
			(xy 95.520913 -241.391336) (xy 95.500965 -241.344516) (xy 95.488786 -241.295102) (xy 95.484691 -241.244374)
			(xy 95.166434 -241.244374) (xy 95.165939 -241.268981) (xy 95.158044 -241.317558) (xy 95.14246 -241.364239)
			(xy 95.119589 -241.407816) (xy 95.090024 -241.44716) (xy 95.054531 -241.481252) (xy 95.014028 -241.509208)
			(xy 94.969566 -241.530306) (xy 94.922295 -241.543998) (xy 94.87344 -241.54993) (xy 94.824265 -241.547949)
			(xy 94.776046 -241.538105) (xy 94.73003 -241.520653) (xy 94.687409 -241.496046) (xy 94.649288 -241.464921)
			(xy 94.616653 -241.428084) (xy 94.59035 -241.386488) (xy 94.571059 -241.341212) (xy 94.559282 -241.293428)
			(xy 94.555322 -241.244374) (xy 94.236794 -241.244374) (xy 94.236282 -241.26982) (xy 94.228118 -241.320054)
			(xy 94.212002 -241.368328) (xy 94.188351 -241.413391) (xy 94.157778 -241.454077) (xy 94.121074 -241.489332)
			(xy 94.07919 -241.518242) (xy 94.033211 -241.540059) (xy 93.984327 -241.554219) (xy 93.933806 -241.560353)
			(xy 93.882954 -241.558304) (xy 93.83309 -241.548124) (xy 93.785504 -241.530077) (xy 93.74143 -241.504631)
			(xy 93.702008 -241.472444) (xy 93.66826 -241.43435) (xy 93.641059 -241.391336) (xy 93.621111 -241.344516)
			(xy 93.608932 -241.295102) (xy 93.604837 -241.244374) (xy 93.286326 -241.244374) (xy 93.285859 -241.26898)
			(xy 93.277968 -241.317556) (xy 93.262386 -241.364237) (xy 93.239516 -241.407813) (xy 93.209951 -241.447155)
			(xy 93.174457 -241.481245) (xy 93.133954 -241.509198) (xy 93.089491 -241.530291) (xy 93.04222 -241.543978)
			(xy 93.017848 -241.547396) (xy 93.003878 -241.549174) (xy 92.982288 -241.565684) (xy 92.943934 -241.65814)
			(xy 92.940839 -241.666594) (xy 92.940156 -241.684573) (xy 92.94572 -241.701684) (xy 92.951046 -241.70894)
			(xy 92.969876 -241.733614) (xy 93.002557 -241.786383) (xy 93.0292 -241.842445) (xy 93.049478 -241.901109)
			(xy 93.06314 -241.961657) (xy 93.070021 -242.023345) (xy 93.070426 -242.05438) (xy 94.074737 -242.05438)
			(xy 94.078832 -242.003652) (xy 94.091011 -241.954238) (xy 94.110959 -241.907418) (xy 94.13816 -241.864404)
			(xy 94.171908 -241.82631) (xy 94.21133 -241.794123) (xy 94.255404 -241.768677) (xy 94.30299 -241.75063)
			(xy 94.352854 -241.74045) (xy 94.403706 -241.738401) (xy 94.454227 -241.744535) (xy 94.503111 -241.758695)
			(xy 94.54909 -241.780512) (xy 94.590974 -241.809422) (xy 94.627678 -241.844677) (xy 94.658251 -241.885363)
			(xy 94.681902 -241.930426) (xy 94.698018 -241.9787) (xy 94.706182 -242.028934) (xy 94.706694 -242.05438)
			(xy 95.014791 -242.05438) (xy 95.018886 -242.003652) (xy 95.031065 -241.954238) (xy 95.051013 -241.907418)
			(xy 95.078214 -241.864404) (xy 95.111962 -241.82631) (xy 95.151384 -241.794123) (xy 95.195458 -241.768677)
			(xy 95.243044 -241.75063) (xy 95.292908 -241.74045) (xy 95.34376 -241.738401) (xy 95.394281 -241.744535)
			(xy 95.443165 -241.758695) (xy 95.489144 -241.780512) (xy 95.531028 -241.809422) (xy 95.567732 -241.844677)
			(xy 95.598305 -241.885363) (xy 95.621956 -241.930426) (xy 95.638072 -241.9787) (xy 95.646236 -242.028934)
			(xy 95.646748 -242.05438) (xy 95.646236 -242.079826) (xy 95.638072 -242.13006) (xy 95.621956 -242.178334)
			(xy 95.598305 -242.223397) (xy 95.567732 -242.264083) (xy 95.531028 -242.299338) (xy 95.489144 -242.328248)
			(xy 95.443165 -242.350065) (xy 95.394281 -242.364225) (xy 95.34376 -242.370359) (xy 95.292908 -242.36831)
			(xy 95.243044 -242.35813) (xy 95.195458 -242.340083) (xy 95.151384 -242.314637) (xy 95.111962 -242.28245)
			(xy 95.078214 -242.244356) (xy 95.051013 -242.201342) (xy 95.031065 -242.154522) (xy 95.018886 -242.105108)
			(xy 95.014791 -242.05438) (xy 94.706694 -242.05438) (xy 94.706182 -242.079826) (xy 94.698018 -242.13006)
			(xy 94.681902 -242.178334) (xy 94.658251 -242.223397) (xy 94.627678 -242.264083) (xy 94.590974 -242.299338)
			(xy 94.54909 -242.328248) (xy 94.503111 -242.350065) (xy 94.454227 -242.364225) (xy 94.403706 -242.370359)
			(xy 94.352854 -242.36831) (xy 94.30299 -242.35813) (xy 94.255404 -242.340083) (xy 94.21133 -242.314637)
			(xy 94.171908 -242.28245) (xy 94.13816 -242.244356) (xy 94.110959 -242.201342) (xy 94.091011 -242.154522)
			(xy 94.078832 -242.105108) (xy 94.074737 -242.05438) (xy 93.070426 -242.05438) (xy 93.069842 -242.091186)
			(xy 93.060187 -242.164163) (xy 93.04104 -242.235242) (xy 93.012733 -242.303194) (xy 92.994734 -242.335304)
			(xy 92.95003 -242.412266) (xy 92.944254 -242.423479) (xy 92.943335 -242.448655) (xy 92.948252 -242.460272)
			(xy 92.984574 -242.533932) (xy 92.990621 -242.544899) (xy 93.010871 -242.559584) (xy 93.023182 -242.561872)
			(xy 93.047192 -242.565716) (xy 93.093666 -242.580009) (xy 93.137291 -242.601479) (xy 93.176967 -242.629584)
			(xy 93.211694 -242.663616) (xy 93.240597 -242.702715) (xy 93.262946 -242.745897) (xy 93.278177 -242.792072)
			(xy 93.285907 -242.840075) (xy 93.286326 -242.864386) (xy 93.604837 -242.864386) (xy 93.608932 -242.813658)
			(xy 93.621111 -242.764244) (xy 93.641059 -242.717424) (xy 93.66826 -242.67441) (xy 93.702008 -242.636316)
			(xy 93.74143 -242.604129) (xy 93.785504 -242.578683) (xy 93.83309 -242.560636) (xy 93.882954 -242.550456)
			(xy 93.933806 -242.548407) (xy 93.984327 -242.554541) (xy 94.033211 -242.568701) (xy 94.07919 -242.590518)
			(xy 94.121074 -242.619428) (xy 94.157778 -242.654683) (xy 94.188351 -242.695369) (xy 94.212002 -242.740432)
			(xy 94.228118 -242.788706) (xy 94.236282 -242.83894) (xy 94.236794 -242.864386) (xy 94.555322 -242.864386)
			(xy 94.559282 -242.815332) (xy 94.571059 -242.767548) (xy 94.59035 -242.722272) (xy 94.616653 -242.680676)
			(xy 94.649288 -242.643839) (xy 94.687409 -242.612714) (xy 94.73003 -242.588107) (xy 94.776046 -242.570655)
			(xy 94.824265 -242.560811) (xy 94.87344 -242.55883) (xy 94.922295 -242.564762) (xy 94.969566 -242.578454)
			(xy 95.014028 -242.599552) (xy 95.054531 -242.627508) (xy 95.090024 -242.6616) (xy 95.119589 -242.700944)
			(xy 95.14246 -242.744521) (xy 95.158044 -242.791202) (xy 95.165939 -242.839779) (xy 95.166434 -242.864386)
			(xy 95.484691 -242.864386) (xy 95.488786 -242.813658) (xy 95.500965 -242.764244) (xy 95.520913 -242.717424)
			(xy 95.548114 -242.67441) (xy 95.581862 -242.636316) (xy 95.621284 -242.604129) (xy 95.665358 -242.578683)
			(xy 95.712944 -242.560636) (xy 95.762808 -242.550456) (xy 95.81366 -242.548407) (xy 95.864181 -242.554541)
			(xy 95.913065 -242.568701) (xy 95.959044 -242.590518) (xy 96.000928 -242.619428) (xy 96.037632 -242.654683)
			(xy 96.068205 -242.695369) (xy 96.091856 -242.740432) (xy 96.107972 -242.788706) (xy 96.116136 -242.83894)
			(xy 96.116648 -242.864386) (xy 96.116136 -242.889832) (xy 96.107972 -242.940066) (xy 96.091856 -242.98834)
			(xy 96.068205 -243.033403) (xy 96.037632 -243.074089) (xy 96.000928 -243.109344) (xy 95.959044 -243.138254)
			(xy 95.913065 -243.160071) (xy 95.864181 -243.174231) (xy 95.81366 -243.180365) (xy 95.762808 -243.178316)
			(xy 95.712944 -243.168136) (xy 95.665358 -243.150089) (xy 95.621284 -243.124643) (xy 95.581862 -243.092456)
			(xy 95.548114 -243.054362) (xy 95.520913 -243.011348) (xy 95.500965 -242.964528) (xy 95.488786 -242.915114)
			(xy 95.484691 -242.864386) (xy 95.166434 -242.864386) (xy 95.165939 -242.888993) (xy 95.158044 -242.93757)
			(xy 95.14246 -242.984251) (xy 95.119589 -243.027828) (xy 95.090024 -243.067172) (xy 95.054531 -243.101264)
			(xy 95.014028 -243.12922) (xy 94.969566 -243.150318) (xy 94.922295 -243.16401) (xy 94.87344 -243.169942)
			(xy 94.824265 -243.167961) (xy 94.776046 -243.158117) (xy 94.73003 -243.140665) (xy 94.687409 -243.116058)
			(xy 94.649288 -243.084933) (xy 94.616653 -243.048096) (xy 94.59035 -243.0065) (xy 94.571059 -242.961224)
			(xy 94.559282 -242.91344) (xy 94.555322 -242.864386) (xy 94.236794 -242.864386) (xy 94.236282 -242.889832)
			(xy 94.228118 -242.940066) (xy 94.212002 -242.98834) (xy 94.188351 -243.033403) (xy 94.157778 -243.074089)
			(xy 94.121074 -243.109344) (xy 94.07919 -243.138254) (xy 94.033211 -243.160071) (xy 93.984327 -243.174231)
			(xy 93.933806 -243.180365) (xy 93.882954 -243.178316) (xy 93.83309 -243.168136) (xy 93.785504 -243.150089)
			(xy 93.74143 -243.124643) (xy 93.702008 -243.092456) (xy 93.66826 -243.054362) (xy 93.641059 -243.011348)
			(xy 93.621111 -242.964528) (xy 93.608932 -242.915114) (xy 93.604837 -242.864386) (xy 93.286326 -242.864386)
			(xy 93.285858 -242.888992) (xy 93.277966 -242.937566) (xy 93.262382 -242.984245) (xy 93.239512 -243.027819)
			(xy 93.209947 -243.06716) (xy 93.174453 -243.101248) (xy 93.133951 -243.1292) (xy 93.089488 -243.150292)
			(xy 93.042218 -243.163978) (xy 93.017848 -243.167408) (xy 93.003878 -243.169186) (xy 92.982288 -243.185696)
			(xy 92.9386 -243.290852) (xy 92.94241 -243.318284) (xy 92.951046 -243.328952) (xy 92.97552 -243.361431)
			(xy 93.015817 -243.432067) (xy 93.03131 -243.469668) (xy 93.03639 -243.482622) (xy 93.05798 -243.49964)
			(xy 93.171772 -243.514626) (xy 93.197172 -243.503704) (xy 93.205554 -243.492782) (xy 93.220054 -243.473948)
			(xy 93.253904 -243.440583) (xy 93.292516 -243.412866) (xy 93.334956 -243.391467) (xy 93.3802 -243.376903)
			(xy 93.427153 -243.369525) (xy 93.450918 -243.369084) (xy 93.474909 -243.369556) (xy 93.522299 -243.377064)
			(xy 93.567931 -243.391893) (xy 93.610681 -243.413678) (xy 93.649498 -243.441881) (xy 93.683425 -243.475809)
			(xy 93.711628 -243.514627) (xy 93.733411 -243.557379) (xy 93.748238 -243.603011) (xy 93.755745 -243.650401)
			(xy 93.756226 -243.674392) (xy 94.074737 -243.674392) (xy 94.078832 -243.623664) (xy 94.091011 -243.57425)
			(xy 94.110959 -243.52743) (xy 94.13816 -243.484416) (xy 94.171908 -243.446322) (xy 94.21133 -243.414135)
			(xy 94.255404 -243.388689) (xy 94.30299 -243.370642) (xy 94.352854 -243.360462) (xy 94.403706 -243.358413)
			(xy 94.454227 -243.364547) (xy 94.503111 -243.378707) (xy 94.54909 -243.400524) (xy 94.590974 -243.429434)
			(xy 94.627678 -243.464689) (xy 94.658251 -243.505375) (xy 94.681902 -243.550438) (xy 94.698018 -243.598712)
			(xy 94.706182 -243.648946) (xy 94.706694 -243.674392) (xy 95.014791 -243.674392) (xy 95.018886 -243.623664)
			(xy 95.031065 -243.57425) (xy 95.051013 -243.52743) (xy 95.078214 -243.484416) (xy 95.111962 -243.446322)
			(xy 95.151384 -243.414135) (xy 95.195458 -243.388689) (xy 95.243044 -243.370642) (xy 95.292908 -243.360462)
			(xy 95.34376 -243.358413) (xy 95.394281 -243.364547) (xy 95.443165 -243.378707) (xy 95.489144 -243.400524)
			(xy 95.531028 -243.429434) (xy 95.567732 -243.464689) (xy 95.598305 -243.505375) (xy 95.621956 -243.550438)
			(xy 95.638072 -243.598712) (xy 95.646236 -243.648946) (xy 95.646748 -243.674392) (xy 95.646236 -243.699838)
			(xy 95.638072 -243.750072) (xy 95.621956 -243.798346) (xy 95.598305 -243.843409) (xy 95.567732 -243.884095)
			(xy 95.531028 -243.91935) (xy 95.489144 -243.94826) (xy 95.443165 -243.970077) (xy 95.394281 -243.984237)
			(xy 95.34376 -243.990371) (xy 95.292908 -243.988322) (xy 95.243044 -243.978142) (xy 95.195458 -243.960095)
			(xy 95.151384 -243.934649) (xy 95.111962 -243.902462) (xy 95.078214 -243.864368) (xy 95.051013 -243.821354)
			(xy 95.031065 -243.774534) (xy 95.018886 -243.72512) (xy 95.014791 -243.674392) (xy 94.706694 -243.674392)
			(xy 94.706182 -243.699838) (xy 94.698018 -243.750072) (xy 94.681902 -243.798346) (xy 94.658251 -243.843409)
			(xy 94.627678 -243.884095) (xy 94.590974 -243.91935) (xy 94.54909 -243.94826) (xy 94.503111 -243.970077)
			(xy 94.454227 -243.984237) (xy 94.403706 -243.990371) (xy 94.352854 -243.988322) (xy 94.30299 -243.978142)
			(xy 94.255404 -243.960095) (xy 94.21133 -243.934649) (xy 94.171908 -243.902462) (xy 94.13816 -243.864368)
			(xy 94.110959 -243.821354) (xy 94.091011 -243.774534) (xy 94.078832 -243.72512) (xy 94.074737 -243.674392)
			(xy 93.756226 -243.674392) (xy 93.755754 -243.698627) (xy 93.748085 -243.746486) (xy 93.732952 -243.792533)
			(xy 93.710737 -243.835612) (xy 93.681997 -243.874642) (xy 93.647453 -243.908642) (xy 93.607973 -243.93676)
			(xy 93.564547 -243.95829) (xy 93.518266 -243.972691) (xy 93.494352 -243.976652) (xy 93.481906 -243.97843)
			(xy 93.450918 -243.979954) (xy 93.427136 -243.979502) (xy 93.380146 -243.972135) (xy 93.334865 -243.957575)
			(xy 93.292387 -243.936175) (xy 93.253739 -243.90845) (xy 93.219853 -243.875072) (xy 93.2053 -243.856256)
			(xy 93.196918 -243.84508) (xy 93.171518 -243.834158) (xy 93.05798 -243.849144) (xy 93.03639 -243.866162)
			(xy 93.03131 -243.879116) (xy 93.023438 -243.898751) (xy 93.005132 -243.936893) (xy 92.994734 -243.955316)
			(xy 92.84589 -244.211602) (xy 92.826207 -244.244218) (xy 92.779302 -244.304246) (xy 92.752418 -244.331236)
			(xy 92.752164 -244.33149) (xy 92.747084 -244.33657) (xy 92.733622 -244.359684) (xy 92.731844 -244.366542)
			(xy 92.721612 -244.403808) (xy 92.692295 -244.475312) (xy 92.687211 -244.484398) (xy 93.604837 -244.484398)
			(xy 93.608932 -244.43367) (xy 93.621111 -244.384256) (xy 93.641059 -244.337436) (xy 93.66826 -244.294422)
			(xy 93.702008 -244.256328) (xy 93.74143 -244.224141) (xy 93.785504 -244.198695) (xy 93.83309 -244.180648)
			(xy 93.882954 -244.170468) (xy 93.933806 -244.168419) (xy 93.984327 -244.174553) (xy 94.033211 -244.188713)
			(xy 94.07919 -244.21053) (xy 94.121074 -244.23944) (xy 94.157778 -244.274695) (xy 94.188351 -244.315381)
			(xy 94.212002 -244.360444) (xy 94.228118 -244.408718) (xy 94.236282 -244.458952) (xy 94.236794 -244.484398)
			(xy 94.555322 -244.484398) (xy 94.559282 -244.435344) (xy 94.571059 -244.38756) (xy 94.59035 -244.342284)
			(xy 94.616653 -244.300688) (xy 94.649288 -244.263851) (xy 94.687409 -244.232726) (xy 94.73003 -244.208119)
			(xy 94.776046 -244.190667) (xy 94.824265 -244.180823) (xy 94.87344 -244.178842) (xy 94.922295 -244.184774)
			(xy 94.969566 -244.198466) (xy 95.014028 -244.219564) (xy 95.054531 -244.24752) (xy 95.090024 -244.281612)
			(xy 95.119589 -244.320956) (xy 95.14246 -244.364533) (xy 95.158044 -244.411214) (xy 95.165939 -244.459791)
			(xy 95.166434 -244.484398) (xy 95.484691 -244.484398) (xy 95.488786 -244.43367) (xy 95.500965 -244.384256)
			(xy 95.520913 -244.337436) (xy 95.548114 -244.294422) (xy 95.581862 -244.256328) (xy 95.621284 -244.224141)
			(xy 95.665358 -244.198695) (xy 95.712944 -244.180648) (xy 95.762808 -244.170468) (xy 95.81366 -244.168419)
			(xy 95.864181 -244.174553) (xy 95.913065 -244.188713) (xy 95.959044 -244.21053) (xy 96.000928 -244.23944)
			(xy 96.037632 -244.274695) (xy 96.068205 -244.315381) (xy 96.091856 -244.360444) (xy 96.107972 -244.408718)
			(xy 96.116136 -244.458952) (xy 96.116648 -244.484398) (xy 96.116136 -244.509844) (xy 96.107972 -244.560078)
			(xy 96.091856 -244.608352) (xy 96.068205 -244.653415) (xy 96.037632 -244.694101) (xy 96.000928 -244.729356)
			(xy 95.959044 -244.758266) (xy 95.913065 -244.780083) (xy 95.864181 -244.794243) (xy 95.81366 -244.800377)
			(xy 95.762808 -244.798328) (xy 95.712944 -244.788148) (xy 95.665358 -244.770101) (xy 95.621284 -244.744655)
			(xy 95.581862 -244.712468) (xy 95.548114 -244.674374) (xy 95.520913 -244.63136) (xy 95.500965 -244.58454)
			(xy 95.488786 -244.535126) (xy 95.484691 -244.484398) (xy 95.166434 -244.484398) (xy 95.165939 -244.509005)
			(xy 95.158044 -244.557582) (xy 95.14246 -244.604263) (xy 95.119589 -244.64784) (xy 95.090024 -244.687184)
			(xy 95.054531 -244.721276) (xy 95.014028 -244.749232) (xy 94.969566 -244.77033) (xy 94.922295 -244.784022)
			(xy 94.87344 -244.789954) (xy 94.824265 -244.787973) (xy 94.776046 -244.778129) (xy 94.73003 -244.760677)
			(xy 94.687409 -244.73607) (xy 94.649288 -244.704945) (xy 94.616653 -244.668108) (xy 94.59035 -244.626512)
			(xy 94.571059 -244.581236) (xy 94.559282 -244.533452) (xy 94.555322 -244.484398) (xy 94.236794 -244.484398)
			(xy 94.236282 -244.509844) (xy 94.228118 -244.560078) (xy 94.212002 -244.608352) (xy 94.188351 -244.653415)
			(xy 94.157778 -244.694101) (xy 94.121074 -244.729356) (xy 94.07919 -244.758266) (xy 94.033211 -244.780083)
			(xy 93.984327 -244.794243) (xy 93.933806 -244.800377) (xy 93.882954 -244.798328) (xy 93.83309 -244.788148)
			(xy 93.785504 -244.770101) (xy 93.74143 -244.744655) (xy 93.702008 -244.712468) (xy 93.66826 -244.674374)
			(xy 93.641059 -244.63136) (xy 93.621111 -244.58454) (xy 93.608932 -244.535126) (xy 93.604837 -244.484398)
			(xy 92.687211 -244.484398) (xy 92.673424 -244.509036) (xy 92.593922 -244.645942) (xy 92.59078 -244.65182)
			(xy 92.587309 -244.664682) (xy 92.587064 -244.671342) (xy 92.587064 -244.697758) (xy 92.58742 -244.706445)
			(xy 92.593281 -244.722801) (xy 92.598494 -244.729762) (xy 92.604082 -244.73662) (xy 92.618814 -244.745764)
			(xy 92.62745 -244.747542) (xy 92.661066 -244.755208) (xy 92.726235 -244.777731) (xy 92.788138 -244.808101)
			(xy 92.845833 -244.845857) (xy 92.898445 -244.890425) (xy 92.945173 -244.941129) (xy 92.985306 -244.997196)
			(xy 93.018237 -245.057775) (xy 93.03131 -245.08968) (xy 93.03639 -245.102634) (xy 93.058234 -245.119652)
			(xy 93.171772 -245.134638) (xy 93.197172 -245.123716) (xy 93.205554 -245.112794) (xy 93.220053 -245.093959)
			(xy 93.253903 -245.060593) (xy 93.292515 -245.032875) (xy 93.334955 -245.011475) (xy 93.380199 -244.99691)
			(xy 93.427153 -244.989532) (xy 93.450918 -244.989096) (xy 93.474908 -244.989568) (xy 93.522297 -244.997076)
			(xy 93.567929 -245.011905) (xy 93.610679 -245.03369) (xy 93.649495 -245.061894) (xy 93.683421 -245.095822)
			(xy 93.711622 -245.13464) (xy 93.733403 -245.177392) (xy 93.748229 -245.223024) (xy 93.755734 -245.270414)
			(xy 93.756226 -245.294404) (xy 94.074737 -245.294404) (xy 94.078832 -245.243676) (xy 94.091011 -245.194262)
			(xy 94.110959 -245.147442) (xy 94.13816 -245.104428) (xy 94.171908 -245.066334) (xy 94.21133 -245.034147)
			(xy 94.255404 -245.008701) (xy 94.30299 -244.990654) (xy 94.352854 -244.980474) (xy 94.403706 -244.978425)
			(xy 94.454227 -244.984559) (xy 94.503111 -244.998719) (xy 94.54909 -245.020536) (xy 94.590974 -245.049446)
			(xy 94.627678 -245.084701) (xy 94.658251 -245.125387) (xy 94.681902 -245.17045) (xy 94.698018 -245.218724)
			(xy 94.706182 -245.268958) (xy 94.706694 -245.294404) (xy 95.014791 -245.294404) (xy 95.018886 -245.243676)
			(xy 95.031065 -245.194262) (xy 95.051013 -245.147442) (xy 95.078214 -245.104428) (xy 95.111962 -245.066334)
			(xy 95.151384 -245.034147) (xy 95.195458 -245.008701) (xy 95.243044 -244.990654) (xy 95.292908 -244.980474)
			(xy 95.34376 -244.978425) (xy 95.394281 -244.984559) (xy 95.443165 -244.998719) (xy 95.489144 -245.020536)
			(xy 95.531028 -245.049446) (xy 95.567732 -245.084701) (xy 95.598305 -245.125387) (xy 95.621956 -245.17045)
			(xy 95.638072 -245.218724) (xy 95.646236 -245.268958) (xy 95.646748 -245.294404) (xy 95.646236 -245.31985)
			(xy 95.638072 -245.370084) (xy 95.621956 -245.418358) (xy 95.598305 -245.463421) (xy 95.567732 -245.504107)
			(xy 95.531028 -245.539362) (xy 95.489144 -245.568272) (xy 95.443165 -245.590089) (xy 95.394281 -245.604249)
			(xy 95.34376 -245.610383) (xy 95.292908 -245.608334) (xy 95.243044 -245.598154) (xy 95.195458 -245.580107)
			(xy 95.151384 -245.554661) (xy 95.111962 -245.522474) (xy 95.078214 -245.48438) (xy 95.051013 -245.441366)
			(xy 95.031065 -245.394546) (xy 95.018886 -245.345132) (xy 95.014791 -245.294404) (xy 94.706694 -245.294404)
			(xy 94.706182 -245.31985) (xy 94.698018 -245.370084) (xy 94.681902 -245.418358) (xy 94.658251 -245.463421)
			(xy 94.627678 -245.504107) (xy 94.590974 -245.539362) (xy 94.54909 -245.568272) (xy 94.503111 -245.590089)
			(xy 94.454227 -245.604249) (xy 94.403706 -245.610383) (xy 94.352854 -245.608334) (xy 94.30299 -245.598154)
			(xy 94.255404 -245.580107) (xy 94.21133 -245.554661) (xy 94.171908 -245.522474) (xy 94.13816 -245.48438)
			(xy 94.110959 -245.441366) (xy 94.091011 -245.394546) (xy 94.078832 -245.345132) (xy 94.074737 -245.294404)
			(xy 93.756226 -245.294404) (xy 93.755761 -245.318643) (xy 93.748102 -245.366512) (xy 93.732978 -245.412571)
			(xy 93.710768 -245.455662) (xy 93.68203 -245.494704) (xy 93.647485 -245.528715) (xy 93.608002 -245.556843)
			(xy 93.564571 -245.578381) (xy 93.518283 -245.592787) (xy 93.494352 -245.596664) (xy 93.481906 -245.598442)
			(xy 93.450918 -245.599966) (xy 93.427136 -245.599514) (xy 93.380145 -245.592147) (xy 93.334864 -245.577588)
			(xy 93.292386 -245.556188) (xy 93.253736 -245.528464) (xy 93.219849 -245.495087) (xy 93.2053 -245.476268)
			(xy 93.196918 -245.465092) (xy 93.171518 -245.45417) (xy 93.05798 -245.469156) (xy 93.03639 -245.486174)
			(xy 93.03131 -245.499128) (xy 93.023438 -245.518763) (xy 93.005131 -245.556905) (xy 92.994734 -245.575328)
			(xy 92.95003 -245.65229) (xy 92.944235 -245.663503) (xy 92.943282 -245.688696) (xy 92.948252 -245.700296)
			(xy 92.984574 -245.773956) (xy 92.990624 -245.784919) (xy 93.010875 -245.799596) (xy 93.023182 -245.801896)
			(xy 93.047191 -245.80574) (xy 93.093663 -245.820034) (xy 93.137286 -245.841505) (xy 93.176961 -245.86961)
			(xy 93.211685 -245.903642) (xy 93.240585 -245.942741) (xy 93.262931 -245.985923) (xy 93.278159 -246.032097)
			(xy 93.285886 -246.0801) (xy 93.286326 -246.10441) (xy 93.604837 -246.10441) (xy 93.608932 -246.053682)
			(xy 93.621111 -246.004268) (xy 93.641059 -245.957448) (xy 93.66826 -245.914434) (xy 93.702008 -245.87634)
			(xy 93.74143 -245.844153) (xy 93.785504 -245.818707) (xy 93.83309 -245.80066) (xy 93.882954 -245.79048)
			(xy 93.933806 -245.788431) (xy 93.984327 -245.794565) (xy 94.033211 -245.808725) (xy 94.07919 -245.830542)
			(xy 94.121074 -245.859452) (xy 94.157778 -245.894707) (xy 94.188351 -245.935393) (xy 94.212002 -245.980456)
			(xy 94.228118 -246.02873) (xy 94.236282 -246.078964) (xy 94.236794 -246.10441) (xy 94.555322 -246.10441)
			(xy 94.559282 -246.055356) (xy 94.571059 -246.007572) (xy 94.59035 -245.962296) (xy 94.616653 -245.9207)
			(xy 94.649288 -245.883863) (xy 94.687409 -245.852738) (xy 94.73003 -245.828131) (xy 94.776046 -245.810679)
			(xy 94.824265 -245.800835) (xy 94.87344 -245.798854) (xy 94.922295 -245.804786) (xy 94.969566 -245.818478)
			(xy 95.014028 -245.839576) (xy 95.054531 -245.867532) (xy 95.090024 -245.901624) (xy 95.119589 -245.940968)
			(xy 95.14246 -245.984545) (xy 95.158044 -246.031226) (xy 95.165939 -246.079803) (xy 95.166434 -246.10441)
			(xy 95.484691 -246.10441) (xy 95.488786 -246.053682) (xy 95.500965 -246.004268) (xy 95.520913 -245.957448)
			(xy 95.548114 -245.914434) (xy 95.581862 -245.87634) (xy 95.621284 -245.844153) (xy 95.665358 -245.818707)
			(xy 95.712944 -245.80066) (xy 95.762808 -245.79048) (xy 95.81366 -245.788431) (xy 95.864181 -245.794565)
			(xy 95.913065 -245.808725) (xy 95.959044 -245.830542) (xy 96.000928 -245.859452) (xy 96.037632 -245.894707)
			(xy 96.068205 -245.935393) (xy 96.091856 -245.980456) (xy 96.107972 -246.02873) (xy 96.116136 -246.078964)
			(xy 96.116648 -246.10441) (xy 96.116136 -246.129856) (xy 96.107972 -246.18009) (xy 96.091856 -246.228364)
			(xy 96.068205 -246.273427) (xy 96.037632 -246.314113) (xy 96.000928 -246.349368) (xy 95.959044 -246.378278)
			(xy 95.913065 -246.400095) (xy 95.864181 -246.414255) (xy 95.81366 -246.420389) (xy 95.762808 -246.41834)
			(xy 95.712944 -246.40816) (xy 95.665358 -246.390113) (xy 95.621284 -246.364667) (xy 95.581862 -246.33248)
			(xy 95.548114 -246.294386) (xy 95.520913 -246.251372) (xy 95.500965 -246.204552) (xy 95.488786 -246.155138)
			(xy 95.484691 -246.10441) (xy 95.166434 -246.10441) (xy 95.165939 -246.129017) (xy 95.158044 -246.177594)
			(xy 95.14246 -246.224275) (xy 95.119589 -246.267852) (xy 95.090024 -246.307196) (xy 95.054531 -246.341288)
			(xy 95.014028 -246.369244) (xy 94.969566 -246.390342) (xy 94.922295 -246.404034) (xy 94.87344 -246.409966)
			(xy 94.824265 -246.407985) (xy 94.776046 -246.398141) (xy 94.73003 -246.380689) (xy 94.687409 -246.356082)
			(xy 94.649288 -246.324957) (xy 94.616653 -246.28812) (xy 94.59035 -246.246524) (xy 94.571059 -246.201248)
			(xy 94.559282 -246.153464) (xy 94.555322 -246.10441) (xy 94.236794 -246.10441) (xy 94.236282 -246.129856)
			(xy 94.228118 -246.18009) (xy 94.212002 -246.228364) (xy 94.188351 -246.273427) (xy 94.157778 -246.314113)
			(xy 94.121074 -246.349368) (xy 94.07919 -246.378278) (xy 94.033211 -246.400095) (xy 93.984327 -246.414255)
			(xy 93.933806 -246.420389) (xy 93.882954 -246.41834) (xy 93.83309 -246.40816) (xy 93.785504 -246.390113)
			(xy 93.74143 -246.364667) (xy 93.702008 -246.33248) (xy 93.66826 -246.294386) (xy 93.641059 -246.251372)
			(xy 93.621111 -246.204552) (xy 93.608932 -246.155138) (xy 93.604837 -246.10441) (xy 93.286326 -246.10441)
			(xy 93.285864 -246.12902) (xy 93.277981 -246.177603) (xy 93.262405 -246.224292) (xy 93.239538 -246.267877)
			(xy 93.209975 -246.307228) (xy 93.17448 -246.341326) (xy 93.133975 -246.369286) (xy 93.089507 -246.390385)
			(xy 93.042231 -246.404076) (xy 93.017848 -246.407432) (xy 93.003878 -246.40921) (xy 92.982288 -246.42572)
			(xy 92.943934 -246.518176) (xy 92.940846 -246.526629) (xy 92.940175 -246.544602) (xy 92.945747 -246.561703)
			(xy 92.951046 -246.568976) (xy 92.969874 -246.59365) (xy 93.002552 -246.646421) (xy 93.029192 -246.702482)
			(xy 93.049465 -246.761147) (xy 93.063124 -246.821695) (xy 93.07 -246.883382) (xy 93.070426 -246.914416)
			(xy 94.074737 -246.914416) (xy 94.078832 -246.863688) (xy 94.091011 -246.814274) (xy 94.110959 -246.767454)
			(xy 94.13816 -246.72444) (xy 94.171908 -246.686346) (xy 94.21133 -246.654159) (xy 94.255404 -246.628713)
			(xy 94.30299 -246.610666) (xy 94.352854 -246.600486) (xy 94.403706 -246.598437) (xy 94.454227 -246.604571)
			(xy 94.503111 -246.618731) (xy 94.54909 -246.640548) (xy 94.590974 -246.669458) (xy 94.627678 -246.704713)
			(xy 94.658251 -246.745399) (xy 94.681902 -246.790462) (xy 94.698018 -246.838736) (xy 94.706182 -246.88897)
			(xy 94.706694 -246.914416) (xy 95.014791 -246.914416) (xy 95.018886 -246.863688) (xy 95.031065 -246.814274)
			(xy 95.051013 -246.767454) (xy 95.078214 -246.72444) (xy 95.111962 -246.686346) (xy 95.151384 -246.654159)
			(xy 95.195458 -246.628713) (xy 95.243044 -246.610666) (xy 95.292908 -246.600486) (xy 95.34376 -246.598437)
			(xy 95.394281 -246.604571) (xy 95.443165 -246.618731) (xy 95.489144 -246.640548) (xy 95.531028 -246.669458)
			(xy 95.567732 -246.704713) (xy 95.598305 -246.745399) (xy 95.621956 -246.790462) (xy 95.638072 -246.838736)
			(xy 95.646236 -246.88897) (xy 95.646748 -246.914416) (xy 95.646236 -246.939862) (xy 95.638072 -246.990096)
			(xy 95.621956 -247.03837) (xy 95.598305 -247.083433) (xy 95.567732 -247.124119) (xy 95.531028 -247.159374)
			(xy 95.489144 -247.188284) (xy 95.443165 -247.210101) (xy 95.394281 -247.224261) (xy 95.34376 -247.230395)
			(xy 95.292908 -247.228346) (xy 95.243044 -247.218166) (xy 95.195458 -247.200119) (xy 95.151384 -247.174673)
			(xy 95.111962 -247.142486) (xy 95.078214 -247.104392) (xy 95.051013 -247.061378) (xy 95.031065 -247.014558)
			(xy 95.018886 -246.965144) (xy 95.014791 -246.914416) (xy 94.706694 -246.914416) (xy 94.706182 -246.939862)
			(xy 94.698018 -246.990096) (xy 94.681902 -247.03837) (xy 94.658251 -247.083433) (xy 94.627678 -247.124119)
			(xy 94.590974 -247.159374) (xy 94.54909 -247.188284) (xy 94.503111 -247.210101) (xy 94.454227 -247.224261)
			(xy 94.403706 -247.230395) (xy 94.352854 -247.228346) (xy 94.30299 -247.218166) (xy 94.255404 -247.200119)
			(xy 94.21133 -247.174673) (xy 94.171908 -247.142486) (xy 94.13816 -247.104392) (xy 94.110959 -247.061378)
			(xy 94.091011 -247.014558) (xy 94.078832 -246.965144) (xy 94.074737 -246.914416) (xy 93.070426 -246.914416)
			(xy 93.06984 -246.951222) (xy 93.06018 -247.024196) (xy 93.041029 -247.095273) (xy 93.012719 -247.163223)
			(xy 92.994734 -247.19534) (xy 92.95003 -247.272302) (xy 92.944238 -247.283515) (xy 92.94329 -247.308705)
			(xy 92.948252 -247.320308) (xy 92.984574 -247.393968) (xy 92.990626 -247.40493) (xy 93.010876 -247.419603)
			(xy 93.023182 -247.421908) (xy 93.047191 -247.425752) (xy 93.093662 -247.440046) (xy 93.137284 -247.461517)
			(xy 93.176957 -247.489623) (xy 93.211681 -247.523655) (xy 93.240579 -247.562754) (xy 93.262923 -247.605936)
			(xy 93.27815 -247.65211) (xy 93.285875 -247.700112) (xy 93.286326 -247.724422) (xy 93.604837 -247.724422)
			(xy 93.608932 -247.673694) (xy 93.621111 -247.62428) (xy 93.641059 -247.57746) (xy 93.66826 -247.534446)
			(xy 93.702008 -247.496352) (xy 93.74143 -247.464165) (xy 93.785504 -247.438719) (xy 93.83309 -247.420672)
			(xy 93.882954 -247.410492) (xy 93.933806 -247.408443) (xy 93.984327 -247.414577) (xy 94.033211 -247.428737)
			(xy 94.07919 -247.450554) (xy 94.121074 -247.479464) (xy 94.157778 -247.514719) (xy 94.188351 -247.555405)
			(xy 94.212002 -247.600468) (xy 94.228118 -247.648742) (xy 94.236282 -247.698976) (xy 94.236794 -247.724422)
			(xy 94.555322 -247.724422) (xy 94.559282 -247.675368) (xy 94.571059 -247.627584) (xy 94.59035 -247.582308)
			(xy 94.616653 -247.540712) (xy 94.649288 -247.503875) (xy 94.687409 -247.47275) (xy 94.73003 -247.448143)
			(xy 94.776046 -247.430691) (xy 94.824265 -247.420847) (xy 94.87344 -247.418866) (xy 94.922295 -247.424798)
			(xy 94.969566 -247.43849) (xy 95.014028 -247.459588) (xy 95.054531 -247.487544) (xy 95.090024 -247.521636)
			(xy 95.119589 -247.56098) (xy 95.14246 -247.604557) (xy 95.158044 -247.651238) (xy 95.165939 -247.699815)
			(xy 95.166434 -247.724422) (xy 95.484691 -247.724422) (xy 95.488786 -247.673694) (xy 95.500965 -247.62428)
			(xy 95.520913 -247.57746) (xy 95.548114 -247.534446) (xy 95.581862 -247.496352) (xy 95.621284 -247.464165)
			(xy 95.665358 -247.438719) (xy 95.712944 -247.420672) (xy 95.762808 -247.410492) (xy 95.81366 -247.408443)
			(xy 95.864181 -247.414577) (xy 95.913065 -247.428737) (xy 95.959044 -247.450554) (xy 96.000928 -247.479464)
			(xy 96.037632 -247.514719) (xy 96.068205 -247.555405) (xy 96.091856 -247.600468) (xy 96.107972 -247.648742)
			(xy 96.116136 -247.698976) (xy 96.116648 -247.724422) (xy 96.116136 -247.749868) (xy 96.107972 -247.800102)
			(xy 96.091856 -247.848376) (xy 96.068205 -247.893439) (xy 96.037632 -247.934125) (xy 96.000928 -247.96938)
			(xy 95.959044 -247.99829) (xy 95.913065 -248.020107) (xy 95.864181 -248.034267) (xy 95.81366 -248.040401)
			(xy 95.762808 -248.038352) (xy 95.712944 -248.028172) (xy 95.665358 -248.010125) (xy 95.621284 -247.984679)
			(xy 95.581862 -247.952492) (xy 95.548114 -247.914398) (xy 95.520913 -247.871384) (xy 95.500965 -247.824564)
			(xy 95.488786 -247.77515) (xy 95.484691 -247.724422) (xy 95.166434 -247.724422) (xy 95.165939 -247.749029)
			(xy 95.158044 -247.797606) (xy 95.14246 -247.844287) (xy 95.119589 -247.887864) (xy 95.090024 -247.927208)
			(xy 95.054531 -247.9613) (xy 95.014028 -247.989256) (xy 94.969566 -248.010354) (xy 94.922295 -248.024046)
			(xy 94.87344 -248.029978) (xy 94.824265 -248.027997) (xy 94.776046 -248.018153) (xy 94.73003 -248.000701)
			(xy 94.687409 -247.976094) (xy 94.649288 -247.944969) (xy 94.616653 -247.908132) (xy 94.59035 -247.866536)
			(xy 94.571059 -247.82126) (xy 94.559282 -247.773476) (xy 94.555322 -247.724422) (xy 94.236794 -247.724422)
			(xy 94.236282 -247.749868) (xy 94.228118 -247.800102) (xy 94.212002 -247.848376) (xy 94.188351 -247.893439)
			(xy 94.157778 -247.934125) (xy 94.121074 -247.96938) (xy 94.07919 -247.99829) (xy 94.033211 -248.020107)
			(xy 93.984327 -248.034267) (xy 93.933806 -248.040401) (xy 93.882954 -248.038352) (xy 93.83309 -248.028172)
			(xy 93.785504 -248.010125) (xy 93.74143 -247.984679) (xy 93.702008 -247.952492) (xy 93.66826 -247.914398)
			(xy 93.641059 -247.871384) (xy 93.621111 -247.824564) (xy 93.608932 -247.77515) (xy 93.604837 -247.724422)
			(xy 93.286326 -247.724422) (xy 93.285863 -247.749031) (xy 93.277979 -247.797613) (xy 93.262401 -247.844301)
			(xy 93.239534 -247.887884) (xy 93.20997 -247.927233) (xy 93.174476 -247.961329) (xy 93.133971 -247.989289)
			(xy 93.089504 -248.010386) (xy 93.042229 -248.024076) (xy 93.017848 -248.027444) (xy 93.003878 -248.029222)
			(xy 92.982288 -248.045732) (xy 92.9386 -248.150888) (xy 92.94241 -248.17832) (xy 92.951046 -248.188988)
			(xy 92.975518 -248.221468) (xy 93.015811 -248.292106) (xy 93.03131 -248.329704) (xy 93.03639 -248.342658)
			(xy 93.05798 -248.359676) (xy 93.171772 -248.374662) (xy 93.197172 -248.36374) (xy 93.205554 -248.352818)
			(xy 93.220056 -248.333987) (xy 93.253909 -248.300629) (xy 93.292522 -248.272918) (xy 93.334962 -248.251524)
			(xy 93.380203 -248.236963) (xy 93.427155 -248.229587) (xy 93.450918 -248.22912) (xy 93.474909 -248.229568)
			(xy 93.522301 -248.237077) (xy 93.567935 -248.251907) (xy 93.610686 -248.273694) (xy 93.649503 -248.3019)
			(xy 93.68343 -248.335832) (xy 93.71163 -248.374653) (xy 93.73341 -248.417408) (xy 93.748234 -248.463044)
			(xy 93.755736 -248.510437) (xy 93.756226 -248.534428) (xy 94.074737 -248.534428) (xy 94.078832 -248.4837)
			(xy 94.091011 -248.434286) (xy 94.110959 -248.387466) (xy 94.13816 -248.344452) (xy 94.171908 -248.306358)
			(xy 94.21133 -248.274171) (xy 94.255404 -248.248725) (xy 94.30299 -248.230678) (xy 94.352854 -248.220498)
			(xy 94.403706 -248.218449) (xy 94.454227 -248.224583) (xy 94.503111 -248.238743) (xy 94.54909 -248.26056)
			(xy 94.590974 -248.28947) (xy 94.627678 -248.324725) (xy 94.658251 -248.365411) (xy 94.681902 -248.410474)
			(xy 94.698018 -248.458748) (xy 94.706182 -248.508982) (xy 94.706694 -248.534428) (xy 95.014791 -248.534428)
			(xy 95.018886 -248.4837) (xy 95.031065 -248.434286) (xy 95.051013 -248.387466) (xy 95.078214 -248.344452)
			(xy 95.111962 -248.306358) (xy 95.151384 -248.274171) (xy 95.195458 -248.248725) (xy 95.243044 -248.230678)
			(xy 95.292908 -248.220498) (xy 95.34376 -248.218449) (xy 95.394281 -248.224583) (xy 95.443165 -248.238743)
			(xy 95.489144 -248.26056) (xy 95.531028 -248.28947) (xy 95.567732 -248.324725) (xy 95.598305 -248.365411)
			(xy 95.621956 -248.410474) (xy 95.638072 -248.458748) (xy 95.646236 -248.508982) (xy 95.646748 -248.534428)
			(xy 95.646236 -248.559874) (xy 95.638072 -248.610108) (xy 95.621956 -248.658382) (xy 95.598305 -248.703445)
			(xy 95.567732 -248.744131) (xy 95.531028 -248.779386) (xy 95.489144 -248.808296) (xy 95.443165 -248.830113)
			(xy 95.394281 -248.844273) (xy 95.34376 -248.850407) (xy 95.292908 -248.848358) (xy 95.243044 -248.838178)
			(xy 95.195458 -248.820131) (xy 95.151384 -248.794685) (xy 95.111962 -248.762498) (xy 95.078214 -248.724404)
			(xy 95.051013 -248.68139) (xy 95.031065 -248.63457) (xy 95.018886 -248.585156) (xy 95.014791 -248.534428)
			(xy 94.706694 -248.534428) (xy 94.706182 -248.559874) (xy 94.698018 -248.610108) (xy 94.681902 -248.658382)
			(xy 94.658251 -248.703445) (xy 94.627678 -248.744131) (xy 94.590974 -248.779386) (xy 94.54909 -248.808296)
			(xy 94.503111 -248.830113) (xy 94.454227 -248.844273) (xy 94.403706 -248.850407) (xy 94.352854 -248.848358)
			(xy 94.30299 -248.838178) (xy 94.255404 -248.820131) (xy 94.21133 -248.794685) (xy 94.171908 -248.762498)
			(xy 94.13816 -248.724404) (xy 94.110959 -248.68139) (xy 94.091011 -248.63457) (xy 94.078832 -248.585156)
			(xy 94.074737 -248.534428) (xy 93.756226 -248.534428) (xy 93.755759 -248.558666) (xy 93.748097 -248.606532)
			(xy 93.732971 -248.652588) (xy 93.71076 -248.695676) (xy 93.682021 -248.734714) (xy 93.647477 -248.768723)
			(xy 93.607994 -248.796848) (xy 93.564564 -248.818383) (xy 93.518278 -248.832788) (xy 93.494352 -248.836688)
			(xy 93.481906 -248.838466) (xy 93.450918 -248.83999) (xy 93.427136 -248.839538) (xy 93.380145 -248.832172)
			(xy 93.334863 -248.817613) (xy 93.292383 -248.796214) (xy 93.253732 -248.768492) (xy 93.219843 -248.735116)
			(xy 93.2053 -248.716292) (xy 93.196918 -248.705116) (xy 93.171518 -248.694194) (xy 93.05798 -248.70918)
			(xy 93.03639 -248.726198) (xy 93.03131 -248.739152) (xy 93.023437 -248.758787) (xy 93.005129 -248.796928)
			(xy 92.994734 -248.815352) (xy 92.84589 -249.071638) (xy 92.826205 -249.104253) (xy 92.779298 -249.164278)
			(xy 92.752418 -249.191272) (xy 92.752164 -249.191526) (xy 92.747084 -249.196606) (xy 92.733622 -249.21972)
			(xy 92.731844 -249.226578) (xy 92.721616 -249.263846) (xy 92.692306 -249.335353) (xy 92.687221 -249.344434)
			(xy 93.615268 -249.344434) (xy 93.619228 -249.29538) (xy 93.631005 -249.247596) (xy 93.650296 -249.20232)
			(xy 93.676599 -249.160724) (xy 93.709234 -249.123887) (xy 93.747355 -249.092762) (xy 93.789976 -249.068155)
			(xy 93.835992 -249.050703) (xy 93.884211 -249.040859) (xy 93.933386 -249.038878) (xy 93.982241 -249.04481)
			(xy 94.029512 -249.058502) (xy 94.073974 -249.0796) (xy 94.114477 -249.107556) (xy 94.14997 -249.141648)
			(xy 94.179535 -249.180992) (xy 94.202406 -249.224569) (xy 94.21799 -249.27125) (xy 94.225885 -249.319827)
			(xy 94.22638 -249.344434) (xy 94.555322 -249.344434) (xy 94.559282 -249.29538) (xy 94.571059 -249.247596)
			(xy 94.59035 -249.20232) (xy 94.616653 -249.160724) (xy 94.649288 -249.123887) (xy 94.687409 -249.092762)
			(xy 94.73003 -249.068155) (xy 94.776046 -249.050703) (xy 94.824265 -249.040859) (xy 94.87344 -249.038878)
			(xy 94.922295 -249.04481) (xy 94.969566 -249.058502) (xy 95.014028 -249.0796) (xy 95.054531 -249.107556)
			(xy 95.090024 -249.141648) (xy 95.119589 -249.180992) (xy 95.14246 -249.224569) (xy 95.158044 -249.27125)
			(xy 95.165939 -249.319827) (xy 95.166434 -249.344434) (xy 95.165939 -249.369041) (xy 95.158044 -249.417618)
			(xy 95.14246 -249.464299) (xy 95.119589 -249.507876) (xy 95.090024 -249.54722) (xy 95.054531 -249.581312)
			(xy 95.014028 -249.609268) (xy 94.969566 -249.630366) (xy 94.922295 -249.644058) (xy 94.87344 -249.64999)
			(xy 94.824265 -249.648009) (xy 94.776046 -249.638165) (xy 94.73003 -249.620713) (xy 94.687409 -249.596106)
			(xy 94.649288 -249.564981) (xy 94.616653 -249.528144) (xy 94.59035 -249.486548) (xy 94.571059 -249.441272)
			(xy 94.559282 -249.393488) (xy 94.555322 -249.344434) (xy 94.22638 -249.344434) (xy 94.225885 -249.369041)
			(xy 94.21799 -249.417618) (xy 94.202406 -249.464299) (xy 94.179535 -249.507876) (xy 94.14997 -249.54722)
			(xy 94.114477 -249.581312) (xy 94.073974 -249.609268) (xy 94.029512 -249.630366) (xy 93.982241 -249.644058)
			(xy 93.933386 -249.64999) (xy 93.884211 -249.648009) (xy 93.835992 -249.638165) (xy 93.789976 -249.620713)
			(xy 93.747355 -249.596106) (xy 93.709234 -249.564981) (xy 93.676599 -249.528144) (xy 93.650296 -249.486548)
			(xy 93.631005 -249.441272) (xy 93.619228 -249.393488) (xy 93.615268 -249.344434) (xy 92.687221 -249.344434)
			(xy 92.673424 -249.369072) (xy 92.593922 -249.505978) (xy 92.590785 -249.511857) (xy 92.587322 -249.524719)
			(xy 92.587064 -249.531378) (xy 92.587064 -249.557794) (xy 92.58741 -249.566486) (xy 92.593255 -249.582855)
			(xy 92.598494 -249.589798) (xy 92.604082 -249.596656) (xy 92.618814 -249.6058) (xy 92.62745 -249.607578)
			(xy 92.661067 -249.615244) (xy 92.726239 -249.637765) (xy 92.788145 -249.668133) (xy 92.845844 -249.705887)
			(xy 92.89846 -249.750453) (xy 92.945193 -249.801154) (xy 92.985332 -249.857219) (xy 93.01827 -249.917798)
			(xy 93.03131 -249.949716) (xy 93.03639 -249.96267) (xy 93.058234 -249.979688) (xy 93.171772 -249.994674)
			(xy 93.197172 -249.983752) (xy 93.205554 -249.97283) (xy 93.220056 -249.953998) (xy 93.253908 -249.920639)
			(xy 93.292521 -249.892927) (xy 93.334961 -249.871532) (xy 93.380203 -249.85697) (xy 93.427154 -249.849594)
			(xy 93.450918 -249.849132) (xy 93.474909 -249.84958) (xy 93.5223 -249.857089) (xy 93.567933 -249.871919)
			(xy 93.610683 -249.893706) (xy 93.649499 -249.921913) (xy 93.683425 -249.955845) (xy 93.711624 -249.994666)
			(xy 93.733403 -250.037421) (xy 93.748225 -250.083056) (xy 93.755725 -250.130449) (xy 93.756226 -250.15444)
			(xy 94.085168 -250.15444) (xy 94.089128 -250.105386) (xy 94.100905 -250.057602) (xy 94.120196 -250.012326)
			(xy 94.146499 -249.97073) (xy 94.179134 -249.933893) (xy 94.217255 -249.902768) (xy 94.259876 -249.878161)
			(xy 94.305892 -249.860709) (xy 94.354111 -249.850865) (xy 94.403286 -249.848884) (xy 94.452141 -249.854816)
			(xy 94.499412 -249.868508) (xy 94.543874 -249.889606) (xy 94.584377 -249.917562) (xy 94.61987 -249.951654)
			(xy 94.649435 -249.990998) (xy 94.672306 -250.034575) (xy 94.68789 -250.081256) (xy 94.695785 -250.129833)
			(xy 94.69628 -250.15444) (xy 95.014791 -250.15444) (xy 95.018886 -250.103712) (xy 95.031065 -250.054298)
			(xy 95.051013 -250.007478) (xy 95.078214 -249.964464) (xy 95.111962 -249.92637) (xy 95.151384 -249.894183)
			(xy 95.195458 -249.868737) (xy 95.243044 -249.85069) (xy 95.292908 -249.84051) (xy 95.34376 -249.838461)
			(xy 95.394281 -249.844595) (xy 95.443165 -249.858755) (xy 95.489144 -249.880572) (xy 95.531028 -249.909482)
			(xy 95.567732 -249.944737) (xy 95.598305 -249.985423) (xy 95.621956 -250.030486) (xy 95.638072 -250.07876)
			(xy 95.646236 -250.128994) (xy 95.646748 -250.15444) (xy 95.646236 -250.179886) (xy 95.638072 -250.23012)
			(xy 95.621956 -250.278394) (xy 95.598305 -250.323457) (xy 95.567732 -250.364143) (xy 95.531028 -250.399398)
			(xy 95.489144 -250.428308) (xy 95.443165 -250.450125) (xy 95.394281 -250.464285) (xy 95.34376 -250.470419)
			(xy 95.292908 -250.46837) (xy 95.243044 -250.45819) (xy 95.195458 -250.440143) (xy 95.151384 -250.414697)
			(xy 95.111962 -250.38251) (xy 95.078214 -250.344416) (xy 95.051013 -250.301402) (xy 95.031065 -250.254582)
			(xy 95.018886 -250.205168) (xy 95.014791 -250.15444) (xy 94.69628 -250.15444) (xy 94.695785 -250.179047)
			(xy 94.68789 -250.227624) (xy 94.672306 -250.274305) (xy 94.649435 -250.317882) (xy 94.61987 -250.357226)
			(xy 94.584377 -250.391318) (xy 94.543874 -250.419274) (xy 94.499412 -250.440372) (xy 94.452141 -250.454064)
			(xy 94.403286 -250.459996) (xy 94.354111 -250.458015) (xy 94.305892 -250.448171) (xy 94.259876 -250.430719)
			(xy 94.217255 -250.406112) (xy 94.179134 -250.374987) (xy 94.146499 -250.33815) (xy 94.120196 -250.296554)
			(xy 94.100905 -250.251278) (xy 94.089128 -250.203494) (xy 94.085168 -250.15444) (xy 93.756226 -250.15444)
			(xy 93.755758 -250.178677) (xy 93.748095 -250.226542) (xy 93.732968 -250.272596) (xy 93.710755 -250.315682)
			(xy 93.682017 -250.354719) (xy 93.647472 -250.388726) (xy 93.60799 -250.41685) (xy 93.564561 -250.438385)
			(xy 93.518276 -250.452789) (xy 93.494352 -250.4567) (xy 93.481906 -250.458478) (xy 93.450918 -250.460002)
			(xy 93.427135 -250.459551) (xy 93.380144 -250.452184) (xy 93.334862 -250.437626) (xy 93.292382 -250.416227)
			(xy 93.25373 -250.388506) (xy 93.21984 -250.355131) (xy 93.2053 -250.336304) (xy 93.196918 -250.325128)
			(xy 93.171518 -250.314206) (xy 93.05798 -250.329192) (xy 93.03639 -250.34621) (xy 93.03131 -250.359164)
			(xy 93.023437 -250.378799) (xy 93.005128 -250.416939) (xy 92.994734 -250.435364) (xy 92.95003 -250.512326)
			(xy 92.944244 -250.523539) (xy 92.943307 -250.548724) (xy 92.948252 -250.560332) (xy 92.984574 -250.633992)
			(xy 92.990629 -250.64495) (xy 93.01088 -250.659616) (xy 93.023182 -250.661932) (xy 93.04719 -250.665776)
			(xy 93.093659 -250.680071) (xy 93.13728 -250.701542) (xy 93.176951 -250.729648) (xy 93.211672 -250.763681)
			(xy 93.240568 -250.802781) (xy 93.262909 -250.845962) (xy 93.278132 -250.892136) (xy 93.285853 -250.940137)
			(xy 93.286326 -250.964446) (xy 93.615268 -250.964446) (xy 93.619228 -250.915392) (xy 93.631005 -250.867608)
			(xy 93.650296 -250.822332) (xy 93.676599 -250.780736) (xy 93.709234 -250.743899) (xy 93.747355 -250.712774)
			(xy 93.789976 -250.688167) (xy 93.835992 -250.670715) (xy 93.884211 -250.660871) (xy 93.933386 -250.65889)
			(xy 93.982241 -250.664822) (xy 94.029512 -250.678514) (xy 94.073974 -250.699612) (xy 94.114477 -250.727568)
			(xy 94.14997 -250.76166) (xy 94.179535 -250.801004) (xy 94.202406 -250.844581) (xy 94.21799 -250.891262)
			(xy 94.225885 -250.939839) (xy 94.22638 -250.964446) (xy 94.555322 -250.964446) (xy 94.559282 -250.915392)
			(xy 94.571059 -250.867608) (xy 94.59035 -250.822332) (xy 94.616653 -250.780736) (xy 94.649288 -250.743899)
			(xy 94.687409 -250.712774) (xy 94.73003 -250.688167) (xy 94.776046 -250.670715) (xy 94.824265 -250.660871)
			(xy 94.87344 -250.65889) (xy 94.922295 -250.664822) (xy 94.969566 -250.678514) (xy 95.014028 -250.699612)
			(xy 95.054531 -250.727568) (xy 95.090024 -250.76166) (xy 95.119589 -250.801004) (xy 95.14246 -250.844581)
			(xy 95.158044 -250.891262) (xy 95.165939 -250.939839) (xy 95.166434 -250.964446) (xy 95.165939 -250.989053)
			(xy 95.158044 -251.03763) (xy 95.14246 -251.084311) (xy 95.119589 -251.127888) (xy 95.090024 -251.167232)
			(xy 95.054531 -251.201324) (xy 95.014028 -251.22928) (xy 94.969566 -251.250378) (xy 94.922295 -251.26407)
			(xy 94.87344 -251.270002) (xy 94.824265 -251.268021) (xy 94.776046 -251.258177) (xy 94.73003 -251.240725)
			(xy 94.687409 -251.216118) (xy 94.649288 -251.184993) (xy 94.616653 -251.148156) (xy 94.59035 -251.10656)
			(xy 94.571059 -251.061284) (xy 94.559282 -251.0135) (xy 94.555322 -250.964446) (xy 94.22638 -250.964446)
			(xy 94.225885 -250.989053) (xy 94.21799 -251.03763) (xy 94.202406 -251.084311) (xy 94.179535 -251.127888)
			(xy 94.14997 -251.167232) (xy 94.114477 -251.201324) (xy 94.073974 -251.22928) (xy 94.029512 -251.250378)
			(xy 93.982241 -251.26407) (xy 93.933386 -251.270002) (xy 93.884211 -251.268021) (xy 93.835992 -251.258177)
			(xy 93.789976 -251.240725) (xy 93.747355 -251.216118) (xy 93.709234 -251.184993) (xy 93.676599 -251.148156)
			(xy 93.650296 -251.10656) (xy 93.631005 -251.061284) (xy 93.619228 -251.0135) (xy 93.615268 -250.964446)
			(xy 93.286326 -250.964446) (xy 93.285852 -250.988435) (xy 93.27834 -251.035823) (xy 93.263509 -251.081452)
			(xy 93.241723 -251.124199) (xy 93.213519 -251.163013) (xy 93.179592 -251.196938) (xy 93.140775 -251.225138)
			(xy 93.098026 -251.24692) (xy 93.052395 -251.261747) (xy 93.005007 -251.269254) (xy 92.981018 -251.269754)
			(xy 92.956312 -251.26927) (xy 92.907548 -251.261296) (xy 92.860706 -251.245569) (xy 92.81701 -251.222501)
			(xy 92.777601 -251.192694) (xy 92.74351 -251.156926) (xy 92.715627 -251.116134) (xy 92.704666 -251.093986)
			(xy 92.701364 -251.087128) (xy 92.69603 -251.081286) (xy 92.687426 -251.072837) (xy 92.66489 -251.064353)
			(xy 92.65285 -251.06503) (xy 92.640658 -251.0663) (xy 92.620592 -251.079508) (xy 92.593668 -251.126498)
			(xy 92.590567 -251.132314) (xy 92.587214 -251.145055) (xy 92.587064 -251.151644) (xy 92.587064 -251.441712)
			(xy 92.587574 -251.451905) (xy 92.595587 -251.470656) (xy 92.610238 -251.484839) (xy 92.619576 -251.488956)
			(xy 92.61983 -251.48921) (xy 92.643255 -251.49871) (xy 92.686867 -251.52426) (xy 92.725683 -251.556637)
			(xy 92.758643 -251.594957) (xy 92.784851 -251.638177) (xy 92.803592 -251.68512) (xy 92.814356 -251.734506)
			(xy 92.816172 -251.75972) (xy 92.816172 -251.759974) (xy 92.816426 -251.766578) (xy 92.816426 -251.774452)
			(xy 94.074737 -251.774452) (xy 94.078832 -251.723724) (xy 94.091011 -251.67431) (xy 94.110959 -251.62749)
			(xy 94.13816 -251.584476) (xy 94.171908 -251.546382) (xy 94.21133 -251.514195) (xy 94.255404 -251.488749)
			(xy 94.30299 -251.470702) (xy 94.352854 -251.460522) (xy 94.403706 -251.458473) (xy 94.454227 -251.464607)
			(xy 94.503111 -251.478767) (xy 94.54909 -251.500584) (xy 94.590974 -251.529494) (xy 94.627678 -251.564749)
			(xy 94.658251 -251.605435) (xy 94.681902 -251.650498) (xy 94.698018 -251.698772) (xy 94.706182 -251.749006)
			(xy 94.706694 -251.774452) (xy 95.025222 -251.774452) (xy 95.029182 -251.725398) (xy 95.040959 -251.677614)
			(xy 95.06025 -251.632338) (xy 95.086553 -251.590742) (xy 95.119188 -251.553905) (xy 95.157309 -251.52278)
			(xy 95.19993 -251.498173) (xy 95.245946 -251.480721) (xy 95.294165 -251.470877) (xy 95.34334 -251.468896)
			(xy 95.392195 -251.474828) (xy 95.439466 -251.48852) (xy 95.483928 -251.509618) (xy 95.524431 -251.537574)
			(xy 95.559924 -251.571666) (xy 95.589489 -251.61101) (xy 95.61236 -251.654587) (xy 95.627944 -251.701268)
			(xy 95.635839 -251.749845) (xy 95.636334 -251.774452) (xy 95.635839 -251.799059) (xy 95.627944 -251.847636)
			(xy 95.61236 -251.894317) (xy 95.589489 -251.937894) (xy 95.559924 -251.977238) (xy 95.524431 -252.01133)
			(xy 95.483928 -252.039286) (xy 95.439466 -252.060384) (xy 95.392195 -252.074076) (xy 95.34334 -252.080008)
			(xy 95.294165 -252.078027) (xy 95.245946 -252.068183) (xy 95.19993 -252.050731) (xy 95.157309 -252.026124)
			(xy 95.119188 -251.994999) (xy 95.086553 -251.958162) (xy 95.06025 -251.916566) (xy 95.040959 -251.87129)
			(xy 95.029182 -251.823506) (xy 95.025222 -251.774452) (xy 94.706694 -251.774452) (xy 94.706182 -251.799898)
			(xy 94.698018 -251.850132) (xy 94.681902 -251.898406) (xy 94.658251 -251.943469) (xy 94.627678 -251.984155)
			(xy 94.590974 -252.01941) (xy 94.54909 -252.04832) (xy 94.503111 -252.070137) (xy 94.454227 -252.084297)
			(xy 94.403706 -252.090431) (xy 94.352854 -252.088382) (xy 94.30299 -252.078202) (xy 94.255404 -252.060155)
			(xy 94.21133 -252.034709) (xy 94.171908 -252.002522) (xy 94.13816 -251.964428) (xy 94.110959 -251.921414)
			(xy 94.091011 -251.874594) (xy 94.078832 -251.82518) (xy 94.074737 -251.774452) (xy 92.816426 -251.774452)
			(xy 92.815904 -251.799686) (xy 92.807604 -251.849466) (xy 92.791239 -251.897207) (xy 92.767253 -251.94161)
			(xy 92.736298 -251.98147) (xy 92.718128 -251.998988) (xy 92.710508 -252.0061) (xy 92.700602 -252.027436)
			(xy 92.697024 -252.036218) (xy 92.695994 -252.055139) (xy 92.69857 -252.064266) (xy 92.70492 -252.085602)
			(xy 92.70492 -252.085856) (xy 92.706698 -252.09246) (xy 92.72905 -252.175772) (xy 92.731336 -252.184662)
			(xy 92.731336 -252.184916) (xy 92.733368 -252.193044) (xy 92.733622 -252.193806) (xy 92.74302 -252.228858)
			(xy 92.746129 -252.238603) (xy 92.758711 -252.254708) (xy 92.767404 -252.2601) (xy 92.830396 -252.295406)
			(xy 92.840343 -252.300366) (xy 92.862479 -252.302087) (xy 92.873068 -252.298708) (xy 92.873576 -252.298708)
			(xy 92.899505 -252.289626) (xy 92.953552 -252.279796) (xy 92.981018 -252.27915) (xy 92.986606 -252.27915)
			(xy 92.994734 -252.279404) (xy 93.020588 -252.281107) (xy 93.07121 -252.292123) (xy 93.119248 -252.311525)
			(xy 93.163321 -252.338756) (xy 93.202167 -252.373035) (xy 93.234669 -252.413378) (xy 93.259896 -252.458629)
			(xy 93.277124 -252.507488) (xy 93.285859 -252.558554) (xy 93.286326 -252.584458) (xy 93.604837 -252.584458)
			(xy 93.608932 -252.53373) (xy 93.621111 -252.484316) (xy 93.641059 -252.437496) (xy 93.66826 -252.394482)
			(xy 93.702008 -252.356388) (xy 93.74143 -252.324201) (xy 93.785504 -252.298755) (xy 93.83309 -252.280708)
			(xy 93.882954 -252.270528) (xy 93.933806 -252.268479) (xy 93.984327 -252.274613) (xy 94.033211 -252.288773)
			(xy 94.07919 -252.31059) (xy 94.121074 -252.3395) (xy 94.157778 -252.374755) (xy 94.188351 -252.415441)
			(xy 94.212002 -252.460504) (xy 94.228118 -252.508778) (xy 94.236282 -252.559012) (xy 94.236794 -252.584458)
			(xy 94.555322 -252.584458) (xy 94.559282 -252.535404) (xy 94.571059 -252.48762) (xy 94.59035 -252.442344)
			(xy 94.616653 -252.400748) (xy 94.649288 -252.363911) (xy 94.687409 -252.332786) (xy 94.73003 -252.308179)
			(xy 94.776046 -252.290727) (xy 94.824265 -252.280883) (xy 94.87344 -252.278902) (xy 94.922295 -252.284834)
			(xy 94.969566 -252.298526) (xy 95.014028 -252.319624) (xy 95.054531 -252.34758) (xy 95.090024 -252.381672)
			(xy 95.119589 -252.421016) (xy 95.14246 -252.464593) (xy 95.158044 -252.511274) (xy 95.165939 -252.559851)
			(xy 95.166434 -252.584458) (xy 95.165939 -252.609065) (xy 95.158044 -252.657642) (xy 95.14246 -252.704323)
			(xy 95.119589 -252.7479) (xy 95.090024 -252.787244) (xy 95.054531 -252.821336) (xy 95.014028 -252.849292)
			(xy 94.969566 -252.87039) (xy 94.922295 -252.884082) (xy 94.87344 -252.890014) (xy 94.824265 -252.888033)
			(xy 94.776046 -252.878189) (xy 94.73003 -252.860737) (xy 94.687409 -252.83613) (xy 94.649288 -252.805005)
			(xy 94.616653 -252.768168) (xy 94.59035 -252.726572) (xy 94.571059 -252.681296) (xy 94.559282 -252.633512)
			(xy 94.555322 -252.584458) (xy 94.236794 -252.584458) (xy 94.236282 -252.609904) (xy 94.228118 -252.660138)
			(xy 94.212002 -252.708412) (xy 94.188351 -252.753475) (xy 94.157778 -252.794161) (xy 94.121074 -252.829416)
			(xy 94.07919 -252.858326) (xy 94.033211 -252.880143) (xy 93.984327 -252.894303) (xy 93.933806 -252.900437)
			(xy 93.882954 -252.898388) (xy 93.83309 -252.888208) (xy 93.785504 -252.870161) (xy 93.74143 -252.844715)
			(xy 93.702008 -252.812528) (xy 93.66826 -252.774434) (xy 93.641059 -252.73142) (xy 93.621111 -252.6846)
			(xy 93.608932 -252.635186) (xy 93.604837 -252.584458) (xy 93.286326 -252.584458) (xy 93.285861 -252.609065)
			(xy 93.277971 -252.657643) (xy 93.26239 -252.704326) (xy 93.239521 -252.747904) (xy 93.209957 -252.787248)
			(xy 93.174463 -252.82134) (xy 93.133959 -252.849295) (xy 93.089495 -252.87039) (xy 93.042223 -252.884077)
			(xy 93.017848 -252.88748) (xy 93.003878 -252.889258) (xy 92.982288 -252.905768) (xy 92.9386 -253.010924)
			(xy 92.94241 -253.038356) (xy 92.951046 -253.049024) (xy 92.975522 -253.081502) (xy 93.015822 -253.152137)
			(xy 93.03131 -253.18974) (xy 93.03639 -253.202694) (xy 93.05798 -253.219712) (xy 93.171772 -253.234698)
			(xy 93.197172 -253.223776) (xy 93.205554 -253.212854) (xy 93.220055 -253.194021) (xy 93.253906 -253.160659)
			(xy 93.292519 -253.132945) (xy 93.334958 -253.111548) (xy 93.380201 -253.096985) (xy 93.427154 -253.089608)
			(xy 93.450918 -253.089156) (xy 93.474909 -253.089628) (xy 93.522301 -253.097136) (xy 93.567935 -253.111965)
			(xy 93.610688 -253.133749) (xy 93.649507 -253.161952) (xy 93.683437 -253.195879) (xy 93.711642 -253.234697)
			(xy 93.733429 -253.277448) (xy 93.74826 -253.323081) (xy 93.755771 -253.370473) (xy 93.756226 -253.394464)
			(xy 94.074737 -253.394464) (xy 94.078832 -253.343736) (xy 94.091011 -253.294322) (xy 94.110959 -253.247502)
			(xy 94.13816 -253.204488) (xy 94.171908 -253.166394) (xy 94.21133 -253.134207) (xy 94.255404 -253.108761)
			(xy 94.30299 -253.090714) (xy 94.352854 -253.080534) (xy 94.403706 -253.078485) (xy 94.454227 -253.084619)
			(xy 94.503111 -253.098779) (xy 94.54909 -253.120596) (xy 94.590974 -253.149506) (xy 94.627678 -253.184761)
			(xy 94.658251 -253.225447) (xy 94.681902 -253.27051) (xy 94.698018 -253.318784) (xy 94.706182 -253.369018)
			(xy 94.706694 -253.394464) (xy 95.014791 -253.394464) (xy 95.018886 -253.343736) (xy 95.031065 -253.294322)
			(xy 95.051013 -253.247502) (xy 95.078214 -253.204488) (xy 95.111962 -253.166394) (xy 95.151384 -253.134207)
			(xy 95.195458 -253.108761) (xy 95.243044 -253.090714) (xy 95.292908 -253.080534) (xy 95.34376 -253.078485)
			(xy 95.394281 -253.084619) (xy 95.443165 -253.098779) (xy 95.489144 -253.120596) (xy 95.531028 -253.149506)
			(xy 95.567732 -253.184761) (xy 95.598305 -253.225447) (xy 95.621956 -253.27051) (xy 95.638072 -253.318784)
			(xy 95.646236 -253.369018) (xy 95.646748 -253.394464) (xy 95.646236 -253.41991) (xy 95.638072 -253.470144)
			(xy 95.621956 -253.518418) (xy 95.598305 -253.563481) (xy 95.567732 -253.604167) (xy 95.531028 -253.639422)
			(xy 95.489144 -253.668332) (xy 95.443165 -253.690149) (xy 95.394281 -253.704309) (xy 95.34376 -253.710443)
			(xy 95.292908 -253.708394) (xy 95.243044 -253.698214) (xy 95.195458 -253.680167) (xy 95.151384 -253.654721)
			(xy 95.111962 -253.622534) (xy 95.078214 -253.58444) (xy 95.051013 -253.541426) (xy 95.031065 -253.494606)
			(xy 95.018886 -253.445192) (xy 95.014791 -253.394464) (xy 94.706694 -253.394464) (xy 94.706182 -253.41991)
			(xy 94.698018 -253.470144) (xy 94.681902 -253.518418) (xy 94.658251 -253.563481) (xy 94.627678 -253.604167)
			(xy 94.590974 -253.639422) (xy 94.54909 -253.668332) (xy 94.503111 -253.690149) (xy 94.454227 -253.704309)
			(xy 94.403706 -253.710443) (xy 94.352854 -253.708394) (xy 94.30299 -253.698214) (xy 94.255404 -253.680167)
			(xy 94.21133 -253.654721) (xy 94.171908 -253.622534) (xy 94.13816 -253.58444) (xy 94.110959 -253.541426)
			(xy 94.091011 -253.494606) (xy 94.078832 -253.445192) (xy 94.074737 -253.394464) (xy 93.756226 -253.394464)
			(xy 93.755756 -253.4187) (xy 93.74809 -253.466562) (xy 93.73296 -253.512613) (xy 93.710747 -253.555696)
			(xy 93.682008 -253.59473) (xy 93.647464 -253.628734) (xy 93.607982 -253.656855) (xy 93.564555 -253.678387)
			(xy 93.518272 -253.69279) (xy 93.494352 -253.696724) (xy 93.481906 -253.698502) (xy 93.450918 -253.700026)
			(xy 93.427135 -253.699575) (xy 93.380143 -253.692208) (xy 93.33486 -253.677651) (xy 93.292379 -253.656254)
			(xy 93.253725 -253.628533) (xy 93.219833 -253.59516) (xy 93.2053 -253.576328) (xy 93.196918 -253.565152)
			(xy 93.171518 -253.55423) (xy 93.05798 -253.569216) (xy 93.03639 -253.586234) (xy 93.03131 -253.599188)
			(xy 93.023436 -253.618822) (xy 93.005126 -253.656962) (xy 92.994734 -253.675388) (xy 92.84589 -253.931674)
			(xy 92.826208 -253.964291) (xy 92.779306 -254.024321) (xy 92.752418 -254.051308) (xy 92.752164 -254.051562)
			(xy 92.747084 -254.056642) (xy 92.733622 -254.079756) (xy 92.731844 -254.086614) (xy 92.721614 -254.123881)
			(xy 92.6923 -254.195386) (xy 92.687215 -254.20447) (xy 93.604837 -254.20447) (xy 93.608932 -254.153742)
			(xy 93.621111 -254.104328) (xy 93.641059 -254.057508) (xy 93.66826 -254.014494) (xy 93.702008 -253.9764)
			(xy 93.74143 -253.944213) (xy 93.785504 -253.918767) (xy 93.83309 -253.90072) (xy 93.882954 -253.89054)
			(xy 93.933806 -253.888491) (xy 93.984327 -253.894625) (xy 94.033211 -253.908785) (xy 94.07919 -253.930602)
			(xy 94.121074 -253.959512) (xy 94.157778 -253.994767) (xy 94.188351 -254.035453) (xy 94.212002 -254.080516)
			(xy 94.228118 -254.12879) (xy 94.236282 -254.179024) (xy 94.236794 -254.20447) (xy 94.555322 -254.20447)
			(xy 94.559282 -254.155416) (xy 94.571059 -254.107632) (xy 94.59035 -254.062356) (xy 94.616653 -254.02076)
			(xy 94.649288 -253.983923) (xy 94.687409 -253.952798) (xy 94.73003 -253.928191) (xy 94.776046 -253.910739)
			(xy 94.824265 -253.900895) (xy 94.87344 -253.898914) (xy 94.922295 -253.904846) (xy 94.969566 -253.918538)
			(xy 95.014028 -253.939636) (xy 95.054531 -253.967592) (xy 95.090024 -254.001684) (xy 95.119589 -254.041028)
			(xy 95.14246 -254.084605) (xy 95.158044 -254.131286) (xy 95.165939 -254.179863) (xy 95.166434 -254.20447)
			(xy 95.165939 -254.229077) (xy 95.158044 -254.277654) (xy 95.14246 -254.324335) (xy 95.119589 -254.367912)
			(xy 95.090024 -254.407256) (xy 95.054531 -254.441348) (xy 95.014028 -254.469304) (xy 94.969566 -254.490402)
			(xy 94.922295 -254.504094) (xy 94.87344 -254.510026) (xy 94.824265 -254.508045) (xy 94.776046 -254.498201)
			(xy 94.73003 -254.480749) (xy 94.687409 -254.456142) (xy 94.649288 -254.425017) (xy 94.616653 -254.38818)
			(xy 94.59035 -254.346584) (xy 94.571059 -254.301308) (xy 94.559282 -254.253524) (xy 94.555322 -254.20447)
			(xy 94.236794 -254.20447) (xy 94.236282 -254.229916) (xy 94.228118 -254.28015) (xy 94.212002 -254.328424)
			(xy 94.188351 -254.373487) (xy 94.157778 -254.414173) (xy 94.121074 -254.449428) (xy 94.07919 -254.478338)
			(xy 94.033211 -254.500155) (xy 93.984327 -254.514315) (xy 93.933806 -254.520449) (xy 93.882954 -254.5184)
			(xy 93.83309 -254.50822) (xy 93.785504 -254.490173) (xy 93.74143 -254.464727) (xy 93.702008 -254.43254)
			(xy 93.66826 -254.394446) (xy 93.641059 -254.351432) (xy 93.621111 -254.304612) (xy 93.608932 -254.255198)
			(xy 93.604837 -254.20447) (xy 92.687215 -254.20447) (xy 92.673424 -254.229108) (xy 92.593922 -254.366014)
			(xy 92.590777 -254.371891) (xy 92.587298 -254.384753) (xy 92.587064 -254.391414) (xy 92.587064 -254.41783)
			(xy 92.587416 -254.426519) (xy 92.593269 -254.442881) (xy 92.598494 -254.449834) (xy 92.604082 -254.456692)
			(xy 92.618814 -254.465836) (xy 92.62745 -254.467614) (xy 92.661067 -254.47528) (xy 92.726237 -254.497802)
			(xy 92.788141 -254.528171) (xy 92.845838 -254.565926) (xy 92.898451 -254.610494) (xy 92.945181 -254.661196)
			(xy 92.985318 -254.717262) (xy 93.018251 -254.777841) (xy 93.03131 -254.809752) (xy 93.03639 -254.822706)
			(xy 93.058234 -254.839724) (xy 93.171772 -254.85471) (xy 93.197172 -254.843788) (xy 93.205554 -254.832866)
			(xy 93.220054 -254.814033) (xy 93.253906 -254.780669) (xy 93.292517 -254.752954) (xy 93.334957 -254.731556)
			(xy 93.3802 -254.716993) (xy 93.427154 -254.709616) (xy 93.450918 -254.709168) (xy 93.474909 -254.70964)
			(xy 93.5223 -254.717148) (xy 93.567933 -254.731977) (xy 93.610685 -254.753761) (xy 93.649503 -254.781964)
			(xy 93.683432 -254.815892) (xy 93.711636 -254.85471) (xy 93.733421 -254.897461) (xy 93.74825 -254.943094)
			(xy 93.75576 -254.990485) (xy 93.756226 -255.014476) (xy 94.074737 -255.014476) (xy 94.078832 -254.963748)
			(xy 94.091011 -254.914334) (xy 94.110959 -254.867514) (xy 94.13816 -254.8245) (xy 94.171908 -254.786406)
			(xy 94.21133 -254.754219) (xy 94.255404 -254.728773) (xy 94.30299 -254.710726) (xy 94.352854 -254.700546)
			(xy 94.403706 -254.698497) (xy 94.454227 -254.704631) (xy 94.503111 -254.718791) (xy 94.54909 -254.740608)
			(xy 94.590974 -254.769518) (xy 94.627678 -254.804773) (xy 94.658251 -254.845459) (xy 94.681902 -254.890522)
			(xy 94.698018 -254.938796) (xy 94.706182 -254.98903) (xy 94.706694 -255.014476) (xy 95.014791 -255.014476)
			(xy 95.018886 -254.963748) (xy 95.031065 -254.914334) (xy 95.051013 -254.867514) (xy 95.078214 -254.8245)
			(xy 95.111962 -254.786406) (xy 95.151384 -254.754219) (xy 95.195458 -254.728773) (xy 95.243044 -254.710726)
			(xy 95.292908 -254.700546) (xy 95.34376 -254.698497) (xy 95.394281 -254.704631) (xy 95.443165 -254.718791)
			(xy 95.489144 -254.740608) (xy 95.531028 -254.769518) (xy 95.567732 -254.804773) (xy 95.598305 -254.845459)
			(xy 95.621956 -254.890522) (xy 95.638072 -254.938796) (xy 95.646236 -254.98903) (xy 95.646748 -255.014476)
			(xy 95.646236 -255.039922) (xy 95.638072 -255.090156) (xy 95.621956 -255.13843) (xy 95.598305 -255.183493)
			(xy 95.567732 -255.224179) (xy 95.531028 -255.259434) (xy 95.489144 -255.288344) (xy 95.443165 -255.310161)
			(xy 95.394281 -255.324321) (xy 95.34376 -255.330455) (xy 95.292908 -255.328406) (xy 95.243044 -255.318226)
			(xy 95.195458 -255.300179) (xy 95.151384 -255.274733) (xy 95.111962 -255.242546) (xy 95.078214 -255.204452)
			(xy 95.051013 -255.161438) (xy 95.031065 -255.114618) (xy 95.018886 -255.065204) (xy 95.014791 -255.014476)
			(xy 94.706694 -255.014476) (xy 94.706182 -255.039922) (xy 94.698018 -255.090156) (xy 94.681902 -255.13843)
			(xy 94.658251 -255.183493) (xy 94.627678 -255.224179) (xy 94.590974 -255.259434) (xy 94.54909 -255.288344)
			(xy 94.503111 -255.310161) (xy 94.454227 -255.324321) (xy 94.403706 -255.330455) (xy 94.352854 -255.328406)
			(xy 94.30299 -255.318226) (xy 94.255404 -255.300179) (xy 94.21133 -255.274733) (xy 94.171908 -255.242546)
			(xy 94.13816 -255.204452) (xy 94.110959 -255.161438) (xy 94.091011 -255.114618) (xy 94.078832 -255.065204)
			(xy 94.074737 -255.014476) (xy 93.756226 -255.014476) (xy 93.756086 -255.027239) (xy 93.75392 -255.052672)
			(xy 93.751908 -255.065276) (xy 93.747124 -255.090436) (xy 93.730284 -255.138798) (xy 93.705618 -255.183677)
			(xy 93.673817 -255.223817) (xy 93.635769 -255.258094) (xy 93.592541 -255.285549) (xy 93.54534 -255.305414)
			(xy 93.495489 -255.317133) (xy 93.469968 -255.319276) (xy 93.469714 -255.319276) (xy 93.460476 -255.320183)
			(xy 93.443536 -255.327735) (xy 93.436694 -255.334008) (xy 93.200474 -255.570228) (xy 93.199204 -255.609852)
			(xy 93.212158 -255.625092) (xy 93.229475 -255.646052) (xy 93.257156 -255.692841) (xy 93.276106 -255.743794)
			(xy 93.285726 -255.7973) (xy 93.286326 -255.824482) (xy 93.604837 -255.824482) (xy 93.608932 -255.773754)
			(xy 93.621111 -255.72434) (xy 93.641059 -255.67752) (xy 93.66826 -255.634506) (xy 93.702008 -255.596412)
			(xy 93.74143 -255.564225) (xy 93.785504 -255.538779) (xy 93.83309 -255.520732) (xy 93.882954 -255.510552)
			(xy 93.933806 -255.508503) (xy 93.984327 -255.514637) (xy 94.033211 -255.528797) (xy 94.07919 -255.550614)
			(xy 94.121074 -255.579524) (xy 94.157778 -255.614779) (xy 94.188351 -255.655465) (xy 94.212002 -255.700528)
			(xy 94.228118 -255.748802) (xy 94.236282 -255.799036) (xy 94.236794 -255.824482) (xy 94.555322 -255.824482)
			(xy 94.559282 -255.775428) (xy 94.571059 -255.727644) (xy 94.59035 -255.682368) (xy 94.616653 -255.640772)
			(xy 94.649288 -255.603935) (xy 94.687409 -255.57281) (xy 94.73003 -255.548203) (xy 94.776046 -255.530751)
			(xy 94.824265 -255.520907) (xy 94.87344 -255.518926) (xy 94.922295 -255.524858) (xy 94.969566 -255.53855)
			(xy 95.014028 -255.559648) (xy 95.054531 -255.587604) (xy 95.090024 -255.621696) (xy 95.119589 -255.66104)
			(xy 95.14246 -255.704617) (xy 95.158044 -255.751298) (xy 95.165939 -255.799875) (xy 95.166434 -255.824482)
			(xy 95.165939 -255.849089) (xy 95.158044 -255.897666) (xy 95.14246 -255.944347) (xy 95.119589 -255.987924)
			(xy 95.090024 -256.027268) (xy 95.054531 -256.06136) (xy 95.014028 -256.089316) (xy 94.969566 -256.110414)
			(xy 94.922295 -256.124106) (xy 94.87344 -256.130038) (xy 94.824265 -256.128057) (xy 94.776046 -256.118213)
			(xy 94.73003 -256.100761) (xy 94.687409 -256.076154) (xy 94.649288 -256.045029) (xy 94.616653 -256.008192)
			(xy 94.59035 -255.966596) (xy 94.571059 -255.92132) (xy 94.559282 -255.873536) (xy 94.555322 -255.824482)
			(xy 94.236794 -255.824482) (xy 94.236282 -255.849928) (xy 94.228118 -255.900162) (xy 94.212002 -255.948436)
			(xy 94.188351 -255.993499) (xy 94.157778 -256.034185) (xy 94.121074 -256.06944) (xy 94.07919 -256.09835)
			(xy 94.033211 -256.120167) (xy 93.984327 -256.134327) (xy 93.933806 -256.140461) (xy 93.882954 -256.138412)
			(xy 93.83309 -256.128232) (xy 93.785504 -256.110185) (xy 93.74143 -256.084739) (xy 93.702008 -256.052552)
			(xy 93.66826 -256.014458) (xy 93.641059 -255.971444) (xy 93.621111 -255.924624) (xy 93.608932 -255.87521)
			(xy 93.604837 -255.824482) (xy 93.286326 -255.824482) (xy 93.285857 -255.848475) (xy 93.278353 -255.89587)
			(xy 93.263527 -255.941507) (xy 93.241745 -255.984264) (xy 93.213542 -256.023086) (xy 93.179614 -256.057019)
			(xy 93.140794 -256.085226) (xy 93.09804 -256.107014) (xy 93.052405 -256.121845) (xy 93.005011 -256.129354)
			(xy 92.981018 -256.12979) (xy 92.953835 -256.129198) (xy 92.900328 -256.119574) (xy 92.84937 -256.100628)
			(xy 92.802573 -256.072958) (xy 92.781628 -256.055622) (xy 92.762578 -256.056384) (xy 92.732606 -256.0574)
			(xy 92.723374 -256.058125) (xy 92.706313 -256.065286) (xy 92.699332 -256.07137) (xy 92.698824 -256.071878)
			(xy 92.587064 -256.183638) (xy 92.578642 -256.193094) (xy 92.571464 -256.217343) (xy 92.573348 -256.229866)
			(xy 92.593414 -256.325878) (xy 92.609924 -256.345182) (xy 92.622116 -256.350008) (xy 92.646293 -256.360019)
			(xy 92.691083 -256.38707) (xy 92.730603 -256.421362) (xy 92.763698 -256.461891) (xy 92.789398 -256.507469)
			(xy 92.80695 -256.556762) (xy 92.81584 -256.608325) (xy 92.816426 -256.634488) (xy 93.145114 -256.634488)
			(xy 93.149074 -256.585434) (xy 93.160851 -256.53765) (xy 93.180142 -256.492374) (xy 93.206445 -256.450778)
			(xy 93.23908 -256.413941) (xy 93.277201 -256.382816) (xy 93.319822 -256.358209) (xy 93.365838 -256.340757)
			(xy 93.414057 -256.330913) (xy 93.463232 -256.328932) (xy 93.512087 -256.334864) (xy 93.559358 -256.348556)
			(xy 93.60382 -256.369654) (xy 93.644323 -256.39761) (xy 93.679816 -256.431702) (xy 93.709381 -256.471046)
			(xy 93.732252 -256.514623) (xy 93.747836 -256.561304) (xy 93.755731 -256.609881) (xy 93.756226 -256.634488)
			(xy 94.074737 -256.634488) (xy 94.078832 -256.58376) (xy 94.091011 -256.534346) (xy 94.110959 -256.487526)
			(xy 94.13816 -256.444512) (xy 94.171908 -256.406418) (xy 94.21133 -256.374231) (xy 94.255404 -256.348785)
			(xy 94.30299 -256.330738) (xy 94.352854 -256.320558) (xy 94.403706 -256.318509) (xy 94.454227 -256.324643)
			(xy 94.503111 -256.338803) (xy 94.54909 -256.36062) (xy 94.590974 -256.38953) (xy 94.627678 -256.424785)
			(xy 94.658251 -256.465471) (xy 94.681902 -256.510534) (xy 94.698018 -256.558808) (xy 94.706182 -256.609042)
			(xy 94.706694 -256.634488) (xy 95.025222 -256.634488) (xy 95.029182 -256.585434) (xy 95.040959 -256.53765)
			(xy 95.06025 -256.492374) (xy 95.086553 -256.450778) (xy 95.119188 -256.413941) (xy 95.157309 -256.382816)
			(xy 95.19993 -256.358209) (xy 95.245946 -256.340757) (xy 95.294165 -256.330913) (xy 95.34334 -256.328932)
			(xy 95.392195 -256.334864) (xy 95.439466 -256.348556) (xy 95.483928 -256.369654) (xy 95.524431 -256.39761)
			(xy 95.559924 -256.431702) (xy 95.589489 -256.471046) (xy 95.61236 -256.514623) (xy 95.627944 -256.561304)
			(xy 95.635839 -256.609881) (xy 95.636334 -256.634488) (xy 95.635839 -256.659095) (xy 95.627944 -256.707672)
			(xy 95.61236 -256.754353) (xy 95.589489 -256.79793) (xy 95.559924 -256.837274) (xy 95.524431 -256.871366)
			(xy 95.483928 -256.899322) (xy 95.439466 -256.92042) (xy 95.392195 -256.934112) (xy 95.34334 -256.940044)
			(xy 95.294165 -256.938063) (xy 95.245946 -256.928219) (xy 95.19993 -256.910767) (xy 95.157309 -256.88616)
			(xy 95.119188 -256.855035) (xy 95.086553 -256.818198) (xy 95.06025 -256.776602) (xy 95.040959 -256.731326)
			(xy 95.029182 -256.683542) (xy 95.025222 -256.634488) (xy 94.706694 -256.634488) (xy 94.706182 -256.659934)
			(xy 94.698018 -256.710168) (xy 94.681902 -256.758442) (xy 94.658251 -256.803505) (xy 94.627678 -256.844191)
			(xy 94.590974 -256.879446) (xy 94.54909 -256.908356) (xy 94.503111 -256.930173) (xy 94.454227 -256.944333)
			(xy 94.403706 -256.950467) (xy 94.352854 -256.948418) (xy 94.30299 -256.938238) (xy 94.255404 -256.920191)
			(xy 94.21133 -256.894745) (xy 94.171908 -256.862558) (xy 94.13816 -256.824464) (xy 94.110959 -256.78145)
			(xy 94.091011 -256.73463) (xy 94.078832 -256.685216) (xy 94.074737 -256.634488) (xy 93.756226 -256.634488)
			(xy 93.755731 -256.659095) (xy 93.747836 -256.707672) (xy 93.732252 -256.754353) (xy 93.709381 -256.79793)
			(xy 93.679816 -256.837274) (xy 93.644323 -256.871366) (xy 93.60382 -256.899322) (xy 93.559358 -256.92042)
			(xy 93.512087 -256.934112) (xy 93.463232 -256.940044) (xy 93.414057 -256.938063) (xy 93.365838 -256.928219)
			(xy 93.319822 -256.910767) (xy 93.277201 -256.88616) (xy 93.23908 -256.855035) (xy 93.206445 -256.818198)
			(xy 93.180142 -256.776602) (xy 93.160851 -256.731326) (xy 93.149074 -256.683542) (xy 93.145114 -256.634488)
			(xy 92.816426 -256.634488) (xy 92.815956 -256.65848) (xy 92.808452 -256.705875) (xy 92.793626 -256.751511)
			(xy 92.771843 -256.794267) (xy 92.74364 -256.833089) (xy 92.709712 -256.867021) (xy 92.670893 -256.895227)
			(xy 92.628139 -256.917014) (xy 92.582504 -256.931845) (xy 92.53511 -256.939354) (xy 92.511118 -256.939796)
			(xy 92.484958 -256.939252) (xy 92.433403 -256.930328) (xy 92.384122 -256.912753) (xy 92.338554 -256.887041)
			(xy 92.298031 -256.853944) (xy 92.263737 -256.81443) (xy 92.236674 -256.769651) (xy 92.226638 -256.745486)
			(xy 92.221812 -256.733294) (xy 92.202508 -256.716784) (xy 92.106496 -256.696718) (xy 92.093974 -256.69479)
			(xy 92.069717 -256.701993) (xy 92.060268 -256.710434) (xy 91.836748 -256.933954) (xy 91.829349 -256.940797)
			(xy 91.81075 -256.94852) (xy 91.80068 -256.94894) (xy 91.12758 -256.94894) (xy 91.121711 -256.949088)
			(xy 91.110286 -256.951776) (xy 91.104974 -256.954274) (xy 91.080336 -256.96672) (xy 91.0717 -256.973578)
			(xy 91.068144 -256.97815) (xy 91.047012 -257.004197) (xy 90.999498 -257.051543) (xy 90.946635 -257.092831)
			(xy 90.889191 -257.127461) (xy 90.827998 -257.154931) (xy 90.763946 -257.174843) (xy 90.697964 -257.186907)
			(xy 90.63101 -257.190947) (xy 90.564056 -257.186907) (xy 90.498074 -257.174843) (xy 90.434022 -257.154931)
			(xy 90.372829 -257.127461) (xy 90.315385 -257.092831) (xy 90.262522 -257.051543) (xy 90.215008 -257.004197)
			(xy 90.193876 -256.97815) (xy 90.19032 -256.973578) (xy 90.181684 -256.96672) (xy 90.157046 -256.954274)
			(xy 90.15172 -256.951816) (xy 90.140304 -256.949127) (xy 90.13444 -256.94894) (xy 80.353662 -256.94894)
			(xy 80.343596 -256.949371) (xy 80.325005 -256.9571) (xy 80.317594 -256.963926) (xy 80.108806 -257.172714)
			(xy 80.10144 -257.179826) (xy 80.09382 -257.198622) (xy 80.09382 -257.930396) (xy 98.711261 -257.930396)
			(xy 98.715291 -257.877898) (xy 98.727288 -257.82663) (xy 98.746971 -257.777795) (xy 98.773877 -257.732536)
			(xy 98.807377 -257.691915) (xy 98.846685 -257.656884) (xy 98.89088 -257.628264) (xy 98.938925 -257.606725)
			(xy 98.989696 -257.592773) (xy 99.042001 -257.586735) (xy 99.094615 -257.588752) (xy 99.146305 -257.598776)
			(xy 99.195858 -257.616574) (xy 99.242114 -257.641727) (xy 99.283988 -257.673646) (xy 99.3205 -257.711584)
			(xy 99.350792 -257.75465) (xy 99.374155 -257.801835) (xy 99.390041 -257.852034) (xy 99.398078 -257.90407)
			(xy 99.398582 -257.930396) (xy 100.611181 -257.930396) (xy 100.615211 -257.877898) (xy 100.627208 -257.82663)
			(xy 100.646891 -257.777795) (xy 100.673797 -257.732536) (xy 100.707297 -257.691915) (xy 100.746605 -257.656884)
			(xy 100.7908 -257.628264) (xy 100.838845 -257.606725) (xy 100.889616 -257.592773) (xy 100.941921 -257.586735)
			(xy 100.994535 -257.588752) (xy 101.046225 -257.598776) (xy 101.095778 -257.616574) (xy 101.142034 -257.641727)
			(xy 101.183908 -257.673646) (xy 101.22042 -257.711584) (xy 101.250712 -257.75465) (xy 101.274075 -257.801835)
			(xy 101.289961 -257.852034) (xy 101.297998 -257.90407) (xy 101.298502 -257.930396) (xy 102.511101 -257.930396)
			(xy 102.515131 -257.877898) (xy 102.527128 -257.82663) (xy 102.546811 -257.777795) (xy 102.573717 -257.732536)
			(xy 102.607217 -257.691915) (xy 102.646525 -257.656884) (xy 102.69072 -257.628264) (xy 102.738765 -257.606725)
			(xy 102.789536 -257.592773) (xy 102.841841 -257.586735) (xy 102.894455 -257.588752) (xy 102.946145 -257.598776)
			(xy 102.995698 -257.616574) (xy 103.041954 -257.641727) (xy 103.083828 -257.673646) (xy 103.12034 -257.711584)
			(xy 103.150632 -257.75465) (xy 103.173995 -257.801835) (xy 103.189881 -257.852034) (xy 103.197918 -257.90407)
			(xy 103.198422 -257.930396) (xy 103.197918 -257.956722) (xy 103.189881 -258.008758) (xy 103.173995 -258.058957)
			(xy 103.150632 -258.106142) (xy 103.12034 -258.149208) (xy 103.083828 -258.187146) (xy 103.041954 -258.219065)
			(xy 102.995698 -258.244218) (xy 102.946145 -258.262016) (xy 102.894455 -258.27204) (xy 102.841841 -258.274057)
			(xy 102.789536 -258.268019) (xy 102.738765 -258.254067) (xy 102.69072 -258.232528) (xy 102.646525 -258.203908)
			(xy 102.607217 -258.168877) (xy 102.573717 -258.128256) (xy 102.546811 -258.082997) (xy 102.527128 -258.034162)
			(xy 102.515131 -257.982894) (xy 102.511101 -257.930396) (xy 101.298502 -257.930396) (xy 101.297998 -257.956722)
			(xy 101.289961 -258.008758) (xy 101.274075 -258.058957) (xy 101.250712 -258.106142) (xy 101.22042 -258.149208)
			(xy 101.183908 -258.187146) (xy 101.142034 -258.219065) (xy 101.095778 -258.244218) (xy 101.046225 -258.262016)
			(xy 100.994535 -258.27204) (xy 100.941921 -258.274057) (xy 100.889616 -258.268019) (xy 100.838845 -258.254067)
			(xy 100.7908 -258.232528) (xy 100.746605 -258.203908) (xy 100.707297 -258.168877) (xy 100.673797 -258.128256)
			(xy 100.646891 -258.082997) (xy 100.627208 -258.034162) (xy 100.615211 -257.982894) (xy 100.611181 -257.930396)
			(xy 99.398582 -257.930396) (xy 99.398078 -257.956722) (xy 99.390041 -258.008758) (xy 99.374155 -258.058957)
			(xy 99.350792 -258.106142) (xy 99.3205 -258.149208) (xy 99.283988 -258.187146) (xy 99.242114 -258.219065)
			(xy 99.195858 -258.244218) (xy 99.146305 -258.262016) (xy 99.094615 -258.27204) (xy 99.042001 -258.274057)
			(xy 98.989696 -258.268019) (xy 98.938925 -258.254067) (xy 98.89088 -258.232528) (xy 98.846685 -258.203908)
			(xy 98.807377 -258.168877) (xy 98.773877 -258.128256) (xy 98.746971 -258.082997) (xy 98.727288 -258.034162)
			(xy 98.715291 -257.982894) (xy 98.711261 -257.930396) (xy 80.09382 -257.930396) (xy 80.09382 -258.38023)
			(xy 106.061259 -258.38023) (xy 106.065289 -258.327732) (xy 106.077286 -258.276464) (xy 106.096969 -258.227629)
			(xy 106.123875 -258.18237) (xy 106.157375 -258.141749) (xy 106.196683 -258.106718) (xy 106.240878 -258.078098)
			(xy 106.288923 -258.056559) (xy 106.339694 -258.042607) (xy 106.391999 -258.036569) (xy 106.444613 -258.038586)
			(xy 106.496303 -258.04861) (xy 106.545856 -258.066408) (xy 106.592112 -258.091561) (xy 106.633986 -258.12348)
			(xy 106.670498 -258.161418) (xy 106.70079 -258.204484) (xy 106.724153 -258.251669) (xy 106.740039 -258.301868)
			(xy 106.748076 -258.353904) (xy 106.74858 -258.38023) (xy 106.748076 -258.406556) (xy 106.740039 -258.458592)
			(xy 106.724153 -258.508791) (xy 106.70079 -258.555976) (xy 106.670498 -258.599042) (xy 106.633986 -258.63698)
			(xy 106.592112 -258.668899) (xy 106.545856 -258.694052) (xy 106.496303 -258.71185) (xy 106.444613 -258.721874)
			(xy 106.391999 -258.723891) (xy 106.339694 -258.717853) (xy 106.288923 -258.703901) (xy 106.240878 -258.682362)
			(xy 106.196683 -258.653742) (xy 106.157375 -258.618711) (xy 106.123875 -258.57809) (xy 106.096969 -258.532831)
			(xy 106.077286 -258.483996) (xy 106.065289 -258.432728) (xy 106.061259 -258.38023) (xy 80.09382 -258.38023)
			(xy 80.09382 -258.830318) (xy 98.711261 -258.830318) (xy 98.715291 -258.77782) (xy 98.727288 -258.726552)
			(xy 98.746971 -258.677717) (xy 98.773877 -258.632458) (xy 98.807377 -258.591837) (xy 98.846685 -258.556806)
			(xy 98.89088 -258.528186) (xy 98.938925 -258.506647) (xy 98.989696 -258.492695) (xy 99.042001 -258.486657)
			(xy 99.094615 -258.488674) (xy 99.146305 -258.498698) (xy 99.195858 -258.516496) (xy 99.242114 -258.541649)
			(xy 99.283988 -258.573568) (xy 99.3205 -258.611506) (xy 99.350792 -258.654572) (xy 99.374155 -258.701757)
			(xy 99.390041 -258.751956) (xy 99.398078 -258.803992) (xy 99.398582 -258.830318) (xy 100.611181 -258.830318)
			(xy 100.615211 -258.77782) (xy 100.627208 -258.726552) (xy 100.646891 -258.677717) (xy 100.673797 -258.632458)
			(xy 100.707297 -258.591837) (xy 100.746605 -258.556806) (xy 100.7908 -258.528186) (xy 100.838845 -258.506647)
			(xy 100.889616 -258.492695) (xy 100.941921 -258.486657) (xy 100.994535 -258.488674) (xy 101.046225 -258.498698)
			(xy 101.095778 -258.516496) (xy 101.142034 -258.541649) (xy 101.183908 -258.573568) (xy 101.22042 -258.611506)
			(xy 101.250712 -258.654572) (xy 101.274075 -258.701757) (xy 101.289961 -258.751956) (xy 101.297998 -258.803992)
			(xy 101.298502 -258.830318) (xy 102.511101 -258.830318) (xy 102.515131 -258.77782) (xy 102.527128 -258.726552)
			(xy 102.546811 -258.677717) (xy 102.573717 -258.632458) (xy 102.607217 -258.591837) (xy 102.646525 -258.556806)
			(xy 102.69072 -258.528186) (xy 102.738765 -258.506647) (xy 102.789536 -258.492695) (xy 102.841841 -258.486657)
			(xy 102.894455 -258.488674) (xy 102.946145 -258.498698) (xy 102.995698 -258.516496) (xy 103.041954 -258.541649)
			(xy 103.083828 -258.573568) (xy 103.12034 -258.611506) (xy 103.150632 -258.654572) (xy 103.173995 -258.701757)
			(xy 103.189881 -258.751956) (xy 103.197918 -258.803992) (xy 103.198422 -258.830318) (xy 103.197918 -258.856644)
			(xy 103.189881 -258.90868) (xy 103.173995 -258.958879) (xy 103.150632 -259.006064) (xy 103.12034 -259.04913)
			(xy 103.083828 -259.087068) (xy 103.041954 -259.118987) (xy 102.995698 -259.14414) (xy 102.946145 -259.161938)
			(xy 102.894455 -259.171962) (xy 102.841841 -259.173979) (xy 102.789536 -259.167941) (xy 102.738765 -259.153989)
			(xy 102.69072 -259.13245) (xy 102.646525 -259.10383) (xy 102.607217 -259.068799) (xy 102.573717 -259.028178)
			(xy 102.546811 -258.982919) (xy 102.527128 -258.934084) (xy 102.515131 -258.882816) (xy 102.511101 -258.830318)
			(xy 101.298502 -258.830318) (xy 101.297998 -258.856644) (xy 101.289961 -258.90868) (xy 101.274075 -258.958879)
			(xy 101.250712 -259.006064) (xy 101.22042 -259.04913) (xy 101.183908 -259.087068) (xy 101.142034 -259.118987)
			(xy 101.095778 -259.14414) (xy 101.046225 -259.161938) (xy 100.994535 -259.171962) (xy 100.941921 -259.173979)
			(xy 100.889616 -259.167941) (xy 100.838845 -259.153989) (xy 100.7908 -259.13245) (xy 100.746605 -259.10383)
			(xy 100.707297 -259.068799) (xy 100.673797 -259.028178) (xy 100.646891 -258.982919) (xy 100.627208 -258.934084)
			(xy 100.615211 -258.882816) (xy 100.611181 -258.830318) (xy 99.398582 -258.830318) (xy 99.398078 -258.856644)
			(xy 99.390041 -258.90868) (xy 99.374155 -258.958879) (xy 99.350792 -259.006064) (xy 99.3205 -259.04913)
			(xy 99.283988 -259.087068) (xy 99.242114 -259.118987) (xy 99.195858 -259.14414) (xy 99.146305 -259.161938)
			(xy 99.094615 -259.171962) (xy 99.042001 -259.173979) (xy 98.989696 -259.167941) (xy 98.938925 -259.153989)
			(xy 98.89088 -259.13245) (xy 98.846685 -259.10383) (xy 98.807377 -259.068799) (xy 98.773877 -259.028178)
			(xy 98.746971 -258.982919) (xy 98.727288 -258.934084) (xy 98.715291 -258.882816) (xy 98.711261 -258.830318)
			(xy 80.09382 -258.830318) (xy 80.09382 -259.330444) (xy 106.061259 -259.330444) (xy 106.065289 -259.277946)
			(xy 106.077286 -259.226678) (xy 106.096969 -259.177843) (xy 106.123875 -259.132584) (xy 106.157375 -259.091963)
			(xy 106.196683 -259.056932) (xy 106.240878 -259.028312) (xy 106.288923 -259.006773) (xy 106.339694 -258.992821)
			(xy 106.391999 -258.986783) (xy 106.444613 -258.9888) (xy 106.496303 -258.998824) (xy 106.545856 -259.016622)
			(xy 106.592112 -259.041775) (xy 106.633986 -259.073694) (xy 106.670498 -259.111632) (xy 106.70079 -259.154698)
			(xy 106.724153 -259.201883) (xy 106.740039 -259.252082) (xy 106.748076 -259.304118) (xy 106.74858 -259.330444)
			(xy 106.748076 -259.35677) (xy 106.740039 -259.408806) (xy 106.724153 -259.459005) (xy 106.70079 -259.50619)
			(xy 106.670498 -259.549256) (xy 106.633986 -259.587194) (xy 106.592112 -259.619113) (xy 106.545856 -259.644266)
			(xy 106.496303 -259.662064) (xy 106.444613 -259.672088) (xy 106.391999 -259.674105) (xy 106.339694 -259.668067)
			(xy 106.288923 -259.654115) (xy 106.240878 -259.632576) (xy 106.196683 -259.603956) (xy 106.157375 -259.568925)
			(xy 106.123875 -259.528304) (xy 106.096969 -259.483045) (xy 106.077286 -259.43421) (xy 106.065289 -259.382942)
			(xy 106.061259 -259.330444) (xy 80.09382 -259.330444) (xy 80.09382 -259.73024) (xy 98.711261 -259.73024)
			(xy 98.715291 -259.677742) (xy 98.727288 -259.626474) (xy 98.746971 -259.577639) (xy 98.773877 -259.53238)
			(xy 98.807377 -259.491759) (xy 98.846685 -259.456728) (xy 98.89088 -259.428108) (xy 98.938925 -259.406569)
			(xy 98.989696 -259.392617) (xy 99.042001 -259.386579) (xy 99.094615 -259.388596) (xy 99.146305 -259.39862)
			(xy 99.195858 -259.416418) (xy 99.242114 -259.441571) (xy 99.283988 -259.47349) (xy 99.3205 -259.511428)
			(xy 99.350792 -259.554494) (xy 99.374155 -259.601679) (xy 99.390041 -259.651878) (xy 99.398078 -259.703914)
			(xy 99.398582 -259.73024) (xy 100.611181 -259.73024) (xy 100.615211 -259.677742) (xy 100.627208 -259.626474)
			(xy 100.646891 -259.577639) (xy 100.673797 -259.53238) (xy 100.707297 -259.491759) (xy 100.746605 -259.456728)
			(xy 100.7908 -259.428108) (xy 100.838845 -259.406569) (xy 100.889616 -259.392617) (xy 100.941921 -259.386579)
			(xy 100.994535 -259.388596) (xy 101.046225 -259.39862) (xy 101.095778 -259.416418) (xy 101.142034 -259.441571)
			(xy 101.183908 -259.47349) (xy 101.22042 -259.511428) (xy 101.250712 -259.554494) (xy 101.274075 -259.601679)
			(xy 101.289961 -259.651878) (xy 101.297998 -259.703914) (xy 101.298502 -259.73024) (xy 102.511101 -259.73024)
			(xy 102.515131 -259.677742) (xy 102.527128 -259.626474) (xy 102.546811 -259.577639) (xy 102.573717 -259.53238)
			(xy 102.607217 -259.491759) (xy 102.646525 -259.456728) (xy 102.69072 -259.428108) (xy 102.738765 -259.406569)
			(xy 102.789536 -259.392617) (xy 102.841841 -259.386579) (xy 102.894455 -259.388596) (xy 102.946145 -259.39862)
			(xy 102.995698 -259.416418) (xy 103.041954 -259.441571) (xy 103.083828 -259.47349) (xy 103.12034 -259.511428)
			(xy 103.150632 -259.554494) (xy 103.173995 -259.601679) (xy 103.189881 -259.651878) (xy 103.197918 -259.703914)
			(xy 103.198422 -259.73024) (xy 103.197918 -259.756566) (xy 103.189881 -259.808602) (xy 103.173995 -259.858801)
			(xy 103.150632 -259.905986) (xy 103.12034 -259.949052) (xy 103.083828 -259.98699) (xy 103.041954 -260.018909)
			(xy 102.995698 -260.044062) (xy 102.946145 -260.06186) (xy 102.894455 -260.071884) (xy 102.841841 -260.073901)
			(xy 102.789536 -260.067863) (xy 102.738765 -260.053911) (xy 102.69072 -260.032372) (xy 102.646525 -260.003752)
			(xy 102.607217 -259.968721) (xy 102.573717 -259.9281) (xy 102.546811 -259.882841) (xy 102.527128 -259.834006)
			(xy 102.515131 -259.782738) (xy 102.511101 -259.73024) (xy 101.298502 -259.73024) (xy 101.297998 -259.756566)
			(xy 101.289961 -259.808602) (xy 101.274075 -259.858801) (xy 101.250712 -259.905986) (xy 101.22042 -259.949052)
			(xy 101.183908 -259.98699) (xy 101.142034 -260.018909) (xy 101.095778 -260.044062) (xy 101.046225 -260.06186)
			(xy 100.994535 -260.071884) (xy 100.941921 -260.073901) (xy 100.889616 -260.067863) (xy 100.838845 -260.053911)
			(xy 100.7908 -260.032372) (xy 100.746605 -260.003752) (xy 100.707297 -259.968721) (xy 100.673797 -259.9281)
			(xy 100.646891 -259.882841) (xy 100.627208 -259.834006) (xy 100.615211 -259.782738) (xy 100.611181 -259.73024)
			(xy 99.398582 -259.73024) (xy 99.398078 -259.756566) (xy 99.390041 -259.808602) (xy 99.374155 -259.858801)
			(xy 99.350792 -259.905986) (xy 99.3205 -259.949052) (xy 99.283988 -259.98699) (xy 99.242114 -260.018909)
			(xy 99.195858 -260.044062) (xy 99.146305 -260.06186) (xy 99.094615 -260.071884) (xy 99.042001 -260.073901)
			(xy 98.989696 -260.067863) (xy 98.938925 -260.053911) (xy 98.89088 -260.032372) (xy 98.846685 -260.003752)
			(xy 98.807377 -259.968721) (xy 98.773877 -259.9281) (xy 98.746971 -259.882841) (xy 98.727288 -259.834006)
			(xy 98.715291 -259.782738) (xy 98.711261 -259.73024) (xy 80.09382 -259.73024) (xy 80.09382 -260.280404)
			(xy 106.061259 -260.280404) (xy 106.065289 -260.227906) (xy 106.077286 -260.176638) (xy 106.096969 -260.127803)
			(xy 106.123875 -260.082544) (xy 106.157375 -260.041923) (xy 106.196683 -260.006892) (xy 106.240878 -259.978272)
			(xy 106.288923 -259.956733) (xy 106.339694 -259.942781) (xy 106.391999 -259.936743) (xy 106.444613 -259.93876)
			(xy 106.496303 -259.948784) (xy 106.545856 -259.966582) (xy 106.592112 -259.991735) (xy 106.633986 -260.023654)
			(xy 106.670498 -260.061592) (xy 106.70079 -260.104658) (xy 106.724153 -260.151843) (xy 106.740039 -260.202042)
			(xy 106.748076 -260.254078) (xy 106.74858 -260.280404) (xy 106.748076 -260.30673) (xy 106.740039 -260.358766)
			(xy 106.724153 -260.408965) (xy 106.70079 -260.45615) (xy 106.670498 -260.499216) (xy 106.633986 -260.537154)
			(xy 106.592112 -260.569073) (xy 106.545856 -260.594226) (xy 106.496303 -260.612024) (xy 106.444613 -260.622048)
			(xy 106.391999 -260.624065) (xy 106.339694 -260.618027) (xy 106.288923 -260.604075) (xy 106.240878 -260.582536)
			(xy 106.196683 -260.553916) (xy 106.157375 -260.518885) (xy 106.123875 -260.478264) (xy 106.096969 -260.433005)
			(xy 106.077286 -260.38417) (xy 106.065289 -260.332902) (xy 106.061259 -260.280404) (xy 80.09382 -260.280404)
			(xy 80.09382 -261.184898) (xy 80.094277 -261.194776) (xy 80.101717 -261.213078) (xy 80.108298 -261.220458)
			(xy 80.108552 -261.220712) (xy 80.403954 -261.516114) (xy 80.404462 -261.516622) (xy 80.411842 -261.523206)
			(xy 80.430142 -261.530658) (xy 80.440022 -261.5311) (xy 81.25968 -261.5311) (xy 81.26958 -261.530623)
			(xy 81.287906 -261.523123) (xy 81.302047 -261.509263) (xy 81.306416 -261.500366) (xy 81.30667 -261.49935)
			(xy 81.34096 -261.409942) (xy 81.344228 -261.400184) (xy 81.343539 -261.379635) (xy 81.334858 -261.360997)
			(xy 81.327498 -261.353808) (xy 81.308692 -261.336283) (xy 81.276651 -261.296093) (xy 81.251788 -261.251107)
			(xy 81.234805 -261.202595) (xy 81.226181 -261.151924) (xy 81.225644 -261.126224) (xy 81.226166 -261.100969)
			(xy 81.234479 -261.051147) (xy 81.25088 -261.003373) (xy 81.274921 -260.95895) (xy 81.305945 -260.91909)
			(xy 81.343107 -260.88488) (xy 81.385393 -260.857254) (xy 81.431649 -260.836964) (xy 81.480614 -260.824564)
			(xy 81.530952 -260.820393) (xy 81.58129 -260.824564) (xy 81.630255 -260.836964) (xy 81.676511 -260.857254)
			(xy 81.718797 -260.88488) (xy 81.755959 -260.91909) (xy 81.786983 -260.95895) (xy 81.811024 -261.003373)
			(xy 81.827425 -261.051147) (xy 81.835738 -261.100969) (xy 81.83626 -261.126224) (xy 81.835735 -261.151927)
			(xy 81.827132 -261.202606) (xy 81.810156 -261.251127) (xy 81.785288 -261.296116) (xy 81.753231 -261.336301)
			(xy 81.734406 -261.353808) (xy 81.727053 -261.361007) (xy 81.718345 -261.37963) (xy 81.717689 -261.400177)
			(xy 81.720944 -261.409942) (xy 81.754726 -261.498334) (xy 81.755488 -261.500366) (xy 81.759823 -261.509289)
			(xy 81.77396 -261.52318) (xy 81.792313 -261.530661) (xy 81.802224 -261.5311) (xy 82.199734 -261.5311)
			(xy 82.209639 -261.530631) (xy 82.227978 -261.523141) (xy 82.242134 -261.509282) (xy 82.24647 -261.500366)
			(xy 82.246724 -261.49935) (xy 82.281014 -261.409942) (xy 82.284284 -261.400185) (xy 82.283595 -261.379637)
			(xy 82.274908 -261.361002) (xy 82.267552 -261.353808) (xy 82.248749 -261.336282) (xy 82.216711 -261.296091)
			(xy 82.191852 -261.251104) (xy 82.174872 -261.202592) (xy 82.16625 -261.151923) (xy 82.165698 -261.126224)
			(xy 82.16622 -261.100969) (xy 82.174533 -261.051147) (xy 82.190934 -261.003373) (xy 82.214975 -260.95895)
			(xy 82.245999 -260.91909) (xy 82.283161 -260.88488) (xy 82.325447 -260.857254) (xy 82.371703 -260.836964)
			(xy 82.420668 -260.824564) (xy 82.471006 -260.820393) (xy 82.521344 -260.824564) (xy 82.570309 -260.836964)
			(xy 82.616565 -260.857254) (xy 82.658851 -260.88488) (xy 82.696013 -260.91909) (xy 82.727037 -260.95895)
			(xy 82.751078 -261.003373) (xy 82.767479 -261.051147) (xy 82.775792 -261.100969) (xy 82.776314 -261.126224)
			(xy 82.775789 -261.151927) (xy 82.767187 -261.202608) (xy 82.750214 -261.251131) (xy 82.725349 -261.296123)
			(xy 82.693295 -261.336312) (xy 82.67446 -261.353808) (xy 82.667112 -261.361009) (xy 82.658413 -261.379631)
			(xy 82.657757 -261.400175) (xy 82.660998 -261.409942) (xy 82.69478 -261.498334) (xy 82.695542 -261.500366)
			(xy 82.69988 -261.509283) (xy 82.71402 -261.523158) (xy 82.732371 -261.530621) (xy 82.742278 -261.5311)
			(xy 83.139788 -261.5311) (xy 83.149687 -261.530622) (xy 83.16801 -261.52312) (xy 83.182149 -261.50926)
			(xy 83.186524 -261.500366) (xy 83.186778 -261.49935) (xy 83.221068 -261.409942) (xy 83.224336 -261.400184)
			(xy 83.223647 -261.379635) (xy 83.214967 -261.360996) (xy 83.207606 -261.353808) (xy 83.188805 -261.336281)
			(xy 83.156773 -261.296088) (xy 83.131917 -261.251101) (xy 83.11494 -261.20259) (xy 83.106319 -261.151922)
			(xy 83.105752 -261.126224) (xy 83.106274 -261.100969) (xy 83.114587 -261.051147) (xy 83.130988 -261.003373)
			(xy 83.155029 -260.95895) (xy 83.186053 -260.91909) (xy 83.223215 -260.88488) (xy 83.265501 -260.857254)
			(xy 83.311757 -260.836964) (xy 83.360722 -260.824564) (xy 83.41106 -260.820393) (xy 83.461398 -260.824564)
			(xy 83.510363 -260.836964) (xy 83.556619 -260.857254) (xy 83.598905 -260.88488) (xy 83.636067 -260.91909)
			(xy 83.667091 -260.95895) (xy 83.691132 -261.003373) (xy 83.707533 -261.051147) (xy 83.715846 -261.100969)
			(xy 83.716368 -261.126224) (xy 83.715843 -261.151927) (xy 83.70724 -261.202607) (xy 83.690265 -261.251128)
			(xy 83.665397 -261.296117) (xy 83.633341 -261.336303) (xy 83.614514 -261.353808) (xy 83.60716 -261.361006)
			(xy 83.598451 -261.379629) (xy 83.597794 -261.400178) (xy 83.601052 -261.409942) (xy 83.634834 -261.498334)
			(xy 83.635596 -261.500366) (xy 83.639932 -261.509289) (xy 83.654069 -261.523176) (xy 83.672422 -261.530655)
			(xy 83.682332 -261.5311) (xy 84.079842 -261.5311) (xy 84.089746 -261.53063) (xy 84.108083 -261.523138)
			(xy 84.122236 -261.509279) (xy 84.126578 -261.500366) (xy 84.126832 -261.49935) (xy 84.161122 -261.409942)
			(xy 84.164392 -261.400185) (xy 84.163702 -261.379636) (xy 84.155017 -261.361001) (xy 84.14766 -261.353808)
			(xy 84.128856 -261.336282) (xy 84.096819 -261.296091) (xy 84.071959 -261.251105) (xy 84.054978 -261.202593)
			(xy 84.046356 -261.151923) (xy 84.045806 -261.126224) (xy 84.046328 -261.100969) (xy 84.054641 -261.051147)
			(xy 84.071042 -261.003373) (xy 84.095083 -260.95895) (xy 84.126107 -260.91909) (xy 84.163269 -260.88488)
			(xy 84.205555 -260.857254) (xy 84.251811 -260.836964) (xy 84.300776 -260.824564) (xy 84.351114 -260.820393)
			(xy 84.401452 -260.824564) (xy 84.450417 -260.836964) (xy 84.496673 -260.857254) (xy 84.538959 -260.88488)
			(xy 84.576121 -260.91909) (xy 84.607145 -260.95895) (xy 84.631186 -261.003373) (xy 84.647587 -261.051147)
			(xy 84.6559 -261.100969) (xy 84.656422 -261.126224) (xy 84.655897 -261.151927) (xy 84.647295 -261.202608)
			(xy 84.630322 -261.251131) (xy 84.605458 -261.296124) (xy 84.573405 -261.336313) (xy 84.554568 -261.353808)
			(xy 84.547219 -261.361009) (xy 84.538518 -261.379631) (xy 84.537862 -261.400175) (xy 84.541106 -261.409942)
			(xy 84.574888 -261.498334) (xy 84.57565 -261.500366) (xy 84.579988 -261.509283) (xy 84.594129 -261.523155)
			(xy 84.61248 -261.530615) (xy 84.622386 -261.5311) (xy 85.019642 -261.5311) (xy 85.029546 -261.53063)
			(xy 85.047883 -261.523138) (xy 85.062036 -261.509279) (xy 85.066378 -261.500366) (xy 85.066632 -261.49935)
			(xy 85.100922 -261.409942) (xy 85.104192 -261.400185) (xy 85.103502 -261.379636) (xy 85.094817 -261.361001)
			(xy 85.08746 -261.353808) (xy 85.068656 -261.336282) (xy 85.036619 -261.296091) (xy 85.011759 -261.251105)
			(xy 84.994778 -261.202593) (xy 84.986156 -261.151923) (xy 84.985606 -261.126224) (xy 84.986128 -261.100969)
			(xy 84.994441 -261.051147) (xy 85.010842 -261.003373) (xy 85.034883 -260.95895) (xy 85.065907 -260.91909)
			(xy 85.103069 -260.88488) (xy 85.145355 -260.857254) (xy 85.191611 -260.836964) (xy 85.240576 -260.824564)
			(xy 85.290914 -260.820393) (xy 85.341252 -260.824564) (xy 85.390217 -260.836964) (xy 85.436473 -260.857254)
			(xy 85.478759 -260.88488) (xy 85.515921 -260.91909) (xy 85.546945 -260.95895) (xy 85.570986 -261.003373)
			(xy 85.587387 -261.051147) (xy 85.5957 -261.100969) (xy 85.596222 -261.126224) (xy 85.595697 -261.151927)
			(xy 85.587095 -261.202608) (xy 85.570122 -261.251131) (xy 85.545258 -261.296124) (xy 85.513205 -261.336313)
			(xy 85.494368 -261.353808) (xy 85.487019 -261.361009) (xy 85.478318 -261.379631) (xy 85.477662 -261.400175)
			(xy 85.480906 -261.409942) (xy 85.514688 -261.498334) (xy 85.51545 -261.500366) (xy 85.519788 -261.509283)
			(xy 85.533929 -261.523155) (xy 85.55228 -261.530615) (xy 85.562186 -261.5311) (xy 85.959696 -261.5311)
			(xy 85.969594 -261.530621) (xy 85.987915 -261.523117) (xy 86.002051 -261.509256) (xy 86.006432 -261.500366)
			(xy 86.006686 -261.49935) (xy 86.040976 -261.409942) (xy 86.044244 -261.400184) (xy 86.043554 -261.379635)
			(xy 86.034876 -261.360996) (xy 86.027514 -261.353808) (xy 86.008713 -261.336281) (xy 85.976679 -261.296088)
			(xy 85.951823 -261.251102) (xy 85.934845 -261.20259) (xy 85.926225 -261.151922) (xy 85.92566 -261.126224)
			(xy 85.926182 -261.100969) (xy 85.934495 -261.051147) (xy 85.950896 -261.003373) (xy 85.974937 -260.95895)
			(xy 86.005961 -260.91909) (xy 86.043123 -260.88488) (xy 86.085409 -260.857254) (xy 86.131665 -260.836964)
			(xy 86.18063 -260.824564) (xy 86.230968 -260.820393) (xy 86.281306 -260.824564) (xy 86.330271 -260.836964)
			(xy 86.376527 -260.857254) (xy 86.418813 -260.88488) (xy 86.455975 -260.91909) (xy 86.486999 -260.95895)
			(xy 86.51104 -261.003373) (xy 86.527441 -261.051147) (xy 86.535754 -261.100969) (xy 86.536276 -261.126224)
			(xy 86.535751 -261.151927) (xy 86.527148 -261.202607) (xy 86.510173 -261.251128) (xy 86.485306 -261.296118)
			(xy 86.45325 -261.336304) (xy 86.434422 -261.353808) (xy 86.427067 -261.361006) (xy 86.418356 -261.379629)
			(xy 86.4177 -261.400178) (xy 86.42096 -261.409942) (xy 86.454742 -261.498334) (xy 86.455504 -261.500366)
			(xy 86.45984 -261.509288) (xy 86.473978 -261.523173) (xy 86.49233 -261.530649) (xy 86.50224 -261.5311)
			(xy 87.839804 -261.5311) (xy 87.849701 -261.530619) (xy 87.86802 -261.523114) (xy 87.882154 -261.509253)
			(xy 87.88654 -261.500366) (xy 87.886794 -261.49935) (xy 87.921084 -261.409942) (xy 87.924351 -261.400183)
			(xy 87.923662 -261.379634) (xy 87.914985 -261.360995) (xy 87.907622 -261.353808) (xy 87.88882 -261.336282)
			(xy 87.856786 -261.296089) (xy 87.831929 -261.251102) (xy 87.814951 -261.202591) (xy 87.80633 -261.151922)
			(xy 87.805768 -261.126224) (xy 87.80629 -261.100969) (xy 87.814603 -261.051147) (xy 87.831004 -261.003373)
			(xy 87.855045 -260.95895) (xy 87.886069 -260.91909) (xy 87.923231 -260.88488) (xy 87.965517 -260.857254)
			(xy 88.011773 -260.836964) (xy 88.060738 -260.824564) (xy 88.111076 -260.820393) (xy 88.161414 -260.824564)
			(xy 88.210379 -260.836964) (xy 88.256635 -260.857254) (xy 88.298921 -260.88488) (xy 88.336083 -260.91909)
			(xy 88.367107 -260.95895) (xy 88.391148 -261.003373) (xy 88.407549 -261.051147) (xy 88.415862 -261.100969)
			(xy 88.416384 -261.126224) (xy 88.415859 -261.151927) (xy 88.407257 -261.202607) (xy 88.390282 -261.251129)
			(xy 88.365415 -261.296119) (xy 88.33336 -261.336306) (xy 88.31453 -261.353808) (xy 88.307174 -261.361005)
			(xy 88.298462 -261.379629) (xy 88.297805 -261.400179) (xy 88.301068 -261.409942) (xy 88.33485 -261.498334)
			(xy 88.335612 -261.500366) (xy 88.339948 -261.509287) (xy 88.354087 -261.52317) (xy 88.372439 -261.530643)
			(xy 88.382348 -261.5311) (xy 88.779858 -261.5311) (xy 88.78976 -261.530627) (xy 88.808093 -261.523132)
			(xy 88.82224 -261.509272) (xy 88.826594 -261.500366) (xy 88.826848 -261.49935) (xy 88.861138 -261.409942)
			(xy 88.864407 -261.400184) (xy 88.863718 -261.379636) (xy 88.855034 -261.361) (xy 88.847676 -261.353808)
			(xy 88.828872 -261.336283) (xy 88.796832 -261.296092) (xy 88.771971 -261.251106) (xy 88.754989 -261.202593)
			(xy 88.746367 -261.151923) (xy 88.745822 -261.126224) (xy 88.746344 -261.100969) (xy 88.754657 -261.051147)
			(xy 88.771058 -261.003373) (xy 88.795099 -260.95895) (xy 88.826123 -260.91909) (xy 88.863285 -260.88488)
			(xy 88.905571 -260.857254) (xy 88.951827 -260.836964) (xy 89.000792 -260.824564) (xy 89.05113 -260.820393)
			(xy 89.101468 -260.824564) (xy 89.150433 -260.836964) (xy 89.196689 -260.857254) (xy 89.238975 -260.88488)
			(xy 89.276137 -260.91909) (xy 89.307161 -260.95895) (xy 89.331202 -261.003373) (xy 89.347603 -261.051147)
			(xy 89.355916 -261.100969) (xy 89.356438 -261.126224) (xy 89.355913 -261.151926) (xy 89.347309 -261.202606)
			(xy 89.330333 -261.251126) (xy 89.305463 -261.296114) (xy 89.273405 -261.336297) (xy 89.254584 -261.353808)
			(xy 89.247234 -261.361008) (xy 89.23853 -261.37963) (xy 89.237874 -261.400176) (xy 89.241122 -261.409942)
			(xy 89.274904 -261.498334) (xy 89.275666 -261.500366) (xy 89.28 -261.509292) (xy 89.294136 -261.523188)
			(xy 89.31249 -261.530677) (xy 89.322402 -261.5311) (xy 89.719658 -261.5311) (xy 89.72956 -261.530627)
			(xy 89.747893 -261.523132) (xy 89.76204 -261.509272) (xy 89.766394 -261.500366) (xy 89.766648 -261.49935)
			(xy 89.800938 -261.409942) (xy 89.804207 -261.400184) (xy 89.803518 -261.379636) (xy 89.794834 -261.361)
			(xy 89.787476 -261.353808) (xy 89.768672 -261.336283) (xy 89.736632 -261.296092) (xy 89.711771 -261.251106)
			(xy 89.694789 -261.202593) (xy 89.686167 -261.151923) (xy 89.685622 -261.126224) (xy 89.686144 -261.100969)
			(xy 89.694457 -261.051147) (xy 89.710858 -261.003373) (xy 89.734899 -260.95895) (xy 89.765923 -260.91909)
			(xy 89.803085 -260.88488) (xy 89.845371 -260.857254) (xy 89.891627 -260.836964) (xy 89.940592 -260.824564)
			(xy 89.99093 -260.820393) (xy 90.041268 -260.824564) (xy 90.090233 -260.836964) (xy 90.136489 -260.857254)
			(xy 90.178775 -260.88488) (xy 90.215937 -260.91909) (xy 90.246961 -260.95895) (xy 90.271002 -261.003373)
			(xy 90.287403 -261.051147) (xy 90.295716 -261.100969) (xy 90.296238 -261.126224) (xy 90.295713 -261.151926)
			(xy 90.287109 -261.202606) (xy 90.270133 -261.251126) (xy 90.245263 -261.296114) (xy 90.213205 -261.336297)
			(xy 90.194384 -261.353808) (xy 90.187034 -261.361008) (xy 90.17833 -261.37963) (xy 90.177674 -261.400176)
			(xy 90.180922 -261.409942) (xy 90.214704 -261.498334) (xy 90.215466 -261.500366) (xy 90.2198 -261.509292)
			(xy 90.233936 -261.523188) (xy 90.25229 -261.530677) (xy 90.262202 -261.5311) (xy 90.659712 -261.5311)
			(xy 90.669619 -261.530635) (xy 90.687965 -261.52315) (xy 90.702127 -261.509291) (xy 90.706448 -261.500366)
			(xy 90.706702 -261.49935) (xy 90.740992 -261.409942) (xy 90.744259 -261.400183) (xy 90.743569 -261.379634)
			(xy 90.734893 -261.360994) (xy 90.72753 -261.353808) (xy 90.708728 -261.336282) (xy 90.676693 -261.296089)
			(xy 90.651835 -261.251103) (xy 90.634857 -261.202591) (xy 90.626235 -261.151922) (xy 90.625676 -261.126224)
			(xy 90.626198 -261.100969) (xy 90.634511 -261.051147) (xy 90.650912 -261.003373) (xy 90.674953 -260.95895)
			(xy 90.705977 -260.91909) (xy 90.743139 -260.88488) (xy 90.785425 -260.857254) (xy 90.831681 -260.836964)
			(xy 90.880646 -260.824564) (xy 90.930984 -260.820393) (xy 90.981322 -260.824564) (xy 91.030287 -260.836964)
			(xy 91.076543 -260.857254) (xy 91.118829 -260.88488) (xy 91.155991 -260.91909) (xy 91.187015 -260.95895)
			(xy 91.211056 -261.003373) (xy 91.227457 -261.051147) (xy 91.23577 -261.100969) (xy 91.236292 -261.126224)
			(xy 91.235767 -261.151927) (xy 91.227165 -261.202607) (xy 91.21019 -261.251129) (xy 91.185324 -261.29612)
			(xy 91.153269 -261.336308) (xy 91.134438 -261.353808) (xy 91.127081 -261.361005) (xy 91.118368 -261.379629)
			(xy 91.117711 -261.400179) (xy 91.120976 -261.409942) (xy 91.154758 -261.498334) (xy 91.15552 -261.500366)
			(xy 91.159857 -261.509286) (xy 91.173995 -261.523167) (xy 91.192347 -261.530637) (xy 91.202256 -261.5311)
			(xy 91.599766 -261.5311) (xy 91.609667 -261.530626) (xy 91.627997 -261.523129) (xy 91.642143 -261.509269)
			(xy 91.646502 -261.500366) (xy 91.646756 -261.49935) (xy 91.681046 -261.409942) (xy 91.684315 -261.400184)
			(xy 91.683625 -261.379636) (xy 91.674943 -261.360999) (xy 91.667584 -261.353808) (xy 91.648779 -261.336283)
			(xy 91.616739 -261.296093) (xy 91.591877 -261.251106) (xy 91.574895 -261.202594) (xy 91.566272 -261.151923)
			(xy 91.56573 -261.126224) (xy 91.566174 -261.102231) (xy 91.573678 -261.054835) (xy 91.588505 -261.009196)
			(xy 91.61029 -260.966439) (xy 91.638496 -260.927618) (xy 91.672428 -260.893687) (xy 91.711251 -260.865483)
			(xy 91.754009 -260.8437) (xy 91.799648 -260.828875) (xy 91.847045 -260.821373) (xy 91.871038 -260.820916)
			(xy 91.894801 -260.821371) (xy 91.941753 -260.82874) (xy 91.986996 -260.843293) (xy 92.029439 -260.86468)
			(xy 92.068056 -260.892384) (xy 92.101915 -260.925735) (xy 92.130198 -260.96393) (xy 92.152223 -261.006045)
			(xy 92.167458 -261.051063) (xy 92.175534 -261.097898) (xy 92.176346 -261.121652) (xy 92.176346 -261.126478)
			(xy 92.175986 -261.147347) (xy 92.170261 -261.188691) (xy 92.158957 -261.22887) (xy 92.150946 -261.248144)
			(xy 92.150946 -261.248398) (xy 92.147672 -261.256803) (xy 92.146636 -261.2748) (xy 92.151898 -261.292041)
			(xy 92.157042 -261.299452) (xy 92.219526 -261.38124) (xy 92.24518 -261.391654) (xy 92.258896 -261.389622)
			(xy 92.294964 -261.385304) (xy 92.340684 -261.383272) (xy 92.341192 -261.383272) (xy 92.386912 -261.385304)
			(xy 92.42298 -261.389622) (xy 92.436696 -261.391654) (xy 92.46235 -261.38124) (xy 92.525088 -261.299706)
			(xy 92.530267 -261.292268) (xy 92.535522 -261.274935) (xy 92.534448 -261.256855) (xy 92.531184 -261.248398)
			(xy 92.531184 -261.248144) (xy 92.523219 -261.228989) (xy 92.511952 -261.189064) (xy 92.506196 -261.147981)
			(xy 92.505784 -261.12724) (xy 92.505784 -261.121652) (xy 92.506591 -261.097897) (xy 92.514656 -261.051058)
			(xy 92.529884 -261.006035) (xy 92.551906 -260.963916) (xy 92.580189 -260.92572) (xy 92.614051 -260.892369)
			(xy 92.652674 -260.864669) (xy 92.695122 -260.84329) (xy 92.740371 -260.828748) (xy 92.787328 -260.821396)
			(xy 92.811092 -260.820916) (xy 92.835085 -260.821362) (xy 92.88248 -260.828867) (xy 92.928117 -260.843696)
			(xy 92.970873 -260.865481) (xy 93.009693 -260.893687) (xy 93.043624 -260.927619) (xy 93.071827 -260.966441)
			(xy 93.09361 -261.009198) (xy 93.108436 -261.054836) (xy 93.11594 -261.102231) (xy 93.1164 -261.126224)
			(xy 94.385142 -261.126224) (xy 94.389102 -261.07717) (xy 94.400879 -261.029386) (xy 94.42017 -260.98411)
			(xy 94.446473 -260.942514) (xy 94.479108 -260.905677) (xy 94.517229 -260.874552) (xy 94.55985 -260.849945)
			(xy 94.605866 -260.832493) (xy 94.654085 -260.822649) (xy 94.70326 -260.820668) (xy 94.752115 -260.8266)
			(xy 94.799386 -260.840292) (xy 94.843848 -260.86139) (xy 94.884351 -260.889346) (xy 94.919844 -260.923438)
			(xy 94.949409 -260.962782) (xy 94.97228 -261.006359) (xy 94.987864 -261.05304) (xy 94.995759 -261.101617)
			(xy 94.996254 -261.126224) (xy 95.325196 -261.126224) (xy 95.329156 -261.07717) (xy 95.340933 -261.029386)
			(xy 95.360224 -260.98411) (xy 95.386527 -260.942514) (xy 95.419162 -260.905677) (xy 95.457283 -260.874552)
			(xy 95.499904 -260.849945) (xy 95.54592 -260.832493) (xy 95.594139 -260.822649) (xy 95.643314 -260.820668)
			(xy 95.692169 -260.8266) (xy 95.73944 -260.840292) (xy 95.783902 -260.86139) (xy 95.824405 -260.889346)
			(xy 95.859898 -260.923438) (xy 95.889463 -260.962782) (xy 95.912334 -261.006359) (xy 95.927918 -261.05304)
			(xy 95.935813 -261.101617) (xy 95.936308 -261.126224) (xy 96.26525 -261.126224) (xy 96.26921 -261.07717)
			(xy 96.280987 -261.029386) (xy 96.300278 -260.98411) (xy 96.326581 -260.942514) (xy 96.359216 -260.905677)
			(xy 96.397337 -260.874552) (xy 96.439958 -260.849945) (xy 96.485974 -260.832493) (xy 96.534193 -260.822649)
			(xy 96.583368 -260.820668) (xy 96.632223 -260.8266) (xy 96.679494 -260.840292) (xy 96.723956 -260.86139)
			(xy 96.764459 -260.889346) (xy 96.799952 -260.923438) (xy 96.829517 -260.962782) (xy 96.852388 -261.006359)
			(xy 96.867972 -261.05304) (xy 96.875867 -261.101617) (xy 96.876362 -261.126224) (xy 98.145358 -261.126224)
			(xy 98.149318 -261.07717) (xy 98.161095 -261.029386) (xy 98.180386 -260.98411) (xy 98.206689 -260.942514)
			(xy 98.239324 -260.905677) (xy 98.277445 -260.874552) (xy 98.320066 -260.849945) (xy 98.366082 -260.832493)
			(xy 98.414301 -260.822649) (xy 98.463476 -260.820668) (xy 98.512331 -260.8266) (xy 98.559602 -260.840292)
			(xy 98.604064 -260.86139) (xy 98.644567 -260.889346) (xy 98.68006 -260.923438) (xy 98.709625 -260.962782)
			(xy 98.732496 -261.006359) (xy 98.74808 -261.05304) (xy 98.755975 -261.101617) (xy 98.75647 -261.126224)
			(xy 100.025212 -261.126224) (xy 100.029172 -261.07717) (xy 100.040949 -261.029386) (xy 100.06024 -260.98411)
			(xy 100.086543 -260.942514) (xy 100.119178 -260.905677) (xy 100.157299 -260.874552) (xy 100.19992 -260.849945)
			(xy 100.245936 -260.832493) (xy 100.294155 -260.822649) (xy 100.34333 -260.820668) (xy 100.392185 -260.8266)
			(xy 100.439456 -260.840292) (xy 100.483918 -260.86139) (xy 100.524421 -260.889346) (xy 100.559914 -260.923438)
			(xy 100.589479 -260.962782) (xy 100.61235 -261.006359) (xy 100.627934 -261.05304) (xy 100.635829 -261.101617)
			(xy 100.636324 -261.126224) (xy 100.965266 -261.126224) (xy 100.969226 -261.07717) (xy 100.981003 -261.029386)
			(xy 101.000294 -260.98411) (xy 101.026597 -260.942514) (xy 101.059232 -260.905677) (xy 101.097353 -260.874552)
			(xy 101.139974 -260.849945) (xy 101.18599 -260.832493) (xy 101.234209 -260.822649) (xy 101.283384 -260.820668)
			(xy 101.332239 -260.8266) (xy 101.37951 -260.840292) (xy 101.423972 -260.86139) (xy 101.464475 -260.889346)
			(xy 101.499968 -260.923438) (xy 101.529533 -260.962782) (xy 101.552404 -261.006359) (xy 101.567988 -261.05304)
			(xy 101.575883 -261.101617) (xy 101.576378 -261.126224) (xy 101.90532 -261.126224) (xy 101.90928 -261.07717)
			(xy 101.921057 -261.029386) (xy 101.940348 -260.98411) (xy 101.966651 -260.942514) (xy 101.999286 -260.905677)
			(xy 102.037407 -260.874552) (xy 102.080028 -260.849945) (xy 102.126044 -260.832493) (xy 102.174263 -260.822649)
			(xy 102.223438 -260.820668) (xy 102.272293 -260.8266) (xy 102.319564 -260.840292) (xy 102.364026 -260.86139)
			(xy 102.404529 -260.889346) (xy 102.440022 -260.923438) (xy 102.469587 -260.962782) (xy 102.492458 -261.006359)
			(xy 102.508042 -261.05304) (xy 102.515937 -261.101617) (xy 102.516432 -261.126224) (xy 102.516391 -261.128256)
			(xy 102.842072 -261.128256) (xy 102.846032 -261.079202) (xy 102.857809 -261.031418) (xy 102.8771 -260.986142)
			(xy 102.903403 -260.944546) (xy 102.936038 -260.907709) (xy 102.974159 -260.876584) (xy 103.01678 -260.851977)
			(xy 103.062796 -260.834525) (xy 103.111015 -260.824681) (xy 103.16019 -260.8227) (xy 103.209045 -260.828632)
			(xy 103.256316 -260.842324) (xy 103.300778 -260.863422) (xy 103.341281 -260.891378) (xy 103.376774 -260.92547)
			(xy 103.406339 -260.964814) (xy 103.42921 -261.008391) (xy 103.444794 -261.055072) (xy 103.452689 -261.103649)
			(xy 103.453184 -261.128256) (xy 103.782126 -261.128256) (xy 103.786086 -261.079202) (xy 103.797863 -261.031418)
			(xy 103.817154 -260.986142) (xy 103.843457 -260.944546) (xy 103.876092 -260.907709) (xy 103.914213 -260.876584)
			(xy 103.956834 -260.851977) (xy 104.00285 -260.834525) (xy 104.051069 -260.824681) (xy 104.100244 -260.8227)
			(xy 104.149099 -260.828632) (xy 104.19637 -260.842324) (xy 104.240832 -260.863422) (xy 104.281335 -260.891378)
			(xy 104.316828 -260.92547) (xy 104.346393 -260.964814) (xy 104.369264 -261.008391) (xy 104.384848 -261.055072)
			(xy 104.392743 -261.103649) (xy 104.393238 -261.128256) (xy 104.392743 -261.152863) (xy 104.384848 -261.20144)
			(xy 104.369264 -261.248121) (xy 104.346393 -261.291698) (xy 104.316828 -261.331042) (xy 104.281335 -261.365134)
			(xy 104.240832 -261.39309) (xy 104.19637 -261.414188) (xy 104.149099 -261.42788) (xy 104.100244 -261.433812)
			(xy 104.051069 -261.431831) (xy 104.00285 -261.421987) (xy 103.956834 -261.404535) (xy 103.914213 -261.379928)
			(xy 103.876092 -261.348803) (xy 103.843457 -261.311966) (xy 103.817154 -261.27037) (xy 103.797863 -261.225094)
			(xy 103.786086 -261.17731) (xy 103.782126 -261.128256) (xy 103.453184 -261.128256) (xy 103.452689 -261.152863)
			(xy 103.444794 -261.20144) (xy 103.42921 -261.248121) (xy 103.406339 -261.291698) (xy 103.376774 -261.331042)
			(xy 103.341281 -261.365134) (xy 103.300778 -261.39309) (xy 103.256316 -261.414188) (xy 103.209045 -261.42788)
			(xy 103.16019 -261.433812) (xy 103.111015 -261.431831) (xy 103.062796 -261.421987) (xy 103.01678 -261.404535)
			(xy 102.974159 -261.379928) (xy 102.936038 -261.348803) (xy 102.903403 -261.311966) (xy 102.8771 -261.27037)
			(xy 102.857809 -261.225094) (xy 102.846032 -261.17731) (xy 102.842072 -261.128256) (xy 102.516391 -261.128256)
			(xy 102.515937 -261.150831) (xy 102.508042 -261.199408) (xy 102.492458 -261.246089) (xy 102.469587 -261.289666)
			(xy 102.440022 -261.32901) (xy 102.404529 -261.363102) (xy 102.364026 -261.391058) (xy 102.319564 -261.412156)
			(xy 102.272293 -261.425848) (xy 102.223438 -261.43178) (xy 102.174263 -261.429799) (xy 102.126044 -261.419955)
			(xy 102.080028 -261.402503) (xy 102.037407 -261.377896) (xy 101.999286 -261.346771) (xy 101.966651 -261.309934)
			(xy 101.940348 -261.268338) (xy 101.921057 -261.223062) (xy 101.90928 -261.175278) (xy 101.90532 -261.126224)
			(xy 101.576378 -261.126224) (xy 101.575883 -261.150831) (xy 101.567988 -261.199408) (xy 101.552404 -261.246089)
			(xy 101.529533 -261.289666) (xy 101.499968 -261.32901) (xy 101.464475 -261.363102) (xy 101.423972 -261.391058)
			(xy 101.37951 -261.412156) (xy 101.332239 -261.425848) (xy 101.283384 -261.43178) (xy 101.234209 -261.429799)
			(xy 101.18599 -261.419955) (xy 101.139974 -261.402503) (xy 101.097353 -261.377896) (xy 101.059232 -261.346771)
			(xy 101.026597 -261.309934) (xy 101.000294 -261.268338) (xy 100.981003 -261.223062) (xy 100.969226 -261.175278)
			(xy 100.965266 -261.126224) (xy 100.636324 -261.126224) (xy 100.635829 -261.150831) (xy 100.627934 -261.199408)
			(xy 100.61235 -261.246089) (xy 100.589479 -261.289666) (xy 100.559914 -261.32901) (xy 100.524421 -261.363102)
			(xy 100.483918 -261.391058) (xy 100.439456 -261.412156) (xy 100.392185 -261.425848) (xy 100.34333 -261.43178)
			(xy 100.294155 -261.429799) (xy 100.245936 -261.419955) (xy 100.19992 -261.402503) (xy 100.157299 -261.377896)
			(xy 100.119178 -261.346771) (xy 100.086543 -261.309934) (xy 100.06024 -261.268338) (xy 100.040949 -261.223062)
			(xy 100.029172 -261.175278) (xy 100.025212 -261.126224) (xy 98.75647 -261.126224) (xy 98.755975 -261.150831)
			(xy 98.74808 -261.199408) (xy 98.732496 -261.246089) (xy 98.709625 -261.289666) (xy 98.68006 -261.32901)
			(xy 98.644567 -261.363102) (xy 98.604064 -261.391058) (xy 98.559602 -261.412156) (xy 98.512331 -261.425848)
			(xy 98.463476 -261.43178) (xy 98.414301 -261.429799) (xy 98.366082 -261.419955) (xy 98.320066 -261.402503)
			(xy 98.277445 -261.377896) (xy 98.239324 -261.346771) (xy 98.206689 -261.309934) (xy 98.180386 -261.268338)
			(xy 98.161095 -261.223062) (xy 98.149318 -261.175278) (xy 98.145358 -261.126224) (xy 96.876362 -261.126224)
			(xy 96.875867 -261.150831) (xy 96.867972 -261.199408) (xy 96.852388 -261.246089) (xy 96.829517 -261.289666)
			(xy 96.799952 -261.32901) (xy 96.764459 -261.363102) (xy 96.723956 -261.391058) (xy 96.679494 -261.412156)
			(xy 96.632223 -261.425848) (xy 96.583368 -261.43178) (xy 96.534193 -261.429799) (xy 96.485974 -261.419955)
			(xy 96.439958 -261.402503) (xy 96.397337 -261.377896) (xy 96.359216 -261.346771) (xy 96.326581 -261.309934)
			(xy 96.300278 -261.268338) (xy 96.280987 -261.223062) (xy 96.26921 -261.175278) (xy 96.26525 -261.126224)
			(xy 95.936308 -261.126224) (xy 95.935813 -261.150831) (xy 95.927918 -261.199408) (xy 95.912334 -261.246089)
			(xy 95.889463 -261.289666) (xy 95.859898 -261.32901) (xy 95.824405 -261.363102) (xy 95.783902 -261.391058)
			(xy 95.73944 -261.412156) (xy 95.692169 -261.425848) (xy 95.643314 -261.43178) (xy 95.594139 -261.429799)
			(xy 95.54592 -261.419955) (xy 95.499904 -261.402503) (xy 95.457283 -261.377896) (xy 95.419162 -261.346771)
			(xy 95.386527 -261.309934) (xy 95.360224 -261.268338) (xy 95.340933 -261.223062) (xy 95.329156 -261.175278)
			(xy 95.325196 -261.126224) (xy 94.996254 -261.126224) (xy 94.995759 -261.150831) (xy 94.987864 -261.199408)
			(xy 94.97228 -261.246089) (xy 94.949409 -261.289666) (xy 94.919844 -261.32901) (xy 94.884351 -261.363102)
			(xy 94.843848 -261.391058) (xy 94.799386 -261.412156) (xy 94.752115 -261.425848) (xy 94.70326 -261.43178)
			(xy 94.654085 -261.429799) (xy 94.605866 -261.419955) (xy 94.55985 -261.402503) (xy 94.517229 -261.377896)
			(xy 94.479108 -261.346771) (xy 94.446473 -261.309934) (xy 94.42017 -261.268338) (xy 94.400879 -261.223062)
			(xy 94.389102 -261.175278) (xy 94.385142 -261.126224) (xy 93.1164 -261.126224) (xy 93.115918 -261.151073)
			(xy 93.107878 -261.200117) (xy 93.091997 -261.247211) (xy 93.068697 -261.291109) (xy 93.038592 -261.330652)
			(xy 93.002478 -261.364794) (xy 92.961309 -261.392634) (xy 92.916173 -261.413436) (xy 92.868263 -261.42665)
			(xy 92.843604 -261.429754) (xy 92.8243 -261.431786) (xy 92.798138 -261.460742) (xy 92.798138 -261.4803)
			(xy 92.798558 -261.490318) (xy 92.806229 -261.508829) (xy 92.820403 -261.522992) (xy 92.838919 -261.530649)
			(xy 92.848938 -261.5311) (xy 92.85224 -261.5311) (xy 92.920058 -261.598918) (xy 92.924963 -261.604134)
			(xy 92.931921 -261.61664) (xy 92.933774 -261.623556) (xy 92.936314 -261.634986) (xy 92.950284 -261.652766)
			(xy 93.04274 -261.698232) (xy 93.051366 -261.702096) (xy 93.070177 -261.703798) (xy 93.088323 -261.698555)
			(xy 93.09608 -261.693152) (xy 93.116155 -261.678518) (xy 93.160053 -261.655269) (xy 93.207133 -261.63942)
			(xy 93.256154 -261.63139) (xy 93.280992 -261.630922) (xy 93.304985 -261.631368) (xy 93.352379 -261.638874)
			(xy 93.398016 -261.653702) (xy 93.440771 -261.675487) (xy 93.479592 -261.703693) (xy 93.513521 -261.737625)
			(xy 93.541724 -261.776448) (xy 93.563507 -261.819204) (xy 93.578332 -261.864842) (xy 93.585834 -261.912237)
			(xy 93.5863 -261.93623) (xy 93.915242 -261.93623) (xy 93.919202 -261.887176) (xy 93.930979 -261.839392)
			(xy 93.95027 -261.794116) (xy 93.976573 -261.75252) (xy 94.009208 -261.715683) (xy 94.047329 -261.684558)
			(xy 94.08995 -261.659951) (xy 94.135966 -261.642499) (xy 94.184185 -261.632655) (xy 94.23336 -261.630674)
			(xy 94.282215 -261.636606) (xy 94.329486 -261.650298) (xy 94.373948 -261.671396) (xy 94.414451 -261.699352)
			(xy 94.449944 -261.733444) (xy 94.479509 -261.772788) (xy 94.50238 -261.816365) (xy 94.517964 -261.863046)
			(xy 94.525859 -261.911623) (xy 94.526354 -261.93623) (xy 94.855296 -261.93623) (xy 94.859256 -261.887176)
			(xy 94.871033 -261.839392) (xy 94.890324 -261.794116) (xy 94.916627 -261.75252) (xy 94.949262 -261.715683)
			(xy 94.987383 -261.684558) (xy 95.030004 -261.659951) (xy 95.07602 -261.642499) (xy 95.124239 -261.632655)
			(xy 95.173414 -261.630674) (xy 95.222269 -261.636606) (xy 95.26954 -261.650298) (xy 95.314002 -261.671396)
			(xy 95.354505 -261.699352) (xy 95.389998 -261.733444) (xy 95.419563 -261.772788) (xy 95.442434 -261.816365)
			(xy 95.458018 -261.863046) (xy 95.465913 -261.911623) (xy 95.466408 -261.93623) (xy 95.784919 -261.93623)
			(xy 95.789014 -261.885502) (xy 95.801193 -261.836088) (xy 95.821141 -261.789268) (xy 95.848342 -261.746254)
			(xy 95.88209 -261.70816) (xy 95.921512 -261.675973) (xy 95.965586 -261.650527) (xy 96.013172 -261.63248)
			(xy 96.063036 -261.6223) (xy 96.113888 -261.620251) (xy 96.164409 -261.626385) (xy 96.213293 -261.640545)
			(xy 96.259272 -261.662362) (xy 96.301156 -261.691272) (xy 96.33786 -261.726527) (xy 96.368433 -261.767213)
			(xy 96.392084 -261.812276) (xy 96.4082 -261.86055) (xy 96.416364 -261.910784) (xy 96.416876 -261.93623)
			(xy 97.675204 -261.93623) (xy 97.679164 -261.887176) (xy 97.690941 -261.839392) (xy 97.710232 -261.794116)
			(xy 97.736535 -261.75252) (xy 97.76917 -261.715683) (xy 97.807291 -261.684558) (xy 97.849912 -261.659951)
			(xy 97.895928 -261.642499) (xy 97.944147 -261.632655) (xy 97.993322 -261.630674) (xy 98.042177 -261.636606)
			(xy 98.089448 -261.650298) (xy 98.13391 -261.671396) (xy 98.174413 -261.699352) (xy 98.209906 -261.733444)
			(xy 98.239471 -261.772788) (xy 98.262342 -261.816365) (xy 98.277926 -261.863046) (xy 98.285821 -261.911623)
			(xy 98.286316 -261.93623) (xy 99.555312 -261.93623) (xy 99.559272 -261.887176) (xy 99.571049 -261.839392)
			(xy 99.59034 -261.794116) (xy 99.616643 -261.75252) (xy 99.649278 -261.715683) (xy 99.687399 -261.684558)
			(xy 99.73002 -261.659951) (xy 99.776036 -261.642499) (xy 99.824255 -261.632655) (xy 99.87343 -261.630674)
			(xy 99.922285 -261.636606) (xy 99.969556 -261.650298) (xy 100.014018 -261.671396) (xy 100.054521 -261.699352)
			(xy 100.090014 -261.733444) (xy 100.119579 -261.772788) (xy 100.14245 -261.816365) (xy 100.158034 -261.863046)
			(xy 100.165929 -261.911623) (xy 100.166424 -261.93623) (xy 101.435166 -261.93623) (xy 101.439126 -261.887176)
			(xy 101.450903 -261.839392) (xy 101.470194 -261.794116) (xy 101.496497 -261.75252) (xy 101.529132 -261.715683)
			(xy 101.567253 -261.684558) (xy 101.609874 -261.659951) (xy 101.65589 -261.642499) (xy 101.704109 -261.632655)
			(xy 101.753284 -261.630674) (xy 101.802139 -261.636606) (xy 101.84941 -261.650298) (xy 101.893872 -261.671396)
			(xy 101.934375 -261.699352) (xy 101.969868 -261.733444) (xy 101.999433 -261.772788) (xy 102.022304 -261.816365)
			(xy 102.037888 -261.863046) (xy 102.045783 -261.911623) (xy 102.046278 -261.93623) (xy 102.37522 -261.93623)
			(xy 102.37918 -261.887176) (xy 102.390957 -261.839392) (xy 102.410248 -261.794116) (xy 102.436551 -261.75252)
			(xy 102.469186 -261.715683) (xy 102.507307 -261.684558) (xy 102.549928 -261.659951) (xy 102.595944 -261.642499)
			(xy 102.644163 -261.632655) (xy 102.693338 -261.630674) (xy 102.742193 -261.636606) (xy 102.789464 -261.650298)
			(xy 102.833926 -261.671396) (xy 102.874429 -261.699352) (xy 102.909922 -261.733444) (xy 102.939487 -261.772788)
			(xy 102.962358 -261.816365) (xy 102.977942 -261.863046) (xy 102.985837 -261.911623) (xy 102.986332 -261.93623)
			(xy 102.985837 -261.960837) (xy 102.977942 -262.009414) (xy 102.962358 -262.056095) (xy 102.939487 -262.099672)
			(xy 102.909922 -262.139016) (xy 102.874429 -262.173108) (xy 102.833926 -262.201064) (xy 102.789464 -262.222162)
			(xy 102.742193 -262.235854) (xy 102.693338 -262.241786) (xy 102.644163 -262.239805) (xy 102.595944 -262.229961)
			(xy 102.549928 -262.212509) (xy 102.507307 -262.187902) (xy 102.469186 -262.156777) (xy 102.436551 -262.11994)
			(xy 102.410248 -262.078344) (xy 102.390957 -262.033068) (xy 102.37918 -261.985284) (xy 102.37522 -261.93623)
			(xy 102.046278 -261.93623) (xy 102.045783 -261.960837) (xy 102.037888 -262.009414) (xy 102.022304 -262.056095)
			(xy 101.999433 -262.099672) (xy 101.969868 -262.139016) (xy 101.934375 -262.173108) (xy 101.893872 -262.201064)
			(xy 101.84941 -262.222162) (xy 101.802139 -262.235854) (xy 101.753284 -262.241786) (xy 101.704109 -262.239805)
			(xy 101.65589 -262.229961) (xy 101.609874 -262.212509) (xy 101.567253 -262.187902) (xy 101.529132 -262.156777)
			(xy 101.496497 -262.11994) (xy 101.470194 -262.078344) (xy 101.450903 -262.033068) (xy 101.439126 -261.985284)
			(xy 101.435166 -261.93623) (xy 100.166424 -261.93623) (xy 100.165929 -261.960837) (xy 100.158034 -262.009414)
			(xy 100.14245 -262.056095) (xy 100.119579 -262.099672) (xy 100.090014 -262.139016) (xy 100.054521 -262.173108)
			(xy 100.014018 -262.201064) (xy 99.969556 -262.222162) (xy 99.922285 -262.235854) (xy 99.87343 -262.241786)
			(xy 99.824255 -262.239805) (xy 99.776036 -262.229961) (xy 99.73002 -262.212509) (xy 99.687399 -262.187902)
			(xy 99.649278 -262.156777) (xy 99.616643 -262.11994) (xy 99.59034 -262.078344) (xy 99.571049 -262.033068)
			(xy 99.559272 -261.985284) (xy 99.555312 -261.93623) (xy 98.286316 -261.93623) (xy 98.285821 -261.960837)
			(xy 98.277926 -262.009414) (xy 98.262342 -262.056095) (xy 98.239471 -262.099672) (xy 98.209906 -262.139016)
			(xy 98.174413 -262.173108) (xy 98.13391 -262.201064) (xy 98.089448 -262.222162) (xy 98.042177 -262.235854)
			(xy 97.993322 -262.241786) (xy 97.944147 -262.239805) (xy 97.895928 -262.229961) (xy 97.849912 -262.212509)
			(xy 97.807291 -262.187902) (xy 97.76917 -262.156777) (xy 97.736535 -262.11994) (xy 97.710232 -262.078344)
			(xy 97.690941 -262.033068) (xy 97.679164 -261.985284) (xy 97.675204 -261.93623) (xy 96.416876 -261.93623)
			(xy 96.416364 -261.961676) (xy 96.4082 -262.01191) (xy 96.392084 -262.060184) (xy 96.368433 -262.105247)
			(xy 96.33786 -262.145933) (xy 96.301156 -262.181188) (xy 96.259272 -262.210098) (xy 96.213293 -262.231915)
			(xy 96.164409 -262.246075) (xy 96.113888 -262.252209) (xy 96.063036 -262.25016) (xy 96.013172 -262.23998)
			(xy 95.965586 -262.221933) (xy 95.921512 -262.196487) (xy 95.88209 -262.1643) (xy 95.848342 -262.126206)
			(xy 95.821141 -262.083192) (xy 95.801193 -262.036372) (xy 95.789014 -261.986958) (xy 95.784919 -261.93623)
			(xy 95.466408 -261.93623) (xy 95.465913 -261.960837) (xy 95.458018 -262.009414) (xy 95.442434 -262.056095)
			(xy 95.419563 -262.099672) (xy 95.389998 -262.139016) (xy 95.354505 -262.173108) (xy 95.314002 -262.201064)
			(xy 95.26954 -262.222162) (xy 95.222269 -262.235854) (xy 95.173414 -262.241786) (xy 95.124239 -262.239805)
			(xy 95.07602 -262.229961) (xy 95.030004 -262.212509) (xy 94.987383 -262.187902) (xy 94.949262 -262.156777)
			(xy 94.916627 -262.11994) (xy 94.890324 -262.078344) (xy 94.871033 -262.033068) (xy 94.859256 -261.985284)
			(xy 94.855296 -261.93623) (xy 94.526354 -261.93623) (xy 94.525859 -261.960837) (xy 94.517964 -262.009414)
			(xy 94.50238 -262.056095) (xy 94.479509 -262.099672) (xy 94.449944 -262.139016) (xy 94.414451 -262.173108)
			(xy 94.373948 -262.201064) (xy 94.329486 -262.222162) (xy 94.282215 -262.235854) (xy 94.23336 -262.241786)
			(xy 94.184185 -262.239805) (xy 94.135966 -262.229961) (xy 94.08995 -262.212509) (xy 94.047329 -262.187902)
			(xy 94.009208 -262.156777) (xy 93.976573 -262.11994) (xy 93.95027 -262.078344) (xy 93.930979 -262.033068)
			(xy 93.919202 -261.985284) (xy 93.915242 -261.93623) (xy 93.5863 -261.93623) (xy 93.585835 -261.960544)
			(xy 93.57814 -262.008559) (xy 93.562934 -262.054747) (xy 93.540601 -262.097943) (xy 93.511705 -262.137054)
			(xy 93.476977 -262.171091) (xy 93.437293 -262.199196) (xy 93.393658 -262.220656) (xy 93.347173 -262.234932)
			(xy 93.323156 -262.238744) (xy 93.31088 -262.241123) (xy 93.290645 -262.255767) (xy 93.284548 -262.266684)
			(xy 93.248226 -262.340344) (xy 93.243279 -262.351954) (xy 93.244207 -262.377141) (xy 93.250004 -262.38835)
			(xy 93.294708 -262.465312) (xy 93.30518 -262.483791) (xy 93.323617 -262.522059) (xy 93.331538 -262.541766)
			(xy 93.336618 -262.55472) (xy 93.358208 -262.571738) (xy 93.45803 -262.584946) (xy 93.464894 -262.585611)
			(xy 93.47854 -262.58367) (xy 93.484954 -262.581136) (xy 93.491304 -262.578596) (xy 93.501464 -262.570214)
			(xy 93.505782 -262.564626) (xy 93.520285 -262.545796) (xy 93.55414 -262.512439) (xy 93.592753 -262.484727)
			(xy 93.635192 -262.46333) (xy 93.680432 -262.448763) (xy 93.727382 -262.441379) (xy 93.751146 -262.440928)
			(xy 93.776396 -262.441453) (xy 93.826206 -262.449772) (xy 93.873968 -262.466175) (xy 93.918378 -262.490215)
			(xy 93.958227 -262.521236) (xy 93.992427 -262.558392) (xy 94.020046 -262.60067) (xy 94.040329 -262.646918)
			(xy 94.052725 -262.695873) (xy 94.056895 -262.7462) (xy 94.056892 -262.746236) (xy 94.374711 -262.746236)
			(xy 94.378806 -262.695508) (xy 94.390985 -262.646094) (xy 94.410933 -262.599274) (xy 94.438134 -262.55626)
			(xy 94.471882 -262.518166) (xy 94.511304 -262.485979) (xy 94.555378 -262.460533) (xy 94.602964 -262.442486)
			(xy 94.652828 -262.432306) (xy 94.70368 -262.430257) (xy 94.754201 -262.436391) (xy 94.803085 -262.450551)
			(xy 94.849064 -262.472368) (xy 94.890948 -262.501278) (xy 94.927652 -262.536533) (xy 94.958225 -262.577219)
			(xy 94.981876 -262.622282) (xy 94.997992 -262.670556) (xy 95.006156 -262.72079) (xy 95.006668 -262.746236)
			(xy 95.314765 -262.746236) (xy 95.31886 -262.695508) (xy 95.331039 -262.646094) (xy 95.350987 -262.599274)
			(xy 95.378188 -262.55626) (xy 95.411936 -262.518166) (xy 95.451358 -262.485979) (xy 95.495432 -262.460533)
			(xy 95.543018 -262.442486) (xy 95.592882 -262.432306) (xy 95.643734 -262.430257) (xy 95.694255 -262.436391)
			(xy 95.743139 -262.450551) (xy 95.789118 -262.472368) (xy 95.831002 -262.501278) (xy 95.867706 -262.536533)
			(xy 95.898279 -262.577219) (xy 95.92193 -262.622282) (xy 95.938046 -262.670556) (xy 95.94621 -262.72079)
			(xy 95.946722 -262.746236) (xy 96.26525 -262.746236) (xy 96.26921 -262.697182) (xy 96.280987 -262.649398)
			(xy 96.300278 -262.604122) (xy 96.326581 -262.562526) (xy 96.359216 -262.525689) (xy 96.397337 -262.494564)
			(xy 96.439958 -262.469957) (xy 96.485974 -262.452505) (xy 96.534193 -262.442661) (xy 96.583368 -262.44068)
			(xy 96.632223 -262.446612) (xy 96.679494 -262.460304) (xy 96.723956 -262.481402) (xy 96.764459 -262.509358)
			(xy 96.799952 -262.54345) (xy 96.829517 -262.582794) (xy 96.852388 -262.626371) (xy 96.867972 -262.673052)
			(xy 96.875867 -262.721629) (xy 96.876362 -262.746236) (xy 98.145358 -262.746236) (xy 98.149318 -262.697182)
			(xy 98.161095 -262.649398) (xy 98.180386 -262.604122) (xy 98.206689 -262.562526) (xy 98.239324 -262.525689)
			(xy 98.277445 -262.494564) (xy 98.320066 -262.469957) (xy 98.366082 -262.452505) (xy 98.414301 -262.442661)
			(xy 98.463476 -262.44068) (xy 98.512331 -262.446612) (xy 98.559602 -262.460304) (xy 98.604064 -262.481402)
			(xy 98.644567 -262.509358) (xy 98.68006 -262.54345) (xy 98.709625 -262.582794) (xy 98.732496 -262.626371)
			(xy 98.74808 -262.673052) (xy 98.755975 -262.721629) (xy 98.75647 -262.746236) (xy 100.025212 -262.746236)
			(xy 100.029172 -262.697182) (xy 100.040949 -262.649398) (xy 100.06024 -262.604122) (xy 100.086543 -262.562526)
			(xy 100.119178 -262.525689) (xy 100.157299 -262.494564) (xy 100.19992 -262.469957) (xy 100.245936 -262.452505)
			(xy 100.294155 -262.442661) (xy 100.34333 -262.44068) (xy 100.392185 -262.446612) (xy 100.439456 -262.460304)
			(xy 100.483918 -262.481402) (xy 100.524421 -262.509358) (xy 100.559914 -262.54345) (xy 100.589479 -262.582794)
			(xy 100.61235 -262.626371) (xy 100.627934 -262.673052) (xy 100.635829 -262.721629) (xy 100.636324 -262.746236)
			(xy 100.965266 -262.746236) (xy 100.969226 -262.697182) (xy 100.981003 -262.649398) (xy 101.000294 -262.604122)
			(xy 101.026597 -262.562526) (xy 101.059232 -262.525689) (xy 101.097353 -262.494564) (xy 101.139974 -262.469957)
			(xy 101.18599 -262.452505) (xy 101.234209 -262.442661) (xy 101.283384 -262.44068) (xy 101.332239 -262.446612)
			(xy 101.37951 -262.460304) (xy 101.423972 -262.481402) (xy 101.464475 -262.509358) (xy 101.499968 -262.54345)
			(xy 101.529533 -262.582794) (xy 101.552404 -262.626371) (xy 101.567988 -262.673052) (xy 101.575883 -262.721629)
			(xy 101.576378 -262.746236) (xy 101.90532 -262.746236) (xy 101.90928 -262.697182) (xy 101.921057 -262.649398)
			(xy 101.940348 -262.604122) (xy 101.966651 -262.562526) (xy 101.999286 -262.525689) (xy 102.037407 -262.494564)
			(xy 102.080028 -262.469957) (xy 102.126044 -262.452505) (xy 102.174263 -262.442661) (xy 102.223438 -262.44068)
			(xy 102.272293 -262.446612) (xy 102.319564 -262.460304) (xy 102.364026 -262.481402) (xy 102.404529 -262.509358)
			(xy 102.440022 -262.54345) (xy 102.469587 -262.582794) (xy 102.492458 -262.626371) (xy 102.508042 -262.673052)
			(xy 102.515937 -262.721629) (xy 102.516432 -262.746236) (xy 102.515937 -262.770843) (xy 102.508042 -262.81942)
			(xy 102.492458 -262.866101) (xy 102.469587 -262.909678) (xy 102.440022 -262.949022) (xy 102.404529 -262.983114)
			(xy 102.364026 -263.01107) (xy 102.319564 -263.032168) (xy 102.272293 -263.04586) (xy 102.223438 -263.051792)
			(xy 102.174263 -263.049811) (xy 102.126044 -263.039967) (xy 102.080028 -263.022515) (xy 102.037407 -262.997908)
			(xy 101.999286 -262.966783) (xy 101.966651 -262.929946) (xy 101.940348 -262.88835) (xy 101.921057 -262.843074)
			(xy 101.90928 -262.79529) (xy 101.90532 -262.746236) (xy 101.576378 -262.746236) (xy 101.575883 -262.770843)
			(xy 101.567988 -262.81942) (xy 101.552404 -262.866101) (xy 101.529533 -262.909678) (xy 101.499968 -262.949022)
			(xy 101.464475 -262.983114) (xy 101.423972 -263.01107) (xy 101.37951 -263.032168) (xy 101.332239 -263.04586)
			(xy 101.283384 -263.051792) (xy 101.234209 -263.049811) (xy 101.18599 -263.039967) (xy 101.139974 -263.022515)
			(xy 101.097353 -262.997908) (xy 101.059232 -262.966783) (xy 101.026597 -262.929946) (xy 101.000294 -262.88835)
			(xy 100.981003 -262.843074) (xy 100.969226 -262.79529) (xy 100.965266 -262.746236) (xy 100.636324 -262.746236)
			(xy 100.635829 -262.770843) (xy 100.627934 -262.81942) (xy 100.61235 -262.866101) (xy 100.589479 -262.909678)
			(xy 100.559914 -262.949022) (xy 100.524421 -262.983114) (xy 100.483918 -263.01107) (xy 100.439456 -263.032168)
			(xy 100.392185 -263.04586) (xy 100.34333 -263.051792) (xy 100.294155 -263.049811) (xy 100.245936 -263.039967)
			(xy 100.19992 -263.022515) (xy 100.157299 -262.997908) (xy 100.119178 -262.966783) (xy 100.086543 -262.929946)
			(xy 100.06024 -262.88835) (xy 100.040949 -262.843074) (xy 100.029172 -262.79529) (xy 100.025212 -262.746236)
			(xy 98.75647 -262.746236) (xy 98.755975 -262.770843) (xy 98.74808 -262.81942) (xy 98.732496 -262.866101)
			(xy 98.709625 -262.909678) (xy 98.68006 -262.949022) (xy 98.644567 -262.983114) (xy 98.604064 -263.01107)
			(xy 98.559602 -263.032168) (xy 98.512331 -263.04586) (xy 98.463476 -263.051792) (xy 98.414301 -263.049811)
			(xy 98.366082 -263.039967) (xy 98.320066 -263.022515) (xy 98.277445 -262.997908) (xy 98.239324 -262.966783)
			(xy 98.206689 -262.929946) (xy 98.180386 -262.88835) (xy 98.161095 -262.843074) (xy 98.149318 -262.79529)
			(xy 98.145358 -262.746236) (xy 96.876362 -262.746236) (xy 96.875867 -262.770843) (xy 96.867972 -262.81942)
			(xy 96.852388 -262.866101) (xy 96.829517 -262.909678) (xy 96.799952 -262.949022) (xy 96.764459 -262.983114)
			(xy 96.723956 -263.01107) (xy 96.679494 -263.032168) (xy 96.632223 -263.04586) (xy 96.583368 -263.051792)
			(xy 96.534193 -263.049811) (xy 96.485974 -263.039967) (xy 96.439958 -263.022515) (xy 96.397337 -262.997908)
			(xy 96.359216 -262.966783) (xy 96.326581 -262.929946) (xy 96.300278 -262.88835) (xy 96.280987 -262.843074)
			(xy 96.26921 -262.79529) (xy 96.26525 -262.746236) (xy 95.946722 -262.746236) (xy 95.94621 -262.771682)
			(xy 95.938046 -262.821916) (xy 95.92193 -262.87019) (xy 95.898279 -262.915253) (xy 95.867706 -262.955939)
			(xy 95.831002 -262.991194) (xy 95.789118 -263.020104) (xy 95.743139 -263.041921) (xy 95.694255 -263.056081)
			(xy 95.643734 -263.062215) (xy 95.592882 -263.060166) (xy 95.543018 -263.049986) (xy 95.495432 -263.031939)
			(xy 95.451358 -263.006493) (xy 95.411936 -262.974306) (xy 95.378188 -262.936212) (xy 95.350987 -262.893198)
			(xy 95.331039 -262.846378) (xy 95.31886 -262.796964) (xy 95.314765 -262.746236) (xy 95.006668 -262.746236)
			(xy 95.006156 -262.771682) (xy 94.997992 -262.821916) (xy 94.981876 -262.87019) (xy 94.958225 -262.915253)
			(xy 94.927652 -262.955939) (xy 94.890948 -262.991194) (xy 94.849064 -263.020104) (xy 94.803085 -263.041921)
			(xy 94.754201 -263.056081) (xy 94.70368 -263.062215) (xy 94.652828 -263.060166) (xy 94.602964 -263.049986)
			(xy 94.555378 -263.031939) (xy 94.511304 -263.006493) (xy 94.471882 -262.974306) (xy 94.438134 -262.936212)
			(xy 94.410933 -262.893198) (xy 94.390985 -262.846378) (xy 94.378806 -262.796964) (xy 94.374711 -262.746236)
			(xy 94.056892 -262.746236) (xy 94.052725 -262.796527) (xy 94.040329 -262.845482) (xy 94.020046 -262.89173)
			(xy 93.992427 -262.934008) (xy 93.958227 -262.971164) (xy 93.918378 -263.002185) (xy 93.873968 -263.026225)
			(xy 93.826206 -263.042628) (xy 93.776396 -263.050947) (xy 93.751146 -263.051544) (xy 93.72738 -263.051094)
			(xy 93.680422 -263.043731) (xy 93.635173 -263.029176) (xy 93.592729 -263.007781) (xy 93.554116 -262.980063)
			(xy 93.520267 -262.946693) (xy 93.505782 -262.927846) (xy 93.501464 -262.922258) (xy 93.491304 -262.913876)
			(xy 93.484954 -262.911336) (xy 93.478545 -262.908789) (xy 93.464895 -262.906867) (xy 93.45803 -262.907526)
			(xy 93.358462 -262.920734) (xy 93.336618 -262.937752) (xy 93.331538 -262.950706) (xy 93.319555 -262.980001)
			(xy 93.289902 -263.035921) (xy 93.254127 -263.088136) (xy 93.212687 -263.13598) (xy 93.166111 -263.17884)
			(xy 93.114995 -263.216169) (xy 93.059992 -263.24749) (xy 93.001805 -263.272402) (xy 92.97162 -263.281922)
			(xy 92.971366 -263.281922) (xy 92.970604 -263.282176) (xy 92.963152 -263.284795) (xy 92.950228 -263.29386)
			(xy 92.945204 -263.299956) (xy 92.945204 -263.30021) (xy 92.940531 -263.306949) (xy 92.935341 -263.322495)
			(xy 92.935044 -263.33069) (xy 92.935044 -263.452102) (xy 92.935238 -263.45877) (xy 92.938711 -263.471645)
			(xy 92.941902 -263.477502) (xy 92.973398 -263.531604) (xy 92.987195 -263.556242) (xy 93.904811 -263.556242)
			(xy 93.908906 -263.505514) (xy 93.921085 -263.4561) (xy 93.941033 -263.40928) (xy 93.968234 -263.366266)
			(xy 94.001982 -263.328172) (xy 94.041404 -263.295985) (xy 94.085478 -263.270539) (xy 94.133064 -263.252492)
			(xy 94.182928 -263.242312) (xy 94.23378 -263.240263) (xy 94.284301 -263.246397) (xy 94.333185 -263.260557)
			(xy 94.379164 -263.282374) (xy 94.421048 -263.311284) (xy 94.457752 -263.346539) (xy 94.488325 -263.387225)
			(xy 94.511976 -263.432288) (xy 94.528092 -263.480562) (xy 94.536256 -263.530796) (xy 94.536768 -263.556242)
			(xy 94.855296 -263.556242) (xy 94.859256 -263.507188) (xy 94.871033 -263.459404) (xy 94.890324 -263.414128)
			(xy 94.916627 -263.372532) (xy 94.949262 -263.335695) (xy 94.987383 -263.30457) (xy 95.030004 -263.279963)
			(xy 95.07602 -263.262511) (xy 95.124239 -263.252667) (xy 95.173414 -263.250686) (xy 95.222269 -263.256618)
			(xy 95.26954 -263.27031) (xy 95.314002 -263.291408) (xy 95.354505 -263.319364) (xy 95.389998 -263.353456)
			(xy 95.419563 -263.3928) (xy 95.442434 -263.436377) (xy 95.458018 -263.483058) (xy 95.465913 -263.531635)
			(xy 95.466408 -263.556242) (xy 95.784919 -263.556242) (xy 95.789014 -263.505514) (xy 95.801193 -263.4561)
			(xy 95.821141 -263.40928) (xy 95.848342 -263.366266) (xy 95.88209 -263.328172) (xy 95.921512 -263.295985)
			(xy 95.965586 -263.270539) (xy 96.013172 -263.252492) (xy 96.063036 -263.242312) (xy 96.113888 -263.240263)
			(xy 96.164409 -263.246397) (xy 96.213293 -263.260557) (xy 96.259272 -263.282374) (xy 96.301156 -263.311284)
			(xy 96.33786 -263.346539) (xy 96.368433 -263.387225) (xy 96.392084 -263.432288) (xy 96.4082 -263.480562)
			(xy 96.416364 -263.530796) (xy 96.416876 -263.556242) (xy 97.675204 -263.556242) (xy 97.679164 -263.507188)
			(xy 97.690941 -263.459404) (xy 97.710232 -263.414128) (xy 97.736535 -263.372532) (xy 97.76917 -263.335695)
			(xy 97.807291 -263.30457) (xy 97.849912 -263.279963) (xy 97.895928 -263.262511) (xy 97.944147 -263.252667)
			(xy 97.993322 -263.250686) (xy 98.042177 -263.256618) (xy 98.089448 -263.27031) (xy 98.13391 -263.291408)
			(xy 98.174413 -263.319364) (xy 98.209906 -263.353456) (xy 98.239471 -263.3928) (xy 98.262342 -263.436377)
			(xy 98.277926 -263.483058) (xy 98.285821 -263.531635) (xy 98.286316 -263.556242) (xy 99.555312 -263.556242)
			(xy 99.559272 -263.507188) (xy 99.571049 -263.459404) (xy 99.59034 -263.414128) (xy 99.616643 -263.372532)
			(xy 99.649278 -263.335695) (xy 99.687399 -263.30457) (xy 99.73002 -263.279963) (xy 99.776036 -263.262511)
			(xy 99.824255 -263.252667) (xy 99.87343 -263.250686) (xy 99.922285 -263.256618) (xy 99.969556 -263.27031)
			(xy 100.014018 -263.291408) (xy 100.054521 -263.319364) (xy 100.090014 -263.353456) (xy 100.119579 -263.3928)
			(xy 100.14245 -263.436377) (xy 100.158034 -263.483058) (xy 100.165929 -263.531635) (xy 100.166424 -263.556242)
			(xy 101.435166 -263.556242) (xy 101.439126 -263.507188) (xy 101.450903 -263.459404) (xy 101.470194 -263.414128)
			(xy 101.496497 -263.372532) (xy 101.529132 -263.335695) (xy 101.567253 -263.30457) (xy 101.609874 -263.279963)
			(xy 101.65589 -263.262511) (xy 101.704109 -263.252667) (xy 101.753284 -263.250686) (xy 101.802139 -263.256618)
			(xy 101.84941 -263.27031) (xy 101.893872 -263.291408) (xy 101.934375 -263.319364) (xy 101.969868 -263.353456)
			(xy 101.999433 -263.3928) (xy 102.022304 -263.436377) (xy 102.037888 -263.483058) (xy 102.045783 -263.531635)
			(xy 102.046278 -263.556242) (xy 102.045783 -263.580849) (xy 102.037888 -263.629426) (xy 102.022304 -263.676107)
			(xy 101.999433 -263.719684) (xy 101.969868 -263.759028) (xy 101.934375 -263.79312) (xy 101.893872 -263.821076)
			(xy 101.84941 -263.842174) (xy 101.802139 -263.855866) (xy 101.753284 -263.861798) (xy 101.704109 -263.859817)
			(xy 101.65589 -263.849973) (xy 101.609874 -263.832521) (xy 101.567253 -263.807914) (xy 101.529132 -263.776789)
			(xy 101.496497 -263.739952) (xy 101.470194 -263.698356) (xy 101.450903 -263.65308) (xy 101.439126 -263.605296)
			(xy 101.435166 -263.556242) (xy 100.166424 -263.556242) (xy 100.165929 -263.580849) (xy 100.158034 -263.629426)
			(xy 100.14245 -263.676107) (xy 100.119579 -263.719684) (xy 100.090014 -263.759028) (xy 100.054521 -263.79312)
			(xy 100.014018 -263.821076) (xy 99.969556 -263.842174) (xy 99.922285 -263.855866) (xy 99.87343 -263.861798)
			(xy 99.824255 -263.859817) (xy 99.776036 -263.849973) (xy 99.73002 -263.832521) (xy 99.687399 -263.807914)
			(xy 99.649278 -263.776789) (xy 99.616643 -263.739952) (xy 99.59034 -263.698356) (xy 99.571049 -263.65308)
			(xy 99.559272 -263.605296) (xy 99.555312 -263.556242) (xy 98.286316 -263.556242) (xy 98.285821 -263.580849)
			(xy 98.277926 -263.629426) (xy 98.262342 -263.676107) (xy 98.239471 -263.719684) (xy 98.209906 -263.759028)
			(xy 98.174413 -263.79312) (xy 98.13391 -263.821076) (xy 98.089448 -263.842174) (xy 98.042177 -263.855866)
			(xy 97.993322 -263.861798) (xy 97.944147 -263.859817) (xy 97.895928 -263.849973) (xy 97.849912 -263.832521)
			(xy 97.807291 -263.807914) (xy 97.76917 -263.776789) (xy 97.736535 -263.739952) (xy 97.710232 -263.698356)
			(xy 97.690941 -263.65308) (xy 97.679164 -263.605296) (xy 97.675204 -263.556242) (xy 96.416876 -263.556242)
			(xy 96.416364 -263.581688) (xy 96.4082 -263.631922) (xy 96.392084 -263.680196) (xy 96.368433 -263.725259)
			(xy 96.33786 -263.765945) (xy 96.301156 -263.8012) (xy 96.259272 -263.83011) (xy 96.213293 -263.851927)
			(xy 96.164409 -263.866087) (xy 96.113888 -263.872221) (xy 96.063036 -263.870172) (xy 96.013172 -263.859992)
			(xy 95.965586 -263.841945) (xy 95.921512 -263.816499) (xy 95.88209 -263.784312) (xy 95.848342 -263.746218)
			(xy 95.821141 -263.703204) (xy 95.801193 -263.656384) (xy 95.789014 -263.60697) (xy 95.784919 -263.556242)
			(xy 95.466408 -263.556242) (xy 95.465913 -263.580849) (xy 95.458018 -263.629426) (xy 95.442434 -263.676107)
			(xy 95.419563 -263.719684) (xy 95.389998 -263.759028) (xy 95.354505 -263.79312) (xy 95.314002 -263.821076)
			(xy 95.26954 -263.842174) (xy 95.222269 -263.855866) (xy 95.173414 -263.861798) (xy 95.124239 -263.859817)
			(xy 95.07602 -263.849973) (xy 95.030004 -263.832521) (xy 94.987383 -263.807914) (xy 94.949262 -263.776789)
			(xy 94.916627 -263.739952) (xy 94.890324 -263.698356) (xy 94.871033 -263.65308) (xy 94.859256 -263.605296)
			(xy 94.855296 -263.556242) (xy 94.536768 -263.556242) (xy 94.536256 -263.581688) (xy 94.528092 -263.631922)
			(xy 94.511976 -263.680196) (xy 94.488325 -263.725259) (xy 94.457752 -263.765945) (xy 94.421048 -263.8012)
			(xy 94.379164 -263.83011) (xy 94.333185 -263.851927) (xy 94.284301 -263.866087) (xy 94.23378 -263.872221)
			(xy 94.182928 -263.870172) (xy 94.133064 -263.859992) (xy 94.085478 -263.841945) (xy 94.041404 -263.816499)
			(xy 94.001982 -263.784312) (xy 93.968234 -263.746218) (xy 93.941033 -263.703204) (xy 93.921085 -263.656384)
			(xy 93.908906 -263.60697) (xy 93.904811 -263.556242) (xy 92.987195 -263.556242) (xy 92.99228 -263.565323)
			(xy 93.0216 -263.636827) (xy 93.031818 -263.674098) (xy 93.033596 -263.680956) (xy 93.047058 -263.70407)
			(xy 93.052138 -263.70915) (xy 93.052392 -263.709404) (xy 93.079243 -263.736423) (xy 93.126144 -263.796447)
			(xy 93.145864 -263.829038) (xy 93.294708 -264.085324) (xy 93.305179 -264.103803) (xy 93.323616 -264.142071)
			(xy 93.331538 -264.161778) (xy 93.336618 -264.174732) (xy 93.358208 -264.19175) (xy 93.45803 -264.204958)
			(xy 93.464894 -264.205622) (xy 93.47854 -264.203682) (xy 93.484954 -264.201148) (xy 93.491304 -264.198608)
			(xy 93.501464 -264.190226) (xy 93.505782 -264.184638) (xy 93.520285 -264.165807) (xy 93.55414 -264.132449)
			(xy 93.592752 -264.104736) (xy 93.635191 -264.083338) (xy 93.680431 -264.068771) (xy 93.727382 -264.061386)
			(xy 93.751146 -264.06094) (xy 93.776395 -264.061465) (xy 93.826203 -264.069783) (xy 93.873963 -264.086186)
			(xy 93.918372 -264.110225) (xy 93.958219 -264.141245) (xy 93.992418 -264.1784) (xy 94.020035 -264.220676)
			(xy 94.040318 -264.266922) (xy 94.052713 -264.315875) (xy 94.056883 -264.3662) (xy 94.056879 -264.366248)
			(xy 94.374711 -264.366248) (xy 94.378806 -264.31552) (xy 94.390985 -264.266106) (xy 94.410933 -264.219286)
			(xy 94.438134 -264.176272) (xy 94.471882 -264.138178) (xy 94.511304 -264.105991) (xy 94.555378 -264.080545)
			(xy 94.602964 -264.062498) (xy 94.652828 -264.052318) (xy 94.70368 -264.050269) (xy 94.754201 -264.056403)
			(xy 94.803085 -264.070563) (xy 94.849064 -264.09238) (xy 94.890948 -264.12129) (xy 94.927652 -264.156545)
			(xy 94.958225 -264.197231) (xy 94.981876 -264.242294) (xy 94.997992 -264.290568) (xy 95.006156 -264.340802)
			(xy 95.006668 -264.366248) (xy 95.314765 -264.366248) (xy 95.31886 -264.31552) (xy 95.331039 -264.266106)
			(xy 95.350987 -264.219286) (xy 95.378188 -264.176272) (xy 95.411936 -264.138178) (xy 95.451358 -264.105991)
			(xy 95.495432 -264.080545) (xy 95.543018 -264.062498) (xy 95.592882 -264.052318) (xy 95.643734 -264.050269)
			(xy 95.694255 -264.056403) (xy 95.743139 -264.070563) (xy 95.789118 -264.09238) (xy 95.831002 -264.12129)
			(xy 95.867706 -264.156545) (xy 95.898279 -264.197231) (xy 95.92193 -264.242294) (xy 95.938046 -264.290568)
			(xy 95.94621 -264.340802) (xy 95.946722 -264.366248) (xy 96.26525 -264.366248) (xy 96.26921 -264.317194)
			(xy 96.280987 -264.26941) (xy 96.300278 -264.224134) (xy 96.326581 -264.182538) (xy 96.359216 -264.145701)
			(xy 96.397337 -264.114576) (xy 96.439958 -264.089969) (xy 96.485974 -264.072517) (xy 96.534193 -264.062673)
			(xy 96.583368 -264.060692) (xy 96.632223 -264.066624) (xy 96.679494 -264.080316) (xy 96.723956 -264.101414)
			(xy 96.764459 -264.12937) (xy 96.799952 -264.163462) (xy 96.829517 -264.202806) (xy 96.852388 -264.246383)
			(xy 96.867972 -264.293064) (xy 96.875867 -264.341641) (xy 96.876362 -264.366248) (xy 98.145358 -264.366248)
			(xy 98.149318 -264.317194) (xy 98.161095 -264.26941) (xy 98.180386 -264.224134) (xy 98.206689 -264.182538)
			(xy 98.239324 -264.145701) (xy 98.277445 -264.114576) (xy 98.320066 -264.089969) (xy 98.366082 -264.072517)
			(xy 98.414301 -264.062673) (xy 98.463476 -264.060692) (xy 98.512331 -264.066624) (xy 98.559602 -264.080316)
			(xy 98.604064 -264.101414) (xy 98.644567 -264.12937) (xy 98.68006 -264.163462) (xy 98.709625 -264.202806)
			(xy 98.732496 -264.246383) (xy 98.74808 -264.293064) (xy 98.755975 -264.341641) (xy 98.75647 -264.366248)
			(xy 100.025212 -264.366248) (xy 100.029172 -264.317194) (xy 100.040949 -264.26941) (xy 100.06024 -264.224134)
			(xy 100.086543 -264.182538) (xy 100.119178 -264.145701) (xy 100.157299 -264.114576) (xy 100.19992 -264.089969)
			(xy 100.245936 -264.072517) (xy 100.294155 -264.062673) (xy 100.34333 -264.060692) (xy 100.392185 -264.066624)
			(xy 100.439456 -264.080316) (xy 100.483918 -264.101414) (xy 100.524421 -264.12937) (xy 100.559914 -264.163462)
			(xy 100.589479 -264.202806) (xy 100.61235 -264.246383) (xy 100.627934 -264.293064) (xy 100.635829 -264.341641)
			(xy 100.636324 -264.366248) (xy 100.965266 -264.366248) (xy 100.969226 -264.317194) (xy 100.981003 -264.26941)
			(xy 101.000294 -264.224134) (xy 101.026597 -264.182538) (xy 101.059232 -264.145701) (xy 101.097353 -264.114576)
			(xy 101.139974 -264.089969) (xy 101.18599 -264.072517) (xy 101.234209 -264.062673) (xy 101.283384 -264.060692)
			(xy 101.332239 -264.066624) (xy 101.37951 -264.080316) (xy 101.423972 -264.101414) (xy 101.464475 -264.12937)
			(xy 101.499968 -264.163462) (xy 101.529533 -264.202806) (xy 101.552404 -264.246383) (xy 101.567988 -264.293064)
			(xy 101.575883 -264.341641) (xy 101.576378 -264.366248) (xy 101.575883 -264.390855) (xy 101.567988 -264.439432)
			(xy 101.552404 -264.486113) (xy 101.529533 -264.52969) (xy 101.499968 -264.569034) (xy 101.464475 -264.603126)
			(xy 101.423972 -264.631082) (xy 101.37951 -264.65218) (xy 101.332239 -264.665872) (xy 101.283384 -264.671804)
			(xy 101.234209 -264.669823) (xy 101.18599 -264.659979) (xy 101.139974 -264.642527) (xy 101.097353 -264.61792)
			(xy 101.059232 -264.586795) (xy 101.026597 -264.549958) (xy 101.000294 -264.508362) (xy 100.981003 -264.463086)
			(xy 100.969226 -264.415302) (xy 100.965266 -264.366248) (xy 100.636324 -264.366248) (xy 100.635829 -264.390855)
			(xy 100.627934 -264.439432) (xy 100.61235 -264.486113) (xy 100.589479 -264.52969) (xy 100.559914 -264.569034)
			(xy 100.524421 -264.603126) (xy 100.483918 -264.631082) (xy 100.439456 -264.65218) (xy 100.392185 -264.665872)
			(xy 100.34333 -264.671804) (xy 100.294155 -264.669823) (xy 100.245936 -264.659979) (xy 100.19992 -264.642527)
			(xy 100.157299 -264.61792) (xy 100.119178 -264.586795) (xy 100.086543 -264.549958) (xy 100.06024 -264.508362)
			(xy 100.040949 -264.463086) (xy 100.029172 -264.415302) (xy 100.025212 -264.366248) (xy 98.75647 -264.366248)
			(xy 98.755975 -264.390855) (xy 98.74808 -264.439432) (xy 98.732496 -264.486113) (xy 98.709625 -264.52969)
			(xy 98.68006 -264.569034) (xy 98.644567 -264.603126) (xy 98.604064 -264.631082) (xy 98.559602 -264.65218)
			(xy 98.512331 -264.665872) (xy 98.463476 -264.671804) (xy 98.414301 -264.669823) (xy 98.366082 -264.659979)
			(xy 98.320066 -264.642527) (xy 98.277445 -264.61792) (xy 98.239324 -264.586795) (xy 98.206689 -264.549958)
			(xy 98.180386 -264.508362) (xy 98.161095 -264.463086) (xy 98.149318 -264.415302) (xy 98.145358 -264.366248)
			(xy 96.876362 -264.366248) (xy 96.875867 -264.390855) (xy 96.867972 -264.439432) (xy 96.852388 -264.486113)
			(xy 96.829517 -264.52969) (xy 96.799952 -264.569034) (xy 96.764459 -264.603126) (xy 96.723956 -264.631082)
			(xy 96.679494 -264.65218) (xy 96.632223 -264.665872) (xy 96.583368 -264.671804) (xy 96.534193 -264.669823)
			(xy 96.485974 -264.659979) (xy 96.439958 -264.642527) (xy 96.397337 -264.61792) (xy 96.359216 -264.586795)
			(xy 96.326581 -264.549958) (xy 96.300278 -264.508362) (xy 96.280987 -264.463086) (xy 96.26921 -264.415302)
			(xy 96.26525 -264.366248) (xy 95.946722 -264.366248) (xy 95.94621 -264.391694) (xy 95.938046 -264.441928)
			(xy 95.92193 -264.490202) (xy 95.898279 -264.535265) (xy 95.867706 -264.575951) (xy 95.831002 -264.611206)
			(xy 95.789118 -264.640116) (xy 95.743139 -264.661933) (xy 95.694255 -264.676093) (xy 95.643734 -264.682227)
			(xy 95.592882 -264.680178) (xy 95.543018 -264.669998) (xy 95.495432 -264.651951) (xy 95.451358 -264.626505)
			(xy 95.411936 -264.594318) (xy 95.378188 -264.556224) (xy 95.350987 -264.51321) (xy 95.331039 -264.46639)
			(xy 95.31886 -264.416976) (xy 95.314765 -264.366248) (xy 95.006668 -264.366248) (xy 95.006156 -264.391694)
			(xy 94.997992 -264.441928) (xy 94.981876 -264.490202) (xy 94.958225 -264.535265) (xy 94.927652 -264.575951)
			(xy 94.890948 -264.611206) (xy 94.849064 -264.640116) (xy 94.803085 -264.661933) (xy 94.754201 -264.676093)
			(xy 94.70368 -264.682227) (xy 94.652828 -264.680178) (xy 94.602964 -264.669998) (xy 94.555378 -264.651951)
			(xy 94.511304 -264.626505) (xy 94.471882 -264.594318) (xy 94.438134 -264.556224) (xy 94.410933 -264.51321)
			(xy 94.390985 -264.46639) (xy 94.378806 -264.416976) (xy 94.374711 -264.366248) (xy 94.056879 -264.366248)
			(xy 94.052713 -264.416525) (xy 94.040318 -264.465478) (xy 94.020035 -264.511724) (xy 93.992418 -264.554001)
			(xy 93.958219 -264.591155) (xy 93.918372 -264.622175) (xy 93.873963 -264.646214) (xy 93.826203 -264.662617)
			(xy 93.776395 -264.670935) (xy 93.751146 -264.671556) (xy 93.727381 -264.671105) (xy 93.680425 -264.663741)
			(xy 93.63518 -264.649183) (xy 93.59274 -264.627783) (xy 93.554132 -264.600061) (xy 93.520291 -264.566686)
			(xy 93.505782 -264.547858) (xy 93.501464 -264.54227) (xy 93.491304 -264.533888) (xy 93.484954 -264.531348)
			(xy 93.478546 -264.5288) (xy 93.464895 -264.526878) (xy 93.45803 -264.527538) (xy 93.358208 -264.540746)
			(xy 93.336618 -264.557764) (xy 93.331538 -264.570718) (xy 93.31599 -264.608391) (xy 93.275571 -264.679158)
			(xy 93.25102 -264.711688) (xy 93.242384 -264.722356) (xy 93.238574 -264.749788) (xy 93.282262 -264.854944)
			(xy 93.303852 -264.871454) (xy 93.317822 -264.873232) (xy 93.342183 -264.876696) (xy 93.389438 -264.890398)
			(xy 93.433886 -264.911498) (xy 93.474376 -264.939451) (xy 93.509861 -264.973534) (xy 93.539423 -265.012865)
			(xy 93.562297 -265.056426) (xy 93.577891 -265.103092) (xy 93.585802 -265.151653) (xy 93.5863 -265.176254)
			(xy 93.904811 -265.176254) (xy 93.908906 -265.125526) (xy 93.921085 -265.076112) (xy 93.941033 -265.029292)
			(xy 93.968234 -264.986278) (xy 94.001982 -264.948184) (xy 94.041404 -264.915997) (xy 94.085478 -264.890551)
			(xy 94.133064 -264.872504) (xy 94.182928 -264.862324) (xy 94.23378 -264.860275) (xy 94.284301 -264.866409)
			(xy 94.333185 -264.880569) (xy 94.379164 -264.902386) (xy 94.421048 -264.931296) (xy 94.457752 -264.966551)
			(xy 94.488325 -265.007237) (xy 94.511976 -265.0523) (xy 94.528092 -265.100574) (xy 94.536256 -265.150808)
			(xy 94.536768 -265.176254) (xy 94.855296 -265.176254) (xy 94.859256 -265.1272) (xy 94.871033 -265.079416)
			(xy 94.890324 -265.03414) (xy 94.916627 -264.992544) (xy 94.949262 -264.955707) (xy 94.987383 -264.924582)
			(xy 95.030004 -264.899975) (xy 95.07602 -264.882523) (xy 95.124239 -264.872679) (xy 95.173414 -264.870698)
			(xy 95.222269 -264.87663) (xy 95.26954 -264.890322) (xy 95.314002 -264.91142) (xy 95.354505 -264.939376)
			(xy 95.389998 -264.973468) (xy 95.419563 -265.012812) (xy 95.442434 -265.056389) (xy 95.458018 -265.10307)
			(xy 95.465913 -265.151647) (xy 95.466408 -265.176254) (xy 95.79535 -265.176254) (xy 95.79931 -265.1272)
			(xy 95.811087 -265.079416) (xy 95.830378 -265.03414) (xy 95.856681 -264.992544) (xy 95.889316 -264.955707)
			(xy 95.927437 -264.924582) (xy 95.970058 -264.899975) (xy 96.016074 -264.882523) (xy 96.064293 -264.872679)
			(xy 96.113468 -264.870698) (xy 96.162323 -264.87663) (xy 96.209594 -264.890322) (xy 96.254056 -264.91142)
			(xy 96.294559 -264.939376) (xy 96.330052 -264.973468) (xy 96.359617 -265.012812) (xy 96.382488 -265.056389)
			(xy 96.398072 -265.10307) (xy 96.405967 -265.151647) (xy 96.406462 -265.176254) (xy 97.675204 -265.176254)
			(xy 97.679164 -265.1272) (xy 97.690941 -265.079416) (xy 97.710232 -265.03414) (xy 97.736535 -264.992544)
			(xy 97.76917 -264.955707) (xy 97.807291 -264.924582) (xy 97.849912 -264.899975) (xy 97.895928 -264.882523)
			(xy 97.944147 -264.872679) (xy 97.993322 -264.870698) (xy 98.042177 -264.87663) (xy 98.089448 -264.890322)
			(xy 98.13391 -264.91142) (xy 98.174413 -264.939376) (xy 98.209906 -264.973468) (xy 98.239471 -265.012812)
			(xy 98.262342 -265.056389) (xy 98.277926 -265.10307) (xy 98.285821 -265.151647) (xy 98.286316 -265.176254)
			(xy 99.555312 -265.176254) (xy 99.559272 -265.1272) (xy 99.571049 -265.079416) (xy 99.59034 -265.03414)
			(xy 99.616643 -264.992544) (xy 99.649278 -264.955707) (xy 99.687399 -264.924582) (xy 99.73002 -264.899975)
			(xy 99.776036 -264.882523) (xy 99.824255 -264.872679) (xy 99.87343 -264.870698) (xy 99.922285 -264.87663)
			(xy 99.969556 -264.890322) (xy 100.014018 -264.91142) (xy 100.054521 -264.939376) (xy 100.090014 -264.973468)
			(xy 100.119579 -265.012812) (xy 100.14245 -265.056389) (xy 100.158034 -265.10307) (xy 100.165929 -265.151647)
			(xy 100.166424 -265.176254) (xy 100.165929 -265.200861) (xy 100.158034 -265.249438) (xy 100.14245 -265.296119)
			(xy 100.119579 -265.339696) (xy 100.090014 -265.37904) (xy 100.054521 -265.413132) (xy 100.014018 -265.441088)
			(xy 99.969556 -265.462186) (xy 99.922285 -265.475878) (xy 99.87343 -265.48181) (xy 99.824255 -265.479829)
			(xy 99.776036 -265.469985) (xy 99.73002 -265.452533) (xy 99.687399 -265.427926) (xy 99.649278 -265.396801)
			(xy 99.616643 -265.359964) (xy 99.59034 -265.318368) (xy 99.571049 -265.273092) (xy 99.559272 -265.225308)
			(xy 99.555312 -265.176254) (xy 98.286316 -265.176254) (xy 98.285821 -265.200861) (xy 98.277926 -265.249438)
			(xy 98.262342 -265.296119) (xy 98.239471 -265.339696) (xy 98.209906 -265.37904) (xy 98.174413 -265.413132)
			(xy 98.13391 -265.441088) (xy 98.089448 -265.462186) (xy 98.042177 -265.475878) (xy 97.993322 -265.48181)
			(xy 97.944147 -265.479829) (xy 97.895928 -265.469985) (xy 97.849912 -265.452533) (xy 97.807291 -265.427926)
			(xy 97.76917 -265.396801) (xy 97.736535 -265.359964) (xy 97.710232 -265.318368) (xy 97.690941 -265.273092)
			(xy 97.679164 -265.225308) (xy 97.675204 -265.176254) (xy 96.406462 -265.176254) (xy 96.405967 -265.200861)
			(xy 96.398072 -265.249438) (xy 96.382488 -265.296119) (xy 96.359617 -265.339696) (xy 96.330052 -265.37904)
			(xy 96.294559 -265.413132) (xy 96.254056 -265.441088) (xy 96.209594 -265.462186) (xy 96.162323 -265.475878)
			(xy 96.113468 -265.48181) (xy 96.064293 -265.479829) (xy 96.016074 -265.469985) (xy 95.970058 -265.452533)
			(xy 95.927437 -265.427926) (xy 95.889316 -265.396801) (xy 95.856681 -265.359964) (xy 95.830378 -265.318368)
			(xy 95.811087 -265.273092) (xy 95.79931 -265.225308) (xy 95.79535 -265.176254) (xy 95.466408 -265.176254)
			(xy 95.465913 -265.200861) (xy 95.458018 -265.249438) (xy 95.442434 -265.296119) (xy 95.419563 -265.339696)
			(xy 95.389998 -265.37904) (xy 95.354505 -265.413132) (xy 95.314002 -265.441088) (xy 95.26954 -265.462186)
			(xy 95.222269 -265.475878) (xy 95.173414 -265.48181) (xy 95.124239 -265.479829) (xy 95.07602 -265.469985)
			(xy 95.030004 -265.452533) (xy 94.987383 -265.427926) (xy 94.949262 -265.396801) (xy 94.916627 -265.359964)
			(xy 94.890324 -265.318368) (xy 94.871033 -265.273092) (xy 94.859256 -265.225308) (xy 94.855296 -265.176254)
			(xy 94.536768 -265.176254) (xy 94.536256 -265.2017) (xy 94.528092 -265.251934) (xy 94.511976 -265.300208)
			(xy 94.488325 -265.345271) (xy 94.457752 -265.385957) (xy 94.421048 -265.421212) (xy 94.379164 -265.450122)
			(xy 94.333185 -265.471939) (xy 94.284301 -265.486099) (xy 94.23378 -265.492233) (xy 94.182928 -265.490184)
			(xy 94.133064 -265.480004) (xy 94.085478 -265.461957) (xy 94.041404 -265.436511) (xy 94.001982 -265.404324)
			(xy 93.968234 -265.36623) (xy 93.941033 -265.323216) (xy 93.921085 -265.276396) (xy 93.908906 -265.226982)
			(xy 93.904811 -265.176254) (xy 93.5863 -265.176254) (xy 93.585857 -265.200249) (xy 93.578356 -265.24765)
			(xy 93.563532 -265.293293) (xy 93.541749 -265.336055) (xy 93.513544 -265.374882) (xy 93.479611 -265.408819)
			(xy 93.440788 -265.437029) (xy 93.398028 -265.458817) (xy 93.352387 -265.473647) (xy 93.304987 -265.481154)
			(xy 93.280992 -265.481562) (xy 93.256354 -265.480546) (xy 93.248743 -265.480263) (xy 93.233895 -265.483623)
			(xy 93.227144 -265.48715) (xy 93.218611 -265.4925) (xy 93.206299 -265.508418) (xy 93.201066 -265.52785)
			(xy 93.203719 -265.547798) (xy 93.208348 -265.556746) (xy 93.242638 -265.615674) (xy 93.247972 -265.623548)
			(xy 93.254945 -265.630959) (xy 93.27316 -265.639989) (xy 93.283278 -265.641074) (xy 93.28658 -265.641074)
		)
		(stroke
			(width 0)
			(type solid)
		)
		(fill yes)
		(layer "In4.Cu")
		(net "PVDDIO_P1")
	)
	(gr_poly
		(pts
			(xy 199.23633 -366.360964) (xy 199.243575 -366.359339) (xy 199.256748 -366.352501) (xy 199.262238 -366.347502)
			(xy 204.797914 -360.811826) (xy 204.804758 -360.804428) (xy 204.812479 -360.785828) (xy 204.8129 -360.775758)
			(xy 204.8129 -358.534716) (xy 204.813339 -358.524653) (xy 204.821074 -358.50607) (xy 204.827886 -358.498648)
			(xy 208.186274 -355.14026) (xy 208.193117 -355.132861) (xy 208.200841 -355.114262) (xy 208.20126 -355.104192)
			(xy 208.20126 -352.352102) (xy 208.201684 -352.342033) (xy 208.209405 -352.323434) (xy 208.216246 -352.316034)
			(xy 209.954622 -350.577658) (xy 209.96147 -350.570261) (xy 209.969202 -350.551662) (xy 209.969608 -350.54159)
			(xy 209.969608 -350.536002) (xy 209.970027 -350.525981) (xy 209.977697 -350.507465) (xy 209.99187 -350.493294)
			(xy 210.010387 -350.485626) (xy 210.020408 -350.485202) (xy 210.86318 -350.485202) (xy 210.873244 -350.484764)
			(xy 210.891827 -350.47703) (xy 210.899248 -350.470216) (xy 218.510866 -342.858598) (xy 218.518268 -342.851762)
			(xy 218.536866 -342.844052) (xy 218.546934 -342.843612) (xy 221.523306 -342.843612) (xy 221.533376 -342.843188)
			(xy 221.55198 -342.835474) (xy 221.559374 -342.828626) (xy 222.58147 -341.80653) (xy 222.588309 -341.799129)
			(xy 222.596022 -341.780531) (xy 222.596456 -341.770462) (xy 222.596456 -340.797896) (xy 222.596113 -340.788908)
			(xy 222.589908 -340.772038) (xy 222.578235 -340.758368) (xy 222.570548 -340.7537) (xy 222.547325 -340.740077)
			(xy 222.504605 -340.707308) (xy 222.466915 -340.668861) (xy 222.435001 -340.6255) (xy 222.409497 -340.578083)
			(xy 222.390909 -340.527554) (xy 222.379606 -340.474913) (xy 222.375813 -340.421207) (xy 222.379604 -340.3675)
			(xy 222.390905 -340.31486) (xy 222.409491 -340.264329) (xy 222.434993 -340.216912) (xy 222.466906 -340.173549)
			(xy 222.504595 -340.135101) (xy 222.547313 -340.10233) (xy 222.570548 -340.088728) (xy 222.5782 -340.084014)
			(xy 222.58986 -340.070351) (xy 222.596113 -340.053512) (xy 222.596456 -340.044532) (xy 222.596456 -333.944976)
			(xy 222.596027 -333.934909) (xy 222.588302 -333.916315) (xy 222.58147 -333.908908) (xy 222.376238 -333.703676)
			(xy 222.363639 -333.690459) (xy 222.343331 -333.66012) (xy 222.329321 -333.626407) (xy 222.322143 -333.590611)
			(xy 222.321628 -333.572358) (xy 222.321628 -332.234032) (xy 222.321125 -332.22398) (xy 222.313406 -332.205416)
			(xy 222.306642 -332.197964) (xy 213.287356 -323.178424) (xy 213.279956 -323.171582) (xy 213.261358 -323.163859)
			(xy 213.251288 -323.163438) (xy 208.259934 -323.163438) (xy 208.249886 -323.163857) (xy 208.231326 -323.17156)
			(xy 208.217145 -323.185797) (xy 208.212944 -323.194934) (xy 208.206848 -323.209158) (xy 208.212944 -323.23913)
			(xy 209.065876 -324.092062) (xy 209.073277 -324.098901) (xy 209.091875 -324.106613) (xy 209.101944 -324.107048)
			(xy 211.00161 -324.107048) (xy 211.010597 -324.106704) (xy 211.027465 -324.100497) (xy 211.041131 -324.088823)
			(xy 211.045806 -324.08114) (xy 211.096352 -323.991732) (xy 211.095844 -323.964554) (xy 211.088478 -323.952616)
			(xy 211.075404 -323.930167) (xy 211.054782 -323.882486) (xy 211.040819 -323.832448) (xy 211.033772 -323.780979)
			(xy 211.03336 -323.755004) (xy 211.033846 -323.727753) (xy 211.041602 -323.673805) (xy 211.056957 -323.62151)
			(xy 211.079599 -323.571933) (xy 211.109065 -323.526083) (xy 211.144756 -323.484892) (xy 211.185947 -323.449201)
			(xy 211.231797 -323.419735) (xy 211.281374 -323.397093) (xy 211.333669 -323.381738) (xy 211.387617 -323.373982)
			(xy 211.442119 -323.373982) (xy 211.496067 -323.381738) (xy 211.548362 -323.397093) (xy 211.597939 -323.419735)
			(xy 211.643789 -323.449201) (xy 211.68498 -323.484892) (xy 211.720671 -323.526083) (xy 211.750137 -323.571933)
			(xy 211.772779 -323.62151) (xy 211.788134 -323.673805) (xy 211.79589 -323.727753) (xy 211.796376 -323.755004)
			(xy 211.79596 -323.780643) (xy 211.789092 -323.83146) (xy 211.775481 -323.880898) (xy 211.75537 -323.928069)
			(xy 211.729124 -323.972121) (xy 211.697214 -324.012261) (xy 211.679028 -324.03034) (xy 211.672218 -324.037569)
			(xy 211.664254 -324.05574) (xy 211.663534 -324.065646) (xy 211.661248 -324.146926) (xy 211.668614 -324.165722)
			(xy 211.675472 -324.173088) (xy 211.694826 -324.194435) (xy 211.727543 -324.241865) (xy 211.752761 -324.293673)
			(xy 211.769905 -324.348683) (xy 211.778586 -324.405644) (xy 211.779104 -324.434454) (xy 211.778549 -324.464435)
			(xy 211.769171 -324.52366) (xy 211.750639 -324.580686) (xy 211.72341 -324.63411) (xy 211.688155 -324.682613)
			(xy 211.667344 -324.704202) (xy 211.613496 -324.75805) (xy 211.59192 -324.778785) (xy 211.543503 -324.813947)
			(xy 211.490185 -324.841107) (xy 211.433275 -324.859596) (xy 211.374175 -324.868961) (xy 211.344256 -324.869556)
			(xy 208.922366 -324.869556) (xy 208.892451 -324.868947) (xy 208.83336 -324.859556) (xy 208.77646 -324.841057)
			(xy 208.723145 -324.813904) (xy 208.674721 -324.778761) (xy 208.653126 -324.75805) (xy 207.353408 -323.458078)
			(xy 207.346014 -323.451222) (xy 207.327415 -323.443472) (xy 207.31734 -323.443092) (xy 162.814508 -323.443092)
			(xy 162.804437 -323.443513) (xy 162.78583 -323.451225) (xy 162.77844 -323.458078) (xy 161.583116 -324.653656)
			(xy 161.561502 -324.674436) (xy 161.512997 -324.709675) (xy 161.459578 -324.736895) (xy 161.40256 -324.755426)
			(xy 161.343345 -324.764813) (xy 161.313368 -324.765416) (xy 161.282981 -324.764808) (xy 161.222981 -324.755137)
			(xy 161.165273 -324.736075) (xy 161.111317 -324.708107) (xy 161.062477 -324.671937) (xy 161.040826 -324.650608)
			(xy 161.033714 -324.643496) (xy 161.015172 -324.635622) (xy 160.932876 -324.635114) (xy 160.922768 -324.63545)
			(xy 160.904039 -324.643044) (xy 160.896554 -324.649846) (xy 158.451296 -327.095104) (xy 214.451436 -327.095104)
			(xy 214.455507 -327.039482) (xy 214.467633 -326.985045) (xy 214.487556 -326.932954) (xy 214.514852 -326.884319)
			(xy 214.548938 -326.840176) (xy 214.589087 -326.801467) (xy 214.634445 -326.769016) (xy 214.684045 -326.743515)
			(xy 214.736829 -326.725508) (xy 214.791672 -326.715378) (xy 214.847406 -326.713341) (xy 214.902843 -326.719441)
			(xy 214.9568 -326.733547) (xy 215.008129 -326.755359) (xy 215.055735 -326.784413) (xy 215.098603 -326.820088)
			(xy 215.13582 -326.861625) (xy 215.166593 -326.908138) (xy 215.190265 -326.958635) (xy 215.206333 -327.012042)
			(xy 215.214453 -327.067218) (xy 215.214962 -327.095104) (xy 215.214453 -327.12299) (xy 215.206333 -327.178166)
			(xy 215.190265 -327.231573) (xy 215.166593 -327.28207) (xy 215.13582 -327.328583) (xy 215.098603 -327.37012)
			(xy 215.055735 -327.405795) (xy 215.008129 -327.434849) (xy 214.9568 -327.456661) (xy 214.902843 -327.470767)
			(xy 214.847406 -327.476867) (xy 214.791672 -327.47483) (xy 214.736829 -327.4647) (xy 214.684045 -327.446693)
			(xy 214.634445 -327.421192) (xy 214.589087 -327.388741) (xy 214.548938 -327.350032) (xy 214.514852 -327.305889)
			(xy 214.487556 -327.257254) (xy 214.467633 -327.205163) (xy 214.455507 -327.150726) (xy 214.451436 -327.095104)
			(xy 158.451296 -327.095104) (xy 158.285942 -327.260458) (xy 158.2791 -327.267858) (xy 158.27138 -327.286456)
			(xy 158.270956 -327.296526) (xy 158.270956 -327.340468) (xy 158.270519 -327.350532) (xy 158.262782 -327.369114)
			(xy 158.25597 -327.376536) (xy 157.423866 -328.20864) (xy 199.140062 -328.20864) (xy 199.144133 -328.153018)
			(xy 199.156259 -328.098581) (xy 199.176182 -328.04649) (xy 199.203478 -327.997855) (xy 199.237564 -327.953712)
			(xy 199.277713 -327.915003) (xy 199.323071 -327.882552) (xy 199.372671 -327.857051) (xy 199.425455 -327.839044)
			(xy 199.480298 -327.828914) (xy 199.536032 -327.826877) (xy 199.591469 -327.832977) (xy 199.645426 -327.847083)
			(xy 199.696755 -327.868895) (xy 199.744361 -327.897949) (xy 199.787229 -327.933624) (xy 199.824446 -327.975161)
			(xy 199.855219 -328.021674) (xy 199.878891 -328.072171) (xy 199.894959 -328.125578) (xy 199.903079 -328.180754)
			(xy 199.903588 -328.20864) (xy 200.029062 -328.20864) (xy 200.033133 -328.153018) (xy 200.045259 -328.098581)
			(xy 200.065182 -328.04649) (xy 200.092478 -327.997855) (xy 200.126564 -327.953712) (xy 200.166713 -327.915003)
			(xy 200.212071 -327.882552) (xy 200.261671 -327.857051) (xy 200.314455 -327.839044) (xy 200.369298 -327.828914)
			(xy 200.425032 -327.826877) (xy 200.480469 -327.832977) (xy 200.534426 -327.847083) (xy 200.585755 -327.868895)
			(xy 200.633361 -327.897949) (xy 200.676229 -327.933624) (xy 200.713446 -327.975161) (xy 200.744219 -328.021674)
			(xy 200.767891 -328.072171) (xy 200.783959 -328.125578) (xy 200.792079 -328.180754) (xy 200.792588 -328.20864)
			(xy 200.918062 -328.20864) (xy 200.922133 -328.153018) (xy 200.934259 -328.098581) (xy 200.954182 -328.04649)
			(xy 200.981478 -327.997855) (xy 201.015564 -327.953712) (xy 201.055713 -327.915003) (xy 201.101071 -327.882552)
			(xy 201.150671 -327.857051) (xy 201.203455 -327.839044) (xy 201.258298 -327.828914) (xy 201.314032 -327.826877)
			(xy 201.369469 -327.832977) (xy 201.423426 -327.847083) (xy 201.474755 -327.868895) (xy 201.522361 -327.897949)
			(xy 201.565229 -327.933624) (xy 201.602446 -327.975161) (xy 201.633219 -328.021674) (xy 201.656891 -328.072171)
			(xy 201.672959 -328.125578) (xy 201.681079 -328.180754) (xy 201.681588 -328.20864) (xy 201.807062 -328.20864)
			(xy 201.811133 -328.153018) (xy 201.823259 -328.098581) (xy 201.843182 -328.04649) (xy 201.870478 -327.997855)
			(xy 201.904564 -327.953712) (xy 201.944713 -327.915003) (xy 201.990071 -327.882552) (xy 202.039671 -327.857051)
			(xy 202.092455 -327.839044) (xy 202.147298 -327.828914) (xy 202.203032 -327.826877) (xy 202.258469 -327.832977)
			(xy 202.312426 -327.847083) (xy 202.363755 -327.868895) (xy 202.411361 -327.897949) (xy 202.454229 -327.933624)
			(xy 202.491446 -327.975161) (xy 202.522219 -328.021674) (xy 202.527468 -328.032872) (xy 214.738456 -328.032872)
			(xy 214.742527 -327.97725) (xy 214.754653 -327.922813) (xy 214.774576 -327.870722) (xy 214.801872 -327.822087)
			(xy 214.835958 -327.777944) (xy 214.876107 -327.739235) (xy 214.921465 -327.706784) (xy 214.971065 -327.681283)
			(xy 215.023849 -327.663276) (xy 215.078692 -327.653146) (xy 215.134426 -327.651109) (xy 215.189863 -327.657209)
			(xy 215.24382 -327.671315) (xy 215.295149 -327.693127) (xy 215.342755 -327.722181) (xy 215.385623 -327.757856)
			(xy 215.42284 -327.799393) (xy 215.453613 -327.845906) (xy 215.477285 -327.896403) (xy 215.493353 -327.94981)
			(xy 215.501473 -328.004986) (xy 215.501982 -328.032872) (xy 215.501473 -328.060758) (xy 215.493353 -328.115934)
			(xy 215.477285 -328.169341) (xy 215.453613 -328.219838) (xy 215.42284 -328.266351) (xy 215.385623 -328.307888)
			(xy 215.342755 -328.343563) (xy 215.295149 -328.372617) (xy 215.24382 -328.394429) (xy 215.189863 -328.408535)
			(xy 215.134426 -328.414635) (xy 215.078692 -328.412598) (xy 215.023849 -328.402468) (xy 214.971065 -328.384461)
			(xy 214.921465 -328.35896) (xy 214.876107 -328.326509) (xy 214.835958 -328.2878) (xy 214.801872 -328.243657)
			(xy 214.774576 -328.195022) (xy 214.754653 -328.142931) (xy 214.742527 -328.088494) (xy 214.738456 -328.032872)
			(xy 202.527468 -328.032872) (xy 202.545891 -328.072171) (xy 202.561959 -328.125578) (xy 202.570079 -328.180754)
			(xy 202.570588 -328.20864) (xy 202.570079 -328.236526) (xy 202.561959 -328.291702) (xy 202.545891 -328.345109)
			(xy 202.522219 -328.395606) (xy 202.491446 -328.442119) (xy 202.454229 -328.483656) (xy 202.411361 -328.519331)
			(xy 202.363755 -328.548385) (xy 202.312426 -328.570197) (xy 202.258469 -328.584303) (xy 202.203032 -328.590403)
			(xy 202.147298 -328.588366) (xy 202.092455 -328.578236) (xy 202.039671 -328.560229) (xy 201.990071 -328.534728)
			(xy 201.944713 -328.502277) (xy 201.904564 -328.463568) (xy 201.870478 -328.419425) (xy 201.843182 -328.37079)
			(xy 201.823259 -328.318699) (xy 201.811133 -328.264262) (xy 201.807062 -328.20864) (xy 201.681588 -328.20864)
			(xy 201.681079 -328.236526) (xy 201.672959 -328.291702) (xy 201.656891 -328.345109) (xy 201.633219 -328.395606)
			(xy 201.602446 -328.442119) (xy 201.565229 -328.483656) (xy 201.522361 -328.519331) (xy 201.474755 -328.548385)
			(xy 201.423426 -328.570197) (xy 201.369469 -328.584303) (xy 201.314032 -328.590403) (xy 201.258298 -328.588366)
			(xy 201.203455 -328.578236) (xy 201.150671 -328.560229) (xy 201.101071 -328.534728) (xy 201.055713 -328.502277)
			(xy 201.015564 -328.463568) (xy 200.981478 -328.419425) (xy 200.954182 -328.37079) (xy 200.934259 -328.318699)
			(xy 200.922133 -328.264262) (xy 200.918062 -328.20864) (xy 200.792588 -328.20864) (xy 200.792079 -328.236526)
			(xy 200.783959 -328.291702) (xy 200.767891 -328.345109) (xy 200.744219 -328.395606) (xy 200.713446 -328.442119)
			(xy 200.676229 -328.483656) (xy 200.633361 -328.519331) (xy 200.585755 -328.548385) (xy 200.534426 -328.570197)
			(xy 200.480469 -328.584303) (xy 200.425032 -328.590403) (xy 200.369298 -328.588366) (xy 200.314455 -328.578236)
			(xy 200.261671 -328.560229) (xy 200.212071 -328.534728) (xy 200.166713 -328.502277) (xy 200.126564 -328.463568)
			(xy 200.092478 -328.419425) (xy 200.065182 -328.37079) (xy 200.045259 -328.318699) (xy 200.033133 -328.264262)
			(xy 200.029062 -328.20864) (xy 199.903588 -328.20864) (xy 199.903079 -328.236526) (xy 199.894959 -328.291702)
			(xy 199.878891 -328.345109) (xy 199.855219 -328.395606) (xy 199.824446 -328.442119) (xy 199.787229 -328.483656)
			(xy 199.744361 -328.519331) (xy 199.696755 -328.548385) (xy 199.645426 -328.570197) (xy 199.591469 -328.584303)
			(xy 199.536032 -328.590403) (xy 199.480298 -328.588366) (xy 199.425455 -328.578236) (xy 199.372671 -328.560229)
			(xy 199.323071 -328.534728) (xy 199.277713 -328.502277) (xy 199.237564 -328.463568) (xy 199.203478 -328.419425)
			(xy 199.176182 -328.37079) (xy 199.156259 -328.318699) (xy 199.144133 -328.264262) (xy 199.140062 -328.20864)
			(xy 157.423866 -328.20864) (xy 156.355451 -329.277055) (xy 197.238541 -329.277055) (xy 197.238541 -329.222545)
			(xy 197.246299 -329.16859) (xy 197.261656 -329.116289) (xy 197.284301 -329.066706) (xy 197.313772 -329.02085)
			(xy 197.349469 -328.979655) (xy 197.390666 -328.94396) (xy 197.436523 -328.914492) (xy 197.486108 -328.891849)
			(xy 197.53841 -328.876494) (xy 197.592365 -328.86874) (xy 197.61962 -328.868278) (xy 197.646992 -328.868713)
			(xy 197.701173 -328.876536) (xy 197.753677 -328.892031) (xy 197.803423 -328.91488) (xy 197.849388 -328.944613)
			(xy 197.870318 -328.962258) (xy 197.870572 -328.962512) (xy 197.877661 -328.968094) (xy 197.894576 -328.974343)
			(xy 197.903592 -328.974704) (xy 197.970648 -328.974704) (xy 197.979662 -328.974321) (xy 197.996579 -328.968091)
			(xy 198.003668 -328.962512) (xy 198.003668 -328.962258) (xy 198.003922 -328.962258) (xy 198.024867 -328.944635)
			(xy 198.070837 -328.914922) (xy 198.120581 -328.892084) (xy 198.173079 -328.876589) (xy 198.227252 -328.868755)
			(xy 198.25462 -328.868278) (xy 198.282153 -328.868754) (xy 198.336646 -328.876679) (xy 198.389435 -328.892348)
			(xy 198.439428 -328.915436) (xy 198.485586 -328.945463) (xy 198.506588 -328.963274) (xy 198.514672 -328.969748)
			(xy 198.534341 -328.97617) (xy 198.544688 -328.97572) (xy 198.618602 -328.969116) (xy 198.628713 -328.967689)
			(xy 198.646665 -328.957995) (xy 198.6534 -328.95032) (xy 198.653908 -328.949812) (xy 198.672086 -328.927612)
			(xy 198.713978 -328.888406) (xy 198.761274 -328.855923) (xy 198.812905 -328.830897) (xy 198.867703 -328.813893)
			(xy 198.924432 -328.805295) (xy 198.95312 -328.804778) (xy 198.980371 -328.805259) (xy 199.034318 -328.813018)
			(xy 199.086612 -328.828375) (xy 199.136189 -328.851017) (xy 199.182038 -328.880484) (xy 199.223228 -328.916176)
			(xy 199.258919 -328.957367) (xy 199.288385 -329.003217) (xy 199.311027 -329.052793) (xy 199.326383 -329.105088)
			(xy 199.334141 -329.159035) (xy 199.334628 -329.186286) (xy 199.334171 -329.213657) (xy 199.326354 -329.267837)
			(xy 199.310864 -329.320341) (xy 199.288019 -329.370088) (xy 199.258291 -329.416053) (xy 199.240648 -329.436984)
			(xy 199.240394 -329.437238) (xy 199.234827 -329.444338) (xy 199.228569 -329.461244) (xy 199.228202 -329.470258)
			(xy 199.228202 -329.537314) (xy 199.228552 -329.546332) (xy 199.234804 -329.563248) (xy 199.240394 -329.570334)
			(xy 199.240648 -329.570334) (xy 199.240648 -329.570588) (xy 199.258276 -329.591531) (xy 199.288003 -329.637497)
			(xy 199.310851 -329.687241) (xy 199.326349 -329.739742) (xy 199.33418 -329.793919) (xy 199.334181 -329.84866)
			(xy 199.326354 -329.902838) (xy 199.310858 -329.955339) (xy 199.288013 -330.005085) (xy 199.258289 -330.051052)
			(xy 199.240648 -330.071984) (xy 199.240394 -330.072238) (xy 199.234827 -330.079338) (xy 199.228569 -330.096244)
			(xy 199.228202 -330.105258) (xy 199.228202 -330.172314) (xy 199.228552 -330.181332) (xy 199.234804 -330.198248)
			(xy 199.240394 -330.205334) (xy 199.240648 -330.205334) (xy 199.240648 -330.205588) (xy 199.258287 -330.22652)
			(xy 199.288001 -330.272492) (xy 199.310837 -330.32224) (xy 199.326328 -330.374741) (xy 199.334155 -330.428917)
			(xy 199.334628 -330.456286) (xy 202.635612 -330.456286) (xy 202.636067 -330.428915) (xy 202.643887 -330.374736)
			(xy 202.659379 -330.322232) (xy 202.682223 -330.272486) (xy 202.71195 -330.226519) (xy 202.729592 -330.205588)
			(xy 202.729846 -330.205334) (xy 202.73543 -330.198246) (xy 202.741677 -330.18133) (xy 202.742038 -330.172314)
			(xy 202.742038 -330.105258) (xy 202.741645 -330.096245) (xy 202.735422 -330.079328) (xy 202.729846 -330.072238)
			(xy 202.729592 -330.072238) (xy 202.729592 -330.071984) (xy 202.711939 -330.051062) (xy 202.682217 -330.005091)
			(xy 202.659375 -329.955343) (xy 202.643881 -329.90284) (xy 202.636055 -329.84866) (xy 202.636056 -329.793919)
			(xy 202.643886 -329.73974) (xy 202.659383 -329.687237) (xy 202.682228 -329.63749) (xy 202.711952 -329.591521)
			(xy 202.729592 -329.570588) (xy 202.729846 -329.570334) (xy 202.73543 -329.563246) (xy 202.741677 -329.54633)
			(xy 202.742038 -329.537314) (xy 202.742038 -329.470258) (xy 202.741645 -329.461245) (xy 202.735422 -329.444328)
			(xy 202.729846 -329.437238) (xy 202.729592 -329.437238) (xy 202.729592 -329.436984) (xy 202.711978 -329.416032)
			(xy 202.682262 -329.370065) (xy 202.659422 -329.320322) (xy 202.643925 -329.267826) (xy 202.63609 -329.213654)
			(xy 202.635612 -329.186286) (xy 202.636042 -329.159032) (xy 202.643801 -329.105079) (xy 202.65916 -329.052779)
			(xy 202.681806 -329.003197) (xy 202.711277 -328.957343) (xy 202.746974 -328.91615) (xy 202.788171 -328.880457)
			(xy 202.834027 -328.850989) (xy 202.883611 -328.828348) (xy 202.935912 -328.812994) (xy 202.989866 -328.805239)
			(xy 203.01712 -328.804778) (xy 203.04584 -328.805265) (xy 203.10263 -328.813885) (xy 203.157484 -328.830927)
			(xy 203.209161 -328.856004) (xy 203.256492 -328.88855) (xy 203.298404 -328.927828) (xy 203.316586 -328.950066)
			(xy 203.31684 -328.95032) (xy 203.323594 -328.957977) (xy 203.341531 -328.967685) (xy 203.351638 -328.969116)
			(xy 203.425552 -328.97572) (xy 203.435899 -328.976186) (xy 203.455567 -328.96975) (xy 203.463652 -328.963274)
			(xy 203.484661 -328.945471) (xy 203.530812 -328.915432) (xy 203.580802 -328.892339) (xy 203.633593 -328.876673)
			(xy 203.688087 -328.868759) (xy 203.71562 -328.868278) (xy 203.742992 -328.868713) (xy 203.797173 -328.876536)
			(xy 203.849677 -328.892031) (xy 203.899423 -328.91488) (xy 203.945388 -328.944613) (xy 203.966318 -328.962258)
			(xy 203.966572 -328.962512) (xy 203.973661 -328.968094) (xy 203.990576 -328.974343) (xy 203.999592 -328.974704)
			(xy 204.066648 -328.974704) (xy 204.075662 -328.974321) (xy 204.092579 -328.968091) (xy 204.099668 -328.962512)
			(xy 204.099668 -328.962258) (xy 204.099922 -328.962258) (xy 204.120867 -328.944635) (xy 204.166837 -328.914922)
			(xy 204.216581 -328.892084) (xy 204.269079 -328.876589) (xy 204.323252 -328.868755) (xy 204.35062 -328.868278)
			(xy 204.377869 -328.868794) (xy 204.431813 -328.876552) (xy 204.484103 -328.891908) (xy 204.533676 -328.91455)
			(xy 204.579522 -328.944016) (xy 204.620708 -328.979706) (xy 204.656396 -329.020894) (xy 204.68586 -329.066742)
			(xy 204.708499 -329.116316) (xy 204.723852 -329.168607) (xy 204.725371 -329.179174) (xy 214.729312 -329.179174)
			(xy 214.733383 -329.123552) (xy 214.745509 -329.069115) (xy 214.765432 -329.017024) (xy 214.792728 -328.968389)
			(xy 214.826814 -328.924246) (xy 214.866963 -328.885537) (xy 214.912321 -328.853086) (xy 214.961921 -328.827585)
			(xy 215.014705 -328.809578) (xy 215.069548 -328.799448) (xy 215.125282 -328.797411) (xy 215.180719 -328.803511)
			(xy 215.234676 -328.817617) (xy 215.286005 -328.839429) (xy 215.333611 -328.868483) (xy 215.376479 -328.904158)
			(xy 215.413696 -328.945695) (xy 215.444469 -328.992208) (xy 215.468141 -329.042705) (xy 215.484209 -329.096112)
			(xy 215.492329 -329.151288) (xy 215.492838 -329.179174) (xy 215.492329 -329.20706) (xy 215.484209 -329.262236)
			(xy 215.468141 -329.315643) (xy 215.444469 -329.36614) (xy 215.413696 -329.412653) (xy 215.376479 -329.45419)
			(xy 215.333611 -329.489865) (xy 215.286005 -329.518919) (xy 215.234676 -329.540731) (xy 215.180719 -329.554837)
			(xy 215.125282 -329.560937) (xy 215.069548 -329.5589) (xy 215.014705 -329.54877) (xy 214.961921 -329.530763)
			(xy 214.912321 -329.505262) (xy 214.866963 -329.472811) (xy 214.826814 -329.434102) (xy 214.792728 -329.389959)
			(xy 214.765432 -329.341324) (xy 214.745509 -329.289233) (xy 214.733383 -329.234796) (xy 214.729312 -329.179174)
			(xy 204.725371 -329.179174) (xy 204.731608 -329.222551) (xy 204.731608 -329.277049) (xy 204.723852 -329.330993)
			(xy 204.708499 -329.383284) (xy 204.68586 -329.432858) (xy 204.656396 -329.478706) (xy 204.620708 -329.519894)
			(xy 204.579522 -329.555584) (xy 204.533676 -329.58505) (xy 204.484103 -329.607692) (xy 204.431813 -329.623048)
			(xy 204.377869 -329.630806) (xy 204.35062 -329.631294) (xy 204.32325 -329.630818) (xy 204.269071 -329.623003)
			(xy 204.216568 -329.607516) (xy 204.166821 -329.584676) (xy 204.120854 -329.554954) (xy 204.099922 -329.537314)
			(xy 204.099668 -329.53706) (xy 204.09257 -329.531491) (xy 204.075662 -329.525235) (xy 204.066648 -329.524868)
			(xy 203.999592 -329.524868) (xy 203.990576 -329.525228) (xy 203.973659 -329.531474) (xy 203.966572 -329.53706)
			(xy 203.966572 -329.537314) (xy 203.966318 -329.537314) (xy 203.945392 -329.55496) (xy 203.899417 -329.584671)
			(xy 203.849668 -329.607505) (xy 203.797166 -329.622994) (xy 203.74299 -329.630821) (xy 203.71562 -329.631294)
			(xy 203.689029 -329.630885) (xy 203.636363 -329.623503) (xy 203.585236 -329.608864) (xy 203.536643 -329.587255)
			(xy 203.491529 -329.559095) (xy 203.450772 -329.524932) (xy 203.415165 -329.48543) (xy 203.399898 -329.463654)
			(xy 203.393005 -329.454667) (xy 203.373511 -329.443195) (xy 203.362306 -329.441556) (xy 203.305156 -329.436476)
			(xy 203.304648 -329.436984) (xy 203.304394 -329.437238) (xy 203.298827 -329.444338) (xy 203.292569 -329.461244)
			(xy 203.292202 -329.470258) (xy 203.292202 -329.537314) (xy 203.292552 -329.546332) (xy 203.298804 -329.563248)
			(xy 203.304394 -329.570334) (xy 203.304648 -329.570334) (xy 203.304648 -329.570588) (xy 203.322276 -329.591531)
			(xy 203.352003 -329.637497) (xy 203.374851 -329.687241) (xy 203.390349 -329.739742) (xy 203.39818 -329.793919)
			(xy 203.398181 -329.84866) (xy 203.390354 -329.902838) (xy 203.374858 -329.955339) (xy 203.352013 -330.005085)
			(xy 203.350636 -330.007214) (xy 204.748636 -330.007214) (xy 204.752707 -329.951592) (xy 204.764833 -329.897155)
			(xy 204.784756 -329.845064) (xy 204.812052 -329.796429) (xy 204.846138 -329.752286) (xy 204.886287 -329.713577)
			(xy 204.931645 -329.681126) (xy 204.981245 -329.655625) (xy 205.034029 -329.637618) (xy 205.088872 -329.627488)
			(xy 205.144606 -329.625451) (xy 205.200043 -329.631551) (xy 205.254 -329.645657) (xy 205.305329 -329.667469)
			(xy 205.352935 -329.696523) (xy 205.395803 -329.732198) (xy 205.43302 -329.773735) (xy 205.463793 -329.820248)
			(xy 205.487465 -329.870745) (xy 205.503533 -329.924152) (xy 205.511653 -329.979328) (xy 205.512162 -330.007214)
			(xy 205.511653 -330.0351) (xy 205.503533 -330.090276) (xy 205.487465 -330.143683) (xy 205.463793 -330.19418)
			(xy 205.43302 -330.240693) (xy 205.395803 -330.28223) (xy 205.352935 -330.317905) (xy 205.305329 -330.346959)
			(xy 205.254 -330.368771) (xy 205.200043 -330.382877) (xy 205.144606 -330.388977) (xy 205.088872 -330.38694)
			(xy 205.034029 -330.37681) (xy 204.981245 -330.358803) (xy 204.931645 -330.333302) (xy 204.886287 -330.300851)
			(xy 204.846138 -330.262142) (xy 204.812052 -330.217999) (xy 204.784756 -330.169364) (xy 204.764833 -330.117273)
			(xy 204.752707 -330.062836) (xy 204.748636 -330.007214) (xy 203.350636 -330.007214) (xy 203.322289 -330.051052)
			(xy 203.304648 -330.071984) (xy 203.304394 -330.072238) (xy 203.298827 -330.079338) (xy 203.292569 -330.096244)
			(xy 203.292202 -330.105258) (xy 203.292202 -330.172314) (xy 203.292552 -330.181332) (xy 203.298804 -330.198248)
			(xy 203.304394 -330.205334) (xy 203.304648 -330.205334) (xy 203.304648 -330.205588) (xy 203.322287 -330.22652)
			(xy 203.352001 -330.272492) (xy 203.374837 -330.32224) (xy 203.390328 -330.374741) (xy 203.398155 -330.428917)
			(xy 203.398628 -330.456286) (xy 203.398142 -330.483537) (xy 203.390386 -330.537485) (xy 203.375031 -330.58978)
			(xy 203.352389 -330.639357) (xy 203.322923 -330.685207) (xy 203.303173 -330.708) (xy 215.898982 -330.708)
			(xy 215.903053 -330.652378) (xy 215.915179 -330.597941) (xy 215.935102 -330.54585) (xy 215.962398 -330.497215)
			(xy 215.996484 -330.453072) (xy 216.036633 -330.414363) (xy 216.081991 -330.381912) (xy 216.131591 -330.356411)
			(xy 216.184375 -330.338404) (xy 216.239218 -330.328274) (xy 216.294952 -330.326237) (xy 216.350389 -330.332337)
			(xy 216.404346 -330.346443) (xy 216.455675 -330.368255) (xy 216.503281 -330.397309) (xy 216.546149 -330.432984)
			(xy 216.583366 -330.474521) (xy 216.614139 -330.521034) (xy 216.637811 -330.571531) (xy 216.653879 -330.624938)
			(xy 216.661999 -330.680114) (xy 216.662508 -330.708) (xy 216.661999 -330.735886) (xy 216.653879 -330.791062)
			(xy 216.637811 -330.844469) (xy 216.614139 -330.894966) (xy 216.583366 -330.941479) (xy 216.546149 -330.983016)
			(xy 216.503281 -331.018691) (xy 216.455675 -331.047745) (xy 216.404346 -331.069557) (xy 216.350389 -331.083663)
			(xy 216.294952 -331.089763) (xy 216.239218 -331.087726) (xy 216.184375 -331.077596) (xy 216.131591 -331.059589)
			(xy 216.081991 -331.034088) (xy 216.036633 -331.001637) (xy 215.996484 -330.962928) (xy 215.962398 -330.918785)
			(xy 215.935102 -330.87015) (xy 215.915179 -330.818059) (xy 215.903053 -330.763622) (xy 215.898982 -330.708)
			(xy 203.303173 -330.708) (xy 203.287232 -330.726398) (xy 203.246041 -330.762089) (xy 203.200191 -330.791555)
			(xy 203.150614 -330.814197) (xy 203.098319 -330.829552) (xy 203.044371 -330.837308) (xy 202.989869 -330.837308)
			(xy 202.935921 -330.829552) (xy 202.883626 -330.814197) (xy 202.834049 -330.791555) (xy 202.788199 -330.762089)
			(xy 202.747008 -330.726398) (xy 202.711317 -330.685207) (xy 202.681851 -330.639357) (xy 202.659209 -330.58978)
			(xy 202.643854 -330.537485) (xy 202.636098 -330.483537) (xy 202.635612 -330.456286) (xy 199.334628 -330.456286)
			(xy 199.334142 -330.483537) (xy 199.326386 -330.537485) (xy 199.311031 -330.58978) (xy 199.288389 -330.639357)
			(xy 199.258923 -330.685207) (xy 199.223232 -330.726398) (xy 199.182041 -330.762089) (xy 199.136191 -330.791555)
			(xy 199.086614 -330.814197) (xy 199.034319 -330.829552) (xy 198.980371 -330.837308) (xy 198.925869 -330.837308)
			(xy 198.871921 -330.829552) (xy 198.819626 -330.814197) (xy 198.770049 -330.791555) (xy 198.724199 -330.762089)
			(xy 198.683008 -330.726398) (xy 198.647317 -330.685207) (xy 198.617851 -330.639357) (xy 198.595209 -330.58978)
			(xy 198.579854 -330.537485) (xy 198.572098 -330.483537) (xy 198.571612 -330.456286) (xy 198.572067 -330.428915)
			(xy 198.579887 -330.374736) (xy 198.595379 -330.322232) (xy 198.618223 -330.272486) (xy 198.64795 -330.226519)
			(xy 198.665592 -330.205588) (xy 198.665846 -330.205334) (xy 198.67143 -330.198246) (xy 198.677677 -330.18133)
			(xy 198.678038 -330.172314) (xy 198.678038 -330.105258) (xy 198.677645 -330.096245) (xy 198.671422 -330.079328)
			(xy 198.665846 -330.072238) (xy 198.665592 -330.072238) (xy 198.665592 -330.071984) (xy 198.647939 -330.051062)
			(xy 198.618217 -330.005091) (xy 198.595375 -329.955343) (xy 198.579881 -329.90284) (xy 198.572055 -329.84866)
			(xy 198.572056 -329.793919) (xy 198.579886 -329.73974) (xy 198.595383 -329.687237) (xy 198.618228 -329.63749)
			(xy 198.647952 -329.591521) (xy 198.665592 -329.570588) (xy 198.665846 -329.570334) (xy 198.67143 -329.563246)
			(xy 198.677677 -329.54633) (xy 198.678038 -329.537314) (xy 198.678038 -329.470258) (xy 198.677645 -329.461245)
			(xy 198.671422 -329.444328) (xy 198.665846 -329.437238) (xy 198.665592 -329.436984) (xy 198.665084 -329.436476)
			(xy 198.607934 -329.441556) (xy 198.596703 -329.443133) (xy 198.577176 -329.454604) (xy 198.570342 -329.463654)
			(xy 198.555076 -329.485426) (xy 198.519452 -329.524904) (xy 198.478688 -329.559048) (xy 198.433573 -329.587194)
			(xy 198.384985 -329.608797) (xy 198.333865 -329.623438) (xy 198.281207 -329.630831) (xy 198.25462 -329.631294)
			(xy 198.22725 -329.630818) (xy 198.173071 -329.623003) (xy 198.120568 -329.607516) (xy 198.070821 -329.584676)
			(xy 198.024854 -329.554954) (xy 198.003922 -329.537314) (xy 198.003668 -329.53706) (xy 197.99657 -329.531491)
			(xy 197.979662 -329.525235) (xy 197.970648 -329.524868) (xy 197.903592 -329.524868) (xy 197.894576 -329.525228)
			(xy 197.877659 -329.531474) (xy 197.870572 -329.53706) (xy 197.870572 -329.537314) (xy 197.870318 -329.537314)
			(xy 197.849392 -329.55496) (xy 197.803417 -329.584671) (xy 197.753668 -329.607505) (xy 197.701166 -329.622994)
			(xy 197.64699 -329.630821) (xy 197.61962 -329.631294) (xy 197.592365 -329.63086) (xy 197.53841 -329.623106)
			(xy 197.486108 -329.607751) (xy 197.436523 -329.585108) (xy 197.390666 -329.55564) (xy 197.349469 -329.519945)
			(xy 197.313772 -329.47875) (xy 197.284301 -329.432894) (xy 197.261656 -329.383311) (xy 197.246299 -329.33101)
			(xy 197.238541 -329.277055) (xy 156.355451 -329.277055) (xy 154.03576 -331.596746) (xy 215.873582 -331.596746)
			(xy 215.877653 -331.541124) (xy 215.889779 -331.486687) (xy 215.909702 -331.434596) (xy 215.936998 -331.385961)
			(xy 215.971084 -331.341818) (xy 216.011233 -331.303109) (xy 216.056591 -331.270658) (xy 216.106191 -331.245157)
			(xy 216.158975 -331.22715) (xy 216.213818 -331.21702) (xy 216.269552 -331.214983) (xy 216.324989 -331.221083)
			(xy 216.378946 -331.235189) (xy 216.430275 -331.257001) (xy 216.477881 -331.286055) (xy 216.520749 -331.32173)
			(xy 216.557966 -331.363267) (xy 216.588739 -331.40978) (xy 216.612411 -331.460277) (xy 216.628479 -331.513684)
			(xy 216.636599 -331.56886) (xy 216.637108 -331.596746) (xy 216.636599 -331.624632) (xy 216.628479 -331.679808)
			(xy 216.612411 -331.733215) (xy 216.588739 -331.783712) (xy 216.557966 -331.830225) (xy 216.520749 -331.871762)
			(xy 216.477881 -331.907437) (xy 216.430275 -331.936491) (xy 216.378946 -331.958303) (xy 216.324989 -331.972409)
			(xy 216.269552 -331.978509) (xy 216.213818 -331.976472) (xy 216.158975 -331.966342) (xy 216.106191 -331.948335)
			(xy 216.056591 -331.922834) (xy 216.011233 -331.890383) (xy 215.971084 -331.851674) (xy 215.936998 -331.807531)
			(xy 215.909702 -331.758896) (xy 215.889779 -331.706805) (xy 215.877653 -331.652368) (xy 215.873582 -331.596746)
			(xy 154.03576 -331.596746) (xy 152.510998 -333.121508) (xy 167.918892 -333.121508) (xy 167.919381 -333.09259)
			(xy 167.928111 -333.035415) (xy 167.945373 -332.980214) (xy 167.97077 -332.928252) (xy 168.00372 -332.880719)
			(xy 168.043469 -332.838706) (xy 168.065958 -332.820518) (xy 168.074757 -332.812903) (xy 168.084943 -332.792008)
			(xy 168.085516 -332.780386) (xy 168.085516 -332.70063) (xy 168.08494 -332.689003) (xy 168.074776 -332.668093)
			(xy 168.065958 -332.660498) (xy 168.043465 -332.642319) (xy 168.003732 -332.600295) (xy 167.970796 -332.552758)
			(xy 167.945409 -332.500794) (xy 167.928155 -332.445595) (xy 167.919427 -332.388424) (xy 167.918892 -332.359508)
			(xy 167.919378 -332.332257) (xy 167.927134 -332.278309) (xy 167.942489 -332.226014) (xy 167.965131 -332.176437)
			(xy 167.994597 -332.130587) (xy 168.030288 -332.089396) (xy 168.071479 -332.053705) (xy 168.117329 -332.024239)
			(xy 168.166906 -332.001597) (xy 168.219201 -331.986242) (xy 168.273149 -331.978486) (xy 168.327651 -331.978486)
			(xy 168.381599 -331.986242) (xy 168.433894 -332.001597) (xy 168.483471 -332.024239) (xy 168.529321 -332.053705)
			(xy 168.570512 -332.089396) (xy 168.606203 -332.130587) (xy 168.635669 -332.176437) (xy 168.658311 -332.226014)
			(xy 168.673666 -332.278309) (xy 168.681422 -332.332257) (xy 168.681908 -332.359508) (xy 168.681358 -332.388424)
			(xy 168.672641 -332.445595) (xy 168.655391 -332.500795) (xy 168.630006 -332.552758) (xy 168.597066 -332.600292)
			(xy 168.557327 -332.642308) (xy 168.534842 -332.660498) (xy 168.526036 -332.668106) (xy 168.515854 -332.689006)
			(xy 168.515284 -332.70063) (xy 168.515284 -332.74) (xy 215.691718 -332.74) (xy 215.695789 -332.684378)
			(xy 215.707915 -332.629941) (xy 215.727838 -332.57785) (xy 215.755134 -332.529215) (xy 215.78922 -332.485072)
			(xy 215.829369 -332.446363) (xy 215.874727 -332.413912) (xy 215.924327 -332.388411) (xy 215.977111 -332.370404)
			(xy 216.031954 -332.360274) (xy 216.087688 -332.358237) (xy 216.143125 -332.364337) (xy 216.197082 -332.378443)
			(xy 216.248411 -332.400255) (xy 216.296017 -332.429309) (xy 216.338885 -332.464984) (xy 216.376102 -332.506521)
			(xy 216.406875 -332.553034) (xy 216.430547 -332.603531) (xy 216.446615 -332.656938) (xy 216.454735 -332.712114)
			(xy 216.455244 -332.74) (xy 216.454735 -332.767886) (xy 216.446615 -332.823062) (xy 216.430547 -332.876469)
			(xy 216.406875 -332.926966) (xy 216.376102 -332.973479) (xy 216.338885 -333.015016) (xy 216.296017 -333.050691)
			(xy 216.248411 -333.079745) (xy 216.197082 -333.101557) (xy 216.143125 -333.115663) (xy 216.087688 -333.121763)
			(xy 216.031954 -333.119726) (xy 215.977111 -333.109596) (xy 215.924327 -333.091589) (xy 215.874727 -333.066088)
			(xy 215.829369 -333.033637) (xy 215.78922 -332.994928) (xy 215.755134 -332.950785) (xy 215.727838 -332.90215)
			(xy 215.707915 -332.850059) (xy 215.695789 -332.795622) (xy 215.691718 -332.74) (xy 168.515284 -332.74)
			(xy 168.515284 -332.780386) (xy 168.515851 -332.792014) (xy 168.526021 -332.812924) (xy 168.534842 -332.820518)
			(xy 168.557343 -332.838688) (xy 168.597075 -332.880714) (xy 168.630011 -332.928253) (xy 168.655396 -332.980218)
			(xy 168.672649 -333.035419) (xy 168.681375 -333.092591) (xy 168.681908 -333.121508) (xy 168.681422 -333.148759)
			(xy 168.673666 -333.202707) (xy 168.658311 -333.255002) (xy 168.635669 -333.304579) (xy 168.606203 -333.350429)
			(xy 168.570512 -333.39162) (xy 168.529321 -333.427311) (xy 168.483471 -333.456777) (xy 168.433894 -333.479419)
			(xy 168.381599 -333.494774) (xy 168.327651 -333.50253) (xy 168.273149 -333.50253) (xy 168.219201 -333.494774)
			(xy 168.166906 -333.479419) (xy 168.117329 -333.456777) (xy 168.071479 -333.427311) (xy 168.030288 -333.39162)
			(xy 167.994597 -333.350429) (xy 167.965131 -333.304579) (xy 167.942489 -333.255002) (xy 167.927134 -333.202707)
			(xy 167.919378 -333.148759) (xy 167.918892 -333.121508) (xy 152.510998 -333.121508) (xy 150.274286 -335.35822)
			(xy 174.360114 -335.35822) (xy 174.363841 -335.304972) (xy 174.374954 -335.252763) (xy 174.393236 -335.202614)
			(xy 174.41833 -335.155502) (xy 174.449747 -335.112349) (xy 174.486872 -335.073996) (xy 174.507652 -335.057242)
			(xy 174.516439 -335.049616) (xy 174.526632 -335.028729) (xy 174.52721 -335.01711) (xy 174.52721 -334.937354)
			(xy 174.52668 -334.925721) (xy 174.516484 -334.904812) (xy 174.507652 -334.897222) (xy 174.486901 -334.88043)
			(xy 174.449772 -334.842081) (xy 174.418351 -334.798931) (xy 174.393252 -334.751822) (xy 174.374964 -334.701675)
			(xy 174.363846 -334.649467) (xy 174.360114 -334.59622) (xy 174.363841 -334.542972) (xy 174.374954 -334.490763)
			(xy 174.393236 -334.440614) (xy 174.41833 -334.393502) (xy 174.449747 -334.350349) (xy 174.486872 -334.311996)
			(xy 174.507652 -334.295242) (xy 174.516439 -334.287616) (xy 174.526632 -334.266729) (xy 174.52721 -334.25511)
			(xy 174.52721 -334.175354) (xy 174.52668 -334.163721) (xy 174.516484 -334.142812) (xy 174.507652 -334.135222)
			(xy 174.485169 -334.117031) (xy 174.445436 -334.07501) (xy 174.412498 -334.027474) (xy 174.38711 -333.975513)
			(xy 174.369853 -333.920316) (xy 174.361122 -333.863148) (xy 174.360586 -333.834232) (xy 174.361072 -333.806981)
			(xy 174.368828 -333.753033) (xy 174.384183 -333.700738) (xy 174.406825 -333.651161) (xy 174.436291 -333.605311)
			(xy 174.471982 -333.56412) (xy 174.513173 -333.528429) (xy 174.559023 -333.498963) (xy 174.6086 -333.476321)
			(xy 174.660895 -333.460966) (xy 174.714843 -333.45321) (xy 174.769345 -333.45321) (xy 174.823293 -333.460966)
			(xy 174.875588 -333.476321) (xy 174.925165 -333.498963) (xy 174.971015 -333.528429) (xy 175.012206 -333.56412)
			(xy 175.047897 -333.605311) (xy 175.077363 -333.651161) (xy 175.100005 -333.700738) (xy 175.11536 -333.753033)
			(xy 175.123116 -333.806981) (xy 175.123602 -333.834232) (xy 175.123034 -333.863147) (xy 175.114315 -333.920316)
			(xy 175.097067 -333.975514) (xy 175.071685 -334.027476) (xy 175.03875 -334.075011) (xy 174.999018 -334.11703)
			(xy 174.976536 -334.135222) (xy 174.967718 -334.142818) (xy 174.957543 -334.163728) (xy 174.956978 -334.175354)
			(xy 174.956978 -334.25511) (xy 174.957534 -334.26674) (xy 174.967712 -334.287649) (xy 174.976536 -334.295242)
			(xy 174.997351 -334.311958) (xy 175.034482 -334.350315) (xy 175.065904 -334.393474) (xy 175.091002 -334.440592)
			(xy 175.109288 -334.490748) (xy 175.120402 -334.542964) (xy 175.12413 -334.59622) (xy 175.120397 -334.649475)
			(xy 175.109277 -334.701689) (xy 175.090986 -334.751844) (xy 175.065883 -334.798959) (xy 175.034457 -334.842115)
			(xy 174.997321 -334.880469) (xy 174.976536 -334.897222) (xy 174.967718 -334.904818) (xy 174.957543 -334.925728)
			(xy 174.956978 -334.937354) (xy 174.956978 -335.01711) (xy 174.957534 -335.02874) (xy 174.967712 -335.049649)
			(xy 174.976536 -335.057242) (xy 174.997351 -335.073958) (xy 175.034482 -335.112315) (xy 175.065904 -335.155474)
			(xy 175.091002 -335.202592) (xy 175.109288 -335.252748) (xy 175.115518 -335.28202) (xy 176.773114 -335.28202)
			(xy 176.776841 -335.228772) (xy 176.787954 -335.176563) (xy 176.806236 -335.126414) (xy 176.83133 -335.079302)
			(xy 176.862747 -335.036149) (xy 176.899872 -334.997796) (xy 176.920652 -334.981042) (xy 176.929439 -334.973416)
			(xy 176.939632 -334.952529) (xy 176.94021 -334.94091) (xy 176.94021 -334.861154) (xy 176.93968 -334.849521)
			(xy 176.929484 -334.828612) (xy 176.920652 -334.821022) (xy 176.899901 -334.80423) (xy 176.862772 -334.765881)
			(xy 176.831351 -334.722731) (xy 176.806252 -334.675622) (xy 176.787964 -334.625475) (xy 176.776846 -334.573267)
			(xy 176.773114 -334.52002) (xy 176.776841 -334.466772) (xy 176.787954 -334.414563) (xy 176.806236 -334.364414)
			(xy 176.83133 -334.317302) (xy 176.862747 -334.274149) (xy 176.899872 -334.235796) (xy 176.920652 -334.219042)
			(xy 176.929439 -334.211416) (xy 176.939632 -334.190529) (xy 176.94021 -334.17891) (xy 176.94021 -334.099154)
			(xy 176.93968 -334.087521) (xy 176.929484 -334.066612) (xy 176.920652 -334.059022) (xy 176.898169 -334.040831)
			(xy 176.858436 -333.99881) (xy 176.825498 -333.951274) (xy 176.80011 -333.899313) (xy 176.782853 -333.844116)
			(xy 176.774122 -333.786948) (xy 176.773586 -333.758032) (xy 176.774072 -333.730781) (xy 176.781828 -333.676833)
			(xy 176.797183 -333.624538) (xy 176.819825 -333.574961) (xy 176.849291 -333.529111) (xy 176.884982 -333.48792)
			(xy 176.926173 -333.452229) (xy 176.972023 -333.422763) (xy 177.0216 -333.400121) (xy 177.073895 -333.384766)
			(xy 177.127843 -333.37701) (xy 177.182345 -333.37701) (xy 177.236293 -333.384766) (xy 177.288588 -333.400121)
			(xy 177.338165 -333.422763) (xy 177.384015 -333.452229) (xy 177.425206 -333.48792) (xy 177.460897 -333.529111)
			(xy 177.490363 -333.574961) (xy 177.513005 -333.624538) (xy 177.52836 -333.676833) (xy 177.536116 -333.730781)
			(xy 177.536602 -333.758032) (xy 177.536034 -333.786947) (xy 177.527315 -333.844116) (xy 177.510067 -333.899314)
			(xy 177.484685 -333.951276) (xy 177.45175 -333.998811) (xy 177.412018 -334.04083) (xy 177.389536 -334.059022)
			(xy 177.380718 -334.066618) (xy 177.370543 -334.087528) (xy 177.369978 -334.099154) (xy 177.369978 -334.17891)
			(xy 177.370534 -334.19054) (xy 177.380712 -334.211449) (xy 177.389536 -334.219042) (xy 177.410351 -334.235758)
			(xy 177.447482 -334.274115) (xy 177.478904 -334.317274) (xy 177.504002 -334.364392) (xy 177.522288 -334.414548)
			(xy 177.533402 -334.466764) (xy 177.53713 -334.52002) (xy 177.533397 -334.573275) (xy 177.522277 -334.625489)
			(xy 177.503986 -334.675644) (xy 177.478883 -334.722759) (xy 177.447457 -334.765915) (xy 177.410321 -334.804269)
			(xy 177.389536 -334.821022) (xy 177.380718 -334.828618) (xy 177.370543 -334.849528) (xy 177.369978 -334.861154)
			(xy 177.369978 -334.94091) (xy 177.370534 -334.95254) (xy 177.380712 -334.973449) (xy 177.389536 -334.981042)
			(xy 177.410351 -334.997758) (xy 177.447482 -335.036115) (xy 177.478904 -335.079274) (xy 177.504002 -335.126392)
			(xy 177.522288 -335.176548) (xy 177.533402 -335.228764) (xy 177.53713 -335.28202) (xy 177.533397 -335.335275)
			(xy 177.526343 -335.368395) (xy 180.425089 -335.368395) (xy 180.42882 -335.315143) (xy 180.439937 -335.26293)
			(xy 180.458225 -335.212777) (xy 180.483325 -335.165663) (xy 180.514748 -335.122508) (xy 180.55188 -335.084155)
			(xy 180.572664 -335.067402) (xy 180.581471 -335.059795) (xy 180.591652 -335.038894) (xy 180.592222 -335.02727)
			(xy 180.592222 -334.947514) (xy 180.591653 -334.935886) (xy 180.581485 -334.914977) (xy 180.572664 -334.907382)
			(xy 180.551873 -334.890638) (xy 180.514742 -334.852284) (xy 180.48332 -334.809128) (xy 180.458221 -334.762014)
			(xy 180.439935 -334.71186) (xy 180.428818 -334.659648) (xy 180.425089 -334.606395) (xy 180.42882 -334.553143)
			(xy 180.439937 -334.50093) (xy 180.458225 -334.450777) (xy 180.483325 -334.403663) (xy 180.514748 -334.360508)
			(xy 180.55188 -334.322155) (xy 180.572664 -334.305402) (xy 180.581471 -334.297795) (xy 180.591652 -334.276894)
			(xy 180.592222 -334.26527) (xy 180.592222 -334.185514) (xy 180.591653 -334.173886) (xy 180.581485 -334.152977)
			(xy 180.572664 -334.145382) (xy 180.550164 -334.12721) (xy 180.510432 -334.085185) (xy 180.477496 -334.037646)
			(xy 180.452111 -333.985681) (xy 180.434857 -333.930481) (xy 180.426131 -333.873309) (xy 180.425598 -333.844392)
			(xy 180.426084 -333.817141) (xy 180.43384 -333.763193) (xy 180.449195 -333.710898) (xy 180.471837 -333.661321)
			(xy 180.501303 -333.615471) (xy 180.536994 -333.57428) (xy 180.578185 -333.538589) (xy 180.624035 -333.509123)
			(xy 180.673612 -333.486481) (xy 180.725907 -333.471126) (xy 180.779855 -333.46337) (xy 180.834357 -333.46337)
			(xy 180.888305 -333.471126) (xy 180.9406 -333.486481) (xy 180.990177 -333.509123) (xy 181.036027 -333.538589)
			(xy 181.077218 -333.57428) (xy 181.112909 -333.615471) (xy 181.142375 -333.661321) (xy 181.165017 -333.710898)
			(xy 181.180372 -333.763193) (xy 181.188128 -333.817141) (xy 181.188614 -333.844392) (xy 181.188123 -333.87331)
			(xy 181.179393 -333.930484) (xy 181.162132 -333.985685) (xy 181.136735 -334.037647) (xy 181.103785 -334.08518)
			(xy 181.064037 -334.127194) (xy 181.041548 -334.145382) (xy 181.03275 -334.152998) (xy 181.022563 -334.173892)
			(xy 181.02199 -334.185514) (xy 181.02199 -334.26527) (xy 181.022564 -334.276897) (xy 181.032729 -334.297807)
			(xy 181.041548 -334.305402) (xy 181.062323 -334.322165) (xy 181.099452 -334.360517) (xy 181.130873 -334.403671)
			(xy 181.155972 -334.450783) (xy 181.174258 -334.500934) (xy 181.185375 -334.553145) (xy 181.189106 -334.606395)
			(xy 181.185377 -334.659646) (xy 181.174261 -334.711856) (xy 181.155976 -334.762008) (xy 181.130879 -334.809121)
			(xy 181.099459 -334.852275) (xy 181.06233 -334.890628) (xy 181.041548 -334.907382) (xy 181.03275 -334.914998)
			(xy 181.022563 -334.935892) (xy 181.02199 -334.947514) (xy 181.02199 -335.02727) (xy 181.022564 -335.038897)
			(xy 181.032729 -335.059807) (xy 181.041548 -335.067402) (xy 181.062323 -335.084165) (xy 181.099452 -335.122517)
			(xy 181.130873 -335.165671) (xy 181.155972 -335.212783) (xy 181.174258 -335.262934) (xy 181.180488 -335.292195)
			(xy 182.838089 -335.292195) (xy 182.84182 -335.238943) (xy 182.852937 -335.18673) (xy 182.871225 -335.136577)
			(xy 182.896325 -335.089463) (xy 182.927748 -335.046308) (xy 182.96488 -335.007955) (xy 182.985664 -334.991202)
			(xy 182.994471 -334.983595) (xy 183.004652 -334.962694) (xy 183.005222 -334.95107) (xy 183.005222 -334.871314)
			(xy 183.004653 -334.859686) (xy 182.994485 -334.838777) (xy 182.985664 -334.831182) (xy 182.964873 -334.814438)
			(xy 182.927742 -334.776084) (xy 182.89632 -334.732928) (xy 182.871221 -334.685814) (xy 182.852935 -334.63566)
			(xy 182.841818 -334.583448) (xy 182.838089 -334.530195) (xy 182.84182 -334.476943) (xy 182.852937 -334.42473)
			(xy 182.871225 -334.374577) (xy 182.896325 -334.327463) (xy 182.927748 -334.284308) (xy 182.96488 -334.245955)
			(xy 182.985664 -334.229202) (xy 182.994471 -334.221595) (xy 183.004652 -334.200694) (xy 183.005222 -334.18907)
			(xy 183.005222 -334.109314) (xy 183.004653 -334.097686) (xy 182.994485 -334.076777) (xy 182.985664 -334.069182)
			(xy 182.963164 -334.05101) (xy 182.923432 -334.008985) (xy 182.890496 -333.961446) (xy 182.865111 -333.909481)
			(xy 182.847857 -333.854281) (xy 182.839131 -333.797109) (xy 182.838598 -333.768192) (xy 182.839084 -333.740941)
			(xy 182.84684 -333.686993) (xy 182.862195 -333.634698) (xy 182.884837 -333.585121) (xy 182.914303 -333.539271)
			(xy 182.949994 -333.49808) (xy 182.991185 -333.462389) (xy 183.037035 -333.432923) (xy 183.086612 -333.410281)
			(xy 183.138907 -333.394926) (xy 183.192855 -333.38717) (xy 183.247357 -333.38717) (xy 183.301305 -333.394926)
			(xy 183.3536 -333.410281) (xy 183.403177 -333.432923) (xy 183.449027 -333.462389) (xy 183.490218 -333.49808)
			(xy 183.525909 -333.539271) (xy 183.555375 -333.585121) (xy 183.578017 -333.634698) (xy 183.593372 -333.686993)
			(xy 183.601128 -333.740941) (xy 183.601614 -333.768192) (xy 183.601123 -333.79711) (xy 183.592393 -333.854284)
			(xy 183.575132 -333.909485) (xy 183.549735 -333.961447) (xy 183.516785 -334.00898) (xy 183.477037 -334.050994)
			(xy 183.454548 -334.069182) (xy 183.44575 -334.076798) (xy 183.435563 -334.097692) (xy 183.43499 -334.109314)
			(xy 183.43499 -334.18907) (xy 183.435564 -334.200697) (xy 183.445729 -334.221607) (xy 183.454548 -334.229202)
			(xy 183.475323 -334.245965) (xy 183.512452 -334.284317) (xy 183.543873 -334.327471) (xy 183.568972 -334.374583)
			(xy 183.587258 -334.424734) (xy 183.598375 -334.476945) (xy 183.602106 -334.530195) (xy 183.598377 -334.583446)
			(xy 183.587261 -334.635656) (xy 183.568976 -334.685808) (xy 183.543879 -334.732921) (xy 183.512459 -334.776075)
			(xy 183.47533 -334.814428) (xy 183.454548 -334.831182) (xy 183.44575 -334.838798) (xy 183.435563 -334.859692)
			(xy 183.43499 -334.871314) (xy 183.43499 -334.95107) (xy 183.435564 -334.962697) (xy 183.445729 -334.983607)
			(xy 183.454548 -334.991202) (xy 183.475323 -335.007965) (xy 183.512452 -335.046317) (xy 183.543873 -335.089471)
			(xy 183.568972 -335.136583) (xy 183.587258 -335.186734) (xy 183.598375 -335.238945) (xy 183.602106 -335.292195)
			(xy 186.495689 -335.292195) (xy 186.49942 -335.238943) (xy 186.510537 -335.18673) (xy 186.528825 -335.136577)
			(xy 186.553925 -335.089463) (xy 186.585348 -335.046308) (xy 186.62248 -335.007955) (xy 186.643264 -334.991202)
			(xy 186.652071 -334.983595) (xy 186.662252 -334.962694) (xy 186.662822 -334.95107) (xy 186.662822 -334.871314)
			(xy 186.662253 -334.859686) (xy 186.652085 -334.838777) (xy 186.643264 -334.831182) (xy 186.622473 -334.814438)
			(xy 186.585342 -334.776084) (xy 186.55392 -334.732928) (xy 186.528821 -334.685814) (xy 186.510535 -334.63566)
			(xy 186.499418 -334.583448) (xy 186.495689 -334.530195) (xy 186.49942 -334.476943) (xy 186.510537 -334.42473)
			(xy 186.528825 -334.374577) (xy 186.553925 -334.327463) (xy 186.585348 -334.284308) (xy 186.62248 -334.245955)
			(xy 186.643264 -334.229202) (xy 186.652071 -334.221595) (xy 186.662252 -334.200694) (xy 186.662822 -334.18907)
			(xy 186.662822 -334.109314) (xy 186.662253 -334.097686) (xy 186.652085 -334.076777) (xy 186.643264 -334.069182)
			(xy 186.620764 -334.05101) (xy 186.581032 -334.008985) (xy 186.548096 -333.961446) (xy 186.522711 -333.909481)
			(xy 186.505457 -333.854281) (xy 186.496731 -333.797109) (xy 186.496198 -333.768192) (xy 186.496684 -333.740941)
			(xy 186.50444 -333.686993) (xy 186.519795 -333.634698) (xy 186.542437 -333.585121) (xy 186.571903 -333.539271)
			(xy 186.607594 -333.49808) (xy 186.648785 -333.462389) (xy 186.694635 -333.432923) (xy 186.744212 -333.410281)
			(xy 186.796507 -333.394926) (xy 186.850455 -333.38717) (xy 186.904957 -333.38717) (xy 186.958905 -333.394926)
			(xy 187.0112 -333.410281) (xy 187.060777 -333.432923) (xy 187.106627 -333.462389) (xy 187.147818 -333.49808)
			(xy 187.183509 -333.539271) (xy 187.212975 -333.585121) (xy 187.235617 -333.634698) (xy 187.250972 -333.686993)
			(xy 187.258728 -333.740941) (xy 187.259214 -333.768192) (xy 187.258723 -333.79711) (xy 187.249993 -333.854284)
			(xy 187.232732 -333.909485) (xy 187.207335 -333.961447) (xy 187.174385 -334.00898) (xy 187.134637 -334.050994)
			(xy 187.112148 -334.069182) (xy 187.10335 -334.076798) (xy 187.093163 -334.097692) (xy 187.09259 -334.109314)
			(xy 187.09259 -334.18907) (xy 187.093164 -334.200697) (xy 187.103329 -334.221607) (xy 187.112148 -334.229202)
			(xy 187.132923 -334.245965) (xy 187.170052 -334.284317) (xy 187.201473 -334.327471) (xy 187.226572 -334.374583)
			(xy 187.244858 -334.424734) (xy 187.255975 -334.476945) (xy 187.259706 -334.530195) (xy 187.255977 -334.583446)
			(xy 187.244861 -334.635656) (xy 187.226576 -334.685808) (xy 187.201479 -334.732921) (xy 187.170059 -334.776075)
			(xy 187.13293 -334.814428) (xy 187.112148 -334.831182) (xy 187.10335 -334.838798) (xy 187.093163 -334.859692)
			(xy 187.09259 -334.871314) (xy 187.09259 -334.95107) (xy 187.093164 -334.962697) (xy 187.103329 -334.983607)
			(xy 187.112148 -334.991202) (xy 187.132923 -335.007965) (xy 187.170052 -335.046317) (xy 187.201473 -335.089471)
			(xy 187.226572 -335.136583) (xy 187.244858 -335.186734) (xy 187.255975 -335.238945) (xy 187.259706 -335.292195)
			(xy 188.959489 -335.292195) (xy 188.96322 -335.238943) (xy 188.974337 -335.18673) (xy 188.992625 -335.136577)
			(xy 189.017725 -335.089463) (xy 189.049148 -335.046308) (xy 189.08628 -335.007955) (xy 189.107064 -334.991202)
			(xy 189.115871 -334.983595) (xy 189.126052 -334.962694) (xy 189.126622 -334.95107) (xy 189.126622 -334.871314)
			(xy 189.126053 -334.859686) (xy 189.115885 -334.838777) (xy 189.107064 -334.831182) (xy 189.086273 -334.814438)
			(xy 189.049142 -334.776084) (xy 189.01772 -334.732928) (xy 188.992621 -334.685814) (xy 188.974335 -334.63566)
			(xy 188.963218 -334.583448) (xy 188.959489 -334.530195) (xy 188.96322 -334.476943) (xy 188.974337 -334.42473)
			(xy 188.992625 -334.374577) (xy 189.017725 -334.327463) (xy 189.049148 -334.284308) (xy 189.08628 -334.245955)
			(xy 189.107064 -334.229202) (xy 189.115871 -334.221595) (xy 189.126052 -334.200694) (xy 189.126622 -334.18907)
			(xy 189.126622 -334.109314) (xy 189.126053 -334.097686) (xy 189.115885 -334.076777) (xy 189.107064 -334.069182)
			(xy 189.084564 -334.05101) (xy 189.044832 -334.008985) (xy 189.011896 -333.961446) (xy 188.986511 -333.909481)
			(xy 188.969257 -333.854281) (xy 188.960531 -333.797109) (xy 188.959998 -333.768192) (xy 188.960484 -333.740941)
			(xy 188.96824 -333.686993) (xy 188.983595 -333.634698) (xy 189.006237 -333.585121) (xy 189.035703 -333.539271)
			(xy 189.071394 -333.49808) (xy 189.112585 -333.462389) (xy 189.158435 -333.432923) (xy 189.208012 -333.410281)
			(xy 189.260307 -333.394926) (xy 189.314255 -333.38717) (xy 189.368757 -333.38717) (xy 189.422705 -333.394926)
			(xy 189.475 -333.410281) (xy 189.524577 -333.432923) (xy 189.570427 -333.462389) (xy 189.611618 -333.49808)
			(xy 189.647309 -333.539271) (xy 189.676775 -333.585121) (xy 189.699417 -333.634698) (xy 189.714772 -333.686993)
			(xy 189.722528 -333.740941) (xy 189.723014 -333.768192) (xy 189.722523 -333.79711) (xy 189.713793 -333.854284)
			(xy 189.696532 -333.909485) (xy 189.671135 -333.961447) (xy 189.638185 -334.00898) (xy 189.598437 -334.050994)
			(xy 189.575948 -334.069182) (xy 189.56715 -334.076798) (xy 189.556963 -334.097692) (xy 189.55639 -334.109314)
			(xy 189.55639 -334.18907) (xy 189.556964 -334.200697) (xy 189.567129 -334.221607) (xy 189.575948 -334.229202)
			(xy 189.596723 -334.245965) (xy 189.633852 -334.284317) (xy 189.665273 -334.327471) (xy 189.690372 -334.374583)
			(xy 189.708658 -334.424734) (xy 189.719775 -334.476945) (xy 189.723506 -334.530195) (xy 189.719777 -334.583446)
			(xy 189.708661 -334.635656) (xy 189.690376 -334.685808) (xy 189.665279 -334.732921) (xy 189.633859 -334.776075)
			(xy 189.59673 -334.814428) (xy 189.575948 -334.831182) (xy 189.56715 -334.838798) (xy 189.556963 -334.859692)
			(xy 189.55639 -334.871314) (xy 189.55639 -334.95107) (xy 189.556964 -334.962697) (xy 189.567129 -334.983607)
			(xy 189.575948 -334.991202) (xy 189.596723 -335.007965) (xy 189.633852 -335.046317) (xy 189.665273 -335.089471)
			(xy 189.690372 -335.136583) (xy 189.708658 -335.186734) (xy 189.719775 -335.238945) (xy 189.721726 -335.266795)
			(xy 192.617089 -335.266795) (xy 192.62082 -335.213543) (xy 192.631937 -335.16133) (xy 192.650225 -335.111177)
			(xy 192.675325 -335.064063) (xy 192.706748 -335.020908) (xy 192.74388 -334.982555) (xy 192.764664 -334.965802)
			(xy 192.773471 -334.958195) (xy 192.783652 -334.937294) (xy 192.784222 -334.92567) (xy 192.784222 -334.845914)
			(xy 192.783653 -334.834286) (xy 192.773485 -334.813377) (xy 192.764664 -334.805782) (xy 192.743873 -334.789038)
			(xy 192.706742 -334.750684) (xy 192.67532 -334.707528) (xy 192.650221 -334.660414) (xy 192.631935 -334.61026)
			(xy 192.620818 -334.558048) (xy 192.617089 -334.504795) (xy 192.62082 -334.451543) (xy 192.631937 -334.39933)
			(xy 192.650225 -334.349177) (xy 192.675325 -334.302063) (xy 192.706748 -334.258908) (xy 192.74388 -334.220555)
			(xy 192.764664 -334.203802) (xy 192.773471 -334.196195) (xy 192.783652 -334.175294) (xy 192.784222 -334.16367)
			(xy 192.784222 -334.083914) (xy 192.783653 -334.072286) (xy 192.773485 -334.051377) (xy 192.764664 -334.043782)
			(xy 192.742164 -334.02561) (xy 192.702432 -333.983585) (xy 192.669496 -333.936046) (xy 192.644111 -333.884081)
			(xy 192.626857 -333.828881) (xy 192.618131 -333.771709) (xy 192.617598 -333.742792) (xy 192.618084 -333.715541)
			(xy 192.62584 -333.661593) (xy 192.641195 -333.609298) (xy 192.663837 -333.559721) (xy 192.693303 -333.513871)
			(xy 192.728994 -333.47268) (xy 192.770185 -333.436989) (xy 192.816035 -333.407523) (xy 192.865612 -333.384881)
			(xy 192.917907 -333.369526) (xy 192.971855 -333.36177) (xy 193.026357 -333.36177) (xy 193.080305 -333.369526)
			(xy 193.1326 -333.384881) (xy 193.182177 -333.407523) (xy 193.228027 -333.436989) (xy 193.269218 -333.47268)
			(xy 193.304909 -333.513871) (xy 193.334375 -333.559721) (xy 193.357017 -333.609298) (xy 193.372372 -333.661593)
			(xy 193.380128 -333.715541) (xy 193.380614 -333.742792) (xy 193.380123 -333.77171) (xy 193.371393 -333.828884)
			(xy 193.354132 -333.884085) (xy 193.328735 -333.936047) (xy 193.295785 -333.98358) (xy 193.256037 -334.025594)
			(xy 193.233548 -334.043782) (xy 193.22475 -334.051398) (xy 193.214563 -334.072292) (xy 193.21399 -334.083914)
			(xy 193.21399 -334.16367) (xy 193.214564 -334.175297) (xy 193.224729 -334.196207) (xy 193.233548 -334.203802)
			(xy 193.254323 -334.220565) (xy 193.291452 -334.258917) (xy 193.322873 -334.302071) (xy 193.347972 -334.349183)
			(xy 193.366258 -334.399334) (xy 193.377375 -334.451545) (xy 193.381106 -334.504795) (xy 193.377377 -334.558046)
			(xy 193.366261 -334.610256) (xy 193.347976 -334.660408) (xy 193.322879 -334.707521) (xy 193.291459 -334.750675)
			(xy 193.25433 -334.789028) (xy 193.233548 -334.805782) (xy 193.22475 -334.813398) (xy 193.214563 -334.834292)
			(xy 193.21399 -334.845914) (xy 193.21399 -334.92567) (xy 193.214564 -334.937297) (xy 193.224729 -334.958207)
			(xy 193.233548 -334.965802) (xy 193.254323 -334.982565) (xy 193.291452 -335.020917) (xy 193.322873 -335.064071)
			(xy 193.347972 -335.111183) (xy 193.366258 -335.161334) (xy 193.377375 -335.213545) (xy 193.381106 -335.266795)
			(xy 195.055489 -335.266795) (xy 195.05922 -335.213543) (xy 195.070337 -335.16133) (xy 195.088625 -335.111177)
			(xy 195.113725 -335.064063) (xy 195.145148 -335.020908) (xy 195.18228 -334.982555) (xy 195.203064 -334.965802)
			(xy 195.211871 -334.958195) (xy 195.222052 -334.937294) (xy 195.222622 -334.92567) (xy 195.222622 -334.845914)
			(xy 195.222053 -334.834286) (xy 195.211885 -334.813377) (xy 195.203064 -334.805782) (xy 195.182273 -334.789038)
			(xy 195.145142 -334.750684) (xy 195.11372 -334.707528) (xy 195.088621 -334.660414) (xy 195.070335 -334.61026)
			(xy 195.059218 -334.558048) (xy 195.055489 -334.504795) (xy 195.05922 -334.451543) (xy 195.070337 -334.39933)
			(xy 195.088625 -334.349177) (xy 195.113725 -334.302063) (xy 195.145148 -334.258908) (xy 195.18228 -334.220555)
			(xy 195.203064 -334.203802) (xy 195.211871 -334.196195) (xy 195.222052 -334.175294) (xy 195.222622 -334.16367)
			(xy 195.222622 -334.083914) (xy 195.222053 -334.072286) (xy 195.211885 -334.051377) (xy 195.203064 -334.043782)
			(xy 195.180564 -334.02561) (xy 195.140832 -333.983585) (xy 195.107896 -333.936046) (xy 195.082511 -333.884081)
			(xy 195.065257 -333.828881) (xy 195.056531 -333.771709) (xy 195.055998 -333.742792) (xy 195.056484 -333.715541)
			(xy 195.06424 -333.661593) (xy 195.079595 -333.609298) (xy 195.102237 -333.559721) (xy 195.131703 -333.513871)
			(xy 195.167394 -333.47268) (xy 195.208585 -333.436989) (xy 195.254435 -333.407523) (xy 195.304012 -333.384881)
			(xy 195.356307 -333.369526) (xy 195.410255 -333.36177) (xy 195.464757 -333.36177) (xy 195.518705 -333.369526)
			(xy 195.571 -333.384881) (xy 195.620577 -333.407523) (xy 195.666427 -333.436989) (xy 195.707618 -333.47268)
			(xy 195.743309 -333.513871) (xy 195.772775 -333.559721) (xy 195.795417 -333.609298) (xy 195.797473 -333.6163)
			(xy 216.231976 -333.6163) (xy 216.236047 -333.560678) (xy 216.248173 -333.506241) (xy 216.268096 -333.45415)
			(xy 216.295392 -333.405515) (xy 216.329478 -333.361372) (xy 216.369627 -333.322663) (xy 216.414985 -333.290212)
			(xy 216.464585 -333.264711) (xy 216.517369 -333.246704) (xy 216.572212 -333.236574) (xy 216.627946 -333.234537)
			(xy 216.683383 -333.240637) (xy 216.73734 -333.254743) (xy 216.788669 -333.276555) (xy 216.836275 -333.305609)
			(xy 216.879143 -333.341284) (xy 216.91636 -333.382821) (xy 216.947133 -333.429334) (xy 216.970805 -333.479831)
			(xy 216.986873 -333.533238) (xy 216.994993 -333.588414) (xy 216.995502 -333.6163) (xy 216.994993 -333.644186)
			(xy 216.986873 -333.699362) (xy 216.970805 -333.752769) (xy 216.947133 -333.803266) (xy 216.91636 -333.849779)
			(xy 216.879143 -333.891316) (xy 216.836275 -333.926991) (xy 216.788669 -333.956045) (xy 216.73734 -333.977857)
			(xy 216.683383 -333.991963) (xy 216.627946 -333.998063) (xy 216.572212 -333.996026) (xy 216.517369 -333.985896)
			(xy 216.464585 -333.967889) (xy 216.414985 -333.942388) (xy 216.369627 -333.909937) (xy 216.329478 -333.871228)
			(xy 216.295392 -333.827085) (xy 216.268096 -333.77845) (xy 216.248173 -333.726359) (xy 216.236047 -333.671922)
			(xy 216.231976 -333.6163) (xy 195.797473 -333.6163) (xy 195.810772 -333.661593) (xy 195.818528 -333.715541)
			(xy 195.819014 -333.742792) (xy 195.818523 -333.77171) (xy 195.809793 -333.828884) (xy 195.792532 -333.884085)
			(xy 195.767135 -333.936047) (xy 195.734185 -333.98358) (xy 195.694437 -334.025594) (xy 195.671948 -334.043782)
			(xy 195.66315 -334.051398) (xy 195.652963 -334.072292) (xy 195.65239 -334.083914) (xy 195.65239 -334.16367)
			(xy 195.652964 -334.175297) (xy 195.663129 -334.196207) (xy 195.671948 -334.203802) (xy 195.692723 -334.220565)
			(xy 195.729852 -334.258917) (xy 195.761273 -334.302071) (xy 195.786372 -334.349183) (xy 195.804658 -334.399334)
			(xy 195.815775 -334.451545) (xy 195.819506 -334.504795) (xy 195.815777 -334.558046) (xy 195.804661 -334.610256)
			(xy 195.786376 -334.660408) (xy 195.761279 -334.707521) (xy 195.729859 -334.750675) (xy 195.69273 -334.789028)
			(xy 195.671948 -334.805782) (xy 195.66315 -334.813398) (xy 195.652963 -334.834292) (xy 195.65239 -334.845914)
			(xy 195.65239 -334.92567) (xy 195.652964 -334.937297) (xy 195.663129 -334.958207) (xy 195.671948 -334.965802)
			(xy 195.692723 -334.982565) (xy 195.729852 -335.020917) (xy 195.761273 -335.064071) (xy 195.786372 -335.111183)
			(xy 195.804658 -335.161334) (xy 195.815775 -335.213545) (xy 195.819506 -335.266795) (xy 195.815777 -335.320046)
			(xy 195.806998 -335.36128) (xy 216.268552 -335.36128) (xy 216.272623 -335.305658) (xy 216.284749 -335.251221)
			(xy 216.304672 -335.19913) (xy 216.331968 -335.150495) (xy 216.366054 -335.106352) (xy 216.406203 -335.067643)
			(xy 216.451561 -335.035192) (xy 216.501161 -335.009691) (xy 216.553945 -334.991684) (xy 216.608788 -334.981554)
			(xy 216.664522 -334.979517) (xy 216.719959 -334.985617) (xy 216.773916 -334.999723) (xy 216.825245 -335.021535)
			(xy 216.872851 -335.050589) (xy 216.915719 -335.086264) (xy 216.952936 -335.127801) (xy 216.983709 -335.174314)
			(xy 217.007381 -335.224811) (xy 217.023449 -335.278218) (xy 217.031569 -335.333394) (xy 217.032078 -335.36128)
			(xy 217.031569 -335.389166) (xy 217.023449 -335.444342) (xy 217.007381 -335.497749) (xy 216.983709 -335.548246)
			(xy 216.952936 -335.594759) (xy 216.915719 -335.636296) (xy 216.886034 -335.661) (xy 217.168982 -335.661)
			(xy 217.173053 -335.605378) (xy 217.185179 -335.550941) (xy 217.205102 -335.49885) (xy 217.232398 -335.450215)
			(xy 217.266484 -335.406072) (xy 217.306633 -335.367363) (xy 217.351991 -335.334912) (xy 217.401591 -335.309411)
			(xy 217.454375 -335.291404) (xy 217.509218 -335.281274) (xy 217.564952 -335.279237) (xy 217.620389 -335.285337)
			(xy 217.674346 -335.299443) (xy 217.725675 -335.321255) (xy 217.773281 -335.350309) (xy 217.816149 -335.385984)
			(xy 217.853366 -335.427521) (xy 217.884139 -335.474034) (xy 217.907811 -335.524531) (xy 217.923879 -335.577938)
			(xy 217.931999 -335.633114) (xy 217.932508 -335.661) (xy 217.931999 -335.688886) (xy 217.923879 -335.744062)
			(xy 217.907811 -335.797469) (xy 217.884139 -335.847966) (xy 217.853366 -335.894479) (xy 217.816149 -335.936016)
			(xy 217.773281 -335.971691) (xy 217.725675 -336.000745) (xy 217.674346 -336.022557) (xy 217.620389 -336.036663)
			(xy 217.564952 -336.042763) (xy 217.509218 -336.040726) (xy 217.454375 -336.030596) (xy 217.401591 -336.012589)
			(xy 217.351991 -335.987088) (xy 217.306633 -335.954637) (xy 217.266484 -335.915928) (xy 217.232398 -335.871785)
			(xy 217.205102 -335.82315) (xy 217.185179 -335.771059) (xy 217.173053 -335.716622) (xy 217.168982 -335.661)
			(xy 216.886034 -335.661) (xy 216.872851 -335.671971) (xy 216.825245 -335.701025) (xy 216.773916 -335.722837)
			(xy 216.719959 -335.736943) (xy 216.664522 -335.743043) (xy 216.608788 -335.741006) (xy 216.553945 -335.730876)
			(xy 216.501161 -335.712869) (xy 216.451561 -335.687368) (xy 216.406203 -335.654917) (xy 216.366054 -335.616208)
			(xy 216.331968 -335.572065) (xy 216.304672 -335.52343) (xy 216.284749 -335.471339) (xy 216.272623 -335.416902)
			(xy 216.268552 -335.36128) (xy 195.806998 -335.36128) (xy 195.804661 -335.372256) (xy 195.786376 -335.422408)
			(xy 195.761279 -335.469521) (xy 195.729859 -335.512675) (xy 195.69273 -335.551028) (xy 195.671948 -335.567782)
			(xy 195.66315 -335.575398) (xy 195.652963 -335.596292) (xy 195.65239 -335.607914) (xy 195.65239 -335.68767)
			(xy 195.652964 -335.699297) (xy 195.663129 -335.720207) (xy 195.671948 -335.727802) (xy 195.694442 -335.74598)
			(xy 195.734175 -335.788004) (xy 195.767111 -335.835542) (xy 195.792497 -335.887505) (xy 195.809752 -335.942705)
			(xy 195.818479 -335.999875) (xy 195.819014 -336.028792) (xy 195.818528 -336.056043) (xy 195.810772 -336.109991)
			(xy 195.795417 -336.162286) (xy 195.772775 -336.211863) (xy 195.743309 -336.257713) (xy 195.707618 -336.298904)
			(xy 195.666427 -336.334595) (xy 195.620577 -336.364061) (xy 195.571 -336.386703) (xy 195.518705 -336.402058)
			(xy 195.464757 -336.409814) (xy 195.410255 -336.409814) (xy 195.356307 -336.402058) (xy 195.304012 -336.386703)
			(xy 195.254435 -336.364061) (xy 195.208585 -336.334595) (xy 195.167394 -336.298904) (xy 195.131703 -336.257713)
			(xy 195.102237 -336.211863) (xy 195.079595 -336.162286) (xy 195.06424 -336.109991) (xy 195.056484 -336.056043)
			(xy 195.055998 -336.028792) (xy 195.056583 -335.999878) (xy 195.065298 -335.942709) (xy 195.082543 -335.887512)
			(xy 195.107922 -335.83555) (xy 195.140854 -335.788014) (xy 195.180584 -335.745994) (xy 195.203064 -335.727802)
			(xy 195.211871 -335.720195) (xy 195.222052 -335.699294) (xy 195.222622 -335.68767) (xy 195.222622 -335.607914)
			(xy 195.222053 -335.596286) (xy 195.211885 -335.575377) (xy 195.203064 -335.567782) (xy 195.182273 -335.551038)
			(xy 195.145142 -335.512684) (xy 195.11372 -335.469528) (xy 195.088621 -335.422414) (xy 195.070335 -335.37226)
			(xy 195.059218 -335.320048) (xy 195.055489 -335.266795) (xy 193.381106 -335.266795) (xy 193.377377 -335.320046)
			(xy 193.366261 -335.372256) (xy 193.347976 -335.422408) (xy 193.322879 -335.469521) (xy 193.291459 -335.512675)
			(xy 193.25433 -335.551028) (xy 193.233548 -335.567782) (xy 193.22475 -335.575398) (xy 193.214563 -335.596292)
			(xy 193.21399 -335.607914) (xy 193.21399 -335.68767) (xy 193.214564 -335.699297) (xy 193.224729 -335.720207)
			(xy 193.233548 -335.727802) (xy 193.256042 -335.74598) (xy 193.295775 -335.788004) (xy 193.328711 -335.835542)
			(xy 193.354097 -335.887505) (xy 193.371352 -335.942705) (xy 193.380079 -335.999875) (xy 193.380614 -336.028792)
			(xy 193.380128 -336.056043) (xy 193.372372 -336.109991) (xy 193.357017 -336.162286) (xy 193.334375 -336.211863)
			(xy 193.304909 -336.257713) (xy 193.269218 -336.298904) (xy 193.228027 -336.334595) (xy 193.182177 -336.364061)
			(xy 193.1326 -336.386703) (xy 193.080305 -336.402058) (xy 193.026357 -336.409814) (xy 192.971855 -336.409814)
			(xy 192.917907 -336.402058) (xy 192.865612 -336.386703) (xy 192.816035 -336.364061) (xy 192.770185 -336.334595)
			(xy 192.728994 -336.298904) (xy 192.693303 -336.257713) (xy 192.663837 -336.211863) (xy 192.641195 -336.162286)
			(xy 192.62584 -336.109991) (xy 192.618084 -336.056043) (xy 192.617598 -336.028792) (xy 192.618183 -335.999878)
			(xy 192.626898 -335.942709) (xy 192.644143 -335.887512) (xy 192.669522 -335.83555) (xy 192.702454 -335.788014)
			(xy 192.742184 -335.745994) (xy 192.764664 -335.727802) (xy 192.773471 -335.720195) (xy 192.783652 -335.699294)
			(xy 192.784222 -335.68767) (xy 192.784222 -335.607914) (xy 192.783653 -335.596286) (xy 192.773485 -335.575377)
			(xy 192.764664 -335.567782) (xy 192.743873 -335.551038) (xy 192.706742 -335.512684) (xy 192.67532 -335.469528)
			(xy 192.650221 -335.422414) (xy 192.631935 -335.37226) (xy 192.620818 -335.320048) (xy 192.617089 -335.266795)
			(xy 189.721726 -335.266795) (xy 189.723506 -335.292195) (xy 189.719777 -335.345446) (xy 189.708661 -335.397656)
			(xy 189.690376 -335.447808) (xy 189.665279 -335.494921) (xy 189.633859 -335.538075) (xy 189.59673 -335.576428)
			(xy 189.575948 -335.593182) (xy 189.56715 -335.600798) (xy 189.556963 -335.621692) (xy 189.55639 -335.633314)
			(xy 189.55639 -335.71307) (xy 189.556964 -335.724697) (xy 189.567129 -335.745607) (xy 189.575948 -335.753202)
			(xy 189.598442 -335.77138) (xy 189.638175 -335.813404) (xy 189.671111 -335.860942) (xy 189.696497 -335.912905)
			(xy 189.713752 -335.968105) (xy 189.722479 -336.025275) (xy 189.723014 -336.054192) (xy 189.722528 -336.081443)
			(xy 189.714772 -336.135391) (xy 189.699417 -336.187686) (xy 189.676775 -336.237263) (xy 189.647309 -336.283113)
			(xy 189.611618 -336.324304) (xy 189.570427 -336.359995) (xy 189.524577 -336.389461) (xy 189.475 -336.412103)
			(xy 189.422705 -336.427458) (xy 189.368757 -336.435214) (xy 189.314255 -336.435214) (xy 189.260307 -336.427458)
			(xy 189.208012 -336.412103) (xy 189.158435 -336.389461) (xy 189.112585 -336.359995) (xy 189.071394 -336.324304)
			(xy 189.035703 -336.283113) (xy 189.006237 -336.237263) (xy 188.983595 -336.187686) (xy 188.96824 -336.135391)
			(xy 188.960484 -336.081443) (xy 188.959998 -336.054192) (xy 188.960583 -336.025278) (xy 188.969298 -335.968109)
			(xy 188.986543 -335.912912) (xy 189.011922 -335.86095) (xy 189.044854 -335.813414) (xy 189.084584 -335.771394)
			(xy 189.107064 -335.753202) (xy 189.115871 -335.745595) (xy 189.126052 -335.724694) (xy 189.126622 -335.71307)
			(xy 189.126622 -335.633314) (xy 189.126053 -335.621686) (xy 189.115885 -335.600777) (xy 189.107064 -335.593182)
			(xy 189.086273 -335.576438) (xy 189.049142 -335.538084) (xy 189.01772 -335.494928) (xy 188.992621 -335.447814)
			(xy 188.974335 -335.39766) (xy 188.963218 -335.345448) (xy 188.959489 -335.292195) (xy 187.259706 -335.292195)
			(xy 187.255977 -335.345446) (xy 187.244861 -335.397656) (xy 187.226576 -335.447808) (xy 187.201479 -335.494921)
			(xy 187.170059 -335.538075) (xy 187.13293 -335.576428) (xy 187.112148 -335.593182) (xy 187.10335 -335.600798)
			(xy 187.093163 -335.621692) (xy 187.09259 -335.633314) (xy 187.09259 -335.71307) (xy 187.093164 -335.724697)
			(xy 187.103329 -335.745607) (xy 187.112148 -335.753202) (xy 187.134642 -335.77138) (xy 187.174375 -335.813404)
			(xy 187.207311 -335.860942) (xy 187.232697 -335.912905) (xy 187.249952 -335.968105) (xy 187.258679 -336.025275)
			(xy 187.259214 -336.054192) (xy 187.258728 -336.081443) (xy 187.250972 -336.135391) (xy 187.235617 -336.187686)
			(xy 187.212975 -336.237263) (xy 187.183509 -336.283113) (xy 187.147818 -336.324304) (xy 187.106627 -336.359995)
			(xy 187.060777 -336.389461) (xy 187.0112 -336.412103) (xy 186.958905 -336.427458) (xy 186.904957 -336.435214)
			(xy 186.850455 -336.435214) (xy 186.796507 -336.427458) (xy 186.744212 -336.412103) (xy 186.694635 -336.389461)
			(xy 186.648785 -336.359995) (xy 186.607594 -336.324304) (xy 186.571903 -336.283113) (xy 186.542437 -336.237263)
			(xy 186.519795 -336.187686) (xy 186.50444 -336.135391) (xy 186.496684 -336.081443) (xy 186.496198 -336.054192)
			(xy 186.496783 -336.025278) (xy 186.505498 -335.968109) (xy 186.522743 -335.912912) (xy 186.548122 -335.86095)
			(xy 186.581054 -335.813414) (xy 186.620784 -335.771394) (xy 186.643264 -335.753202) (xy 186.652071 -335.745595)
			(xy 186.662252 -335.724694) (xy 186.662822 -335.71307) (xy 186.662822 -335.633314) (xy 186.662253 -335.621686)
			(xy 186.652085 -335.600777) (xy 186.643264 -335.593182) (xy 186.622473 -335.576438) (xy 186.585342 -335.538084)
			(xy 186.55392 -335.494928) (xy 186.528821 -335.447814) (xy 186.510535 -335.39766) (xy 186.499418 -335.345448)
			(xy 186.495689 -335.292195) (xy 183.602106 -335.292195) (xy 183.598377 -335.345446) (xy 183.587261 -335.397656)
			(xy 183.568976 -335.447808) (xy 183.543879 -335.494921) (xy 183.512459 -335.538075) (xy 183.47533 -335.576428)
			(xy 183.454548 -335.593182) (xy 183.44575 -335.600798) (xy 183.435563 -335.621692) (xy 183.43499 -335.633314)
			(xy 183.43499 -335.71307) (xy 183.435564 -335.724697) (xy 183.445729 -335.745607) (xy 183.454548 -335.753202)
			(xy 183.477042 -335.77138) (xy 183.516775 -335.813404) (xy 183.549711 -335.860942) (xy 183.575097 -335.912905)
			(xy 183.592352 -335.968105) (xy 183.601079 -336.025275) (xy 183.601614 -336.054192) (xy 183.601128 -336.081443)
			(xy 183.593372 -336.135391) (xy 183.578017 -336.187686) (xy 183.555375 -336.237263) (xy 183.525909 -336.283113)
			(xy 183.490218 -336.324304) (xy 183.449027 -336.359995) (xy 183.403177 -336.389461) (xy 183.3536 -336.412103)
			(xy 183.301305 -336.427458) (xy 183.247357 -336.435214) (xy 183.192855 -336.435214) (xy 183.138907 -336.427458)
			(xy 183.086612 -336.412103) (xy 183.037035 -336.389461) (xy 182.991185 -336.359995) (xy 182.949994 -336.324304)
			(xy 182.914303 -336.283113) (xy 182.884837 -336.237263) (xy 182.862195 -336.187686) (xy 182.84684 -336.135391)
			(xy 182.839084 -336.081443) (xy 182.838598 -336.054192) (xy 182.839183 -336.025278) (xy 182.847898 -335.968109)
			(xy 182.865143 -335.912912) (xy 182.890522 -335.86095) (xy 182.923454 -335.813414) (xy 182.963184 -335.771394)
			(xy 182.985664 -335.753202) (xy 182.994471 -335.745595) (xy 183.004652 -335.724694) (xy 183.005222 -335.71307)
			(xy 183.005222 -335.633314) (xy 183.004653 -335.621686) (xy 182.994485 -335.600777) (xy 182.985664 -335.593182)
			(xy 182.964873 -335.576438) (xy 182.927742 -335.538084) (xy 182.89632 -335.494928) (xy 182.871221 -335.447814)
			(xy 182.852935 -335.39766) (xy 182.841818 -335.345448) (xy 182.838089 -335.292195) (xy 181.180488 -335.292195)
			(xy 181.185375 -335.315145) (xy 181.189106 -335.368395) (xy 181.185377 -335.421646) (xy 181.174261 -335.473856)
			(xy 181.155976 -335.524008) (xy 181.130879 -335.571121) (xy 181.099459 -335.614275) (xy 181.06233 -335.652628)
			(xy 181.041548 -335.669382) (xy 181.03275 -335.676998) (xy 181.022563 -335.697892) (xy 181.02199 -335.709514)
			(xy 181.02199 -335.78927) (xy 181.022564 -335.800897) (xy 181.032729 -335.821807) (xy 181.041548 -335.829402)
			(xy 181.064042 -335.84758) (xy 181.103775 -335.889604) (xy 181.136711 -335.937142) (xy 181.162097 -335.989105)
			(xy 181.179352 -336.044305) (xy 181.188079 -336.101475) (xy 181.188614 -336.130392) (xy 181.188128 -336.157643)
			(xy 181.180372 -336.211591) (xy 181.165017 -336.263886) (xy 181.142375 -336.313463) (xy 181.112909 -336.359313)
			(xy 181.077218 -336.400504) (xy 181.036027 -336.436195) (xy 180.990177 -336.465661) (xy 180.9406 -336.488303)
			(xy 180.888305 -336.503658) (xy 180.834357 -336.511414) (xy 180.779855 -336.511414) (xy 180.725907 -336.503658)
			(xy 180.673612 -336.488303) (xy 180.624035 -336.465661) (xy 180.578185 -336.436195) (xy 180.536994 -336.400504)
			(xy 180.501303 -336.359313) (xy 180.471837 -336.313463) (xy 180.449195 -336.263886) (xy 180.43384 -336.211591)
			(xy 180.426084 -336.157643) (xy 180.425598 -336.130392) (xy 180.426183 -336.101478) (xy 180.434898 -336.044309)
			(xy 180.452143 -335.989112) (xy 180.477522 -335.93715) (xy 180.510454 -335.889614) (xy 180.550184 -335.847594)
			(xy 180.572664 -335.829402) (xy 180.581471 -335.821795) (xy 180.591652 -335.800894) (xy 180.592222 -335.78927)
			(xy 180.592222 -335.709514) (xy 180.591653 -335.697886) (xy 180.581485 -335.676977) (xy 180.572664 -335.669382)
			(xy 180.551873 -335.652638) (xy 180.514742 -335.614284) (xy 180.48332 -335.571128) (xy 180.458221 -335.524014)
			(xy 180.439935 -335.47386) (xy 180.428818 -335.421648) (xy 180.425089 -335.368395) (xy 177.526343 -335.368395)
			(xy 177.522277 -335.387489) (xy 177.503986 -335.437644) (xy 177.478883 -335.484759) (xy 177.447457 -335.527915)
			(xy 177.410321 -335.566269) (xy 177.389536 -335.583022) (xy 177.380718 -335.590618) (xy 177.370543 -335.611528)
			(xy 177.369978 -335.623154) (xy 177.369978 -335.70291) (xy 177.370534 -335.71454) (xy 177.380712 -335.735449)
			(xy 177.389536 -335.743042) (xy 177.412047 -335.7612) (xy 177.451779 -335.803228) (xy 177.484714 -335.85077)
			(xy 177.510097 -335.902737) (xy 177.527348 -335.95794) (xy 177.53607 -336.015114) (xy 177.536602 -336.044032)
			(xy 177.536116 -336.071283) (xy 177.52836 -336.125231) (xy 177.513005 -336.177526) (xy 177.490363 -336.227103)
			(xy 177.460897 -336.272953) (xy 177.425206 -336.314144) (xy 177.384015 -336.349835) (xy 177.338165 -336.379301)
			(xy 177.288588 -336.401943) (xy 177.236293 -336.417298) (xy 177.182345 -336.425054) (xy 177.127843 -336.425054)
			(xy 177.073895 -336.417298) (xy 177.0216 -336.401943) (xy 176.972023 -336.379301) (xy 176.926173 -336.349835)
			(xy 176.884982 -336.314144) (xy 176.849291 -336.272953) (xy 176.819825 -336.227103) (xy 176.797183 -336.177526)
			(xy 176.781828 -336.125231) (xy 176.774072 -336.071283) (xy 176.773586 -336.044032) (xy 176.774095 -336.015114)
			(xy 176.782821 -335.957941) (xy 176.800079 -335.902741) (xy 176.825472 -335.850778) (xy 176.858419 -335.803245)
			(xy 176.898164 -335.76123) (xy 176.920652 -335.743042) (xy 176.929439 -335.735416) (xy 176.939632 -335.714529)
			(xy 176.94021 -335.70291) (xy 176.94021 -335.623154) (xy 176.93968 -335.611521) (xy 176.929484 -335.590612)
			(xy 176.920652 -335.583022) (xy 176.899901 -335.56623) (xy 176.862772 -335.527881) (xy 176.831351 -335.484731)
			(xy 176.806252 -335.437622) (xy 176.787964 -335.387475) (xy 176.776846 -335.335267) (xy 176.773114 -335.28202)
			(xy 175.115518 -335.28202) (xy 175.120402 -335.304964) (xy 175.12413 -335.35822) (xy 175.120397 -335.411475)
			(xy 175.109277 -335.463689) (xy 175.090986 -335.513844) (xy 175.065883 -335.560959) (xy 175.034457 -335.604115)
			(xy 174.997321 -335.642469) (xy 174.976536 -335.659222) (xy 174.967718 -335.666818) (xy 174.957543 -335.687728)
			(xy 174.956978 -335.699354) (xy 174.956978 -335.77911) (xy 174.957534 -335.79074) (xy 174.967712 -335.811649)
			(xy 174.976536 -335.819242) (xy 174.999047 -335.8374) (xy 175.038779 -335.879428) (xy 175.071714 -335.92697)
			(xy 175.097097 -335.978937) (xy 175.114348 -336.03414) (xy 175.12307 -336.091314) (xy 175.123602 -336.120232)
			(xy 175.123116 -336.147483) (xy 175.11536 -336.201431) (xy 175.100005 -336.253726) (xy 175.077363 -336.303303)
			(xy 175.047897 -336.349153) (xy 175.012206 -336.390344) (xy 174.971015 -336.426035) (xy 174.925165 -336.455501)
			(xy 174.875588 -336.478143) (xy 174.823293 -336.493498) (xy 174.769345 -336.501254) (xy 174.714843 -336.501254)
			(xy 174.660895 -336.493498) (xy 174.6086 -336.478143) (xy 174.559023 -336.455501) (xy 174.513173 -336.426035)
			(xy 174.471982 -336.390344) (xy 174.436291 -336.349153) (xy 174.406825 -336.303303) (xy 174.384183 -336.253726)
			(xy 174.368828 -336.201431) (xy 174.361072 -336.147483) (xy 174.360586 -336.120232) (xy 174.361095 -336.091314)
			(xy 174.369821 -336.034141) (xy 174.387079 -335.978941) (xy 174.412472 -335.926978) (xy 174.445419 -335.879445)
			(xy 174.485164 -335.83743) (xy 174.507652 -335.819242) (xy 174.516439 -335.811616) (xy 174.526632 -335.790729)
			(xy 174.52721 -335.77911) (xy 174.52721 -335.699354) (xy 174.52668 -335.687721) (xy 174.516484 -335.666812)
			(xy 174.507652 -335.659222) (xy 174.486901 -335.64243) (xy 174.449772 -335.604081) (xy 174.418351 -335.560931)
			(xy 174.393252 -335.513822) (xy 174.374964 -335.463675) (xy 174.363846 -335.411467) (xy 174.360114 -335.35822)
			(xy 150.274286 -335.35822) (xy 148.578316 -337.05419) (xy 148.571466 -337.061587) (xy 148.563725 -337.080185)
			(xy 148.56333 -337.090258) (xy 148.56333 -340.262718) (xy 172.934884 -340.262718) (xy 172.93534 -340.235347)
			(xy 172.943157 -340.181167) (xy 172.958647 -340.128663) (xy 172.981492 -340.078916) (xy 173.01122 -340.03295)
			(xy 173.028864 -340.01202) (xy 173.029118 -340.011766) (xy 173.034685 -340.004666) (xy 173.040943 -339.987759)
			(xy 173.04131 -339.978746) (xy 173.04131 -339.91169) (xy 173.040955 -339.902673) (xy 173.034706 -339.885756)
			(xy 173.029118 -339.87867) (xy 173.028864 -339.87867) (xy 173.028864 -339.878416) (xy 173.011239 -339.85747)
			(xy 172.981511 -339.811505) (xy 172.958662 -339.761761) (xy 172.943163 -339.709261) (xy 172.935332 -339.655084)
			(xy 172.93533 -339.600343) (xy 172.943157 -339.546165) (xy 172.958653 -339.493664) (xy 172.981498 -339.443919)
			(xy 173.011223 -339.397952) (xy 173.028864 -339.37702) (xy 173.029118 -339.376766) (xy 173.034685 -339.369666)
			(xy 173.040943 -339.352759) (xy 173.04131 -339.343746) (xy 173.04131 -339.27669) (xy 173.040955 -339.267673)
			(xy 173.034706 -339.250756) (xy 173.029118 -339.24367) (xy 173.028864 -339.24367) (xy 173.028864 -339.243416)
			(xy 173.011239 -339.22247) (xy 172.981511 -339.176505) (xy 172.958662 -339.126761) (xy 172.943163 -339.074261)
			(xy 172.935332 -339.020084) (xy 172.93533 -338.965343) (xy 172.943157 -338.911165) (xy 172.958653 -338.858664)
			(xy 172.981498 -338.808919) (xy 173.011223 -338.762952) (xy 173.028864 -338.74202) (xy 173.029118 -338.741766)
			(xy 173.034685 -338.734666) (xy 173.040943 -338.717759) (xy 173.04131 -338.708746) (xy 173.04131 -338.64169)
			(xy 173.040955 -338.632673) (xy 173.034706 -338.615756) (xy 173.029118 -338.60867) (xy 173.028864 -338.60867)
			(xy 173.028864 -338.608416) (xy 173.011239 -338.58747) (xy 172.981511 -338.541505) (xy 172.958662 -338.491761)
			(xy 172.943163 -338.439261) (xy 172.935332 -338.385084) (xy 172.93533 -338.330343) (xy 172.943157 -338.276165)
			(xy 172.958653 -338.223664) (xy 172.981498 -338.173919) (xy 173.011223 -338.127952) (xy 173.028864 -338.10702)
			(xy 173.029118 -338.106766) (xy 173.034685 -338.099666) (xy 173.040943 -338.082759) (xy 173.04131 -338.073746)
			(xy 173.04131 -338.00669) (xy 173.040955 -337.997673) (xy 173.034706 -337.980756) (xy 173.029118 -337.97367)
			(xy 173.028864 -337.97367) (xy 173.028864 -337.973416) (xy 173.011239 -337.95247) (xy 172.981511 -337.906505)
			(xy 172.958662 -337.856761) (xy 172.943163 -337.804261) (xy 172.935332 -337.750084) (xy 172.93533 -337.695343)
			(xy 172.943157 -337.641165) (xy 172.958653 -337.588664) (xy 172.981498 -337.538919) (xy 173.011223 -337.492952)
			(xy 173.028864 -337.47202) (xy 173.029118 -337.471766) (xy 173.034685 -337.464666) (xy 173.040943 -337.447759)
			(xy 173.04131 -337.438746) (xy 173.04131 -337.37169) (xy 173.040955 -337.362673) (xy 173.034706 -337.345756)
			(xy 173.029118 -337.33867) (xy 173.028864 -337.33867) (xy 173.028864 -337.338416) (xy 173.011213 -337.317493)
			(xy 172.981504 -337.271517) (xy 172.958671 -337.221767) (xy 172.943183 -337.169265) (xy 172.935357 -337.115088)
			(xy 172.934884 -337.087718) (xy 172.935372 -337.060466) (xy 172.943126 -337.006516) (xy 172.95848 -336.954219)
			(xy 172.98112 -336.90464) (xy 173.010585 -336.858787) (xy 173.046276 -336.817594) (xy 173.087466 -336.781901)
			(xy 173.133317 -336.752432) (xy 173.182895 -336.729789) (xy 173.235191 -336.714432) (xy 173.28914 -336.706674)
			(xy 173.316392 -336.70621) (xy 173.344029 -336.706721) (xy 173.398725 -336.714708) (xy 173.451696 -336.730501)
			(xy 173.501835 -336.75377) (xy 173.548093 -336.784028) (xy 173.569122 -336.801968) (xy 173.576267 -336.807765)
			(xy 173.593458 -336.814277) (xy 173.60265 -336.814668) (xy 173.670214 -336.814668) (xy 173.6794 -336.814249)
			(xy 173.696584 -336.80774) (xy 173.703742 -336.801968) (xy 173.724753 -336.784003) (xy 173.771009 -336.753732)
			(xy 173.821151 -336.730458) (xy 173.874129 -336.714669) (xy 173.928832 -336.706697) (xy 173.956472 -336.70621)
			(xy 173.983725 -336.706681) (xy 174.037677 -336.714435) (xy 174.089975 -336.729788) (xy 174.139557 -336.752429)
			(xy 174.185411 -336.781896) (xy 174.226604 -336.817589) (xy 174.262298 -336.858781) (xy 174.291766 -336.904635)
			(xy 174.314408 -336.954215) (xy 174.329763 -337.006514) (xy 174.337518 -337.060465) (xy 174.33798 -337.087718)
			(xy 174.337529 -337.115089) (xy 174.329709 -337.169269) (xy 174.314216 -337.221772) (xy 174.291371 -337.271519)
			(xy 174.261643 -337.317485) (xy 174.244 -337.338416) (xy 174.243746 -337.33867) (xy 174.238159 -337.345756)
			(xy 174.231914 -337.362673) (xy 174.231554 -337.37169) (xy 174.231554 -337.438746) (xy 174.231925 -337.447762)
			(xy 174.238162 -337.464679) (xy 174.243746 -337.471766) (xy 174.244 -337.471766) (xy 174.244 -337.47202)
			(xy 174.261657 -337.492939) (xy 174.291379 -337.53891) (xy 174.314222 -337.588659) (xy 174.329716 -337.641162)
			(xy 174.337542 -337.695342) (xy 174.33754 -337.750085) (xy 174.32971 -337.804264) (xy 174.314212 -337.856767)
			(xy 174.291366 -337.906514) (xy 174.261641 -337.952483) (xy 174.244 -337.973416) (xy 174.243746 -337.97367)
			(xy 174.238159 -337.980756) (xy 174.231914 -337.997673) (xy 174.231554 -338.00669) (xy 174.231554 -338.073746)
			(xy 174.231925 -338.082762) (xy 174.238162 -338.099679) (xy 174.243746 -338.106766) (xy 174.244 -338.106766)
			(xy 174.244 -338.10702) (xy 174.261657 -338.127939) (xy 174.291379 -338.17391) (xy 174.314222 -338.223659)
			(xy 174.329716 -338.276162) (xy 174.337542 -338.330342) (xy 174.33754 -338.385085) (xy 174.32971 -338.439264)
			(xy 174.314212 -338.491767) (xy 174.291366 -338.541514) (xy 174.261641 -338.587483) (xy 174.244 -338.608416)
			(xy 174.243746 -338.60867) (xy 174.238159 -338.615756) (xy 174.231914 -338.632673) (xy 174.231554 -338.64169)
			(xy 174.231554 -338.708746) (xy 174.231925 -338.717762) (xy 174.238162 -338.734679) (xy 174.243746 -338.741766)
			(xy 174.244 -338.741766) (xy 174.244 -338.74202) (xy 174.261657 -338.762939) (xy 174.291379 -338.80891)
			(xy 174.314222 -338.858659) (xy 174.329716 -338.911162) (xy 174.337542 -338.965342) (xy 174.33754 -339.020085)
			(xy 174.32971 -339.074264) (xy 174.314212 -339.126767) (xy 174.291366 -339.176514) (xy 174.261641 -339.222483)
			(xy 174.244 -339.243416) (xy 174.243746 -339.24367) (xy 174.238159 -339.250756) (xy 174.231914 -339.267673)
			(xy 174.231554 -339.27669) (xy 174.231554 -339.343746) (xy 174.231925 -339.352762) (xy 174.238162 -339.369679)
			(xy 174.243746 -339.376766) (xy 174.244 -339.376766) (xy 174.244 -339.37702) (xy 174.261657 -339.397939)
			(xy 174.291379 -339.44391) (xy 174.314222 -339.493659) (xy 174.329716 -339.546162) (xy 174.337542 -339.600342)
			(xy 174.33754 -339.655085) (xy 174.32971 -339.709264) (xy 174.314212 -339.761767) (xy 174.291366 -339.811514)
			(xy 174.261641 -339.857483) (xy 174.244 -339.878416) (xy 174.243746 -339.87867) (xy 174.238159 -339.885756)
			(xy 174.231914 -339.902673) (xy 174.231554 -339.91169) (xy 174.231554 -339.978746) (xy 174.231925 -339.987762)
			(xy 174.238162 -340.004679) (xy 174.243746 -340.011766) (xy 174.244 -340.011766) (xy 174.244 -340.01202)
			(xy 174.261615 -340.032971) (xy 174.291331 -340.078939) (xy 174.314171 -340.128682) (xy 174.329668 -340.181178)
			(xy 174.337502 -340.23535) (xy 174.33798 -340.262718) (xy 174.337941 -340.265258) (xy 177.384964 -340.265258)
			(xy 177.385448 -340.237888) (xy 177.393259 -340.183709) (xy 177.408743 -340.131206) (xy 177.431581 -340.081459)
			(xy 177.461304 -340.035492) (xy 177.478944 -340.01456) (xy 177.479198 -340.014306) (xy 177.484788 -340.007222)
			(xy 177.491033 -339.990303) (xy 177.49139 -339.981286) (xy 177.49139 -339.91423) (xy 177.491021 -339.905214)
			(xy 177.484782 -339.888297) (xy 177.479198 -339.88121) (xy 177.478944 -339.88121) (xy 177.478944 -339.880956)
			(xy 177.461261 -339.860057) (xy 177.431537 -339.814084) (xy 177.408693 -339.764332) (xy 177.393199 -339.711825)
			(xy 177.385374 -339.657641) (xy 177.385379 -339.602896) (xy 177.393213 -339.548713) (xy 177.408715 -339.496209)
			(xy 177.431568 -339.446461) (xy 177.4613 -339.400492) (xy 177.478944 -339.37956) (xy 177.479198 -339.379306)
			(xy 177.484788 -339.372222) (xy 177.491033 -339.355303) (xy 177.49139 -339.346286) (xy 177.49139 -339.27923)
			(xy 177.491021 -339.270214) (xy 177.484782 -339.253297) (xy 177.479198 -339.24621) (xy 177.478944 -339.24621)
			(xy 177.478944 -339.245956) (xy 177.461261 -339.225057) (xy 177.431537 -339.179084) (xy 177.408693 -339.129332)
			(xy 177.393199 -339.076825) (xy 177.385374 -339.022641) (xy 177.385379 -338.967896) (xy 177.393213 -338.913713)
			(xy 177.408715 -338.861209) (xy 177.431568 -338.811461) (xy 177.4613 -338.765492) (xy 177.478944 -338.74456)
			(xy 177.479198 -338.744306) (xy 177.484788 -338.737222) (xy 177.491033 -338.720303) (xy 177.49139 -338.711286)
			(xy 177.49139 -338.64423) (xy 177.491021 -338.635214) (xy 177.484782 -338.618297) (xy 177.479198 -338.61121)
			(xy 177.478944 -338.61121) (xy 177.478944 -338.610956) (xy 177.461261 -338.590057) (xy 177.431537 -338.544084)
			(xy 177.408693 -338.494332) (xy 177.393199 -338.441825) (xy 177.385374 -338.387641) (xy 177.385379 -338.332896)
			(xy 177.393213 -338.278713) (xy 177.408715 -338.226209) (xy 177.431568 -338.176461) (xy 177.4613 -338.130492)
			(xy 177.478944 -338.10956) (xy 177.479198 -338.109306) (xy 177.484788 -338.102222) (xy 177.491033 -338.085303)
			(xy 177.49139 -338.076286) (xy 177.49139 -338.00923) (xy 177.491021 -338.000214) (xy 177.484782 -337.983297)
			(xy 177.479198 -337.97621) (xy 177.478944 -337.97621) (xy 177.478944 -337.975956) (xy 177.461261 -337.955057)
			(xy 177.431537 -337.909084) (xy 177.408693 -337.859332) (xy 177.393199 -337.806825) (xy 177.385374 -337.752641)
			(xy 177.385379 -337.697896) (xy 177.393213 -337.643713) (xy 177.408715 -337.591209) (xy 177.431568 -337.541461)
			(xy 177.4613 -337.495492) (xy 177.478944 -337.47456) (xy 177.479198 -337.474306) (xy 177.484788 -337.467222)
			(xy 177.491033 -337.450303) (xy 177.49139 -337.441286) (xy 177.49139 -337.37423) (xy 177.491021 -337.365214)
			(xy 177.484782 -337.348297) (xy 177.479198 -337.34121) (xy 177.478944 -337.34121) (xy 177.478944 -337.340956)
			(xy 177.461325 -337.320008) (xy 177.431608 -337.27404) (xy 177.408768 -337.224297) (xy 177.393272 -337.171799)
			(xy 177.38544 -337.117626) (xy 177.384964 -337.090258) (xy 177.385439 -337.063007) (xy 177.3932 -337.00906)
			(xy 177.408559 -336.956767) (xy 177.431203 -336.907192) (xy 177.460671 -336.861343) (xy 177.496364 -336.820154)
			(xy 177.537554 -336.784463) (xy 177.583404 -336.754996) (xy 177.63298 -336.732354) (xy 177.685274 -336.716997)
			(xy 177.739221 -336.709238) (xy 177.766472 -336.70875) (xy 177.794111 -336.709229) (xy 177.848806 -336.717226)
			(xy 177.901777 -336.733027) (xy 177.951916 -336.756303) (xy 177.998173 -336.786566) (xy 178.019202 -336.804508)
			(xy 178.026358 -336.810289) (xy 178.04354 -336.816813) (xy 178.05273 -336.817208) (xy 178.120294 -336.817208)
			(xy 178.129481 -336.816793) (xy 178.146665 -336.810282) (xy 178.153822 -336.804508) (xy 178.174846 -336.786558)
			(xy 178.221097 -336.756284) (xy 178.271237 -336.733006) (xy 178.324212 -336.717214) (xy 178.378912 -336.709238)
			(xy 178.406552 -336.70875) (xy 178.433802 -336.7093) (xy 178.487747 -336.717049) (xy 178.540041 -336.732397)
			(xy 178.589618 -336.755031) (xy 178.63547 -336.78449) (xy 178.676662 -336.820175) (xy 178.712356 -336.861358)
			(xy 178.741826 -336.907203) (xy 178.764472 -336.956774) (xy 178.779832 -337.009065) (xy 178.787594 -337.063008)
			(xy 178.78806 -337.090258) (xy 178.787579 -337.117628) (xy 178.779766 -337.171807) (xy 178.764281 -337.22431)
			(xy 178.741443 -337.274057) (xy 178.71172 -337.320024) (xy 178.69408 -337.340956) (xy 178.693826 -337.34121)
			(xy 178.68822 -337.348283) (xy 178.681987 -337.365211) (xy 178.681634 -337.37423) (xy 178.681634 -337.441286)
			(xy 178.681991 -337.450303) (xy 178.688238 -337.46722) (xy 178.693826 -337.474306) (xy 178.69408 -337.474306)
			(xy 178.69408 -337.47456) (xy 178.711679 -337.495526) (xy 178.741405 -337.541488) (xy 178.764253 -337.591229)
			(xy 178.779752 -337.643726) (xy 178.787584 -337.6979) (xy 178.787589 -337.752637) (xy 178.779765 -337.806812)
			(xy 178.764275 -337.859312) (xy 178.741436 -337.909056) (xy 178.711717 -337.955023) (xy 178.69408 -337.975956)
			(xy 178.693826 -337.97621) (xy 178.68822 -337.983283) (xy 178.681987 -338.000211) (xy 178.681634 -338.00923)
			(xy 178.681634 -338.076286) (xy 178.681991 -338.085303) (xy 178.688238 -338.10222) (xy 178.693826 -338.109306)
			(xy 178.69408 -338.109306) (xy 178.69408 -338.10956) (xy 178.711679 -338.130526) (xy 178.741405 -338.176488)
			(xy 178.764253 -338.226229) (xy 178.779752 -338.278726) (xy 178.787584 -338.3329) (xy 178.787589 -338.387637)
			(xy 178.779765 -338.441812) (xy 178.764275 -338.494312) (xy 178.741436 -338.544056) (xy 178.711717 -338.590023)
			(xy 178.69408 -338.610956) (xy 178.693826 -338.61121) (xy 178.68822 -338.618283) (xy 178.681987 -338.635211)
			(xy 178.681634 -338.64423) (xy 178.681634 -338.711286) (xy 178.681991 -338.720303) (xy 178.688238 -338.73722)
			(xy 178.693826 -338.744306) (xy 178.69408 -338.744306) (xy 178.69408 -338.74456) (xy 178.711679 -338.765526)
			(xy 178.741405 -338.811488) (xy 178.764253 -338.861229) (xy 178.779752 -338.913726) (xy 178.787584 -338.9679)
			(xy 178.787589 -339.022637) (xy 178.779765 -339.076812) (xy 178.764275 -339.129312) (xy 178.741436 -339.179056)
			(xy 178.711717 -339.225023) (xy 178.69408 -339.245956) (xy 178.693826 -339.24621) (xy 178.68822 -339.253283)
			(xy 178.681987 -339.270211) (xy 178.681634 -339.27923) (xy 178.681634 -339.346286) (xy 178.681991 -339.355303)
			(xy 178.688238 -339.37222) (xy 178.693826 -339.379306) (xy 178.69408 -339.379306) (xy 178.69408 -339.37956)
			(xy 178.711679 -339.400526) (xy 178.741405 -339.446488) (xy 178.764253 -339.496229) (xy 178.779752 -339.548726)
			(xy 178.787584 -339.6029) (xy 178.787589 -339.657637) (xy 178.779765 -339.711812) (xy 178.764275 -339.764312)
			(xy 178.741436 -339.814056) (xy 178.711717 -339.860023) (xy 178.69408 -339.880956) (xy 178.693826 -339.88121)
			(xy 178.68822 -339.888283) (xy 178.681987 -339.905211) (xy 178.681634 -339.91423) (xy 178.681634 -339.981286)
			(xy 178.681991 -339.990303) (xy 178.688238 -340.00722) (xy 178.693826 -340.014306) (xy 178.69408 -340.014306)
			(xy 178.69408 -340.01456) (xy 178.711711 -340.035499) (xy 178.741424 -340.08147) (xy 178.764262 -340.131215)
			(xy 178.779755 -340.183715) (xy 178.787585 -340.237889) (xy 178.78806 -340.265258) (xy 178.787627 -340.291269)
			(xy 178.780551 -340.342808) (xy 178.766539 -340.392908) (xy 178.74585 -340.44064) (xy 178.718867 -340.485118)
			(xy 178.686092 -340.525518) (xy 178.648133 -340.56109) (xy 178.605692 -340.591175) (xy 178.582828 -340.603586)
			(xy 178.572922 -340.608666) (xy 178.559206 -340.6267) (xy 178.53787 -340.72576) (xy 178.542696 -340.74735)
			(xy 178.549554 -340.75624) (xy 178.550062 -340.756748) (xy 178.565358 -340.776977) (xy 178.591081 -340.820683)
			(xy 178.610793 -340.867409) (xy 178.624145 -340.916334) (xy 178.630904 -340.966595) (xy 178.631342 -340.991952)
			(xy 178.630862 -341.019322) (xy 178.62305 -341.073501) (xy 178.607565 -341.126004) (xy 178.584726 -341.175752)
			(xy 178.555003 -341.221718) (xy 178.537362 -341.24265) (xy 178.537108 -341.242904) (xy 178.531515 -341.249986)
			(xy 178.525272 -341.266906) (xy 178.524916 -341.275924) (xy 178.524916 -341.34298) (xy 178.525279 -341.351996)
			(xy 178.531522 -341.368914) (xy 178.537108 -341.376) (xy 178.537362 -341.376) (xy 178.537362 -341.376254)
			(xy 178.554987 -341.397197) (xy 178.584702 -341.443167) (xy 178.607542 -341.492911) (xy 178.623036 -341.545409)
			(xy 178.630867 -341.599584) (xy 178.631342 -341.626952) (xy 180.014626 -341.626952) (xy 180.015116 -341.599583)
			(xy 180.022927 -341.545404) (xy 180.03841 -341.492901) (xy 180.061247 -341.443154) (xy 180.090967 -341.397186)
			(xy 180.108606 -341.376254) (xy 180.10886 -341.376) (xy 180.11446 -341.368923) (xy 180.120697 -341.351999)
			(xy 180.121052 -341.34298) (xy 180.121052 -341.275924) (xy 180.120694 -341.266907) (xy 180.114448 -341.24999)
			(xy 180.10886 -341.242904) (xy 180.108606 -341.242904) (xy 180.108606 -341.24265) (xy 180.090978 -341.221709)
			(xy 180.061264 -341.175739) (xy 180.038426 -341.125994) (xy 180.022932 -341.073495) (xy 180.015101 -341.019321)
			(xy 180.014626 -340.991952) (xy 180.015119 -340.964738) (xy 180.022847 -340.910863) (xy 180.038155 -340.858633)
			(xy 180.060731 -340.80911) (xy 180.090117 -340.763297) (xy 180.125716 -340.722127) (xy 180.145944 -340.703916)
			(xy 180.153708 -340.696571) (xy 180.162789 -340.677244) (xy 180.16347 -340.666578) (xy 180.165502 -340.58098)
			(xy 180.157374 -340.561168) (xy 180.1495 -340.553802) (xy 180.131195 -340.535757) (xy 180.099159 -340.495557)
			(xy 180.072808 -340.451423) (xy 180.052617 -340.404151) (xy 180.038952 -340.354598) (xy 180.03206 -340.303659)
			(xy 180.031644 -340.277958) (xy 180.032133 -340.250588) (xy 180.039944 -340.19641) (xy 180.055427 -340.143907)
			(xy 180.078264 -340.094159) (xy 180.107984 -340.048192) (xy 180.125624 -340.02726) (xy 180.125878 -340.027006)
			(xy 180.131477 -340.019929) (xy 180.137714 -340.003004) (xy 180.13807 -339.993986) (xy 180.13807 -339.92693)
			(xy 180.137705 -339.917914) (xy 180.131464 -339.900997) (xy 180.125878 -339.89391) (xy 180.125624 -339.89391)
			(xy 180.125624 -339.893656) (xy 180.107942 -339.872757) (xy 180.078219 -339.826783) (xy 180.055377 -339.777031)
			(xy 180.039884 -339.724524) (xy 180.032059 -339.670341) (xy 180.032064 -339.615596) (xy 180.039897 -339.561414)
			(xy 180.055399 -339.50891) (xy 180.07825 -339.459162) (xy 180.10798 -339.413193) (xy 180.125624 -339.39226)
			(xy 180.125878 -339.392006) (xy 180.131477 -339.384929) (xy 180.137714 -339.368004) (xy 180.13807 -339.358986)
			(xy 180.13807 -339.29193) (xy 180.137705 -339.282914) (xy 180.131464 -339.265997) (xy 180.125878 -339.25891)
			(xy 180.125624 -339.25891) (xy 180.125624 -339.258656) (xy 180.107942 -339.237757) (xy 180.078219 -339.191783)
			(xy 180.055377 -339.142031) (xy 180.039884 -339.089524) (xy 180.032059 -339.035341) (xy 180.032064 -338.980596)
			(xy 180.039897 -338.926414) (xy 180.055399 -338.87391) (xy 180.07825 -338.824162) (xy 180.10798 -338.778193)
			(xy 180.125624 -338.75726) (xy 180.125878 -338.757006) (xy 180.131477 -338.749929) (xy 180.137714 -338.733004)
			(xy 180.13807 -338.723986) (xy 180.13807 -338.65693) (xy 180.137705 -338.647914) (xy 180.131464 -338.630997)
			(xy 180.125878 -338.62391) (xy 180.125624 -338.62391) (xy 180.125624 -338.623656) (xy 180.107942 -338.602757)
			(xy 180.078219 -338.556783) (xy 180.055377 -338.507031) (xy 180.039884 -338.454524) (xy 180.032059 -338.400341)
			(xy 180.032064 -338.345596) (xy 180.039897 -338.291414) (xy 180.055399 -338.23891) (xy 180.07825 -338.189162)
			(xy 180.10798 -338.143193) (xy 180.125624 -338.12226) (xy 180.125878 -338.122006) (xy 180.131477 -338.114929)
			(xy 180.137714 -338.098004) (xy 180.13807 -338.088986) (xy 180.13807 -338.02193) (xy 180.137705 -338.012914)
			(xy 180.131464 -337.995997) (xy 180.125878 -337.98891) (xy 180.125624 -337.98891) (xy 180.125624 -337.988656)
			(xy 180.108001 -337.967711) (xy 180.078286 -337.921742) (xy 180.055447 -337.871998) (xy 180.039952 -337.8195)
			(xy 180.03212 -337.765326) (xy 180.031644 -337.737958) (xy 180.032075 -337.71253) (xy 180.038826 -337.662123)
			(xy 180.052214 -337.61306) (xy 180.072004 -337.566211) (xy 180.097843 -337.522408) (xy 180.129275 -337.482427)
			(xy 180.147214 -337.4644) (xy 180.147468 -337.464146) (xy 180.153635 -337.457515) (xy 180.161311 -337.441125)
			(xy 180.162454 -337.432142) (xy 180.16855 -337.355942) (xy 180.16347 -337.338162) (xy 180.157882 -337.330796)
			(xy 180.140125 -337.305947) (xy 180.111948 -337.251765) (xy 180.092757 -337.193787) (xy 180.083041 -337.133494)
			(xy 180.082444 -337.102958) (xy 180.082939 -337.075708) (xy 180.0907 -337.021763) (xy 180.106058 -336.969471)
			(xy 180.1287 -336.919897) (xy 180.158166 -336.874049) (xy 180.193857 -336.832861) (xy 180.235044 -336.79717)
			(xy 180.280892 -336.767703) (xy 180.330466 -336.74506) (xy 180.382757 -336.729701) (xy 180.436702 -336.721939)
			(xy 180.463952 -336.72145) (xy 180.49159 -336.721941) (xy 180.546286 -336.729935) (xy 180.599256 -336.745733)
			(xy 180.649395 -336.769006) (xy 180.695653 -336.799267) (xy 180.716682 -336.817208) (xy 180.723814 -336.823023)
			(xy 180.741015 -336.829526) (xy 180.75021 -336.829908) (xy 180.817774 -336.829908) (xy 180.82696 -336.829483)
			(xy 180.844144 -336.82298) (xy 180.851302 -336.817208) (xy 180.872333 -336.799268) (xy 180.918583 -336.768992)
			(xy 180.96872 -336.745713) (xy 181.021694 -336.729918) (xy 181.076393 -336.72194) (xy 181.104032 -336.72145)
			(xy 181.131742 -336.721927) (xy 181.186579 -336.729943) (xy 181.239678 -336.745816) (xy 181.289918 -336.769212)
			(xy 181.33624 -336.799636) (xy 181.377667 -336.836448) (xy 181.395878 -336.85734) (xy 181.402736 -336.865722)
			(xy 181.42204 -336.87512) (xy 181.508146 -336.878168) (xy 181.518867 -336.878098) (xy 181.538726 -336.870059)
			(xy 181.5465 -336.862674) (xy 181.564512 -336.844677) (xy 181.604524 -336.813185) (xy 181.648369 -336.787293)
			(xy 181.695267 -336.76746) (xy 181.744386 -336.754041) (xy 181.794853 -336.747271) (xy 181.820312 -336.74685)
			(xy 181.847562 -336.747366) (xy 181.901506 -336.755124) (xy 181.953798 -336.770478) (xy 182.003372 -336.793118)
			(xy 182.04922 -336.822581) (xy 182.090409 -336.858269) (xy 182.126101 -336.899455) (xy 182.155568 -336.945301)
			(xy 182.178211 -336.994874) (xy 182.19357 -337.047165) (xy 182.201331 -337.101108) (xy 182.20182 -337.128358)
			(xy 182.201434 -337.154335) (xy 182.194383 -337.205809) (xy 182.180405 -337.255849) (xy 182.15976 -337.303526)
			(xy 182.132831 -337.347957) (xy 182.100116 -337.388318) (xy 182.062223 -337.423862) (xy 182.041292 -337.439254)
			(xy 182.031809 -337.446895) (xy 182.020658 -337.4685) (xy 182.019956 -337.480656) (xy 182.019956 -337.56346)
			(xy 182.020637 -337.575624) (xy 182.031783 -337.597246) (xy 182.041292 -337.604862) (xy 182.062217 -337.620257)
			(xy 182.100092 -337.655812) (xy 182.13279 -337.696179) (xy 182.159708 -337.74061) (xy 182.180345 -337.788283)
			(xy 182.194322 -337.838316) (xy 182.201378 -337.889784) (xy 182.20182 -337.915758) (xy 182.201349 -337.943128)
			(xy 182.193535 -337.997308) (xy 182.178048 -338.049812) (xy 182.155207 -338.099559) (xy 182.125482 -338.145525)
			(xy 182.10784 -338.166456) (xy 182.107586 -338.16671) (xy 182.101988 -338.173788) (xy 182.095748 -338.190711)
			(xy 182.095394 -338.19973) (xy 182.095394 -338.266786) (xy 182.095759 -338.275802) (xy 182.102001 -338.292719)
			(xy 182.107586 -338.299806) (xy 182.10784 -338.299806) (xy 182.10784 -338.30006) (xy 182.125441 -338.321025)
			(xy 182.15517 -338.366987) (xy 182.17802 -338.416727) (xy 182.193521 -338.469225) (xy 182.201354 -338.523399)
			(xy 182.201358 -338.578137) (xy 182.193534 -338.632313) (xy 182.178042 -338.684813) (xy 182.1552 -338.734558)
			(xy 182.125479 -338.780524) (xy 182.10784 -338.801456) (xy 182.107586 -338.80171) (xy 182.101988 -338.808788)
			(xy 182.095748 -338.825711) (xy 182.095394 -338.83473) (xy 182.095394 -338.901786) (xy 182.095759 -338.910802)
			(xy 182.102001 -338.927719) (xy 182.107586 -338.934806) (xy 182.10784 -338.934806) (xy 182.10784 -338.93506)
			(xy 182.12548 -338.955991) (xy 182.155191 -339.001965) (xy 182.178026 -339.051713) (xy 182.193517 -339.104213)
			(xy 182.201346 -339.158389) (xy 182.20182 -339.185758) (xy 183.714644 -339.185758) (xy 183.715133 -339.158388)
			(xy 183.722944 -339.10421) (xy 183.738427 -339.051707) (xy 183.761264 -339.001959) (xy 183.790984 -338.955992)
			(xy 183.808624 -338.93506) (xy 183.808878 -338.934806) (xy 183.814477 -338.927729) (xy 183.820714 -338.910804)
			(xy 183.82107 -338.901786) (xy 183.82107 -338.83473) (xy 183.820705 -338.825714) (xy 183.814464 -338.808797)
			(xy 183.808878 -338.80171) (xy 183.808624 -338.80171) (xy 183.808624 -338.801456) (xy 183.790942 -338.780557)
			(xy 183.761219 -338.734583) (xy 183.738377 -338.684831) (xy 183.722884 -338.632324) (xy 183.715059 -338.578141)
			(xy 183.715064 -338.523396) (xy 183.722897 -338.469214) (xy 183.738399 -338.41671) (xy 183.76125 -338.366962)
			(xy 183.79098 -338.320993) (xy 183.808624 -338.30006) (xy 183.808878 -338.299806) (xy 183.814477 -338.292729)
			(xy 183.820714 -338.275804) (xy 183.82107 -338.266786) (xy 183.82107 -338.19973) (xy 183.820705 -338.190714)
			(xy 183.814464 -338.173797) (xy 183.808878 -338.16671) (xy 183.808624 -338.16671) (xy 183.808624 -338.166456)
			(xy 183.791001 -338.145511) (xy 183.761286 -338.099542) (xy 183.738447 -338.049798) (xy 183.722952 -337.9973)
			(xy 183.71512 -337.943126) (xy 183.714644 -337.915758) (xy 183.715057 -337.889782) (xy 183.722106 -337.838309)
			(xy 183.73608 -337.788271) (xy 183.75672 -337.740595) (xy 183.783645 -337.696164) (xy 183.816355 -337.655802)
			(xy 183.854244 -337.620256) (xy 183.875172 -337.604862) (xy 183.884659 -337.597226) (xy 183.895805 -337.575617)
			(xy 183.896508 -337.56346) (xy 183.896508 -337.480656) (xy 183.895832 -337.468491) (xy 183.884684 -337.446868)
			(xy 183.875172 -337.439254) (xy 183.854269 -337.423831) (xy 183.81639 -337.388282) (xy 183.783688 -337.347922)
			(xy 183.756767 -337.303495) (xy 183.736126 -337.255826) (xy 183.722146 -337.205796) (xy 183.715087 -337.154331)
			(xy 183.714644 -337.128358) (xy 183.715139 -337.101108) (xy 183.7229 -337.047163) (xy 183.738258 -336.994871)
			(xy 183.7609 -336.945297) (xy 183.790366 -336.899449) (xy 183.826057 -336.858261) (xy 183.867244 -336.82257)
			(xy 183.913092 -336.793103) (xy 183.962666 -336.77046) (xy 184.014957 -336.755101) (xy 184.068902 -336.747339)
			(xy 184.096152 -336.74685) (xy 184.125808 -336.747405) (xy 184.184404 -336.756591) (xy 184.240873 -336.774733)
			(xy 184.293855 -336.801394) (xy 184.342073 -336.835933) (xy 184.363614 -336.856324) (xy 184.371168 -336.863142)
			(xy 184.39002 -336.87075) (xy 184.40019 -336.871056) (xy 184.47258 -336.869532) (xy 184.48272 -336.868925)
			(xy 184.501325 -336.860822) (xy 184.508648 -336.853784) (xy 184.526731 -336.835375) (xy 184.566968 -336.803068)
			(xy 184.611194 -336.776483) (xy 184.658601 -336.756106) (xy 184.708324 -336.742308) (xy 184.759453 -336.735343)
			(xy 184.785254 -336.734912) (xy 184.812893 -336.735386) (xy 184.86759 -336.743382) (xy 184.920561 -336.759184)
			(xy 184.970699 -336.782461) (xy 185.016956 -336.812726) (xy 185.037984 -336.83067) (xy 185.04511 -336.836493)
			(xy 185.062316 -336.84299) (xy 185.071512 -336.84337) (xy 185.139076 -336.84337) (xy 185.14826 -336.842933)
			(xy 185.165444 -336.836436) (xy 185.172604 -336.83067) (xy 185.193629 -336.812723) (xy 185.239881 -336.782449)
			(xy 185.29002 -336.759172) (xy 185.342995 -336.743379) (xy 185.397695 -336.735401) (xy 185.425334 -336.734912)
			(xy 185.452587 -336.735346) (xy 185.506538 -336.743108) (xy 185.558835 -336.758468) (xy 185.608413 -336.781115)
			(xy 185.654264 -336.810587) (xy 185.695455 -336.846283) (xy 185.731146 -336.887479) (xy 185.760611 -336.933334)
			(xy 185.783251 -336.982916) (xy 185.798604 -337.035215) (xy 185.806358 -337.089167) (xy 185.806842 -337.11642)
			(xy 185.806402 -337.143791) (xy 185.79858 -337.197972) (xy 185.783086 -337.250476) (xy 185.760238 -337.300223)
			(xy 185.730507 -337.346188) (xy 185.712862 -337.367118) (xy 185.712608 -337.367372) (xy 185.707028 -337.374463)
			(xy 185.700777 -337.391376) (xy 185.700416 -337.400392) (xy 185.700416 -337.467448) (xy 185.700795 -337.476463)
			(xy 185.707027 -337.49338) (xy 185.712608 -337.500468) (xy 185.712862 -337.500468) (xy 185.712862 -337.500722)
			(xy 185.730523 -337.521639) (xy 185.760248 -337.567609) (xy 185.783092 -337.617358) (xy 185.798588 -337.669862)
			(xy 185.806415 -337.724043) (xy 185.806412 -337.778787) (xy 185.798581 -337.832967) (xy 185.783082 -337.88547)
			(xy 185.760233 -337.935217) (xy 185.730505 -337.981185) (xy 185.712862 -338.002118) (xy 185.712608 -338.002372)
			(xy 185.707028 -338.009463) (xy 185.700777 -338.026376) (xy 185.700416 -338.035392) (xy 185.700416 -338.102448)
			(xy 185.700795 -338.111463) (xy 185.707027 -338.12838) (xy 185.712608 -338.135468) (xy 185.712862 -338.135468)
			(xy 185.712862 -338.135722) (xy 185.730523 -338.156639) (xy 185.760248 -338.202609) (xy 185.783092 -338.252358)
			(xy 185.798588 -338.304862) (xy 185.806415 -338.359043) (xy 185.806412 -338.413787) (xy 185.798581 -338.467967)
			(xy 185.783082 -338.52047) (xy 185.760233 -338.570217) (xy 185.730505 -338.616185) (xy 185.712862 -338.637118)
			(xy 185.712608 -338.637372) (xy 185.707028 -338.644463) (xy 185.700777 -338.661376) (xy 185.700416 -338.670392)
			(xy 185.700416 -338.737448) (xy 185.700795 -338.746463) (xy 185.707027 -338.76338) (xy 185.712608 -338.770468)
			(xy 185.712862 -338.770468) (xy 185.712862 -338.770722) (xy 185.730523 -338.791639) (xy 185.760248 -338.837609)
			(xy 185.783092 -338.887358) (xy 185.798588 -338.939862) (xy 185.806415 -338.994043) (xy 185.806412 -339.048787)
			(xy 185.798581 -339.102967) (xy 185.783082 -339.15547) (xy 185.760233 -339.205217) (xy 185.730505 -339.251185)
			(xy 185.712862 -339.272118) (xy 185.712608 -339.272372) (xy 185.707028 -339.279463) (xy 185.700777 -339.296376)
			(xy 185.700416 -339.305392) (xy 185.700416 -339.372448) (xy 185.700795 -339.381463) (xy 185.707027 -339.39838)
			(xy 185.712608 -339.405468) (xy 185.712862 -339.405468) (xy 185.712862 -339.405722) (xy 185.730523 -339.426639)
			(xy 185.760248 -339.472609) (xy 185.783092 -339.522358) (xy 185.798588 -339.574862) (xy 185.806415 -339.629043)
			(xy 185.806412 -339.683787) (xy 185.798581 -339.737967) (xy 185.783082 -339.79047) (xy 185.760233 -339.840217)
			(xy 185.730505 -339.886185) (xy 185.712862 -339.907118) (xy 185.712608 -339.907372) (xy 185.707028 -339.914463)
			(xy 185.700777 -339.931376) (xy 185.700416 -339.940392) (xy 185.700416 -340.007448) (xy 185.700795 -340.016463)
			(xy 185.707027 -340.03338) (xy 185.712608 -340.040468) (xy 185.712862 -340.040468) (xy 185.712862 -340.040722)
			(xy 185.730472 -340.061678) (xy 185.76019 -340.107643) (xy 185.783032 -340.157385) (xy 185.798529 -340.20988)
			(xy 185.806365 -340.264052) (xy 185.806373 -340.264496) (xy 188.333126 -340.264496) (xy 188.333583 -340.237125)
			(xy 188.341402 -340.182946) (xy 188.356893 -340.130442) (xy 188.379737 -340.080695) (xy 188.409464 -340.034729)
			(xy 188.427106 -340.013798) (xy 188.42736 -340.013544) (xy 188.432941 -340.006454) (xy 188.43919 -339.98954)
			(xy 188.439552 -339.980524) (xy 188.439552 -339.913468) (xy 188.439221 -339.904448) (xy 188.432957 -339.887531)
			(xy 188.42736 -339.880448) (xy 188.427106 -339.880448) (xy 188.427106 -339.880194) (xy 188.409462 -339.859264)
			(xy 188.379739 -339.813295) (xy 188.356895 -339.763548) (xy 188.3414 -339.711046) (xy 188.333573 -339.656868)
			(xy 188.333573 -339.602126) (xy 188.341402 -339.547948) (xy 188.356898 -339.495446) (xy 188.379742 -339.445699)
			(xy 188.409466 -339.399731) (xy 188.427106 -339.378798) (xy 188.42736 -339.378544) (xy 188.432941 -339.371454)
			(xy 188.43919 -339.35454) (xy 188.439552 -339.345524) (xy 188.439552 -339.278468) (xy 188.439221 -339.269448)
			(xy 188.432957 -339.252531) (xy 188.42736 -339.245448) (xy 188.427106 -339.245448) (xy 188.427106 -339.245194)
			(xy 188.409462 -339.224264) (xy 188.379739 -339.178295) (xy 188.356895 -339.128548) (xy 188.3414 -339.076046)
			(xy 188.333573 -339.021868) (xy 188.333573 -338.967126) (xy 188.341402 -338.912948) (xy 188.356898 -338.860446)
			(xy 188.379742 -338.810699) (xy 188.409466 -338.764731) (xy 188.427106 -338.743798) (xy 188.42736 -338.743544)
			(xy 188.432941 -338.736454) (xy 188.43919 -338.71954) (xy 188.439552 -338.710524) (xy 188.439552 -338.643468)
			(xy 188.439221 -338.634448) (xy 188.432957 -338.617531) (xy 188.42736 -338.610448) (xy 188.427106 -338.610448)
			(xy 188.427106 -338.610194) (xy 188.409462 -338.589264) (xy 188.379739 -338.543295) (xy 188.356895 -338.493548)
			(xy 188.3414 -338.441046) (xy 188.333573 -338.386868) (xy 188.333573 -338.332126) (xy 188.341402 -338.277948)
			(xy 188.356898 -338.225446) (xy 188.379742 -338.175699) (xy 188.409466 -338.129731) (xy 188.427106 -338.108798)
			(xy 188.42736 -338.108544) (xy 188.432941 -338.101454) (xy 188.43919 -338.08454) (xy 188.439552 -338.075524)
			(xy 188.439552 -338.008468) (xy 188.439221 -337.999448) (xy 188.432957 -337.982531) (xy 188.42736 -337.975448)
			(xy 188.427106 -337.975448) (xy 188.427106 -337.975194) (xy 188.409462 -337.954264) (xy 188.379739 -337.908295)
			(xy 188.356895 -337.858548) (xy 188.3414 -337.806046) (xy 188.333573 -337.751868) (xy 188.333573 -337.697126)
			(xy 188.341402 -337.642948) (xy 188.356898 -337.590446) (xy 188.379742 -337.540699) (xy 188.409466 -337.494731)
			(xy 188.427106 -337.473798) (xy 188.42736 -337.473544) (xy 188.432941 -337.466454) (xy 188.43919 -337.44954)
			(xy 188.439552 -337.440524) (xy 188.439552 -337.373468) (xy 188.439221 -337.364448) (xy 188.432957 -337.347531)
			(xy 188.42736 -337.340448) (xy 188.427106 -337.340448) (xy 188.427106 -337.340194) (xy 188.409452 -337.319274)
			(xy 188.379742 -337.273298) (xy 188.356909 -337.223548) (xy 188.341421 -337.171044) (xy 188.333598 -337.116866)
			(xy 188.333126 -337.089496) (xy 188.333552 -337.062242) (xy 188.34131 -337.008287) (xy 188.356668 -336.955987)
			(xy 188.379314 -336.906404) (xy 188.408785 -336.86055) (xy 188.444483 -336.819356) (xy 188.48568 -336.783663)
			(xy 188.531538 -336.754196) (xy 188.581122 -336.731555) (xy 188.633425 -336.716202) (xy 188.687379 -336.708449)
			(xy 188.714634 -336.707988) (xy 188.742272 -336.70848) (xy 188.796968 -336.716472) (xy 188.849939 -336.73227)
			(xy 188.900078 -336.755543) (xy 188.946335 -336.785805) (xy 188.967364 -336.803746) (xy 188.974498 -336.809558)
			(xy 188.991697 -336.816062) (xy 189.000892 -336.816446) (xy 189.068456 -336.816446) (xy 189.07764 -336.816004)
			(xy 189.094824 -336.809511) (xy 189.101984 -336.803746) (xy 189.123014 -336.785804) (xy 189.169265 -336.755531)
			(xy 189.219403 -336.732253) (xy 189.272376 -336.716458) (xy 189.327075 -336.708479) (xy 189.354714 -336.707988)
			(xy 189.382124 -336.708447) (xy 189.436381 -336.716295) (xy 189.488955 -336.731828) (xy 189.538765 -336.754726)
			(xy 189.584785 -336.784517) (xy 189.626067 -336.820589) (xy 189.644274 -336.841084) (xy 189.644528 -336.841338)
			(xy 189.651451 -336.848605) (xy 189.669366 -336.857617) (xy 189.679326 -336.858864) (xy 189.761622 -336.864706)
			(xy 189.780672 -336.858102) (xy 189.788292 -336.851498) (xy 189.809286 -336.833788) (xy 189.855374 -336.803912)
			(xy 189.905266 -336.780946) (xy 189.957934 -336.765365) (xy 190.01229 -336.75749) (xy 190.039752 -336.75701)
			(xy 190.067004 -336.7575) (xy 190.120955 -336.765251) (xy 190.173254 -336.780602) (xy 190.222835 -336.80324)
			(xy 190.268689 -336.832705) (xy 190.309883 -336.868396) (xy 190.345577 -336.909587) (xy 190.375046 -336.955439)
			(xy 190.397688 -337.005018) (xy 190.413043 -337.057315) (xy 190.420798 -337.111266) (xy 190.42126 -337.138518)
			(xy 190.420798 -337.165763) (xy 190.413038 -337.219697) (xy 190.397679 -337.271977) (xy 190.375034 -337.321538)
			(xy 190.345563 -337.367371) (xy 190.309868 -337.408541) (xy 190.268675 -337.444209) (xy 190.246 -337.45932)
			(xy 190.238985 -337.464181) (xy 190.228433 -337.477581) (xy 190.222904 -337.493716) (xy 190.222632 -337.502246)
			(xy 190.222632 -337.58759) (xy 190.222935 -337.596111) (xy 190.228496 -337.61222) (xy 190.239012 -337.62563)
			(xy 190.246 -337.630516) (xy 190.26869 -337.645605) (xy 190.309882 -337.681278) (xy 190.345576 -337.722452)
			(xy 190.375044 -337.768288) (xy 190.397687 -337.817852) (xy 190.413042 -337.870135) (xy 190.420798 -337.924072)
			(xy 190.42126 -337.951318) (xy 190.420814 -337.978689) (xy 190.412993 -338.032869) (xy 190.3975 -338.085373)
			(xy 190.374653 -338.13512) (xy 190.344924 -338.181085) (xy 190.32728 -338.202016) (xy 190.327026 -338.20227)
			(xy 190.321437 -338.209355) (xy 190.315194 -338.226273) (xy 190.314834 -338.23529) (xy 190.314834 -338.302346)
			(xy 190.315209 -338.311361) (xy 190.321443 -338.328279) (xy 190.327026 -338.335366) (xy 190.32728 -338.335366)
			(xy 190.32728 -338.33562) (xy 190.344938 -338.356539) (xy 190.374662 -338.402509) (xy 190.397505 -338.452258)
			(xy 190.413 -338.504762) (xy 190.420827 -338.558942) (xy 190.420825 -338.613685) (xy 190.412994 -338.667865)
			(xy 190.397496 -338.720368) (xy 190.374649 -338.770115) (xy 190.344922 -338.816083) (xy 190.32728 -338.837016)
			(xy 190.327026 -338.83727) (xy 190.321437 -338.844355) (xy 190.315194 -338.861273) (xy 190.314834 -338.87029)
			(xy 190.314834 -338.937346) (xy 190.315209 -338.946361) (xy 190.321443 -338.963279) (xy 190.327026 -338.970366)
			(xy 190.32728 -338.970366) (xy 190.32728 -338.97062) (xy 190.344892 -338.991574) (xy 190.374609 -339.03754)
			(xy 190.39745 -339.087282) (xy 190.412947 -339.139778) (xy 190.420782 -339.19395) (xy 190.42126 -339.221318)
			(xy 192.058544 -339.221318) (xy 192.05901 -339.193948) (xy 192.066826 -339.139768) (xy 192.082315 -339.087265)
			(xy 192.105157 -339.037518) (xy 192.134882 -338.991551) (xy 192.152524 -338.97062) (xy 192.152778 -338.970366)
			(xy 192.158352 -338.963271) (xy 192.164604 -338.94636) (xy 192.16497 -338.937346) (xy 192.16497 -338.87029)
			(xy 192.164624 -338.861272) (xy 192.15837 -338.844355) (xy 192.152778 -338.83727) (xy 192.152524 -338.83727)
			(xy 192.152524 -338.837016) (xy 192.134901 -338.816069) (xy 192.105176 -338.770104) (xy 192.08233 -338.72036)
			(xy 192.066832 -338.66786) (xy 192.059002 -338.613683) (xy 192.059 -338.558944) (xy 192.066826 -338.504767)
			(xy 192.08232 -338.452266) (xy 192.105163 -338.40252) (xy 192.134885 -338.356553) (xy 192.152524 -338.33562)
			(xy 192.152778 -338.335366) (xy 192.158352 -338.328271) (xy 192.164604 -338.31136) (xy 192.16497 -338.302346)
			(xy 192.16497 -338.23529) (xy 192.164624 -338.226272) (xy 192.15837 -338.209355) (xy 192.152778 -338.20227)
			(xy 192.152524 -338.20227) (xy 192.152524 -338.202016) (xy 192.134883 -338.181086) (xy 192.10517 -338.135113)
			(xy 192.082334 -338.085365) (xy 192.066844 -338.032864) (xy 192.059017 -337.978687) (xy 192.058544 -337.951318)
			(xy 192.059032 -337.924074) (xy 192.066787 -337.870141) (xy 192.082141 -337.817861) (xy 192.104782 -337.7683)
			(xy 192.134249 -337.722467) (xy 192.169941 -337.681297) (xy 192.21113 -337.645627) (xy 192.233804 -337.630516)
			(xy 192.240803 -337.625635) (xy 192.251358 -337.612244) (xy 192.256894 -337.596117) (xy 192.257172 -337.58759)
			(xy 192.257172 -337.502246) (xy 192.256886 -337.493723) (xy 192.251325 -337.477609) (xy 192.240798 -337.464201)
			(xy 192.233804 -337.45932) (xy 192.211131 -337.444206) (xy 192.169939 -337.408537) (xy 192.134244 -337.367368)
			(xy 192.104773 -337.321536) (xy 192.082128 -337.271976) (xy 192.066769 -337.219696) (xy 192.059009 -337.165763)
			(xy 192.058544 -337.138518) (xy 192.059095 -337.111269) (xy 192.066848 -337.057327) (xy 192.082198 -337.005036)
			(xy 192.104834 -336.955462) (xy 192.134293 -336.909614) (xy 192.169978 -336.868425) (xy 192.211161 -336.832733)
			(xy 192.257004 -336.803265) (xy 192.306574 -336.780621) (xy 192.358862 -336.765262) (xy 192.412803 -336.7575)
			(xy 192.440052 -336.75701) (xy 192.468271 -336.757497) (xy 192.524093 -336.765807) (xy 192.578081 -336.782251)
			(xy 192.629056 -336.806472) (xy 192.675906 -336.83794) (xy 192.6971 -336.856578) (xy 192.703958 -336.862928)
			(xy 192.721738 -336.869786) (xy 192.799716 -336.869786) (xy 192.809161 -336.869471) (xy 192.826781 -336.862672)
			(xy 192.834006 -336.856578) (xy 192.83426 -336.856324) (xy 192.855469 -336.837597) (xy 192.902388 -336.805982)
			(xy 192.953462 -336.781643) (xy 193.007571 -336.765115) (xy 193.063528 -336.756761) (xy 193.091816 -336.756248)
			(xy 193.09207 -336.756248) (xy 193.120085 -336.756756) (xy 193.175508 -336.764981) (xy 193.229135 -336.781214)
			(xy 193.279814 -336.805108) (xy 193.32646 -336.83615) (xy 193.347594 -336.854546) (xy 193.354452 -336.860896)
			(xy 193.372232 -336.867754) (xy 193.4591 -336.867754) (xy 193.47688 -336.860896) (xy 193.483738 -336.854546)
			(xy 193.504868 -336.836141) (xy 193.5515 -336.80507) (xy 193.602179 -336.781164) (xy 193.655813 -336.764937)
			(xy 193.711245 -336.756739) (xy 193.739262 -336.756248) (xy 193.739516 -336.756248) (xy 193.766766 -336.756763)
			(xy 193.82071 -336.76452) (xy 193.873002 -336.779875) (xy 193.922576 -336.802515) (xy 193.968424 -336.831979)
			(xy 194.009613 -336.867667) (xy 194.045304 -336.908853) (xy 194.074772 -336.954699) (xy 194.097415 -337.004272)
			(xy 194.112774 -337.056563) (xy 194.120535 -337.110506) (xy 194.121024 -337.137756) (xy 194.120551 -337.165126)
			(xy 194.112737 -337.219306) (xy 194.097251 -337.271809) (xy 194.07441 -337.321557) (xy 194.044686 -337.367523)
			(xy 194.027044 -337.388454) (xy 194.02679 -337.388708) (xy 194.021193 -337.395787) (xy 194.014953 -337.41271)
			(xy 194.014598 -337.421728) (xy 194.014598 -337.488784) (xy 194.014963 -337.4978) (xy 194.021205 -337.514717)
			(xy 194.02679 -337.521804) (xy 194.027044 -337.521804) (xy 194.027044 -337.522058) (xy 194.044643 -337.543025)
			(xy 194.074372 -337.588986) (xy 194.097221 -337.638727) (xy 194.112722 -337.691224) (xy 194.120556 -337.745398)
			(xy 194.12056 -337.800136) (xy 194.112736 -337.854311) (xy 194.111168 -337.859624) (xy 211.392006 -337.859624)
			(xy 211.396077 -337.804002) (xy 211.408203 -337.749565) (xy 211.428126 -337.697474) (xy 211.455422 -337.648839)
			(xy 211.489508 -337.604696) (xy 211.529657 -337.565987) (xy 211.575015 -337.533536) (xy 211.624615 -337.508035)
			(xy 211.677399 -337.490028) (xy 211.732242 -337.479898) (xy 211.787976 -337.477861) (xy 211.843413 -337.483961)
			(xy 211.89737 -337.498067) (xy 211.948699 -337.519879) (xy 211.996305 -337.548933) (xy 212.039173 -337.584608)
			(xy 212.07639 -337.626145) (xy 212.107163 -337.672658) (xy 212.130835 -337.723155) (xy 212.146903 -337.776562)
			(xy 212.155023 -337.831738) (xy 212.155532 -337.859624) (xy 212.155023 -337.88751) (xy 212.146903 -337.942686)
			(xy 212.130835 -337.996093) (xy 212.107163 -338.04659) (xy 212.07639 -338.093103) (xy 212.039173 -338.13464)
			(xy 211.996305 -338.170315) (xy 211.948699 -338.199369) (xy 211.89737 -338.221181) (xy 211.843413 -338.235287)
			(xy 211.787976 -338.241387) (xy 211.732242 -338.23935) (xy 211.677399 -338.22922) (xy 211.624615 -338.211213)
			(xy 211.575015 -338.185712) (xy 211.529657 -338.153261) (xy 211.489508 -338.114552) (xy 211.455422 -338.070409)
			(xy 211.428126 -338.021774) (xy 211.408203 -337.969683) (xy 211.396077 -337.915246) (xy 211.392006 -337.859624)
			(xy 194.111168 -337.859624) (xy 194.097245 -337.906811) (xy 194.074404 -337.956556) (xy 194.044683 -338.002522)
			(xy 194.027044 -338.023454) (xy 194.02679 -338.023708) (xy 194.021193 -338.030787) (xy 194.014953 -338.04771)
			(xy 194.014598 -338.056728) (xy 194.014598 -338.123784) (xy 194.014963 -338.1328) (xy 194.021205 -338.149717)
			(xy 194.02679 -338.156804) (xy 194.027044 -338.156804) (xy 194.027044 -338.157058) (xy 194.044643 -338.178025)
			(xy 194.074372 -338.223986) (xy 194.085748 -338.248752) (xy 216.305382 -338.248752) (xy 216.309453 -338.19313)
			(xy 216.321579 -338.138693) (xy 216.341502 -338.086602) (xy 216.368798 -338.037967) (xy 216.402884 -337.993824)
			(xy 216.443033 -337.955115) (xy 216.488391 -337.922664) (xy 216.537991 -337.897163) (xy 216.590775 -337.879156)
			(xy 216.645618 -337.869026) (xy 216.701352 -337.866989) (xy 216.756789 -337.873089) (xy 216.810746 -337.887195)
			(xy 216.862075 -337.909007) (xy 216.909681 -337.938061) (xy 216.920422 -337.947) (xy 217.168982 -337.947)
			(xy 217.173053 -337.891378) (xy 217.185179 -337.836941) (xy 217.205102 -337.78485) (xy 217.232398 -337.736215)
			(xy 217.266484 -337.692072) (xy 217.306633 -337.653363) (xy 217.351991 -337.620912) (xy 217.401591 -337.595411)
			(xy 217.454375 -337.577404) (xy 217.509218 -337.567274) (xy 217.564952 -337.565237) (xy 217.620389 -337.571337)
			(xy 217.674346 -337.585443) (xy 217.725675 -337.607255) (xy 217.773281 -337.636309) (xy 217.816149 -337.671984)
			(xy 217.853366 -337.713521) (xy 217.884139 -337.760034) (xy 217.907811 -337.810531) (xy 217.923879 -337.863938)
			(xy 217.931999 -337.919114) (xy 217.932508 -337.947) (xy 217.931999 -337.974886) (xy 217.923879 -338.030062)
			(xy 217.907811 -338.083469) (xy 217.884139 -338.133966) (xy 217.853366 -338.180479) (xy 217.816149 -338.222016)
			(xy 217.773281 -338.257691) (xy 217.725675 -338.286745) (xy 217.674346 -338.308557) (xy 217.620389 -338.322663)
			(xy 217.564952 -338.328763) (xy 217.509218 -338.326726) (xy 217.454375 -338.316596) (xy 217.401591 -338.298589)
			(xy 217.351991 -338.273088) (xy 217.306633 -338.240637) (xy 217.266484 -338.201928) (xy 217.232398 -338.157785)
			(xy 217.205102 -338.10915) (xy 217.185179 -338.057059) (xy 217.173053 -338.002622) (xy 217.168982 -337.947)
			(xy 216.920422 -337.947) (xy 216.952549 -337.973736) (xy 216.989766 -338.015273) (xy 217.020539 -338.061786)
			(xy 217.044211 -338.112283) (xy 217.060279 -338.16569) (xy 217.068399 -338.220866) (xy 217.068908 -338.248752)
			(xy 217.068399 -338.276638) (xy 217.060279 -338.331814) (xy 217.044211 -338.385221) (xy 217.020539 -338.435718)
			(xy 216.989766 -338.482231) (xy 216.952549 -338.523768) (xy 216.909681 -338.559443) (xy 216.862075 -338.588497)
			(xy 216.810746 -338.610309) (xy 216.756789 -338.624415) (xy 216.701352 -338.630515) (xy 216.645618 -338.628478)
			(xy 216.590775 -338.618348) (xy 216.537991 -338.600341) (xy 216.488391 -338.57484) (xy 216.443033 -338.542389)
			(xy 216.402884 -338.50368) (xy 216.368798 -338.459537) (xy 216.341502 -338.410902) (xy 216.321579 -338.358811)
			(xy 216.309453 -338.304374) (xy 216.305382 -338.248752) (xy 194.085748 -338.248752) (xy 194.097221 -338.273727)
			(xy 194.112722 -338.326224) (xy 194.120556 -338.380398) (xy 194.12056 -338.435136) (xy 194.112736 -338.489311)
			(xy 194.097245 -338.541811) (xy 194.074404 -338.591556) (xy 194.044683 -338.637522) (xy 194.027044 -338.658454)
			(xy 194.02679 -338.658708) (xy 194.021193 -338.665787) (xy 194.014953 -338.68271) (xy 194.014598 -338.691728)
			(xy 194.014598 -338.758784) (xy 194.014963 -338.7678) (xy 194.021205 -338.784717) (xy 194.02679 -338.791804)
			(xy 194.027044 -338.791804) (xy 194.027044 -338.792058) (xy 194.044684 -338.812989) (xy 194.074394 -338.858963)
			(xy 194.084024 -338.879942) (xy 198.275192 -338.879942) (xy 198.279263 -338.82432) (xy 198.291389 -338.769883)
			(xy 198.311312 -338.717792) (xy 198.338608 -338.669157) (xy 198.372694 -338.625014) (xy 198.412843 -338.586305)
			(xy 198.458201 -338.553854) (xy 198.507801 -338.528353) (xy 198.560585 -338.510346) (xy 198.615428 -338.500216)
			(xy 198.671162 -338.498179) (xy 198.726599 -338.504279) (xy 198.780556 -338.518385) (xy 198.831885 -338.540197)
			(xy 198.879491 -338.569251) (xy 198.922359 -338.604926) (xy 198.959576 -338.646463) (xy 198.990349 -338.692976)
			(xy 199.014021 -338.743473) (xy 199.030089 -338.79688) (xy 199.038209 -338.852056) (xy 199.038718 -338.879942)
			(xy 199.038209 -338.907828) (xy 199.030089 -338.963004) (xy 199.014021 -339.016411) (xy 198.990349 -339.066908)
			(xy 198.959576 -339.113421) (xy 198.922359 -339.154958) (xy 198.879491 -339.190633) (xy 198.831885 -339.219687)
			(xy 198.780556 -339.241499) (xy 198.726599 -339.255605) (xy 198.671162 -339.261705) (xy 198.615428 -339.259668)
			(xy 198.560585 -339.249538) (xy 198.507801 -339.231531) (xy 198.458201 -339.20603) (xy 198.412843 -339.173579)
			(xy 198.372694 -339.13487) (xy 198.338608 -339.090727) (xy 198.311312 -339.042092) (xy 198.291389 -338.990001)
			(xy 198.279263 -338.935564) (xy 198.275192 -338.879942) (xy 194.084024 -338.879942) (xy 194.09723 -338.908711)
			(xy 194.112721 -338.961211) (xy 194.12055 -339.015387) (xy 194.121024 -339.042756) (xy 194.121024 -339.04301)
			(xy 194.120594 -339.069151) (xy 194.113456 -339.120943) (xy 194.099302 -339.171272) (xy 194.078398 -339.219193)
			(xy 194.051137 -339.263804) (xy 194.034918 -339.28431) (xy 194.029076 -339.291422) (xy 194.02298 -339.308948)
			(xy 194.026282 -339.394546) (xy 194.033394 -339.411564) (xy 194.039744 -339.418168) (xy 194.059187 -339.439532)
			(xy 194.092074 -339.487018) (xy 194.11742 -339.538923) (xy 194.134645 -339.594058) (xy 194.143354 -339.651161)
			(xy 194.143884 -339.680042) (xy 194.143884 -339.680296) (xy 194.143419 -339.707666) (xy 194.135602 -339.761846)
			(xy 194.120113 -339.814349) (xy 194.09727 -339.864096) (xy 194.067545 -339.910062) (xy 194.049904 -339.930994)
			(xy 194.04965 -339.931248) (xy 194.044073 -339.938341) (xy 194.037822 -339.955253) (xy 194.037458 -339.964268)
			(xy 194.037458 -340.031324) (xy 194.037791 -340.040344) (xy 194.044054 -340.057261) (xy 194.04965 -340.064344)
			(xy 194.049904 -340.064344) (xy 194.049904 -340.064598) (xy 194.067556 -340.085519) (xy 194.090967 -340.121748)
			(xy 203.227938 -340.121748) (xy 203.232009 -340.066126) (xy 203.244135 -340.011689) (xy 203.264058 -339.959598)
			(xy 203.291354 -339.910963) (xy 203.32544 -339.86682) (xy 203.365589 -339.828111) (xy 203.410947 -339.79566)
			(xy 203.460547 -339.770159) (xy 203.513331 -339.752152) (xy 203.568174 -339.742022) (xy 203.623908 -339.739985)
			(xy 203.679345 -339.746085) (xy 203.733302 -339.760191) (xy 203.784631 -339.782003) (xy 203.832237 -339.811057)
			(xy 203.875105 -339.846732) (xy 203.912322 -339.888269) (xy 203.943095 -339.934782) (xy 203.966767 -339.985279)
			(xy 203.982835 -340.038686) (xy 203.990955 -340.093862) (xy 203.991464 -340.121748) (xy 203.990955 -340.149634)
			(xy 203.982835 -340.20481) (xy 203.977105 -340.223856) (xy 211.445094 -340.223856) (xy 211.4456 -340.195976)
			(xy 211.453697 -340.140808) (xy 211.46974 -340.087407) (xy 211.493389 -340.036911) (xy 211.524138 -339.990396)
			(xy 211.561332 -339.948855) (xy 211.604179 -339.913173) (xy 211.62772 -339.898228) (xy 211.639912 -339.890165)
			(xy 211.659478 -339.868466) (xy 211.672103 -339.842117) (xy 211.676753 -339.813273) (xy 211.67305 -339.784291)
			(xy 211.661294 -339.757543) (xy 211.642449 -339.735215) (xy 211.630514 -339.726778) (xy 211.608255 -339.711565)
			(xy 211.567858 -339.675858) (xy 211.532887 -339.634824) (xy 211.504037 -339.589277) (xy 211.481881 -339.540125)
			(xy 211.466861 -339.488344) (xy 211.459275 -339.434966) (xy 211.45881 -339.408008) (xy 211.459296 -339.380757)
			(xy 211.467052 -339.326809) (xy 211.482407 -339.274514) (xy 211.505049 -339.224937) (xy 211.534515 -339.179087)
			(xy 211.570206 -339.137896) (xy 211.611397 -339.102205) (xy 211.657247 -339.072739) (xy 211.706824 -339.050097)
			(xy 211.759119 -339.034742) (xy 211.813067 -339.026986) (xy 211.867569 -339.026986) (xy 211.921517 -339.034742)
			(xy 211.973812 -339.050097) (xy 212.023389 -339.072739) (xy 212.069239 -339.102205) (xy 212.11043 -339.137896)
			(xy 212.146121 -339.179087) (xy 212.175587 -339.224937) (xy 212.198229 -339.274514) (xy 212.213584 -339.326809)
			(xy 212.22134 -339.380757) (xy 212.221826 -339.408008) (xy 212.22133 -339.435889) (xy 212.213237 -339.491059)
			(xy 212.197194 -339.544462) (xy 212.173545 -339.59496) (xy 212.142793 -339.641474) (xy 212.105595 -339.683014)
			(xy 212.062743 -339.718693) (xy 212.0392 -339.733636) (xy 212.026946 -339.741615) (xy 212.007373 -339.76333)
			(xy 211.994748 -339.789698) (xy 211.990104 -339.818561) (xy 211.99382 -339.847558) (xy 212.005593 -339.874317)
			(xy 212.02446 -339.896649) (xy 212.036406 -339.905086) (xy 212.058631 -339.920348) (xy 212.086203 -339.94471)
			(xy 216.224102 -339.94471) (xy 216.228173 -339.889088) (xy 216.240299 -339.834651) (xy 216.260222 -339.78256)
			(xy 216.287518 -339.733925) (xy 216.321604 -339.689782) (xy 216.361753 -339.651073) (xy 216.407111 -339.618622)
			(xy 216.456711 -339.593121) (xy 216.509495 -339.575114) (xy 216.564338 -339.564984) (xy 216.620072 -339.562947)
			(xy 216.675509 -339.569047) (xy 216.729466 -339.583153) (xy 216.780795 -339.604965) (xy 216.828401 -339.634019)
			(xy 216.871269 -339.669694) (xy 216.908486 -339.711231) (xy 216.939259 -339.757744) (xy 216.962931 -339.808241)
			(xy 216.978999 -339.861648) (xy 216.987119 -339.916824) (xy 216.987628 -339.94471) (xy 216.987119 -339.972596)
			(xy 216.978999 -340.027772) (xy 216.962931 -340.081179) (xy 216.939259 -340.131676) (xy 216.908486 -340.178189)
			(xy 216.871269 -340.219726) (xy 216.855319 -340.233) (xy 217.168982 -340.233) (xy 217.173053 -340.177378)
			(xy 217.185179 -340.122941) (xy 217.205102 -340.07085) (xy 217.232398 -340.022215) (xy 217.266484 -339.978072)
			(xy 217.306633 -339.939363) (xy 217.351991 -339.906912) (xy 217.401591 -339.881411) (xy 217.454375 -339.863404)
			(xy 217.509218 -339.853274) (xy 217.564952 -339.851237) (xy 217.620389 -339.857337) (xy 217.674346 -339.871443)
			(xy 217.725675 -339.893255) (xy 217.773281 -339.922309) (xy 217.816149 -339.957984) (xy 217.853366 -339.999521)
			(xy 217.884139 -340.046034) (xy 217.907811 -340.096531) (xy 217.923879 -340.149938) (xy 217.931999 -340.205114)
			(xy 217.932508 -340.233) (xy 217.931999 -340.260886) (xy 217.923879 -340.316062) (xy 217.907811 -340.369469)
			(xy 217.884139 -340.419966) (xy 217.853366 -340.466479) (xy 217.816149 -340.508016) (xy 217.773281 -340.543691)
			(xy 217.725675 -340.572745) (xy 217.674346 -340.594557) (xy 217.620389 -340.608663) (xy 217.564952 -340.614763)
			(xy 217.509218 -340.612726) (xy 217.454375 -340.602596) (xy 217.401591 -340.584589) (xy 217.351991 -340.559088)
			(xy 217.306633 -340.526637) (xy 217.266484 -340.487928) (xy 217.232398 -340.443785) (xy 217.205102 -340.39515)
			(xy 217.185179 -340.343059) (xy 217.173053 -340.288622) (xy 217.168982 -340.233) (xy 216.855319 -340.233)
			(xy 216.828401 -340.255401) (xy 216.780795 -340.284455) (xy 216.729466 -340.306267) (xy 216.675509 -340.320373)
			(xy 216.620072 -340.326473) (xy 216.564338 -340.324436) (xy 216.509495 -340.314306) (xy 216.456711 -340.296299)
			(xy 216.407111 -340.270798) (xy 216.361753 -340.238347) (xy 216.321604 -340.199638) (xy 216.287518 -340.155495)
			(xy 216.260222 -340.10686) (xy 216.240299 -340.054769) (xy 216.228173 -340.000332) (xy 216.224102 -339.94471)
			(xy 212.086203 -339.94471) (xy 212.099031 -339.956044) (xy 212.134008 -339.997069) (xy 212.162864 -340.042607)
			(xy 212.185025 -340.091752) (xy 212.200051 -340.143527) (xy 212.207643 -340.196901) (xy 212.20811 -340.223856)
			(xy 212.207624 -340.251107) (xy 212.199868 -340.305055) (xy 212.184513 -340.35735) (xy 212.161871 -340.406927)
			(xy 212.132405 -340.452777) (xy 212.096714 -340.493968) (xy 212.055523 -340.529659) (xy 212.009673 -340.559125)
			(xy 211.960096 -340.581767) (xy 211.907801 -340.597122) (xy 211.853853 -340.604878) (xy 211.799351 -340.604878)
			(xy 211.745403 -340.597122) (xy 211.693108 -340.581767) (xy 211.643531 -340.559125) (xy 211.597681 -340.529659)
			(xy 211.55649 -340.493968) (xy 211.520799 -340.452777) (xy 211.491333 -340.406927) (xy 211.468691 -340.35735)
			(xy 211.453336 -340.305055) (xy 211.44558 -340.251107) (xy 211.445094 -340.223856) (xy 203.977105 -340.223856)
			(xy 203.966767 -340.258217) (xy 203.943095 -340.308714) (xy 203.912322 -340.355227) (xy 203.875105 -340.396764)
			(xy 203.832237 -340.432439) (xy 203.784631 -340.461493) (xy 203.733302 -340.483305) (xy 203.679345 -340.497411)
			(xy 203.623908 -340.503511) (xy 203.568174 -340.501474) (xy 203.513331 -340.491344) (xy 203.460547 -340.473337)
			(xy 203.410947 -340.447836) (xy 203.365589 -340.415385) (xy 203.32544 -340.376676) (xy 203.291354 -340.332533)
			(xy 203.264058 -340.283898) (xy 203.244135 -340.231807) (xy 203.232009 -340.17737) (xy 203.227938 -340.121748)
			(xy 194.090967 -340.121748) (xy 194.097266 -340.131495) (xy 194.120099 -340.181245) (xy 194.135587 -340.233748)
			(xy 194.143412 -340.287926) (xy 194.143884 -340.315296) (xy 194.143441 -340.34255) (xy 194.135684 -340.396503)
			(xy 194.120327 -340.448802) (xy 194.097683 -340.498384) (xy 194.068213 -340.544238) (xy 194.032518 -340.585432)
			(xy 193.991322 -340.621125) (xy 193.945467 -340.650593) (xy 193.895884 -340.673234) (xy 193.843583 -340.688588)
			(xy 193.78963 -340.696342) (xy 193.762376 -340.696804) (xy 193.735746 -340.696357) (xy 193.683004 -340.688946)
			(xy 193.631805 -340.674271) (xy 193.583145 -340.652617) (xy 193.53797 -340.624405) (xy 193.517266 -340.60765)
			(xy 193.509353 -340.601584) (xy 193.490403 -340.595443) (xy 193.480436 -340.595712) (xy 193.409824 -340.6013)
			(xy 193.400028 -340.602449) (xy 193.382382 -340.611218) (xy 193.375534 -340.618318) (xy 193.357363 -340.638279)
			(xy 193.316318 -340.673338) (xy 193.270742 -340.702263) (xy 193.221544 -340.724476) (xy 193.169708 -340.739535)
			(xy 193.116266 -340.747139) (xy 193.089276 -340.747604) (xy 193.062024 -340.747145) (xy 193.008075 -340.739385)
			(xy 192.95578 -340.724026) (xy 192.906202 -340.701382) (xy 192.860352 -340.671913) (xy 192.819162 -340.636219)
			(xy 192.78347 -340.595026) (xy 192.754005 -340.549173) (xy 192.731364 -340.499594) (xy 192.716009 -340.447298)
			(xy 192.708253 -340.393348) (xy 192.707768 -340.366096) (xy 192.708215 -340.338725) (xy 192.716035 -340.284544)
			(xy 192.731528 -340.23204) (xy 192.754374 -340.182294) (xy 192.784104 -340.136328) (xy 192.801748 -340.115398)
			(xy 192.802002 -340.115144) (xy 192.807577 -340.108049) (xy 192.81383 -340.091139) (xy 192.814194 -340.082124)
			(xy 192.814194 -340.015068) (xy 192.813853 -340.006049) (xy 192.807595 -339.989133) (xy 192.802002 -339.982048)
			(xy 192.801748 -339.982048) (xy 192.801748 -339.981794) (xy 192.7841 -339.960869) (xy 192.754388 -339.914895)
			(xy 192.731553 -339.865146) (xy 192.716064 -339.812643) (xy 192.70824 -339.758466) (xy 192.707768 -339.731096)
			(xy 192.707879 -339.719764) (xy 192.70928 -339.697144) (xy 192.710562 -339.685884) (xy 192.710562 -339.68563)
			(xy 192.711223 -339.677003) (xy 192.707333 -339.660152) (xy 192.698085 -339.645538) (xy 192.691512 -339.63991)
			(xy 192.612264 -339.57768) (xy 192.58661 -339.57387) (xy 192.57391 -339.578442) (xy 192.541622 -339.58982)
			(xy 192.474278 -339.602088) (xy 192.440052 -339.602826) (xy 192.4128 -339.602367) (xy 192.358853 -339.594604)
			(xy 192.306559 -339.579244) (xy 192.256982 -339.556599) (xy 192.211133 -339.527129) (xy 192.169944 -339.491435)
			(xy 192.134253 -339.450243) (xy 192.104787 -339.404391) (xy 192.082145 -339.354813) (xy 192.066789 -339.302518)
			(xy 192.059031 -339.24857) (xy 192.058544 -339.221318) (xy 190.42126 -339.221318) (xy 190.420862 -339.248574)
			(xy 190.413101 -339.302529) (xy 190.39774 -339.354831) (xy 190.375092 -339.404415) (xy 190.345618 -339.45027)
			(xy 190.309917 -339.491464) (xy 190.268717 -339.527157) (xy 190.222857 -339.556624) (xy 190.173269 -339.579263)
			(xy 190.120965 -339.594615) (xy 190.067008 -339.602366) (xy 190.039752 -339.602826) (xy 190.039498 -339.602826)
			(xy 190.009056 -339.602234) (xy 189.94895 -339.592528) (xy 189.919864 -339.583522) (xy 189.907858 -339.580411)
			(xy 189.883441 -339.58451) (xy 189.873128 -339.591396) (xy 189.79642 -339.649816) (xy 189.785752 -339.672676)
			(xy 189.786514 -339.685376) (xy 189.787022 -339.705696) (xy 189.786573 -339.733067) (xy 189.778754 -339.787248)
			(xy 189.763262 -339.839752) (xy 189.740416 -339.889498) (xy 189.710686 -339.935464) (xy 189.693042 -339.956394)
			(xy 189.692788 -339.956648) (xy 189.687216 -339.963744) (xy 189.680961 -339.980654) (xy 189.680596 -339.989668)
			(xy 189.680596 -340.056724) (xy 189.680943 -340.065742) (xy 189.687198 -340.082659) (xy 189.692788 -340.089744)
			(xy 189.693042 -340.089744) (xy 189.693042 -340.089998) (xy 189.710701 -340.110914) (xy 189.740408 -340.156892)
			(xy 189.76324 -340.206644) (xy 189.778727 -340.259148) (xy 189.786551 -340.313326) (xy 189.787022 -340.340696)
			(xy 189.786519 -340.367947) (xy 189.778763 -340.421893) (xy 189.763409 -340.474186) (xy 189.740769 -340.523763)
			(xy 189.711305 -340.569612) (xy 189.675615 -340.610802) (xy 189.634427 -340.646494) (xy 189.588579 -340.675961)
			(xy 189.539003 -340.698603) (xy 189.48671 -340.713959) (xy 189.432764 -340.721717) (xy 189.405514 -340.722204)
			(xy 189.376493 -340.721645) (xy 189.319122 -340.712855) (xy 189.263744 -340.695475) (xy 189.211638 -340.669908)
			(xy 189.164006 -340.636742) (xy 189.121948 -340.596744) (xy 189.103762 -340.574122) (xy 189.097104 -340.566253)
			(xy 189.079147 -340.556165) (xy 189.068964 -340.554564) (xy 188.98616 -340.54542) (xy 188.966348 -340.551262)
			(xy 188.958474 -340.557866) (xy 188.937839 -340.574444) (xy 188.892847 -340.60233) (xy 188.844432 -340.623728)
			(xy 188.793524 -340.638227) (xy 188.7411 -340.64555) (xy 188.714634 -340.646004) (xy 188.687382 -340.645513)
			(xy 188.633432 -340.637761) (xy 188.581134 -340.622409) (xy 188.531554 -340.59977) (xy 188.4857 -340.570305)
			(xy 188.444507 -340.534614) (xy 188.408813 -340.493424) (xy 188.379345 -340.447573) (xy 188.356702 -340.397994)
			(xy 188.341346 -340.345698) (xy 188.333589 -340.291748) (xy 188.333126 -340.264496) (xy 185.806373 -340.264496)
			(xy 185.806842 -340.29142) (xy 185.806386 -340.318035) (xy 185.798985 -340.370749) (xy 185.784314 -340.421918)
			(xy 185.762661 -340.470546) (xy 185.74893 -340.49335) (xy 185.748676 -340.493604) (xy 185.743597 -340.502919)
			(xy 185.740698 -340.523909) (xy 185.743088 -340.534244) (xy 185.76671 -340.617302) (xy 185.780426 -340.633558)
			(xy 185.790332 -340.638384) (xy 185.813987 -340.650488) (xy 185.85794 -340.680349) (xy 185.897327 -340.716017)
			(xy 185.931386 -340.756803) (xy 185.95946 -340.801919) (xy 185.981005 -340.850492) (xy 185.995605 -340.901584)
			(xy 186.002978 -340.954207) (xy 186.003438 -340.980776) (xy 186.002973 -341.008146) (xy 185.995157 -341.062326)
			(xy 185.979669 -341.11483) (xy 185.956826 -341.164577) (xy 185.9271 -341.210543) (xy 185.909458 -341.231474)
			(xy 185.909204 -341.231728) (xy 185.903642 -341.238831) (xy 185.89738 -341.255735) (xy 185.897012 -341.264748)
			(xy 185.897012 -341.331804) (xy 185.897364 -341.340821) (xy 185.903615 -341.357738) (xy 185.909204 -341.364824)
			(xy 185.909458 -341.364824) (xy 185.909458 -341.365078) (xy 185.927094 -341.386013) (xy 185.956807 -341.431984)
			(xy 185.979645 -341.481731) (xy 185.995136 -341.534231) (xy 185.999578 -341.564976) (xy 187.451746 -341.564976)
			(xy 187.452187 -341.537605) (xy 187.460009 -341.483424) (xy 187.475503 -341.43092) (xy 187.498351 -341.381174)
			(xy 187.528082 -341.335208) (xy 187.545726 -341.314278) (xy 187.54598 -341.314024) (xy 187.551572 -341.306942)
			(xy 187.557813 -341.290021) (xy 187.558172 -341.281004) (xy 187.558172 -341.213948) (xy 187.557798 -341.204933)
			(xy 187.551563 -341.188015) (xy 187.54598 -341.180928) (xy 187.545726 -341.180928) (xy 187.545726 -341.180674)
			(xy 187.528112 -341.159721) (xy 187.498396 -341.113755) (xy 187.475554 -341.064012) (xy 187.460058 -341.011516)
			(xy 187.452223 -340.957344) (xy 187.451746 -340.929976) (xy 187.452232 -340.902725) (xy 187.459988 -340.848777)
			(xy 187.475343 -340.796482) (xy 187.497985 -340.746905) (xy 187.527451 -340.701055) (xy 187.563142 -340.659864)
			(xy 187.604333 -340.624173) (xy 187.650183 -340.594707) (xy 187.69976 -340.572065) (xy 187.752055 -340.55671)
			(xy 187.806003 -340.548954) (xy 187.860505 -340.548954) (xy 187.914453 -340.55671) (xy 187.966748 -340.572065)
			(xy 188.016325 -340.594707) (xy 188.062175 -340.624173) (xy 188.103366 -340.659864) (xy 188.139057 -340.701055)
			(xy 188.168523 -340.746905) (xy 188.191165 -340.796482) (xy 188.20652 -340.848777) (xy 188.214276 -340.902725)
			(xy 188.214762 -340.929976) (xy 188.214291 -340.957346) (xy 188.206476 -341.011525) (xy 188.190988 -341.064029)
			(xy 188.168148 -341.113776) (xy 188.138423 -341.159743) (xy 188.120782 -341.180674) (xy 188.120528 -341.180928)
			(xy 188.114957 -341.188025) (xy 188.108703 -341.204934) (xy 188.108336 -341.213948) (xy 188.108336 -341.281004)
			(xy 188.108683 -341.290022) (xy 188.114937 -341.306939) (xy 188.120528 -341.314024) (xy 188.120782 -341.314024)
			(xy 188.120782 -341.314278) (xy 188.138421 -341.33521) (xy 188.168134 -341.381182) (xy 188.19097 -341.43093)
			(xy 188.206461 -341.483431) (xy 188.214288 -341.537607) (xy 188.214762 -341.564976) (xy 188.214276 -341.592227)
			(xy 188.20652 -341.646175) (xy 188.191165 -341.69847) (xy 188.168523 -341.748047) (xy 188.139057 -341.793897)
			(xy 188.103366 -341.835088) (xy 188.069195 -341.864696) (xy 193.232786 -341.864696) (xy 193.233253 -341.837326)
			(xy 193.241071 -341.783147) (xy 193.25656 -341.730644) (xy 193.279402 -341.680897) (xy 193.309125 -341.63493)
			(xy 193.326766 -341.613998) (xy 193.32702 -341.613744) (xy 193.332597 -341.606651) (xy 193.338849 -341.589739)
			(xy 193.339212 -341.580724) (xy 193.339212 -341.513668) (xy 193.338868 -341.50465) (xy 193.332611 -341.487733)
			(xy 193.32702 -341.480648) (xy 193.326766 -341.480648) (xy 193.326766 -341.480394) (xy 193.309105 -341.459479)
			(xy 193.279398 -341.413501) (xy 193.256567 -341.363749) (xy 193.241081 -341.311245) (xy 193.233257 -341.257066)
			(xy 193.232786 -341.229696) (xy 193.233272 -341.202445) (xy 193.241028 -341.148497) (xy 193.256383 -341.096202)
			(xy 193.279025 -341.046625) (xy 193.308491 -341.000775) (xy 193.344182 -340.959584) (xy 193.385373 -340.923893)
			(xy 193.431223 -340.894427) (xy 193.4808 -340.871785) (xy 193.533095 -340.85643) (xy 193.587043 -340.848674)
			(xy 193.641545 -340.848674) (xy 193.695493 -340.85643) (xy 193.747788 -340.871785) (xy 193.797365 -340.894427)
			(xy 193.843215 -340.923893) (xy 193.884406 -340.959584) (xy 193.920097 -341.000775) (xy 193.949563 -341.046625)
			(xy 193.972205 -341.096202) (xy 193.98756 -341.148497) (xy 193.995316 -341.202445) (xy 193.995802 -341.229696)
			(xy 193.995333 -341.257066) (xy 193.987516 -341.311245) (xy 193.972027 -341.363748) (xy 193.949186 -341.413495)
			(xy 193.919463 -341.459462) (xy 193.901822 -341.480394) (xy 193.901568 -341.480648) (xy 193.895993 -341.487743)
			(xy 193.889741 -341.504653) (xy 193.889376 -341.513668) (xy 193.889376 -341.580724) (xy 193.889727 -341.589741)
			(xy 193.895979 -341.606658) (xy 193.901568 -341.613744) (xy 193.901822 -341.613744) (xy 193.901822 -341.613998)
			(xy 193.919477 -341.634917) (xy 193.949186 -341.680894) (xy 193.972018 -341.730645) (xy 193.987506 -341.783148)
			(xy 193.99533 -341.837326) (xy 193.995452 -341.844376) (xy 195.422266 -341.844376) (xy 195.422702 -341.817004)
			(xy 195.430525 -341.762823) (xy 195.44602 -341.710319) (xy 195.468869 -341.660573) (xy 195.498601 -341.614608)
			(xy 195.516246 -341.593678) (xy 195.5165 -341.593424) (xy 195.522083 -341.586335) (xy 195.528332 -341.56942)
			(xy 195.528692 -341.560404) (xy 195.528692 -341.493348) (xy 195.528314 -341.484333) (xy 195.522081 -341.467416)
			(xy 195.5165 -341.460328) (xy 195.516246 -341.460328) (xy 195.516246 -341.460074) (xy 195.498635 -341.439119)
			(xy 195.468918 -341.393153) (xy 195.446075 -341.343412) (xy 195.430578 -341.290916) (xy 195.422743 -341.236744)
			(xy 195.422266 -341.209376) (xy 195.422752 -341.182125) (xy 195.430508 -341.128177) (xy 195.445863 -341.075882)
			(xy 195.468505 -341.026305) (xy 195.497971 -340.980455) (xy 195.533662 -340.939264) (xy 195.574853 -340.903573)
			(xy 195.620703 -340.874107) (xy 195.67028 -340.851465) (xy 195.722575 -340.83611) (xy 195.776523 -340.828354)
			(xy 195.831025 -340.828354) (xy 195.884973 -340.83611) (xy 195.937268 -340.851465) (xy 195.986845 -340.874107)
			(xy 196.032695 -340.903573) (xy 196.073886 -340.939264) (xy 196.109577 -340.980455) (xy 196.139043 -341.026305)
			(xy 196.161685 -341.075882) (xy 196.17704 -341.128177) (xy 196.184796 -341.182125) (xy 196.185282 -341.209376)
			(xy 196.184806 -341.236746) (xy 196.176991 -341.290925) (xy 196.161505 -341.343428) (xy 196.138665 -341.393175)
			(xy 196.108942 -341.439142) (xy 196.091302 -341.460074) (xy 196.091048 -341.460328) (xy 196.085479 -341.467427)
			(xy 196.079223 -341.484334) (xy 196.078856 -341.493348) (xy 196.078856 -341.560404) (xy 196.079199 -341.569423)
			(xy 196.085455 -341.58634) (xy 196.091048 -341.593424) (xy 196.091302 -341.593424) (xy 196.091302 -341.593678)
			(xy 196.108945 -341.614607) (xy 196.138656 -341.660581) (xy 196.161491 -341.710329) (xy 196.176981 -341.76283)
			(xy 196.184809 -341.817007) (xy 196.185234 -341.841582) (xy 211.416644 -341.841582) (xy 211.420715 -341.78596)
			(xy 211.432841 -341.731523) (xy 211.452764 -341.679432) (xy 211.48006 -341.630797) (xy 211.514146 -341.586654)
			(xy 211.554295 -341.547945) (xy 211.599653 -341.515494) (xy 211.649253 -341.489993) (xy 211.702037 -341.471986)
			(xy 211.75688 -341.461856) (xy 211.812614 -341.459819) (xy 211.868051 -341.465919) (xy 211.922008 -341.480025)
			(xy 211.973337 -341.501837) (xy 212.020943 -341.530891) (xy 212.063811 -341.566566) (xy 212.101028 -341.608103)
			(xy 212.131801 -341.654616) (xy 212.155473 -341.705113) (xy 212.171541 -341.75852) (xy 212.179661 -341.813696)
			(xy 212.18017 -341.841582) (xy 212.179661 -341.869468) (xy 212.178494 -341.877396) (xy 212.714584 -341.877396)
			(xy 212.718655 -341.821774) (xy 212.730781 -341.767337) (xy 212.750704 -341.715246) (xy 212.778 -341.666611)
			(xy 212.812086 -341.622468) (xy 212.852235 -341.583759) (xy 212.897593 -341.551308) (xy 212.947193 -341.525807)
			(xy 212.999977 -341.5078) (xy 213.05482 -341.49767) (xy 213.110554 -341.495633) (xy 213.165991 -341.501733)
			(xy 213.219948 -341.515839) (xy 213.271277 -341.537651) (xy 213.318883 -341.566705) (xy 213.361751 -341.60238)
			(xy 213.398968 -341.643917) (xy 213.429741 -341.69043) (xy 213.453413 -341.740927) (xy 213.469481 -341.794334)
			(xy 213.477601 -341.84951) (xy 213.47811 -341.877396) (xy 213.477601 -341.905282) (xy 213.469481 -341.960458)
			(xy 213.453413 -342.013865) (xy 213.429741 -342.064362) (xy 213.398968 -342.110875) (xy 213.361751 -342.152412)
			(xy 213.318883 -342.188087) (xy 213.271277 -342.217141) (xy 213.219948 -342.238953) (xy 213.165991 -342.253059)
			(xy 213.110554 -342.259159) (xy 213.05482 -342.257122) (xy 212.999977 -342.246992) (xy 212.947193 -342.228985)
			(xy 212.897593 -342.203484) (xy 212.852235 -342.171033) (xy 212.812086 -342.132324) (xy 212.778 -342.088181)
			(xy 212.750704 -342.039546) (xy 212.730781 -341.987455) (xy 212.718655 -341.933018) (xy 212.714584 -341.877396)
			(xy 212.178494 -341.877396) (xy 212.171541 -341.924644) (xy 212.155473 -341.978051) (xy 212.131801 -342.028548)
			(xy 212.101028 -342.075061) (xy 212.063811 -342.116598) (xy 212.020943 -342.152273) (xy 211.973337 -342.181327)
			(xy 211.922008 -342.203139) (xy 211.868051 -342.217245) (xy 211.812614 -342.223345) (xy 211.75688 -342.221308)
			(xy 211.702037 -342.211178) (xy 211.649253 -342.193171) (xy 211.599653 -342.16767) (xy 211.554295 -342.135219)
			(xy 211.514146 -342.09651) (xy 211.48006 -342.052367) (xy 211.452764 -342.003732) (xy 211.432841 -341.951641)
			(xy 211.420715 -341.897204) (xy 211.416644 -341.841582) (xy 196.185234 -341.841582) (xy 196.185282 -341.844376)
			(xy 196.184796 -341.871627) (xy 196.17704 -341.925575) (xy 196.161685 -341.97787) (xy 196.139043 -342.027447)
			(xy 196.109577 -342.073297) (xy 196.073886 -342.114488) (xy 196.032695 -342.150179) (xy 195.986845 -342.179645)
			(xy 195.937268 -342.202287) (xy 195.884973 -342.217642) (xy 195.831025 -342.225398) (xy 195.776523 -342.225398)
			(xy 195.722575 -342.217642) (xy 195.67028 -342.202287) (xy 195.620703 -342.179645) (xy 195.574853 -342.150179)
			(xy 195.533662 -342.114488) (xy 195.497971 -342.073297) (xy 195.468505 -342.027447) (xy 195.445863 -341.97787)
			(xy 195.430508 -341.925575) (xy 195.422752 -341.871627) (xy 195.422266 -341.844376) (xy 193.995452 -341.844376)
			(xy 193.995802 -341.864696) (xy 193.995316 -341.891947) (xy 193.98756 -341.945895) (xy 193.972205 -341.99819)
			(xy 193.949563 -342.047767) (xy 193.920097 -342.093617) (xy 193.884406 -342.134808) (xy 193.843215 -342.170499)
			(xy 193.797365 -342.199965) (xy 193.747788 -342.222607) (xy 193.695493 -342.237962) (xy 193.641545 -342.245718)
			(xy 193.587043 -342.245718) (xy 193.533095 -342.237962) (xy 193.4808 -342.222607) (xy 193.431223 -342.199965)
			(xy 193.385373 -342.170499) (xy 193.344182 -342.134808) (xy 193.308491 -342.093617) (xy 193.279025 -342.047767)
			(xy 193.256383 -341.99819) (xy 193.241028 -341.945895) (xy 193.233272 -341.891947) (xy 193.232786 -341.864696)
			(xy 188.069195 -341.864696) (xy 188.062175 -341.870779) (xy 188.016325 -341.900245) (xy 187.966748 -341.922887)
			(xy 187.914453 -341.938242) (xy 187.860505 -341.945998) (xy 187.806003 -341.945998) (xy 187.752055 -341.938242)
			(xy 187.69976 -341.922887) (xy 187.650183 -341.900245) (xy 187.604333 -341.870779) (xy 187.563142 -341.835088)
			(xy 187.527451 -341.793897) (xy 187.497985 -341.748047) (xy 187.475343 -341.69847) (xy 187.459988 -341.646175)
			(xy 187.452232 -341.592227) (xy 187.451746 -341.564976) (xy 185.999578 -341.564976) (xy 186.002964 -341.588407)
			(xy 186.003438 -341.615776) (xy 186.002952 -341.643027) (xy 185.995196 -341.696975) (xy 185.979841 -341.74927)
			(xy 185.957199 -341.798847) (xy 185.927733 -341.844697) (xy 185.892042 -341.885888) (xy 185.850851 -341.921579)
			(xy 185.805001 -341.951045) (xy 185.755424 -341.973687) (xy 185.703129 -341.989042) (xy 185.649181 -341.996798)
			(xy 185.594679 -341.996798) (xy 185.540731 -341.989042) (xy 185.488436 -341.973687) (xy 185.438859 -341.951045)
			(xy 185.393009 -341.921579) (xy 185.351818 -341.885888) (xy 185.316127 -341.844697) (xy 185.286661 -341.798847)
			(xy 185.264019 -341.74927) (xy 185.248664 -341.696975) (xy 185.240908 -341.643027) (xy 185.240422 -341.615776)
			(xy 185.240869 -341.588405) (xy 185.24869 -341.534225) (xy 185.264184 -341.481721) (xy 185.28703 -341.431975)
			(xy 185.316759 -341.386009) (xy 185.334402 -341.365078) (xy 185.334656 -341.364824) (xy 185.340245 -341.35774)
			(xy 185.346489 -341.340821) (xy 185.346848 -341.331804) (xy 185.346848 -341.264748) (xy 185.346479 -341.255732)
			(xy 185.340241 -341.238814) (xy 185.334656 -341.231728) (xy 185.334402 -341.231728) (xy 185.334402 -341.231474)
			(xy 185.316784 -341.210525) (xy 185.287069 -341.164557) (xy 185.264229 -341.114813) (xy 185.248733 -341.062317)
			(xy 185.240899 -341.008144) (xy 185.240422 -340.980776) (xy 185.240866 -340.95416) (xy 185.24827 -340.901446)
			(xy 185.262943 -340.850276) (xy 185.284601 -340.801649) (xy 185.298334 -340.778846) (xy 185.298588 -340.778592)
			(xy 185.303668 -340.769278) (xy 185.306568 -340.748287) (xy 185.304176 -340.737952) (xy 185.280554 -340.654894)
			(xy 185.266838 -340.638638) (xy 185.256932 -340.633812) (xy 185.237436 -340.62388) (xy 185.200642 -340.600198)
			(xy 185.183526 -340.586568) (xy 185.175906 -340.580218) (xy 185.157364 -340.574376) (xy 185.077608 -340.580472)
			(xy 185.067912 -340.581648) (xy 185.050401 -340.590255) (xy 185.043572 -340.597236) (xy 185.025414 -340.616781)
			(xy 184.984579 -340.65111) (xy 184.939358 -340.679413) (xy 184.890633 -340.701136) (xy 184.839356 -340.715856)
			(xy 184.786528 -340.723285) (xy 184.759854 -340.723728) (xy 184.732603 -340.723265) (xy 184.678655 -340.715503)
			(xy 184.626361 -340.700143) (xy 184.576785 -340.677498) (xy 184.530936 -340.648029) (xy 184.489747 -340.612335)
			(xy 184.454056 -340.571143) (xy 184.42459 -340.525292) (xy 184.401948 -340.475715) (xy 184.386592 -340.42342)
			(xy 184.378833 -340.369472) (xy 184.378346 -340.34222) (xy 184.378813 -340.31485) (xy 184.386629 -340.26067)
			(xy 184.402117 -340.208167) (xy 184.424959 -340.15842) (xy 184.454684 -340.112453) (xy 184.472326 -340.091522)
			(xy 184.47258 -340.091268) (xy 184.478154 -340.084173) (xy 184.484406 -340.067262) (xy 184.484772 -340.058248)
			(xy 184.484772 -339.991192) (xy 184.484425 -339.982174) (xy 184.478171 -339.965257) (xy 184.47258 -339.958172)
			(xy 184.472326 -339.958172) (xy 184.472326 -339.957918) (xy 184.454686 -339.936987) (xy 184.424973 -339.891014)
			(xy 184.402137 -339.841266) (xy 184.386646 -339.788765) (xy 184.378819 -339.734589) (xy 184.378346 -339.70722)
			(xy 184.378521 -339.692168) (xy 184.380933 -339.662161) (xy 184.383172 -339.647276) (xy 184.384172 -339.638334)
			(xy 184.380605 -339.62071) (xy 184.371206 -339.605381) (xy 184.364376 -339.599524) (xy 184.294526 -339.544406)
			(xy 184.287244 -339.539125) (xy 184.270121 -339.53364) (xy 184.252158 -339.53441) (xy 184.243726 -339.537548)
			(xy 184.243472 -339.537548) (xy 184.220054 -339.546925) (xy 184.171374 -339.560152) (xy 184.121374 -339.566841)
			(xy 184.096152 -339.567266) (xy 184.068898 -339.566867) (xy 184.014945 -339.559103) (xy 183.962646 -339.543739)
			(xy 183.913066 -339.521089) (xy 183.867213 -339.491614) (xy 183.826023 -339.455914) (xy 183.790332 -339.414715)
			(xy 183.760867 -339.368855) (xy 183.738229 -339.31927) (xy 183.722878 -339.266967) (xy 183.715127 -339.213012)
			(xy 183.714644 -339.185758) (xy 182.20182 -339.185758) (xy 182.201306 -339.213009) (xy 182.193555 -339.266958)
			(xy 182.178205 -339.319254) (xy 182.155568 -339.368833) (xy 182.126105 -339.414686) (xy 182.090417 -339.455879)
			(xy 182.049229 -339.491573) (xy 182.003381 -339.521042) (xy 181.953805 -339.543686) (xy 181.901511 -339.559043)
			(xy 181.847563 -339.566802) (xy 181.820312 -339.567266) (xy 181.793841 -339.566818) (xy 181.741411 -339.559475)
			(xy 181.690499 -339.544957) (xy 181.642082 -339.523542) (xy 181.597089 -339.495641) (xy 181.556384 -339.461789)
			(xy 181.520748 -339.422637) (xy 181.490865 -339.378935) (xy 181.478682 -339.35543) (xy 181.472766 -339.345111)
			(xy 181.453692 -339.330946) (xy 181.442106 -339.328252) (xy 181.384194 -339.317838) (xy 181.377336 -339.32495)
			(xy 181.370787 -339.332354) (xy 181.36333 -339.350638) (xy 181.362858 -339.36051) (xy 181.362858 -339.39226)
			(xy 181.363334 -339.402075) (xy 181.370787 -339.420239) (xy 181.377336 -339.427566) (xy 181.397491 -339.449082)
			(xy 181.431639 -339.497137) (xy 181.457989 -339.549872) (xy 181.475914 -339.606033) (xy 181.484988 -339.664282)
			(xy 181.48554 -339.693758) (xy 181.485064 -339.721128) (xy 181.477251 -339.775307) (xy 181.461765 -339.827811)
			(xy 181.438925 -339.877558) (xy 181.409201 -339.923525) (xy 181.39156 -339.944456) (xy 181.391306 -339.94471)
			(xy 181.38571 -339.95179) (xy 181.379469 -339.968712) (xy 181.379114 -339.97773) (xy 181.379114 -340.044786)
			(xy 181.379475 -340.053803) (xy 181.385719 -340.07072) (xy 181.391306 -340.077806) (xy 181.39156 -340.077806)
			(xy 181.39156 -340.07806) (xy 181.409188 -340.099001) (xy 181.438903 -340.144971) (xy 181.461741 -340.194716)
			(xy 181.477235 -340.247215) (xy 181.485065 -340.301389) (xy 181.48554 -340.328758) (xy 181.485006 -340.356008)
			(xy 181.477255 -340.409955) (xy 181.461906 -340.46225) (xy 181.439271 -340.511828) (xy 181.40981 -340.557679)
			(xy 181.374124 -340.598872) (xy 181.332939 -340.634566) (xy 181.287093 -340.664035) (xy 181.237519 -340.68668)
			(xy 181.185227 -340.70204) (xy 181.131282 -340.7098) (xy 181.104032 -340.710266) (xy 181.076262 -340.70976)
			(xy 181.021309 -340.70171) (xy 180.968105 -340.685777) (xy 180.917773 -340.662296) (xy 180.871379 -340.631764)
			(xy 180.829902 -340.594827) (xy 180.811678 -340.573868) (xy 180.805074 -340.565994) (xy 180.78704 -340.55685)
			(xy 180.693568 -340.549738) (xy 180.67401 -340.556342) (xy 180.66639 -340.5632) (xy 180.663342 -340.565994)
			(xy 180.655571 -340.573333) (xy 180.646495 -340.592665) (xy 180.645816 -340.603332) (xy 180.643784 -340.68893)
			(xy 180.651912 -340.708742) (xy 180.659786 -340.716108) (xy 180.678093 -340.734151) (xy 180.710129 -340.774351)
			(xy 180.736481 -340.818486) (xy 180.756671 -340.865757) (xy 180.770335 -340.915311) (xy 180.777226 -340.96625)
			(xy 180.777642 -340.991952) (xy 180.777162 -341.019322) (xy 180.76935 -341.073501) (xy 180.753865 -341.126004)
			(xy 180.731026 -341.175752) (xy 180.701303 -341.221718) (xy 180.683662 -341.24265) (xy 180.683408 -341.242904)
			(xy 180.677815 -341.249986) (xy 180.671572 -341.266906) (xy 180.671216 -341.275924) (xy 180.671216 -341.34298)
			(xy 180.671579 -341.351996) (xy 180.677822 -341.368914) (xy 180.683408 -341.376) (xy 180.683662 -341.376)
			(xy 180.683662 -341.376254) (xy 180.701287 -341.397197) (xy 180.731002 -341.443167) (xy 180.753842 -341.492911)
			(xy 180.769336 -341.545409) (xy 180.777167 -341.599584) (xy 180.777642 -341.626952) (xy 180.777156 -341.654203)
			(xy 180.7694 -341.708151) (xy 180.754045 -341.760446) (xy 180.731403 -341.810023) (xy 180.701937 -341.855873)
			(xy 180.666246 -341.897064) (xy 180.625055 -341.932755) (xy 180.579205 -341.962221) (xy 180.529628 -341.984863)
			(xy 180.477333 -342.000218) (xy 180.423385 -342.007974) (xy 180.368883 -342.007974) (xy 180.314935 -342.000218)
			(xy 180.26264 -341.984863) (xy 180.213063 -341.962221) (xy 180.167213 -341.932755) (xy 180.126022 -341.897064)
			(xy 180.090331 -341.855873) (xy 180.060865 -341.810023) (xy 180.038223 -341.760446) (xy 180.022868 -341.708151)
			(xy 180.015112 -341.654203) (xy 180.014626 -341.626952) (xy 178.631342 -341.626952) (xy 178.630856 -341.654203)
			(xy 178.6231 -341.708151) (xy 178.607745 -341.760446) (xy 178.585103 -341.810023) (xy 178.555637 -341.855873)
			(xy 178.519946 -341.897064) (xy 178.478755 -341.932755) (xy 178.432905 -341.962221) (xy 178.383328 -341.984863)
			(xy 178.331033 -342.000218) (xy 178.277085 -342.007974) (xy 178.222583 -342.007974) (xy 178.168635 -342.000218)
			(xy 178.11634 -341.984863) (xy 178.066763 -341.962221) (xy 178.020913 -341.932755) (xy 177.979722 -341.897064)
			(xy 177.944031 -341.855873) (xy 177.914565 -341.810023) (xy 177.891923 -341.760446) (xy 177.876568 -341.708151)
			(xy 177.868812 -341.654203) (xy 177.868326 -341.626952) (xy 177.868816 -341.599583) (xy 177.876627 -341.545404)
			(xy 177.89211 -341.492901) (xy 177.914947 -341.443154) (xy 177.944667 -341.397186) (xy 177.962306 -341.376254)
			(xy 177.96256 -341.376) (xy 177.96816 -341.368923) (xy 177.974397 -341.351999) (xy 177.974752 -341.34298)
			(xy 177.974752 -341.275924) (xy 177.974394 -341.266907) (xy 177.968148 -341.24999) (xy 177.96256 -341.242904)
			(xy 177.962306 -341.242904) (xy 177.962306 -341.24265) (xy 177.944678 -341.221709) (xy 177.914964 -341.175739)
			(xy 177.892126 -341.125994) (xy 177.876632 -341.073495) (xy 177.868801 -341.019321) (xy 177.868326 -340.991952)
			(xy 177.868848 -340.96382) (xy 177.877097 -340.908166) (xy 177.893438 -340.854328) (xy 177.917516 -340.803478)
			(xy 177.948807 -340.756719) (xy 177.986633 -340.715069) (xy 178.030171 -340.679432) (xy 178.078474 -340.650583)
			(xy 178.104292 -340.6394) (xy 178.115401 -340.633962) (xy 178.131205 -340.614993) (xy 178.134518 -340.603078)
			(xy 178.146964 -340.544912) (xy 178.138074 -340.53653) (xy 178.130703 -340.529904) (xy 178.112412 -340.52232)
			(xy 178.102514 -340.521798) (xy 178.07051 -340.521798) (xy 178.060603 -340.522268) (xy 178.042302 -340.52987)
			(xy 178.03495 -340.53653) (xy 178.013399 -340.557106) (xy 177.965038 -340.591911) (xy 177.911851 -340.618767)
			(xy 177.855132 -340.63702) (xy 177.796264 -340.646225) (xy 177.766472 -340.646766) (xy 177.739217 -340.646371)
			(xy 177.685261 -340.638609) (xy 177.632959 -340.623247) (xy 177.583376 -340.600599) (xy 177.537521 -340.571124)
			(xy 177.496328 -340.535423) (xy 177.460634 -340.494223) (xy 177.431168 -340.448362) (xy 177.408528 -340.398775)
			(xy 177.393176 -340.346471) (xy 177.385424 -340.292514) (xy 177.384964 -340.265258) (xy 174.337941 -340.265258)
			(xy 174.337562 -340.289973) (xy 174.329802 -340.343927) (xy 174.314442 -340.396227) (xy 174.291795 -340.445809)
			(xy 174.262323 -340.491664) (xy 174.226624 -340.532857) (xy 174.185427 -340.56855) (xy 174.139569 -340.598017)
			(xy 174.089984 -340.620658) (xy 174.037682 -340.636011) (xy 173.983727 -340.643765) (xy 173.956472 -340.644226)
			(xy 173.928834 -340.643727) (xy 173.874139 -340.635736) (xy 173.821168 -340.61994) (xy 173.771029 -340.596668)
			(xy 173.724771 -340.566409) (xy 173.703742 -340.548468) (xy 173.696605 -340.54266) (xy 173.679408 -340.536153)
			(xy 173.670214 -340.535768) (xy 173.60265 -340.535768) (xy 173.593466 -340.536209) (xy 173.576282 -340.542702)
			(xy 173.569122 -340.548468) (xy 173.56836 -340.548976) (xy 173.560356 -340.55637) (xy 173.550867 -340.575957)
			(xy 173.550072 -340.586822) (xy 173.550331 -340.598359) (xy 173.559885 -340.619341) (xy 173.577621 -340.634071)
			(xy 173.58868 -340.637368) (xy 173.615784 -340.64465) (xy 173.667598 -340.666219) (xy 173.715691 -340.695148)
			(xy 173.759026 -340.730812) (xy 173.796667 -340.772442) (xy 173.827801 -340.819138) (xy 173.851756 -340.869893)
			(xy 173.868014 -340.92361) (xy 173.876226 -340.97913) (xy 173.876716 -341.007192) (xy 173.876266 -341.034563)
			(xy 173.868447 -341.088744) (xy 173.852956 -341.141248) (xy 173.83011 -341.190994) (xy 173.80038 -341.23696)
			(xy 173.782736 -341.25789) (xy 173.782482 -341.258144) (xy 173.776911 -341.265241) (xy 173.770655 -341.28215)
			(xy 173.77029 -341.291164) (xy 173.77029 -341.35822) (xy 173.77064 -341.367238) (xy 173.776893 -341.384154)
			(xy 173.782482 -341.39124) (xy 173.782736 -341.39124) (xy 173.782736 -341.391494) (xy 173.800391 -341.412413)
			(xy 173.8301 -341.45839) (xy 173.852932 -341.508141) (xy 173.868419 -341.560644) (xy 173.876244 -341.614822)
			(xy 173.876716 -341.642192) (xy 173.87623 -341.669443) (xy 173.868474 -341.723391) (xy 173.853119 -341.775686)
			(xy 173.830477 -341.825263) (xy 173.801011 -341.871113) (xy 173.76532 -341.912304) (xy 173.724129 -341.947995)
			(xy 173.678279 -341.977461) (xy 173.628702 -342.000103) (xy 173.576407 -342.015458) (xy 173.522459 -342.023214)
			(xy 173.467957 -342.023214) (xy 173.414009 -342.015458) (xy 173.361714 -342.000103) (xy 173.312137 -341.977461)
			(xy 173.266287 -341.947995) (xy 173.225096 -341.912304) (xy 173.189405 -341.871113) (xy 173.159939 -341.825263)
			(xy 173.137297 -341.775686) (xy 173.121942 -341.723391) (xy 173.114186 -341.669443) (xy 173.1137 -341.642192)
			(xy 173.114161 -341.614822) (xy 173.12198 -341.560642) (xy 173.137471 -341.508139) (xy 173.160313 -341.458392)
			(xy 173.190039 -341.412426) (xy 173.20768 -341.391494) (xy 173.207934 -341.39124) (xy 173.213514 -341.384149)
			(xy 173.219763 -341.367235) (xy 173.220126 -341.35822) (xy 173.220126 -341.291164) (xy 173.219781 -341.282146)
			(xy 173.213524 -341.265229) (xy 173.207934 -341.258144) (xy 173.20768 -341.258144) (xy 173.20768 -341.25789)
			(xy 173.19002 -341.236975) (xy 173.160312 -341.190997) (xy 173.13748 -341.141245) (xy 173.121994 -341.088741)
			(xy 173.114171 -341.034562) (xy 173.1137 -341.007192) (xy 173.11411 -340.981285) (xy 173.121135 -340.929949)
			(xy 173.135041 -340.880036) (xy 173.155572 -340.832463) (xy 173.182352 -340.788105) (xy 173.198282 -340.76767)
			(xy 173.205228 -340.758188) (xy 173.210376 -340.735278) (xy 173.208188 -340.723728) (xy 173.186598 -340.634066)
			(xy 173.171358 -340.615778) (xy 173.16069 -340.610952) (xy 173.135824 -340.599335) (xy 173.089438 -340.569997)
			(xy 173.047738 -340.534313) (xy 173.011585 -340.493018) (xy 172.981725 -340.446967) (xy 172.958776 -340.397111)
			(xy 172.943213 -340.344479) (xy 172.935356 -340.29016) (xy 172.934884 -340.262718) (xy 148.56333 -340.262718)
			(xy 148.56333 -351.895156) (xy 150.737316 -351.895156) (xy 150.737316 -345.222576) (xy 150.737941 -345.197593)
			(xy 150.747682 -345.148586) (xy 150.766785 -345.102417) (xy 150.794519 -345.060855) (xy 150.811738 -345.042744)
			(xy 154.625802 -341.22868) (xy 154.6439 -341.211427) (xy 154.685444 -341.183617) (xy 154.731615 -341.164443)
			(xy 154.780638 -341.154642) (xy 154.805634 -341.154004) (xy 160.287462 -341.154004) (xy 160.312456 -341.154669)
			(xy 160.361477 -341.164465) (xy 160.407648 -341.18363) (xy 160.449196 -341.211429) (xy 160.467294 -341.22868)
			(xy 160.865566 -341.626952) (xy 170.9547 -341.626952) (xy 170.955197 -341.599583) (xy 170.963007 -341.545405)
			(xy 170.978489 -341.492902) (xy 171.001324 -341.443155) (xy 171.031042 -341.397187) (xy 171.04868 -341.376254)
			(xy 171.048934 -341.376) (xy 171.05453 -341.36892) (xy 171.06077 -341.351998) (xy 171.061126 -341.34298)
			(xy 171.061126 -341.275924) (xy 171.060752 -341.266909) (xy 171.054516 -341.249992) (xy 171.048934 -341.242904)
			(xy 171.04868 -341.242904) (xy 171.04868 -341.24265) (xy 171.031048 -341.221712) (xy 171.001336 -341.175741)
			(xy 170.978499 -341.125995) (xy 170.963006 -341.073495) (xy 170.955175 -341.019321) (xy 170.9547 -340.991952)
			(xy 170.955186 -340.964701) (xy 170.962942 -340.910753) (xy 170.978297 -340.858458) (xy 171.000939 -340.808881)
			(xy 171.030405 -340.763031) (xy 171.066096 -340.72184) (xy 171.107287 -340.686149) (xy 171.153137 -340.656683)
			(xy 171.202714 -340.634041) (xy 171.255009 -340.618686) (xy 171.308957 -340.61093) (xy 171.363459 -340.61093)
			(xy 171.417407 -340.618686) (xy 171.469702 -340.634041) (xy 171.519279 -340.656683) (xy 171.565129 -340.686149)
			(xy 171.60632 -340.72184) (xy 171.642011 -340.763031) (xy 171.671477 -340.808881) (xy 171.694119 -340.858458)
			(xy 171.709474 -340.910753) (xy 171.71723 -340.964701) (xy 171.717716 -340.991952) (xy 171.717242 -341.019322)
			(xy 171.709429 -341.073502) (xy 171.693943 -341.126006) (xy 171.671103 -341.175753) (xy 171.641378 -341.221719)
			(xy 171.623736 -341.24265) (xy 171.623482 -341.242904) (xy 171.617886 -341.249984) (xy 171.611645 -341.266906)
			(xy 171.61129 -341.275924) (xy 171.61129 -341.34298) (xy 171.611659 -341.351996) (xy 171.617898 -341.368913)
			(xy 171.623482 -341.376) (xy 171.623736 -341.376) (xy 171.623736 -341.376254) (xy 171.641373 -341.397188)
			(xy 171.671084 -341.443161) (xy 171.693919 -341.492908) (xy 171.709411 -341.545408) (xy 171.717241 -341.599583)
			(xy 171.717716 -341.626952) (xy 171.71723 -341.654203) (xy 171.709474 -341.708151) (xy 171.694119 -341.760446)
			(xy 171.671477 -341.810023) (xy 171.642011 -341.855873) (xy 171.60632 -341.897064) (xy 171.565129 -341.932755)
			(xy 171.519279 -341.962221) (xy 171.469702 -341.984863) (xy 171.417407 -342.000218) (xy 171.363459 -342.007974)
			(xy 171.308957 -342.007974) (xy 171.255009 -342.000218) (xy 171.202714 -341.984863) (xy 171.153137 -341.962221)
			(xy 171.107287 -341.932755) (xy 171.066096 -341.897064) (xy 171.030405 -341.855873) (xy 171.000939 -341.810023)
			(xy 170.978297 -341.760446) (xy 170.962942 -341.708151) (xy 170.955186 -341.654203) (xy 170.9547 -341.626952)
			(xy 160.865566 -341.626952) (xy 161.757614 -342.519) (xy 217.168982 -342.519) (xy 217.173053 -342.463378)
			(xy 217.185179 -342.408941) (xy 217.205102 -342.35685) (xy 217.232398 -342.308215) (xy 217.266484 -342.264072)
			(xy 217.306633 -342.225363) (xy 217.351991 -342.192912) (xy 217.401591 -342.167411) (xy 217.454375 -342.149404)
			(xy 217.509218 -342.139274) (xy 217.564952 -342.137237) (xy 217.620389 -342.143337) (xy 217.674346 -342.157443)
			(xy 217.725675 -342.179255) (xy 217.773281 -342.208309) (xy 217.816149 -342.243984) (xy 217.853366 -342.285521)
			(xy 217.884139 -342.332034) (xy 217.907811 -342.382531) (xy 217.923879 -342.435938) (xy 217.931999 -342.491114)
			(xy 217.932508 -342.519) (xy 217.931999 -342.546886) (xy 217.923879 -342.602062) (xy 217.907811 -342.655469)
			(xy 217.884139 -342.705966) (xy 217.853366 -342.752479) (xy 217.816149 -342.794016) (xy 217.773281 -342.829691)
			(xy 217.725675 -342.858745) (xy 217.674346 -342.880557) (xy 217.620389 -342.894663) (xy 217.564952 -342.900763)
			(xy 217.509218 -342.898726) (xy 217.454375 -342.888596) (xy 217.401591 -342.870589) (xy 217.351991 -342.845088)
			(xy 217.306633 -342.812637) (xy 217.266484 -342.773928) (xy 217.232398 -342.729785) (xy 217.205102 -342.68115)
			(xy 217.185179 -342.629059) (xy 217.173053 -342.574622) (xy 217.168982 -342.519) (xy 161.757614 -342.519)
			(xy 161.82086 -342.582246) (xy 161.838124 -342.600335) (xy 161.865935 -342.641881) (xy 161.885106 -342.688055)
			(xy 161.894902 -342.737081) (xy 161.895536 -342.762078) (xy 161.895536 -342.922352) (xy 202.582016 -342.922352)
			(xy 202.586087 -342.86673) (xy 202.598213 -342.812293) (xy 202.618136 -342.760202) (xy 202.645432 -342.711567)
			(xy 202.679518 -342.667424) (xy 202.719667 -342.628715) (xy 202.765025 -342.596264) (xy 202.814625 -342.570763)
			(xy 202.867409 -342.552756) (xy 202.922252 -342.542626) (xy 202.977986 -342.540589) (xy 203.033423 -342.546689)
			(xy 203.08738 -342.560795) (xy 203.138709 -342.582607) (xy 203.186315 -342.611661) (xy 203.229183 -342.647336)
			(xy 203.2664 -342.688873) (xy 203.297173 -342.735386) (xy 203.320845 -342.785883) (xy 203.336913 -342.83929)
			(xy 203.345033 -342.894466) (xy 203.345542 -342.922352) (xy 203.345033 -342.950238) (xy 203.336913 -343.005414)
			(xy 203.320845 -343.058821) (xy 203.297173 -343.109318) (xy 203.2664 -343.155831) (xy 203.229183 -343.197368)
			(xy 203.186315 -343.233043) (xy 203.138709 -343.262097) (xy 203.08738 -343.283909) (xy 203.033423 -343.298015)
			(xy 202.977986 -343.304115) (xy 202.922252 -343.302078) (xy 202.867409 -343.291948) (xy 202.814625 -343.273941)
			(xy 202.765025 -343.24844) (xy 202.719667 -343.215989) (xy 202.679518 -343.17728) (xy 202.645432 -343.133137)
			(xy 202.618136 -343.084502) (xy 202.598213 -343.032411) (xy 202.586087 -342.977974) (xy 202.582016 -342.922352)
			(xy 161.895536 -342.922352) (xy 161.895536 -343.362788) (xy 161.895958 -343.372858) (xy 161.90368 -343.391456)
			(xy 161.910522 -343.398856) (xy 161.91484 -343.403174) (xy 161.922235 -343.41002) (xy 161.940838 -343.417737)
			(xy 161.950908 -343.41816) (xy 165.102794 -343.41816) (xy 165.112865 -343.418573) (xy 165.131464 -343.426301)
			(xy 165.137489 -343.431876) (xy 212.785958 -343.431876) (xy 212.790029 -343.376254) (xy 212.802155 -343.321817)
			(xy 212.822078 -343.269726) (xy 212.849374 -343.221091) (xy 212.88346 -343.176948) (xy 212.923609 -343.138239)
			(xy 212.968967 -343.105788) (xy 213.018567 -343.080287) (xy 213.071351 -343.06228) (xy 213.126194 -343.05215)
			(xy 213.181928 -343.050113) (xy 213.237365 -343.056213) (xy 213.291322 -343.070319) (xy 213.342651 -343.092131)
			(xy 213.390257 -343.121185) (xy 213.433125 -343.15686) (xy 213.470342 -343.198397) (xy 213.501115 -343.24491)
			(xy 213.524787 -343.295407) (xy 213.540855 -343.348814) (xy 213.548975 -343.40399) (xy 213.549484 -343.431876)
			(xy 213.548975 -343.459762) (xy 213.540855 -343.514938) (xy 213.524787 -343.568345) (xy 213.501115 -343.618842)
			(xy 213.470342 -343.665355) (xy 213.433125 -343.706892) (xy 213.390257 -343.742567) (xy 213.342651 -343.771621)
			(xy 213.291322 -343.793433) (xy 213.237365 -343.807539) (xy 213.181928 -343.813639) (xy 213.126194 -343.811602)
			(xy 213.071351 -343.801472) (xy 213.018567 -343.783465) (xy 212.968967 -343.757964) (xy 212.923609 -343.725513)
			(xy 212.88346 -343.686804) (xy 212.849374 -343.642661) (xy 212.822078 -343.594026) (xy 212.802155 -343.541935)
			(xy 212.790029 -343.487498) (xy 212.785958 -343.431876) (xy 165.137489 -343.431876) (xy 165.138862 -343.433146)
			(xy 166.53591 -344.8304) (xy 201.363834 -344.8304) (xy 201.36434 -344.801482) (xy 201.373069 -344.74431)
			(xy 201.390329 -344.68911) (xy 201.415723 -344.637149) (xy 201.448669 -344.589615) (xy 201.488413 -344.547599)
			(xy 201.5109 -344.52941) (xy 201.519693 -344.521789) (xy 201.529884 -344.500899) (xy 201.530458 -344.489278)
			(xy 201.530458 -344.409522) (xy 201.529906 -344.397891) (xy 201.519728 -344.376981) (xy 201.5109 -344.36939)
			(xy 201.488412 -344.351205) (xy 201.448677 -344.309184) (xy 201.415738 -344.261648) (xy 201.390351 -344.209685)
			(xy 201.373096 -344.154487) (xy 201.364368 -344.097316) (xy 201.363834 -344.0684) (xy 201.36432 -344.041149)
			(xy 201.372076 -343.987201) (xy 201.387431 -343.934906) (xy 201.410073 -343.885329) (xy 201.439539 -343.839479)
			(xy 201.47523 -343.798288) (xy 201.516421 -343.762597) (xy 201.562271 -343.733131) (xy 201.611848 -343.710489)
			(xy 201.664143 -343.695134) (xy 201.718091 -343.687378) (xy 201.772593 -343.687378) (xy 201.826541 -343.695134)
			(xy 201.878836 -343.710489) (xy 201.928413 -343.733131) (xy 201.974263 -343.762597) (xy 202.015454 -343.798288)
			(xy 202.051145 -343.839479) (xy 202.080611 -343.885329) (xy 202.103253 -343.934906) (xy 202.118608 -343.987201)
			(xy 202.126364 -344.041149) (xy 202.12685 -344.0684) (xy 202.126351 -344.097318) (xy 202.11762 -344.154491)
			(xy 202.10036 -344.209691) (xy 202.074965 -344.261653) (xy 202.052577 -344.293952) (xy 205.807816 -344.293952)
			(xy 205.811887 -344.23833) (xy 205.824013 -344.183893) (xy 205.843936 -344.131802) (xy 205.871232 -344.083167)
			(xy 205.905318 -344.039024) (xy 205.945467 -344.000315) (xy 205.990825 -343.967864) (xy 206.040425 -343.942363)
			(xy 206.093209 -343.924356) (xy 206.148052 -343.914226) (xy 206.203786 -343.912189) (xy 206.259223 -343.918289)
			(xy 206.31318 -343.932395) (xy 206.364509 -343.954207) (xy 206.412115 -343.983261) (xy 206.454983 -344.018936)
			(xy 206.4922 -344.060473) (xy 206.522973 -344.106986) (xy 206.546645 -344.157483) (xy 206.562713 -344.21089)
			(xy 206.570833 -344.266066) (xy 206.571342 -344.293952) (xy 206.570833 -344.321838) (xy 206.562713 -344.377014)
			(xy 206.546645 -344.430421) (xy 206.522973 -344.480918) (xy 206.4922 -344.527431) (xy 206.454983 -344.568968)
			(xy 206.412115 -344.604643) (xy 206.364509 -344.633697) (xy 206.31318 -344.655509) (xy 206.259223 -344.669615)
			(xy 206.203786 -344.675715) (xy 206.148052 -344.673678) (xy 206.093209 -344.663548) (xy 206.040425 -344.645541)
			(xy 205.990825 -344.62004) (xy 205.945467 -344.587589) (xy 205.905318 -344.54888) (xy 205.871232 -344.504737)
			(xy 205.843936 -344.456102) (xy 205.824013 -344.404011) (xy 205.811887 -344.349574) (xy 205.807816 -344.293952)
			(xy 202.052577 -344.293952) (xy 202.042017 -344.309186) (xy 202.002272 -344.351201) (xy 201.979784 -344.36939)
			(xy 201.970988 -344.377008) (xy 201.960799 -344.397901) (xy 201.960226 -344.409522) (xy 201.960226 -344.489278)
			(xy 201.960783 -344.500908) (xy 201.970958 -344.521818) (xy 201.979784 -344.52941) (xy 202.002269 -344.547599)
			(xy 202.042005 -344.589619) (xy 202.074944 -344.637154) (xy 202.100332 -344.689116) (xy 202.117588 -344.744314)
			(xy 202.126316 -344.801484) (xy 202.12685 -344.8304) (xy 202.126364 -344.857651) (xy 202.118608 -344.911599)
			(xy 202.106502 -344.952828) (xy 213.241888 -344.952828) (xy 213.245959 -344.897206) (xy 213.258085 -344.842769)
			(xy 213.278008 -344.790678) (xy 213.305304 -344.742043) (xy 213.33939 -344.6979) (xy 213.379539 -344.659191)
			(xy 213.424897 -344.62674) (xy 213.474497 -344.601239) (xy 213.527281 -344.583232) (xy 213.582124 -344.573102)
			(xy 213.637858 -344.571065) (xy 213.693295 -344.577165) (xy 213.747252 -344.591271) (xy 213.798581 -344.613083)
			(xy 213.846187 -344.642137) (xy 213.889055 -344.677812) (xy 213.926272 -344.719349) (xy 213.957045 -344.765862)
			(xy 213.980717 -344.816359) (xy 213.996785 -344.869766) (xy 214.004905 -344.924942) (xy 214.005414 -344.952828)
			(xy 214.004905 -344.980714) (xy 213.996785 -345.03589) (xy 213.980717 -345.089297) (xy 213.957045 -345.139794)
			(xy 213.926272 -345.186307) (xy 213.889055 -345.227844) (xy 213.846187 -345.263519) (xy 213.798581 -345.292573)
			(xy 213.747252 -345.314385) (xy 213.693295 -345.328491) (xy 213.637858 -345.334591) (xy 213.582124 -345.332554)
			(xy 213.527281 -345.322424) (xy 213.474497 -345.304417) (xy 213.424897 -345.278916) (xy 213.379539 -345.246465)
			(xy 213.33939 -345.207756) (xy 213.305304 -345.163613) (xy 213.278008 -345.114978) (xy 213.258085 -345.062887)
			(xy 213.245959 -345.00845) (xy 213.241888 -344.952828) (xy 202.106502 -344.952828) (xy 202.103253 -344.963894)
			(xy 202.080611 -345.013471) (xy 202.051145 -345.059321) (xy 202.015454 -345.100512) (xy 201.974263 -345.136203)
			(xy 201.928413 -345.165669) (xy 201.878836 -345.188311) (xy 201.826541 -345.203666) (xy 201.772593 -345.211422)
			(xy 201.718091 -345.211422) (xy 201.664143 -345.203666) (xy 201.611848 -345.188311) (xy 201.562271 -345.165669)
			(xy 201.516421 -345.136203) (xy 201.47523 -345.100512) (xy 201.439539 -345.059321) (xy 201.410073 -345.013471)
			(xy 201.387431 -344.963894) (xy 201.372076 -344.911599) (xy 201.36432 -344.857651) (xy 201.363834 -344.8304)
			(xy 166.53591 -344.8304) (xy 166.865554 -345.160092) (xy 166.872377 -345.167506) (xy 166.880108 -345.186094)
			(xy 166.88054 -345.19616) (xy 166.88054 -346.302076) (xy 167.694608 -346.302076) (xy 167.698679 -346.246454)
			(xy 167.710805 -346.192017) (xy 167.730728 -346.139926) (xy 167.758024 -346.091291) (xy 167.79211 -346.047148)
			(xy 167.832259 -346.008439) (xy 167.877617 -345.975988) (xy 167.927217 -345.950487) (xy 167.980001 -345.93248)
			(xy 168.034844 -345.92235) (xy 168.090578 -345.920313) (xy 168.146015 -345.926413) (xy 168.199972 -345.940519)
			(xy 168.251301 -345.962331) (xy 168.298907 -345.991385) (xy 168.341775 -346.02706) (xy 168.378992 -346.068597)
			(xy 168.409765 -346.11511) (xy 168.433437 -346.165607) (xy 168.449505 -346.219014) (xy 168.457625 -346.27419)
			(xy 168.458134 -346.302076) (xy 168.457625 -346.329962) (xy 168.449505 -346.385138) (xy 168.433437 -346.438545)
			(xy 168.409765 -346.489042) (xy 168.378992 -346.535555) (xy 168.341775 -346.577092) (xy 168.334676 -346.583)
			(xy 201.363834 -346.583) (xy 201.36434 -346.554082) (xy 201.373069 -346.49691) (xy 201.390329 -346.44171)
			(xy 201.415723 -346.389749) (xy 201.448669 -346.342215) (xy 201.488413 -346.300199) (xy 201.5109 -346.28201)
			(xy 201.519693 -346.274389) (xy 201.529884 -346.253499) (xy 201.530458 -346.241878) (xy 201.530458 -346.162122)
			(xy 201.529906 -346.150491) (xy 201.519728 -346.129581) (xy 201.5109 -346.12199) (xy 201.488412 -346.103805)
			(xy 201.448677 -346.061784) (xy 201.415738 -346.014248) (xy 201.390351 -345.962285) (xy 201.373096 -345.907087)
			(xy 201.364368 -345.849916) (xy 201.363834 -345.821) (xy 201.36432 -345.793749) (xy 201.372076 -345.739801)
			(xy 201.387431 -345.687506) (xy 201.410073 -345.637929) (xy 201.439539 -345.592079) (xy 201.47523 -345.550888)
			(xy 201.516421 -345.515197) (xy 201.562271 -345.485731) (xy 201.611848 -345.463089) (xy 201.664143 -345.447734)
			(xy 201.718091 -345.439978) (xy 201.772593 -345.439978) (xy 201.826541 -345.447734) (xy 201.878836 -345.463089)
			(xy 201.928413 -345.485731) (xy 201.974263 -345.515197) (xy 202.015454 -345.550888) (xy 202.051145 -345.592079)
			(xy 202.080611 -345.637929) (xy 202.103253 -345.687506) (xy 202.118608 -345.739801) (xy 202.126364 -345.793749)
			(xy 202.12685 -345.821) (xy 202.126351 -345.849918) (xy 202.11762 -345.907091) (xy 202.10036 -345.962291)
			(xy 202.074965 -346.014253) (xy 202.042017 -346.061786) (xy 202.002272 -346.103801) (xy 201.979784 -346.12199)
			(xy 201.970988 -346.129608) (xy 201.960799 -346.150501) (xy 201.960226 -346.162122) (xy 201.960226 -346.241878)
			(xy 201.960783 -346.253508) (xy 201.970958 -346.274418) (xy 201.979784 -346.28201) (xy 202.002269 -346.300199)
			(xy 202.042005 -346.342219) (xy 202.074944 -346.389754) (xy 202.100332 -346.441716) (xy 202.117588 -346.496914)
			(xy 202.126316 -346.554084) (xy 202.12685 -346.583) (xy 202.126364 -346.610251) (xy 202.118608 -346.664199)
			(xy 202.103253 -346.716494) (xy 202.100419 -346.7227) (xy 213.35187 -346.7227) (xy 213.355941 -346.667078)
			(xy 213.368067 -346.612641) (xy 213.38799 -346.56055) (xy 213.415286 -346.511915) (xy 213.449372 -346.467772)
			(xy 213.489521 -346.429063) (xy 213.534879 -346.396612) (xy 213.584479 -346.371111) (xy 213.637263 -346.353104)
			(xy 213.692106 -346.342974) (xy 213.74784 -346.340937) (xy 213.803277 -346.347037) (xy 213.857234 -346.361143)
			(xy 213.908563 -346.382955) (xy 213.956169 -346.412009) (xy 213.999037 -346.447684) (xy 214.036254 -346.489221)
			(xy 214.067027 -346.535734) (xy 214.090699 -346.586231) (xy 214.106767 -346.639638) (xy 214.114887 -346.694814)
			(xy 214.115396 -346.7227) (xy 214.114887 -346.750586) (xy 214.106767 -346.805762) (xy 214.090699 -346.859169)
			(xy 214.067027 -346.909666) (xy 214.036254 -346.956179) (xy 213.999037 -346.997716) (xy 213.956169 -347.033391)
			(xy 213.908563 -347.062445) (xy 213.857234 -347.084257) (xy 213.803277 -347.098363) (xy 213.74784 -347.104463)
			(xy 213.692106 -347.102426) (xy 213.637263 -347.092296) (xy 213.584479 -347.074289) (xy 213.534879 -347.048788)
			(xy 213.489521 -347.016337) (xy 213.449372 -346.977628) (xy 213.415286 -346.933485) (xy 213.38799 -346.88485)
			(xy 213.368067 -346.832759) (xy 213.355941 -346.778322) (xy 213.35187 -346.7227) (xy 202.100419 -346.7227)
			(xy 202.080611 -346.766071) (xy 202.051145 -346.811921) (xy 202.015454 -346.853112) (xy 201.974263 -346.888803)
			(xy 201.928413 -346.918269) (xy 201.878836 -346.940911) (xy 201.826541 -346.956266) (xy 201.772593 -346.964022)
			(xy 201.718091 -346.964022) (xy 201.664143 -346.956266) (xy 201.611848 -346.940911) (xy 201.562271 -346.918269)
			(xy 201.516421 -346.888803) (xy 201.47523 -346.853112) (xy 201.439539 -346.811921) (xy 201.410073 -346.766071)
			(xy 201.387431 -346.716494) (xy 201.372076 -346.664199) (xy 201.36432 -346.610251) (xy 201.363834 -346.583)
			(xy 168.334676 -346.583) (xy 168.298907 -346.612767) (xy 168.251301 -346.641821) (xy 168.199972 -346.663633)
			(xy 168.146015 -346.677739) (xy 168.090578 -346.683839) (xy 168.034844 -346.681802) (xy 167.980001 -346.671672)
			(xy 167.927217 -346.653665) (xy 167.877617 -346.628164) (xy 167.832259 -346.595713) (xy 167.79211 -346.557004)
			(xy 167.758024 -346.512861) (xy 167.730728 -346.464226) (xy 167.710805 -346.412135) (xy 167.698679 -346.357698)
			(xy 167.694608 -346.302076) (xy 166.88054 -346.302076) (xy 166.88054 -347.268848) (xy 203.547 -347.268848)
			(xy 203.547 -347.214352) (xy 203.554755 -347.160411) (xy 203.570108 -347.108122) (xy 203.592745 -347.05855)
			(xy 203.622206 -347.012704) (xy 203.657892 -346.971517) (xy 203.699075 -346.935828) (xy 203.744918 -346.906362)
			(xy 203.794488 -346.88372) (xy 203.846775 -346.868363) (xy 203.900716 -346.860603) (xy 203.927964 -346.860114)
			(xy 203.955334 -346.860598) (xy 204.009512 -346.868411) (xy 204.062015 -346.883896) (xy 204.111762 -346.906733)
			(xy 204.15773 -346.936454) (xy 204.178662 -346.954094) (xy 204.178916 -346.954348) (xy 204.18599 -346.959953)
			(xy 204.202917 -346.966188) (xy 204.211936 -346.96654) (xy 204.278992 -346.96654) (xy 204.28801 -346.966192)
			(xy 204.304928 -346.95994) (xy 204.312012 -346.954348) (xy 204.312012 -346.954094) (xy 204.312266 -346.954094)
			(xy 204.333199 -346.936456) (xy 204.379172 -346.906745) (xy 204.428919 -346.883908) (xy 204.481419 -346.868417)
			(xy 204.535595 -346.860588) (xy 204.562964 -346.860114) (xy 204.589876 -346.860595) (xy 204.643163 -346.868196)
			(xy 204.694856 -346.883196) (xy 204.743935 -346.905299) (xy 204.766926 -346.919296) (xy 204.76718 -346.919296)
			(xy 204.775203 -346.923891) (xy 204.793311 -346.927542) (xy 204.802486 -346.926408) (xy 204.869288 -346.915486)
			(xy 204.878413 -346.913542) (xy 204.894436 -346.904011) (xy 204.90053 -346.896944) (xy 204.91875 -346.875108)
			(xy 204.960565 -346.836565) (xy 205.007637 -346.804656) (xy 205.058924 -346.780086) (xy 205.11329 -346.763401)
			(xy 205.16953 -346.75497) (xy 205.197964 -346.75445) (xy 205.225212 -346.755012) (xy 205.279155 -346.762762)
			(xy 205.331446 -346.778111) (xy 205.38102 -346.800744) (xy 205.426869 -346.830203) (xy 205.468058 -346.865887)
			(xy 205.50375 -346.907069) (xy 205.533218 -346.952911) (xy 205.555862 -347.002481) (xy 205.571221 -347.054768)
			(xy 205.578983 -347.10871) (xy 205.579472 -347.135958) (xy 205.578988 -347.163328) (xy 205.571176 -347.217506)
			(xy 205.555691 -347.270009) (xy 205.532853 -347.319757) (xy 205.503132 -347.365724) (xy 205.485492 -347.386656)
			(xy 205.485238 -347.38691) (xy 205.479634 -347.393984) (xy 205.473399 -347.410911) (xy 205.473046 -347.41993)
			(xy 205.473046 -347.486986) (xy 205.4734 -347.496003) (xy 205.479649 -347.512921) (xy 205.485238 -347.520006)
			(xy 205.485492 -347.520006) (xy 205.485492 -347.52026) (xy 205.503125 -347.541197) (xy 205.532838 -347.587169)
			(xy 205.555675 -347.636915) (xy 205.571168 -347.689414) (xy 205.578997 -347.743589) (xy 205.579472 -347.770958)
			(xy 205.578986 -347.798209) (xy 205.57123 -347.852157) (xy 205.555875 -347.904452) (xy 205.533233 -347.954029)
			(xy 205.503767 -347.999879) (xy 205.468076 -348.04107) (xy 205.426885 -348.076761) (xy 205.381035 -348.106227)
			(xy 205.331458 -348.128869) (xy 205.279163 -348.144224) (xy 205.225215 -348.15198) (xy 205.170713 -348.15198)
			(xy 205.116765 -348.144224) (xy 205.06447 -348.128869) (xy 205.014893 -348.106227) (xy 204.969043 -348.076761)
			(xy 204.927852 -348.04107) (xy 204.892161 -347.999879) (xy 204.862695 -347.954029) (xy 204.840053 -347.904452)
			(xy 204.824698 -347.852157) (xy 204.816942 -347.798209) (xy 204.816456 -347.770958) (xy 204.816456 -347.770704)
			(xy 204.816596 -347.756361) (xy 204.818759 -347.727756) (xy 204.820774 -347.713554) (xy 204.822806 -347.700346)
			(xy 204.813408 -347.675708) (xy 204.736446 -347.611192) (xy 204.729468 -347.605905) (xy 204.713039 -347.599903)
			(xy 204.695548 -347.599767) (xy 204.68717 -347.602302) (xy 204.657048 -347.612043) (xy 204.594616 -347.62251)
			(xy 204.562964 -347.62313) (xy 204.535592 -347.622702) (xy 204.481411 -347.614878) (xy 204.428907 -347.599381)
			(xy 204.37916 -347.57653) (xy 204.333196 -347.546796) (xy 204.312266 -347.52915) (xy 204.312012 -347.528896)
			(xy 204.304927 -347.523308) (xy 204.288009 -347.517062) (xy 204.278992 -347.516704) (xy 204.211936 -347.516704)
			(xy 204.202921 -347.517077) (xy 204.186004 -347.523313) (xy 204.178916 -347.528896) (xy 204.178916 -347.52915)
			(xy 204.178662 -347.52915) (xy 204.157711 -347.546766) (xy 204.111744 -347.576483) (xy 204.062002 -347.599324)
			(xy 204.009505 -347.61482) (xy 203.955332 -347.622654) (xy 203.927964 -347.62313) (xy 203.900716 -347.622597)
			(xy 203.846775 -347.614837) (xy 203.794488 -347.59948) (xy 203.744918 -347.576838) (xy 203.699075 -347.547372)
			(xy 203.657892 -347.511683) (xy 203.622206 -347.470496) (xy 203.592745 -347.42465) (xy 203.570108 -347.375078)
			(xy 203.554755 -347.322789) (xy 203.547 -347.268848) (xy 166.88054 -347.268848) (xy 166.88054 -348.000574)
			(xy 167.718484 -348.000574) (xy 167.722555 -347.944952) (xy 167.734681 -347.890515) (xy 167.754604 -347.838424)
			(xy 167.7819 -347.789789) (xy 167.815986 -347.745646) (xy 167.856135 -347.706937) (xy 167.901493 -347.674486)
			(xy 167.951093 -347.648985) (xy 168.003877 -347.630978) (xy 168.05872 -347.620848) (xy 168.114454 -347.618811)
			(xy 168.169891 -347.624911) (xy 168.223848 -347.639017) (xy 168.275177 -347.660829) (xy 168.322783 -347.689883)
			(xy 168.365651 -347.725558) (xy 168.402868 -347.767095) (xy 168.433641 -347.813608) (xy 168.457313 -347.864105)
			(xy 168.473381 -347.917512) (xy 168.481501 -347.972688) (xy 168.48201 -348.000574) (xy 168.481501 -348.02846)
			(xy 168.473381 -348.083636) (xy 168.457313 -348.137043) (xy 168.433641 -348.18754) (xy 168.402868 -348.234053)
			(xy 168.365651 -348.27559) (xy 168.322783 -348.311265) (xy 168.275177 -348.340319) (xy 168.223848 -348.362131)
			(xy 168.169891 -348.376237) (xy 168.114454 -348.382337) (xy 168.05872 -348.3803) (xy 168.003877 -348.37017)
			(xy 167.951093 -348.352163) (xy 167.901493 -348.326662) (xy 167.856135 -348.294211) (xy 167.815986 -348.255502)
			(xy 167.7819 -348.211359) (xy 167.754604 -348.162724) (xy 167.734681 -348.110633) (xy 167.722555 -348.056196)
			(xy 167.718484 -348.000574) (xy 166.88054 -348.000574) (xy 166.88054 -349.7163) (xy 168.443412 -349.7163)
			(xy 168.447426 -349.652506) (xy 168.459404 -349.589717) (xy 168.479157 -349.528925) (xy 168.506374 -349.471088)
			(xy 168.540625 -349.417119) (xy 168.58137 -349.367868) (xy 168.627967 -349.324112) (xy 168.679681 -349.286541)
			(xy 168.735695 -349.255749) (xy 168.795128 -349.23222) (xy 168.857041 -349.216325) (xy 168.920458 -349.208316)
			(xy 168.952418 -349.207836) (xy 169.49801 -349.207836) (xy 169.531294 -349.208416) (xy 169.597288 -349.217152)
			(xy 169.661579 -349.234421) (xy 169.723068 -349.259927) (xy 169.780705 -349.293235) (xy 169.833505 -349.333777)
			(xy 169.85742 -349.356934) (xy 170.14571 -349.645224) (xy 170.16891 -349.669103) (xy 170.209472 -349.721899)
			(xy 170.242792 -349.779539) (xy 170.2683 -349.841037) (xy 170.28556 -349.905339) (xy 170.294275 -349.971345)
			(xy 170.294808 -350.004634) (xy 170.294808 -351.319084) (xy 170.294249 -351.352061) (xy 170.285714 -351.41746)
			(xy 170.268797 -351.481208) (xy 170.243784 -351.542235) (xy 170.211093 -351.599516) (xy 170.171272 -351.652092)
			(xy 170.148504 -351.675954) (xy 170.141862 -351.683313) (xy 170.134288 -351.701614) (xy 170.133772 -351.711514)
			(xy 170.133772 -352.950272) (xy 178.85537 -352.950272) (xy 178.855851 -352.922361) (xy 178.863989 -352.867135)
			(xy 178.880088 -352.813684) (xy 178.903803 -352.763149) (xy 178.934629 -352.71661) (xy 178.952906 -352.69551)
			(xy 178.958799 -352.68833) (xy 178.965452 -352.671007) (xy 178.96586 -352.661728) (xy 178.96586 -352.584004)
			(xy 178.959256 -352.566732) (xy 178.952906 -352.55962) (xy 178.934617 -352.538529) (xy 178.903791 -352.491989)
			(xy 178.880078 -352.441452) (xy 178.863984 -352.387998) (xy 178.855853 -352.33277) (xy 178.85537 -352.304858)
			(xy 178.855856 -352.277607) (xy 178.863612 -352.223659) (xy 178.878967 -352.171364) (xy 178.901609 -352.121787)
			(xy 178.931075 -352.075937) (xy 178.966766 -352.034746) (xy 179.007957 -351.999055) (xy 179.053807 -351.969589)
			(xy 179.103384 -351.946947) (xy 179.155679 -351.931592) (xy 179.209627 -351.923836) (xy 179.264129 -351.923836)
			(xy 179.318077 -351.931592) (xy 179.370372 -351.946947) (xy 179.419949 -351.969589) (xy 179.465799 -351.999055)
			(xy 179.50699 -352.034746) (xy 179.542681 -352.075937) (xy 179.572147 -352.121787) (xy 179.594789 -352.171364)
			(xy 179.610144 -352.223659) (xy 179.6179 -352.277607) (xy 179.618386 -352.304858) (xy 179.617909 -352.332769)
			(xy 179.609768 -352.387995) (xy 179.593667 -352.441445) (xy 179.569952 -352.491979) (xy 179.539127 -352.538519)
			(xy 179.52085 -352.55962) (xy 179.514939 -352.566787) (xy 179.508298 -352.58412) (xy 179.507896 -352.593402)
			(xy 179.507896 -352.671126) (xy 179.5145 -352.688398) (xy 179.52085 -352.69551) (xy 179.539115 -352.71662)
			(xy 179.569943 -352.763156) (xy 179.593659 -352.813688) (xy 179.609759 -352.867137) (xy 179.617898 -352.922362)
			(xy 179.618386 -352.950272) (xy 179.6179 -352.977523) (xy 179.610144 -353.031471) (xy 179.594789 -353.083766)
			(xy 179.572147 -353.133343) (xy 179.542681 -353.179193) (xy 179.50699 -353.220384) (xy 179.465799 -353.256075)
			(xy 179.422658 -353.2838) (xy 183.237633 -353.2838) (xy 183.241801 -353.228186) (xy 183.25421 -353.173815)
			(xy 183.274583 -353.1219) (xy 183.302466 -353.073601) (xy 183.337236 -353.029997) (xy 183.378116 -352.992062)
			(xy 183.424192 -352.960642) (xy 183.474437 -352.936441) (xy 183.527727 -352.919998) (xy 183.582873 -352.91168)
			(xy 183.610758 -352.911156) (xy 183.63718 -352.91159) (xy 183.689497 -352.919048) (xy 183.740235 -352.933819)
			(xy 183.788379 -352.955607) (xy 183.832963 -352.983977) (xy 183.853328 -353.000818) (xy 183.860186 -353.00666)
			(xy 183.877204 -353.01301) (xy 183.961532 -353.01301) (xy 183.97855 -353.00666) (xy 183.985408 -353.000818)
			(xy 184.005774 -352.983979) (xy 184.05036 -352.955614) (xy 184.098504 -352.933827) (xy 184.149241 -352.919056)
			(xy 184.201556 -352.911596) (xy 184.2544 -352.911596) (xy 184.306715 -352.919056) (xy 184.357452 -352.933827)
			(xy 184.405596 -352.955614) (xy 184.450182 -352.983979) (xy 184.470548 -353.000818) (xy 184.477406 -353.00666)
			(xy 184.494424 -353.01301) (xy 184.578752 -353.01301) (xy 184.59577 -353.00666) (xy 184.602628 -353.000818)
			(xy 184.614414 -352.990981) (xy 184.639338 -352.973051) (xy 184.652412 -352.965004) (xy 184.652666 -352.96475)
			(xy 184.661833 -352.958508) (xy 184.674091 -352.94006) (xy 184.676288 -352.92919) (xy 184.690004 -352.840798)
			(xy 184.683654 -352.819208) (xy 184.676034 -352.810826) (xy 184.658169 -352.789823) (xy 184.62806 -352.743633)
			(xy 184.604911 -352.69359) (xy 184.589205 -352.640736) (xy 184.58127 -352.586173) (xy 184.580784 -352.558604)
			(xy 184.581258 -352.53103) (xy 184.58921 -352.476458) (xy 184.604933 -352.423598) (xy 184.628102 -352.373552)
			(xy 184.658233 -352.327362) (xy 184.694698 -352.28599) (xy 184.715404 -352.267774) (xy 184.723492 -352.26023)
			(xy 184.732839 -352.24021) (xy 184.733438 -352.229166) (xy 184.733438 -352.151442) (xy 184.732866 -352.140393)
			(xy 184.723506 -352.12037) (xy 184.715404 -352.112834) (xy 184.694707 -352.094608) (xy 184.658235 -352.053242)
			(xy 184.628101 -352.007055) (xy 184.604933 -351.95701) (xy 184.589214 -351.904151) (xy 184.581271 -351.849578)
			(xy 184.580784 -351.822004) (xy 184.58127 -351.794753) (xy 184.589026 -351.740805) (xy 184.604381 -351.68851)
			(xy 184.627023 -351.638933) (xy 184.656489 -351.593083) (xy 184.69218 -351.551892) (xy 184.733371 -351.516201)
			(xy 184.779221 -351.486735) (xy 184.828798 -351.464093) (xy 184.881093 -351.448738) (xy 184.935041 -351.440982)
			(xy 184.989543 -351.440982) (xy 185.043491 -351.448738) (xy 185.095786 -351.464093) (xy 185.145363 -351.486735)
			(xy 185.191213 -351.516201) (xy 185.232404 -351.551892) (xy 185.268095 -351.593083) (xy 185.297561 -351.638933)
			(xy 185.320203 -351.68851) (xy 185.335558 -351.740805) (xy 185.343314 -351.794753) (xy 185.3438 -351.822004)
			(xy 185.343337 -351.849579) (xy 185.335384 -351.904152) (xy 185.319658 -351.957012) (xy 185.296488 -352.007057)
			(xy 185.266355 -352.053247) (xy 185.229887 -352.094618) (xy 185.20918 -352.112834) (xy 185.201086 -352.120372)
			(xy 185.191743 -352.140397) (xy 185.191146 -352.151442) (xy 185.191146 -352.229166) (xy 185.191719 -352.240215)
			(xy 185.201079 -352.260237) (xy 185.20918 -352.267774) (xy 185.229878 -352.286) (xy 185.26635 -352.327365)
			(xy 185.296484 -352.373552) (xy 185.319653 -352.423597) (xy 185.335372 -352.476457) (xy 185.343314 -352.53103)
			(xy 185.3438 -352.558604) (xy 185.343259 -352.587026) (xy 185.334845 -352.643242) (xy 185.318173 -352.697584)
			(xy 185.293614 -352.748848) (xy 185.261712 -352.795894) (xy 185.223177 -352.83768) (xy 185.178861 -352.873278)
			(xy 185.15457 -352.888042) (xy 185.144664 -352.89363) (xy 185.131964 -352.912172) (xy 185.121245 -352.975672)
			(xy 187.181998 -352.975672) (xy 187.182472 -352.94776) (xy 187.190611 -352.892534) (xy 187.20671 -352.839083)
			(xy 187.230427 -352.788548) (xy 187.261255 -352.742009) (xy 187.279534 -352.72091) (xy 187.285431 -352.713733)
			(xy 187.292081 -352.696407) (xy 187.292488 -352.687128) (xy 187.292488 -352.609404) (xy 187.285884 -352.592132)
			(xy 187.279534 -352.58502) (xy 187.261234 -352.563939) (xy 187.230412 -352.517395) (xy 187.206702 -352.466855)
			(xy 187.19061 -352.4134) (xy 187.182481 -352.35817) (xy 187.181998 -352.330258) (xy 187.182484 -352.303007)
			(xy 187.19024 -352.249059) (xy 187.205595 -352.196764) (xy 187.228237 -352.147187) (xy 187.257703 -352.101337)
			(xy 187.293394 -352.060146) (xy 187.334585 -352.024455) (xy 187.380435 -351.994989) (xy 187.430012 -351.972347)
			(xy 187.482307 -351.956992) (xy 187.536255 -351.949236) (xy 187.590757 -351.949236) (xy 187.644705 -351.956992)
			(xy 187.697 -351.972347) (xy 187.746577 -351.994989) (xy 187.792427 -352.024455) (xy 187.833618 -352.060146)
			(xy 187.869309 -352.101337) (xy 187.898775 -352.147187) (xy 187.921417 -352.196764) (xy 187.936772 -352.249059)
			(xy 187.944528 -352.303007) (xy 187.945014 -352.330258) (xy 187.944555 -352.35817) (xy 187.936412 -352.413397)
			(xy 187.920309 -352.466848) (xy 187.896589 -352.517383) (xy 187.865758 -352.563921) (xy 187.847478 -352.58502)
			(xy 187.84157 -352.592189) (xy 187.834926 -352.609521) (xy 187.834524 -352.618802) (xy 187.834524 -352.696526)
			(xy 187.841128 -352.713798) (xy 187.847478 -352.72091) (xy 187.865731 -352.74203) (xy 187.896563 -352.788562)
			(xy 187.920284 -352.839092) (xy 187.936386 -352.892539) (xy 187.944526 -352.947762) (xy 187.945014 -352.975672)
			(xy 187.944528 -353.002923) (xy 187.936772 -353.056871) (xy 187.921417 -353.109166) (xy 187.898775 -353.158743)
			(xy 187.869309 -353.204593) (xy 187.833618 -353.245784) (xy 187.792427 -353.281475) (xy 187.749286 -353.3092)
			(xy 191.564233 -353.3092) (xy 191.568401 -353.253584) (xy 191.580811 -353.19921) (xy 191.601187 -353.147293)
			(xy 191.629072 -353.098992) (xy 191.663845 -353.055387) (xy 191.704728 -353.017452) (xy 191.750809 -352.986033)
			(xy 191.801057 -352.961833) (xy 191.854351 -352.945392) (xy 191.9095 -352.937078) (xy 191.937386 -352.936556)
			(xy 191.963807 -352.937032) (xy 192.016121 -352.944479) (xy 192.066859 -352.959241) (xy 192.115004 -352.98102)
			(xy 192.15959 -353.009381) (xy 192.179956 -353.026218) (xy 192.186814 -353.03206) (xy 192.203832 -353.03841)
			(xy 192.28816 -353.03841) (xy 192.305178 -353.03206) (xy 192.312036 -353.026218) (xy 192.332402 -353.009379)
			(xy 192.376988 -352.981014) (xy 192.425132 -352.959227) (xy 192.475869 -352.944456) (xy 192.528184 -352.936996)
			(xy 192.581028 -352.936996) (xy 192.633343 -352.944456) (xy 192.68408 -352.959227) (xy 192.732224 -352.981014)
			(xy 192.77681 -353.009379) (xy 192.797176 -353.026218) (xy 192.804034 -353.03206) (xy 192.821052 -353.03841)
			(xy 192.90538 -353.03841) (xy 192.922398 -353.03206) (xy 192.929256 -353.026218) (xy 192.943154 -353.014639)
			(xy 192.972794 -352.993899) (xy 192.988438 -352.984816) (xy 192.998264 -352.978642) (xy 193.011493 -352.959605)
			(xy 193.013838 -352.94824) (xy 193.0273 -352.857054) (xy 193.020442 -352.834956) (xy 193.012314 -352.82632)
			(xy 192.992734 -352.804937) (xy 192.959615 -352.757351) (xy 192.934083 -352.705299) (xy 192.916729 -352.649981)
			(xy 192.907952 -352.592672) (xy 192.907412 -352.563684) (xy 192.907931 -352.536111) (xy 192.915872 -352.481541)
			(xy 192.931586 -352.428682) (xy 192.954746 -352.378635) (xy 192.98487 -352.332444) (xy 193.021329 -352.291071)
			(xy 193.042032 -352.272854) (xy 193.050133 -352.265323) (xy 193.059472 -352.245293) (xy 193.060066 -352.234246)
			(xy 193.060066 -352.156522) (xy 193.059497 -352.145473) (xy 193.050133 -352.125451) (xy 193.042032 -352.117914)
			(xy 193.021331 -352.099692) (xy 192.984858 -352.058326) (xy 192.954724 -352.012139) (xy 192.931556 -351.962093)
			(xy 192.915838 -351.909232) (xy 192.907898 -351.854658) (xy 192.907412 -351.827084) (xy 192.907898 -351.799833)
			(xy 192.915654 -351.745885) (xy 192.931009 -351.69359) (xy 192.953651 -351.644013) (xy 192.983117 -351.598163)
			(xy 193.018808 -351.556972) (xy 193.059999 -351.521281) (xy 193.105849 -351.491815) (xy 193.155426 -351.469173)
			(xy 193.207721 -351.453818) (xy 193.261669 -351.446062) (xy 193.316171 -351.446062) (xy 193.370119 -351.453818)
			(xy 193.422414 -351.469173) (xy 193.471991 -351.491815) (xy 193.517841 -351.521281) (xy 193.559032 -351.556972)
			(xy 193.594723 -351.598163) (xy 193.624189 -351.644013) (xy 193.646831 -351.69359) (xy 193.662186 -351.745885)
			(xy 193.669942 -351.799833) (xy 193.670428 -351.827084) (xy 193.669942 -351.854658) (xy 193.661992 -351.909229)
			(xy 193.64627 -351.962088) (xy 193.623104 -352.012134) (xy 193.592976 -352.058324) (xy 193.556513 -352.099697)
			(xy 193.535808 -352.117914) (xy 193.527727 -352.125465) (xy 193.518376 -352.145479) (xy 193.517774 -352.156522)
			(xy 193.517774 -352.234246) (xy 193.518349 -352.245295) (xy 193.527707 -352.265318) (xy 193.535808 -352.272854)
			(xy 193.556502 -352.291084) (xy 193.592973 -352.332449) (xy 193.623107 -352.378635) (xy 193.646276 -352.428679)
			(xy 193.661996 -352.481538) (xy 193.66994 -352.53611) (xy 193.670428 -352.563684) (xy 193.669837 -352.592875)
			(xy 193.660932 -352.650574) (xy 193.643341 -352.706243) (xy 193.617476 -352.758583) (xy 193.583941 -352.806372)
			(xy 193.543517 -352.848496) (xy 193.497149 -352.88397) (xy 193.4718 -352.898456) (xy 193.461878 -352.904519)
			(xy 193.448379 -352.923421) (xy 193.445892 -352.934778) (xy 193.430906 -353.02571) (xy 193.437764 -353.047808)
			(xy 193.445638 -353.056444) (xy 193.464098 -353.077219) (xy 193.495309 -353.123201) (xy 193.519344 -353.173309)
			(xy 193.535671 -353.22643) (xy 193.543929 -353.281387) (xy 193.544444 -353.309174) (xy 193.543919 -353.335788)
			(xy 193.536348 -353.388476) (xy 193.521355 -353.43955) (xy 193.499246 -353.48797) (xy 193.470472 -353.53275)
			(xy 193.435617 -353.572981) (xy 193.395392 -353.607841) (xy 193.350615 -353.636621) (xy 193.302198 -353.658737)
			(xy 193.251127 -353.673737) (xy 193.19844 -353.681316) (xy 193.171826 -353.681792) (xy 193.145405 -353.681321)
			(xy 193.09309 -353.673875) (xy 193.042351 -353.659113) (xy 192.994207 -353.637332) (xy 192.949621 -353.608969)
			(xy 192.929256 -353.59213) (xy 192.922398 -353.586288) (xy 192.90538 -353.579938) (xy 192.821052 -353.579938)
			(xy 192.804034 -353.586288) (xy 192.797176 -353.59213) (xy 192.77681 -353.608969) (xy 192.732224 -353.637334)
			(xy 192.68408 -353.659121) (xy 192.633343 -353.673892) (xy 192.581028 -353.681352) (xy 192.528184 -353.681352)
			(xy 192.475869 -353.673892) (xy 192.425132 -353.659121) (xy 192.376988 -353.637334) (xy 192.332402 -353.608969)
			(xy 192.312036 -353.59213) (xy 192.305178 -353.586288) (xy 192.28816 -353.579938) (xy 192.203832 -353.579938)
			(xy 192.186814 -353.586288) (xy 192.179956 -353.59213) (xy 192.159598 -353.608978) (xy 192.115007 -353.637334)
			(xy 192.066861 -353.659112) (xy 192.016122 -353.673877) (xy 191.963808 -353.681334) (xy 191.937386 -353.681792)
			(xy 191.9095 -353.681322) (xy 191.854351 -353.673008) (xy 191.801057 -353.656567) (xy 191.750809 -353.632367)
			(xy 191.704728 -353.600948) (xy 191.663845 -353.563013) (xy 191.629072 -353.519408) (xy 191.601187 -353.471107)
			(xy 191.580811 -353.41919) (xy 191.568401 -353.364816) (xy 191.564233 -353.3092) (xy 187.749286 -353.3092)
			(xy 187.746577 -353.310941) (xy 187.697 -353.333583) (xy 187.644705 -353.348938) (xy 187.590757 -353.356694)
			(xy 187.536255 -353.356694) (xy 187.482307 -353.348938) (xy 187.430012 -353.333583) (xy 187.380435 -353.310941)
			(xy 187.334585 -353.281475) (xy 187.293394 -353.245784) (xy 187.257703 -353.204593) (xy 187.228237 -353.158743)
			(xy 187.205595 -353.109166) (xy 187.19024 -353.056871) (xy 187.182484 -353.002923) (xy 187.181998 -352.975672)
			(xy 185.121245 -352.975672) (xy 185.1152 -353.011486) (xy 185.121296 -353.033076) (xy 185.128662 -353.041712)
			(xy 185.145403 -353.062036) (xy 185.173607 -353.106501) (xy 185.195266 -353.154496) (xy 185.209948 -353.205062)
			(xy 185.217362 -353.257192) (xy 185.217816 -353.28352) (xy 185.217816 -353.283774) (xy 185.217342 -353.310391)
			(xy 185.209769 -353.363084) (xy 185.194774 -353.414163) (xy 185.172662 -353.462588) (xy 185.143883 -353.507373)
			(xy 185.109023 -353.547606) (xy 185.068792 -353.582469) (xy 185.024009 -353.61125) (xy 184.975586 -353.633366)
			(xy 184.924508 -353.648364) (xy 184.871815 -353.65594) (xy 184.845198 -353.656392) (xy 184.818776 -353.655937)
			(xy 184.76646 -353.648487) (xy 184.715722 -353.633721) (xy 184.667577 -353.611937) (xy 184.622993 -353.58357)
			(xy 184.602628 -353.56673) (xy 184.59577 -353.560888) (xy 184.578752 -353.554538) (xy 184.494424 -353.554538)
			(xy 184.477406 -353.560888) (xy 184.470548 -353.56673) (xy 184.450182 -353.583569) (xy 184.405596 -353.611934)
			(xy 184.357452 -353.633721) (xy 184.306715 -353.648492) (xy 184.2544 -353.655952) (xy 184.201556 -353.655952)
			(xy 184.149241 -353.648492) (xy 184.098504 -353.633721) (xy 184.05036 -353.611934) (xy 184.005774 -353.583569)
			(xy 183.985408 -353.56673) (xy 183.97855 -353.560888) (xy 183.961532 -353.554538) (xy 183.877204 -353.554538)
			(xy 183.860186 -353.560888) (xy 183.853328 -353.56673) (xy 183.832943 -353.583544) (xy 183.78836 -353.611905)
			(xy 183.74022 -353.63369) (xy 183.689487 -353.648463) (xy 183.637178 -353.655929) (xy 183.610758 -353.656392)
			(xy 183.582873 -353.65592) (xy 183.527727 -353.647602) (xy 183.474437 -353.631159) (xy 183.424192 -353.606958)
			(xy 183.378116 -353.575538) (xy 183.337236 -353.537603) (xy 183.302466 -353.493999) (xy 183.274583 -353.4457)
			(xy 183.25421 -353.393785) (xy 183.241801 -353.339414) (xy 183.237633 -353.2838) (xy 179.422658 -353.2838)
			(xy 179.419949 -353.285541) (xy 179.370372 -353.308183) (xy 179.318077 -353.323538) (xy 179.264129 -353.331294)
			(xy 179.209627 -353.331294) (xy 179.155679 -353.323538) (xy 179.103384 -353.308183) (xy 179.053807 -353.285541)
			(xy 179.007957 -353.256075) (xy 178.966766 -353.220384) (xy 178.931075 -353.179193) (xy 178.901609 -353.133343)
			(xy 178.878967 -353.083766) (xy 178.863612 -353.031471) (xy 178.855856 -352.977523) (xy 178.85537 -352.950272)
			(xy 170.133772 -352.950272) (xy 170.133772 -354.017326) (xy 170.134165 -354.027399) (xy 170.141906 -354.045998)
			(xy 170.148758 -354.053394) (xy 170.277282 -354.181918) (xy 179.813202 -354.181918) (xy 179.817273 -354.126296)
			(xy 179.829399 -354.071859) (xy 179.849322 -354.019768) (xy 179.876618 -353.971133) (xy 179.910704 -353.92699)
			(xy 179.950853 -353.888281) (xy 179.996211 -353.85583) (xy 180.045811 -353.830329) (xy 180.098595 -353.812322)
			(xy 180.153438 -353.802192) (xy 180.209172 -353.800155) (xy 180.264609 -353.806255) (xy 180.318566 -353.820361)
			(xy 180.369895 -353.842173) (xy 180.417501 -353.871227) (xy 180.460369 -353.906902) (xy 180.497586 -353.948439)
			(xy 180.528359 -353.994952) (xy 180.552031 -354.045449) (xy 180.568099 -354.098856) (xy 180.576219 -354.154032)
			(xy 180.576728 -354.181918) (xy 180.576219 -354.209804) (xy 180.568099 -354.26498) (xy 180.552031 -354.318387)
			(xy 180.528359 -354.368884) (xy 180.497586 -354.415397) (xy 180.460369 -354.456934) (xy 180.417501 -354.492609)
			(xy 180.369895 -354.521663) (xy 180.318566 -354.543475) (xy 180.264609 -354.557581) (xy 180.209172 -354.563681)
			(xy 180.153438 -354.561644) (xy 180.098595 -354.551514) (xy 180.045811 -354.533507) (xy 179.996211 -354.508006)
			(xy 179.950853 -354.475555) (xy 179.910704 -354.436846) (xy 179.876618 -354.392703) (xy 179.849322 -354.344068)
			(xy 179.829399 -354.291977) (xy 179.817273 -354.23754) (xy 179.813202 -354.181918) (xy 170.277282 -354.181918)
			(xy 170.70451 -354.609146) (xy 170.711907 -354.615989) (xy 170.730509 -354.623706) (xy 170.740578 -354.624132)
			(xy 176.827942 -354.624132) (xy 176.837819 -354.623663) (xy 176.856118 -354.616229) (xy 176.863502 -354.609654)
			(xy 176.86401 -354.609146) (xy 176.864518 -354.608638) (xy 176.888425 -354.585526) (xy 176.941211 -354.545087)
			(xy 176.998818 -354.511875) (xy 177.060264 -354.486455) (xy 177.124498 -354.469263) (xy 177.190426 -354.460591)
			(xy 177.223674 -354.460048) (xy 177.25439 -354.460516) (xy 177.315375 -354.467918) (xy 177.375023 -354.482617)
			(xy 177.432465 -354.504399) (xy 177.486861 -354.532946) (xy 177.537421 -354.567842) (xy 177.583405 -354.608579)
			(xy 177.624143 -354.654561) (xy 177.659041 -354.705118) (xy 177.687591 -354.759513) (xy 177.709376 -354.816954)
			(xy 177.724078 -354.876601) (xy 177.731483 -354.937586) (xy 177.731928 -354.968302) (xy 177.731631 -354.987352)
			(xy 179.031136 -354.987352) (xy 179.035207 -354.93173) (xy 179.047333 -354.877293) (xy 179.067256 -354.825202)
			(xy 179.094552 -354.776567) (xy 179.128638 -354.732424) (xy 179.168787 -354.693715) (xy 179.214145 -354.661264)
			(xy 179.263745 -354.635763) (xy 179.316529 -354.617756) (xy 179.371372 -354.607626) (xy 179.427106 -354.605589)
			(xy 179.482543 -354.611689) (xy 179.5365 -354.625795) (xy 179.587829 -354.647607) (xy 179.635435 -354.676661)
			(xy 179.678303 -354.712336) (xy 179.71552 -354.753873) (xy 179.746293 -354.800386) (xy 179.769965 -354.850883)
			(xy 179.786033 -354.90429) (xy 179.794153 -354.959466) (xy 179.794662 -354.987352) (xy 179.794153 -355.015238)
			(xy 179.786033 -355.070414) (xy 179.769965 -355.123821) (xy 179.746293 -355.174318) (xy 179.71552 -355.220831)
			(xy 179.678303 -355.262368) (xy 179.635435 -355.298043) (xy 179.587829 -355.327097) (xy 179.5365 -355.348909)
			(xy 179.482543 -355.363015) (xy 179.427106 -355.369115) (xy 179.371372 -355.367078) (xy 179.316529 -355.356948)
			(xy 179.263745 -355.338941) (xy 179.214145 -355.31344) (xy 179.168787 -355.280989) (xy 179.128638 -355.24228)
			(xy 179.094552 -355.198137) (xy 179.067256 -355.149502) (xy 179.047333 -355.097411) (xy 179.035207 -355.042974)
			(xy 179.031136 -354.987352) (xy 177.731631 -354.987352) (xy 177.731409 -355.001582) (xy 177.722732 -355.067574)
			(xy 177.705512 -355.131868) (xy 177.680045 -355.193363) (xy 177.646768 -355.251006) (xy 177.606249 -355.303812)
			(xy 177.583084 -355.327712) (xy 177.426366 -355.48443) (xy 177.846988 -355.48443) (xy 177.851059 -355.428808)
			(xy 177.863185 -355.374371) (xy 177.883108 -355.32228) (xy 177.910404 -355.273645) (xy 177.94449 -355.229502)
			(xy 177.984639 -355.190793) (xy 178.029997 -355.158342) (xy 178.079597 -355.132841) (xy 178.132381 -355.114834)
			(xy 178.187224 -355.104704) (xy 178.242958 -355.102667) (xy 178.298395 -355.108767) (xy 178.352352 -355.122873)
			(xy 178.403681 -355.144685) (xy 178.451287 -355.173739) (xy 178.494155 -355.209414) (xy 178.531372 -355.250951)
			(xy 178.562145 -355.297464) (xy 178.585817 -355.347961) (xy 178.601885 -355.401368) (xy 178.610005 -355.456544)
			(xy 178.610514 -355.48443) (xy 178.610005 -355.512316) (xy 178.601885 -355.567492) (xy 178.585817 -355.620899)
			(xy 178.562145 -355.671396) (xy 178.531372 -355.717909) (xy 178.494155 -355.759446) (xy 178.451287 -355.795121)
			(xy 178.403681 -355.824175) (xy 178.352352 -355.845987) (xy 178.298395 -355.860093) (xy 178.242958 -355.866193)
			(xy 178.187224 -355.864156) (xy 178.132381 -355.854026) (xy 178.079597 -355.836019) (xy 178.029997 -355.810518)
			(xy 177.984639 -355.778067) (xy 177.94449 -355.739358) (xy 177.910404 -355.695215) (xy 177.883108 -355.64658)
			(xy 177.863185 -355.594489) (xy 177.851059 -355.540052) (xy 177.846988 -355.48443) (xy 177.426366 -355.48443)
			(xy 177.418746 -355.49205) (xy 177.394843 -355.515224) (xy 177.342052 -355.555787) (xy 177.284416 -355.58911)
			(xy 177.222923 -355.614623) (xy 177.158625 -355.631889) (xy 177.092624 -355.640612) (xy 177.059336 -355.641148)
			(xy 170.50893 -355.641148) (xy 170.475644 -355.640611) (xy 170.409649 -355.631867) (xy 170.345357 -355.61459)
			(xy 170.283868 -355.589076) (xy 170.226232 -355.55576) (xy 170.173433 -355.515211) (xy 170.14952 -355.49205)
			(xy 169.265854 -354.608384) (xy 169.242651 -354.584508) (xy 169.202091 -354.531711) (xy 169.168772 -354.47407)
			(xy 169.143264 -354.412571) (xy 169.126004 -354.348269) (xy 169.117289 -354.282263) (xy 169.116756 -354.248974)
			(xy 169.116756 -351.48012) (xy 169.117318 -351.447134) (xy 169.125895 -351.381722) (xy 169.142856 -351.317968)
			(xy 169.167916 -351.25694) (xy 169.200655 -351.199665) (xy 169.240523 -351.147102) (xy 169.263314 -351.12325)
			(xy 169.263568 -351.122996) (xy 169.270018 -351.115624) (xy 169.277339 -351.097474) (xy 169.277792 -351.08769)
			(xy 169.277792 -351.045018) (xy 169.248074 -351.0153) (xy 169.227246 -351.0153) (xy 169.218497 -351.015639)
			(xy 169.202006 -351.021493) (xy 169.194988 -351.02673) (xy 169.194734 -351.026984) (xy 169.174181 -351.04335)
			(xy 169.129412 -351.070846) (xy 169.081291 -351.091934) (xy 169.03073 -351.106215) (xy 168.978688 -351.113418)
			(xy 168.952418 -351.113852) (xy 168.925167 -351.113302) (xy 168.871221 -351.105548) (xy 168.818927 -351.090195)
			(xy 168.76935 -351.067556) (xy 168.7235 -351.038092) (xy 168.68231 -351.002403) (xy 168.646618 -350.961214)
			(xy 168.617152 -350.915366) (xy 168.594511 -350.86579) (xy 168.579156 -350.813497) (xy 168.571399 -350.759551)
			(xy 168.571399 -350.705049) (xy 168.579156 -350.651103) (xy 168.594511 -350.59881) (xy 168.617152 -350.549234)
			(xy 168.646618 -350.503386) (xy 168.68231 -350.462197) (xy 168.7235 -350.426508) (xy 168.76935 -350.397044)
			(xy 168.818927 -350.374405) (xy 168.871221 -350.359052) (xy 168.925167 -350.351298) (xy 168.952418 -350.350836)
			(xy 168.98307 -350.351448) (xy 169.043586 -350.361253) (xy 169.101756 -350.380608) (xy 169.129202 -350.39427)
			(xy 169.137069 -350.397997) (xy 169.154301 -350.400404) (xy 169.17135 -350.396929) (xy 169.178986 -350.392746)
			(xy 169.253408 -350.347534) (xy 169.260676 -350.342738) (xy 169.271632 -350.329211) (xy 169.277443 -350.312803)
			(xy 169.277792 -350.3041) (xy 169.277792 -350.275652) (xy 169.277351 -350.26564) (xy 169.269674 -350.247146)
			(xy 169.255507 -350.232994) (xy 169.237004 -350.225338) (xy 169.226992 -350.224852) (xy 168.952418 -350.224852)
			(xy 168.920458 -350.224284) (xy 168.857041 -350.216275) (xy 168.795128 -350.20038) (xy 168.735695 -350.176851)
			(xy 168.679681 -350.146059) (xy 168.627967 -350.108488) (xy 168.58137 -350.064732) (xy 168.540625 -350.015481)
			(xy 168.506374 -349.961512) (xy 168.479157 -349.903675) (xy 168.459404 -349.842883) (xy 168.447426 -349.780094)
			(xy 168.443412 -349.7163) (xy 166.88054 -349.7163) (xy 166.88054 -351.487486) (xy 166.880123 -351.497557)
			(xy 166.872398 -351.516155) (xy 166.865554 -351.523554) (xy 165.736524 -352.652838) (xy 165.729114 -352.659665)
			(xy 165.710522 -352.667391) (xy 165.700456 -352.667824) (xy 159.65678 -352.667824) (xy 159.646707 -352.667429)
			(xy 159.628108 -352.659689) (xy 159.620712 -352.652838) (xy 158.965646 -351.997772) (xy 158.958808 -351.99037)
			(xy 158.951085 -351.971773) (xy 158.95066 -351.961704) (xy 158.95066 -351.878646) (xy 158.950229 -351.867923)
			(xy 158.941552 -351.848319) (xy 158.933896 -351.8408) (xy 158.878016 -351.790508) (xy 158.869812 -351.78367)
			(xy 158.849562 -351.776952) (xy 158.8389 -351.777554) (xy 158.838646 -351.777554) (xy 158.828894 -351.778498)
			(xy 158.809327 -351.779516) (xy 158.79953 -351.779586) (xy 158.772274 -351.779169) (xy 158.718317 -351.771415)
			(xy 158.666012 -351.756061) (xy 158.616425 -351.733419) (xy 158.570566 -351.70395) (xy 158.529367 -351.668254)
			(xy 158.493668 -351.627058) (xy 158.464196 -351.581201) (xy 158.44155 -351.531616) (xy 158.426191 -351.479313)
			(xy 158.418433 -351.425356) (xy 158.418433 -351.370844) (xy 158.426191 -351.316887) (xy 158.44155 -351.264584)
			(xy 158.464196 -351.214999) (xy 158.493668 -351.169142) (xy 158.529367 -351.127946) (xy 158.570566 -351.09225)
			(xy 158.616425 -351.062781) (xy 158.666012 -351.040139) (xy 158.718317 -351.024785) (xy 158.772274 -351.017031)
			(xy 158.79953 -351.01657) (xy 158.809327 -351.016633) (xy 158.828895 -351.017651) (xy 158.838646 -351.018602)
			(xy 158.8389 -351.018602) (xy 158.849547 -351.019079) (xy 158.869755 -351.012382) (xy 158.878016 -351.005648)
			(xy 158.933896 -350.955356) (xy 158.941438 -350.947756) (xy 158.950098 -350.928202) (xy 158.95066 -350.91751)
			(xy 158.95066 -350.562926) (xy 158.950027 -350.551509) (xy 158.940128 -350.530931) (xy 158.93161 -350.523302)
			(xy 158.869888 -350.473772) (xy 158.860548 -350.467135) (xy 158.838261 -350.461976) (xy 158.826962 -350.463866)
			(xy 158.806464 -350.468144) (xy 158.764841 -350.472726) (xy 158.743904 -350.47301) (xy 158.716651 -350.472543)
			(xy 158.6627 -350.464786) (xy 158.610402 -350.449431) (xy 158.560822 -350.426789) (xy 158.514968 -350.397321)
			(xy 158.473775 -350.361628) (xy 158.438081 -350.320435) (xy 158.408613 -350.274582) (xy 158.385971 -350.225002)
			(xy 158.370614 -350.172704) (xy 158.362857 -350.118753) (xy 158.362857 -350.064247) (xy 158.370614 -350.010296)
			(xy 158.385971 -349.957998) (xy 158.408613 -349.908418) (xy 158.438081 -349.862565) (xy 158.473775 -349.821372)
			(xy 158.514968 -349.785679) (xy 158.560822 -349.756211) (xy 158.610402 -349.733569) (xy 158.6627 -349.718214)
			(xy 158.716651 -349.710457) (xy 158.743904 -349.709994) (xy 158.764841 -349.710273) (xy 158.806465 -349.714858)
			(xy 158.826962 -349.719138) (xy 158.838261 -349.721058) (xy 158.860562 -349.715897) (xy 158.869888 -349.709232)
			(xy 158.93161 -349.659702) (xy 158.940131 -349.652075) (xy 158.95003 -349.631496) (xy 158.95066 -349.620078)
			(xy 158.95066 -349.266002) (xy 158.949943 -349.253942) (xy 158.938956 -349.232468) (xy 158.929578 -349.224854)
			(xy 158.853124 -349.169482) (xy 158.828994 -349.165672) (xy 158.81731 -349.169482) (xy 158.788285 -349.178466)
			(xy 158.728307 -349.188159) (xy 158.69793 -349.188786) (xy 158.670677 -349.188317) (xy 158.616725 -349.180563)
			(xy 158.564426 -349.16521) (xy 158.514844 -349.142569) (xy 158.46899 -349.113102) (xy 158.427797 -349.077409)
			(xy 158.392102 -349.036216) (xy 158.362635 -348.990363) (xy 158.339993 -348.940782) (xy 158.324638 -348.888483)
			(xy 158.316884 -348.834531) (xy 158.316422 -348.807278) (xy 158.316422 -348.80677) (xy 158.31689 -348.779931)
			(xy 158.324431 -348.726785) (xy 158.339359 -348.675225) (xy 158.34995 -348.65056) (xy 158.354268 -348.641162)
			(xy 158.354776 -348.620588) (xy 158.324042 -348.543372) (xy 158.319864 -348.534068) (xy 158.305579 -348.519533)
			(xy 158.296356 -348.515178) (xy 158.287212 -348.511368) (xy 158.27927 -348.507651) (xy 158.266332 -348.495834)
			(xy 158.258109 -348.48036) (xy 158.256478 -348.471744) (xy 158.256478 -345.12504) (xy 158.256047 -345.115019)
			(xy 158.248386 -345.096498) (xy 158.234217 -345.082324) (xy 158.215699 -345.074656) (xy 158.205678 -345.07424)
			(xy 154.771344 -345.07424) (xy 154.761276 -345.074678) (xy 154.742677 -345.082389) (xy 154.735276 -345.089226)
			(xy 153.435558 -346.38869) (xy 153.428724 -346.396095) (xy 153.421002 -346.414691) (xy 153.420572 -346.424758)
			(xy 153.420572 -347.260164) (xy 156.09138 -347.260164) (xy 156.095451 -347.204542) (xy 156.107577 -347.150105)
			(xy 156.1275 -347.098014) (xy 156.154796 -347.049379) (xy 156.188882 -347.005236) (xy 156.229031 -346.966527)
			(xy 156.274389 -346.934076) (xy 156.323989 -346.908575) (xy 156.376773 -346.890568) (xy 156.431616 -346.880438)
			(xy 156.48735 -346.878401) (xy 156.542787 -346.884501) (xy 156.596744 -346.898607) (xy 156.648073 -346.920419)
			(xy 156.695679 -346.949473) (xy 156.738547 -346.985148) (xy 156.775764 -347.026685) (xy 156.806537 -347.073198)
			(xy 156.830209 -347.123695) (xy 156.846277 -347.177102) (xy 156.854397 -347.232278) (xy 156.854906 -347.260164)
			(xy 156.854397 -347.28805) (xy 156.846277 -347.343226) (xy 156.830209 -347.396633) (xy 156.806537 -347.44713)
			(xy 156.775764 -347.493643) (xy 156.738547 -347.53518) (xy 156.695679 -347.570855) (xy 156.648073 -347.599909)
			(xy 156.596744 -347.621721) (xy 156.542787 -347.635827) (xy 156.48735 -347.641927) (xy 156.431616 -347.63989)
			(xy 156.376773 -347.62976) (xy 156.323989 -347.611753) (xy 156.274389 -347.586252) (xy 156.229031 -347.553801)
			(xy 156.188882 -347.515092) (xy 156.154796 -347.470949) (xy 156.1275 -347.422314) (xy 156.107577 -347.370223)
			(xy 156.095451 -347.315786) (xy 156.09138 -347.260164) (xy 153.420572 -347.260164) (xy 153.420572 -348.96806)
			(xy 154.087574 -348.96806) (xy 154.091645 -348.912438) (xy 154.103771 -348.858001) (xy 154.123694 -348.80591)
			(xy 154.15099 -348.757275) (xy 154.185076 -348.713132) (xy 154.225225 -348.674423) (xy 154.270583 -348.641972)
			(xy 154.320183 -348.616471) (xy 154.372967 -348.598464) (xy 154.42781 -348.588334) (xy 154.483544 -348.586297)
			(xy 154.538981 -348.592397) (xy 154.592938 -348.606503) (xy 154.644267 -348.628315) (xy 154.691873 -348.657369)
			(xy 154.734741 -348.693044) (xy 154.771958 -348.734581) (xy 154.802731 -348.781094) (xy 154.826403 -348.831591)
			(xy 154.842471 -348.884998) (xy 154.850591 -348.940174) (xy 154.8511 -348.96806) (xy 154.850591 -348.995946)
			(xy 154.842471 -349.051122) (xy 154.826403 -349.104529) (xy 154.802731 -349.155026) (xy 154.771958 -349.201539)
			(xy 154.734741 -349.243076) (xy 154.701393 -349.270828) (xy 156.241748 -349.270828) (xy 156.245819 -349.215206)
			(xy 156.257945 -349.160769) (xy 156.277868 -349.108678) (xy 156.305164 -349.060043) (xy 156.33925 -349.0159)
			(xy 156.379399 -348.977191) (xy 156.424757 -348.94474) (xy 156.474357 -348.919239) (xy 156.527141 -348.901232)
			(xy 156.581984 -348.891102) (xy 156.637718 -348.889065) (xy 156.693155 -348.895165) (xy 156.747112 -348.909271)
			(xy 156.798441 -348.931083) (xy 156.846047 -348.960137) (xy 156.888915 -348.995812) (xy 156.926132 -349.037349)
			(xy 156.956905 -349.083862) (xy 156.980577 -349.134359) (xy 156.996645 -349.187766) (xy 157.004765 -349.242942)
			(xy 157.005274 -349.270828) (xy 157.004765 -349.298714) (xy 156.996645 -349.35389) (xy 156.980577 -349.407297)
			(xy 156.956905 -349.457794) (xy 156.926132 -349.504307) (xy 156.888915 -349.545844) (xy 156.846047 -349.581519)
			(xy 156.798441 -349.610573) (xy 156.747112 -349.632385) (xy 156.693155 -349.646491) (xy 156.637718 -349.652591)
			(xy 156.581984 -349.650554) (xy 156.527141 -349.640424) (xy 156.474357 -349.622417) (xy 156.424757 -349.596916)
			(xy 156.379399 -349.564465) (xy 156.33925 -349.525756) (xy 156.305164 -349.481613) (xy 156.277868 -349.432978)
			(xy 156.257945 -349.380887) (xy 156.245819 -349.32645) (xy 156.241748 -349.270828) (xy 154.701393 -349.270828)
			(xy 154.691873 -349.278751) (xy 154.644267 -349.307805) (xy 154.592938 -349.329617) (xy 154.538981 -349.343723)
			(xy 154.483544 -349.349823) (xy 154.42781 -349.347786) (xy 154.372967 -349.337656) (xy 154.320183 -349.319649)
			(xy 154.270583 -349.294148) (xy 154.225225 -349.261697) (xy 154.185076 -349.222988) (xy 154.15099 -349.178845)
			(xy 154.123694 -349.13021) (xy 154.103771 -349.078119) (xy 154.091645 -349.023682) (xy 154.087574 -348.96806)
			(xy 153.420572 -348.96806) (xy 153.420572 -350.93021) (xy 153.420973 -350.940282) (xy 153.428709 -350.958881)
			(xy 153.435558 -350.966278) (xy 154.572208 -352.102928) (xy 156.238192 -352.102928) (xy 156.242263 -352.047306)
			(xy 156.254389 -351.992869) (xy 156.274312 -351.940778) (xy 156.301608 -351.892143) (xy 156.335694 -351.848)
			(xy 156.375843 -351.809291) (xy 156.421201 -351.77684) (xy 156.470801 -351.751339) (xy 156.523585 -351.733332)
			(xy 156.578428 -351.723202) (xy 156.634162 -351.721165) (xy 156.689599 -351.727265) (xy 156.743556 -351.741371)
			(xy 156.794885 -351.763183) (xy 156.842491 -351.792237) (xy 156.885359 -351.827912) (xy 156.922576 -351.869449)
			(xy 156.953349 -351.915962) (xy 156.977021 -351.966459) (xy 156.993089 -352.019866) (xy 157.001209 -352.075042)
			(xy 157.001718 -352.102928) (xy 157.001209 -352.130814) (xy 156.993089 -352.18599) (xy 156.977021 -352.239397)
			(xy 156.953349 -352.289894) (xy 156.922576 -352.336407) (xy 156.885359 -352.377944) (xy 156.842491 -352.413619)
			(xy 156.794885 -352.442673) (xy 156.743556 -352.464485) (xy 156.689599 -352.478591) (xy 156.634162 -352.484691)
			(xy 156.578428 -352.482654) (xy 156.523585 -352.472524) (xy 156.470801 -352.454517) (xy 156.421201 -352.429016)
			(xy 156.375843 -352.396565) (xy 156.335694 -352.357856) (xy 156.301608 -352.313713) (xy 156.274312 -352.265078)
			(xy 156.254389 -352.212987) (xy 156.242263 -352.15855) (xy 156.238192 -352.102928) (xy 154.572208 -352.102928)
			(xy 156.36367 -353.89439) (xy 157.69539 -353.89439) (xy 157.699461 -353.838768) (xy 157.711587 -353.784331)
			(xy 157.73151 -353.73224) (xy 157.758806 -353.683605) (xy 157.792892 -353.639462) (xy 157.833041 -353.600753)
			(xy 157.878399 -353.568302) (xy 157.927999 -353.542801) (xy 157.980783 -353.524794) (xy 158.035626 -353.514664)
			(xy 158.09136 -353.512627) (xy 158.146797 -353.518727) (xy 158.200754 -353.532833) (xy 158.252083 -353.554645)
			(xy 158.299689 -353.583699) (xy 158.342557 -353.619374) (xy 158.379774 -353.660911) (xy 158.410547 -353.707424)
			(xy 158.411153 -353.708716) (xy 159.770824 -353.708716) (xy 159.774895 -353.653094) (xy 159.787021 -353.598657)
			(xy 159.806944 -353.546566) (xy 159.83424 -353.497931) (xy 159.868326 -353.453788) (xy 159.908475 -353.415079)
			(xy 159.953833 -353.382628) (xy 160.003433 -353.357127) (xy 160.056217 -353.33912) (xy 160.11106 -353.32899)
			(xy 160.166794 -353.326953) (xy 160.219895 -353.332796) (xy 165.19474 -353.332796) (xy 165.198811 -353.277174)
			(xy 165.210937 -353.222737) (xy 165.23086 -353.170646) (xy 165.258156 -353.122011) (xy 165.292242 -353.077868)
			(xy 165.332391 -353.039159) (xy 165.377749 -353.006708) (xy 165.427349 -352.981207) (xy 165.480133 -352.9632)
			(xy 165.534976 -352.95307) (xy 165.59071 -352.951033) (xy 165.646147 -352.957133) (xy 165.700104 -352.971239)
			(xy 165.751433 -352.993051) (xy 165.799039 -353.022105) (xy 165.841907 -353.05778) (xy 165.879124 -353.099317)
			(xy 165.909897 -353.14583) (xy 165.933569 -353.196327) (xy 165.949637 -353.249734) (xy 165.957757 -353.30491)
			(xy 165.958266 -353.332796) (xy 165.957757 -353.360682) (xy 165.949637 -353.415858) (xy 165.933569 -353.469265)
			(xy 165.909897 -353.519762) (xy 165.879124 -353.566275) (xy 165.841907 -353.607812) (xy 165.799039 -353.643487)
			(xy 165.751433 -353.672541) (xy 165.700104 -353.694353) (xy 165.646147 -353.708459) (xy 165.59071 -353.714559)
			(xy 165.534976 -353.712522) (xy 165.480133 -353.702392) (xy 165.427349 -353.684385) (xy 165.377749 -353.658884)
			(xy 165.332391 -353.626433) (xy 165.292242 -353.587724) (xy 165.258156 -353.543581) (xy 165.23086 -353.494946)
			(xy 165.210937 -353.442855) (xy 165.198811 -353.388418) (xy 165.19474 -353.332796) (xy 160.219895 -353.332796)
			(xy 160.222231 -353.333053) (xy 160.276188 -353.347159) (xy 160.327517 -353.368971) (xy 160.375123 -353.398025)
			(xy 160.417991 -353.4337) (xy 160.455208 -353.475237) (xy 160.485981 -353.52175) (xy 160.509653 -353.572247)
			(xy 160.525721 -353.625654) (xy 160.533841 -353.68083) (xy 160.53435 -353.708716) (xy 160.533841 -353.736602)
			(xy 160.525721 -353.791778) (xy 160.509653 -353.845185) (xy 160.485981 -353.895682) (xy 160.471544 -353.917504)
			(xy 161.123628 -353.917504) (xy 161.127699 -353.861882) (xy 161.139825 -353.807445) (xy 161.159748 -353.755354)
			(xy 161.187044 -353.706719) (xy 161.22113 -353.662576) (xy 161.261279 -353.623867) (xy 161.306637 -353.591416)
			(xy 161.356237 -353.565915) (xy 161.409021 -353.547908) (xy 161.463864 -353.537778) (xy 161.519598 -353.535741)
			(xy 161.575035 -353.541841) (xy 161.628992 -353.555947) (xy 161.680321 -353.577759) (xy 161.727927 -353.606813)
			(xy 161.770795 -353.642488) (xy 161.808012 -353.684025) (xy 161.838785 -353.730538) (xy 161.862457 -353.781035)
			(xy 161.878525 -353.834442) (xy 161.886645 -353.889618) (xy 161.887154 -353.917504) (xy 161.886645 -353.94539)
			(xy 161.878525 -354.000566) (xy 161.862457 -354.053973) (xy 161.838785 -354.10447) (xy 161.808012 -354.150983)
			(xy 161.770795 -354.19252) (xy 161.727927 -354.228195) (xy 161.680321 -354.257249) (xy 161.628992 -354.279061)
			(xy 161.575035 -354.293167) (xy 161.519598 -354.299267) (xy 161.463864 -354.29723) (xy 161.409021 -354.2871)
			(xy 161.356237 -354.269093) (xy 161.306637 -354.243592) (xy 161.261279 -354.211141) (xy 161.22113 -354.172432)
			(xy 161.187044 -354.128289) (xy 161.159748 -354.079654) (xy 161.139825 -354.027563) (xy 161.127699 -353.973126)
			(xy 161.123628 -353.917504) (xy 160.471544 -353.917504) (xy 160.455208 -353.942195) (xy 160.417991 -353.983732)
			(xy 160.375123 -354.019407) (xy 160.327517 -354.048461) (xy 160.276188 -354.070273) (xy 160.222231 -354.084379)
			(xy 160.166794 -354.090479) (xy 160.11106 -354.088442) (xy 160.056217 -354.078312) (xy 160.003433 -354.060305)
			(xy 159.953833 -354.034804) (xy 159.908475 -354.002353) (xy 159.868326 -353.963644) (xy 159.83424 -353.919501)
			(xy 159.806944 -353.870866) (xy 159.787021 -353.818775) (xy 159.774895 -353.764338) (xy 159.770824 -353.708716)
			(xy 158.411153 -353.708716) (xy 158.434219 -353.757921) (xy 158.450287 -353.811328) (xy 158.458407 -353.866504)
			(xy 158.458916 -353.89439) (xy 158.458407 -353.922276) (xy 158.450287 -353.977452) (xy 158.434219 -354.030859)
			(xy 158.410547 -354.081356) (xy 158.379774 -354.127869) (xy 158.342557 -354.169406) (xy 158.299689 -354.205081)
			(xy 158.252083 -354.234135) (xy 158.200754 -354.255947) (xy 158.146797 -354.270053) (xy 158.09136 -354.276153)
			(xy 158.035626 -354.274116) (xy 157.980783 -354.263986) (xy 157.927999 -354.245979) (xy 157.878399 -354.220478)
			(xy 157.833041 -354.188027) (xy 157.792892 -354.149318) (xy 157.758806 -354.105175) (xy 157.73151 -354.05654)
			(xy 157.711587 -354.004449) (xy 157.699461 -353.950012) (xy 157.69539 -353.89439) (xy 156.36367 -353.89439)
			(xy 158.622746 -356.153466) (xy 158.630175 -356.16027) (xy 158.648752 -356.168012) (xy 158.658814 -356.168452)
			(xy 178.536092 -356.168452) (xy 178.546162 -356.168035) (xy 178.564761 -356.16031) (xy 178.57216 -356.153466)
			(xy 178.981862 -355.743764) (xy 178.999922 -355.726465) (xy 179.041475 -355.69865) (xy 179.087657 -355.679476)
			(xy 179.136692 -355.669681) (xy 179.161694 -355.669088) (xy 179.406042 -355.669088) (xy 179.416114 -355.668688)
			(xy 179.434712 -355.66095) (xy 179.44211 -355.654102) (xy 179.888642 -355.207824) (xy 179.90673 -355.190559)
			(xy 179.948277 -355.162749) (xy 179.994451 -355.143578) (xy 180.043477 -355.133783) (xy 180.068474 -355.133148)
			(xy 180.390546 -355.133148) (xy 180.400593 -355.132791) (xy 180.41919 -355.125194) (xy 180.426614 -355.118416)
			(xy 180.608986 -354.936044) (xy 180.62194 -354.923852) (xy 180.624641 -354.921373) (xy 180.62936 -354.915763)
			(xy 180.631338 -354.912676) (xy 180.646443 -354.889664) (xy 180.682168 -354.84779) (xy 180.723533 -354.811477)
			(xy 180.769683 -354.781478) (xy 180.819662 -354.758416) (xy 180.872433 -354.742766) (xy 180.926905 -354.734854)
			(xy 180.954426 -354.734368) (xy 180.981677 -354.734854) (xy 181.035623 -354.742613) (xy 181.087917 -354.75797)
			(xy 181.137492 -354.780613) (xy 181.183341 -354.810079) (xy 181.224531 -354.845771) (xy 181.260222 -354.88696)
			(xy 181.289688 -354.932809) (xy 181.312331 -354.982385) (xy 181.327687 -355.034679) (xy 181.335447 -355.088625)
			(xy 181.335934 -355.115876) (xy 181.335425 -355.14335) (xy 181.327537 -355.197728) (xy 181.311922 -355.25041)
			(xy 181.309272 -355.256154) (xy 181.577661 -355.256154) (xy 181.577661 -355.201646) (xy 181.585419 -355.147692)
			(xy 181.600777 -355.095392) (xy 181.623423 -355.045809) (xy 181.652894 -354.999955) (xy 181.688592 -354.958762)
			(xy 181.729789 -354.923069) (xy 181.775646 -354.893602) (xy 181.825231 -354.870963) (xy 181.877533 -354.85561)
			(xy 181.931488 -354.847858) (xy 181.958742 -354.847398) (xy 181.958996 -354.847398) (xy 181.9842 -354.847791)
			(xy 182.034168 -354.854432) (xy 182.082823 -354.86761) (xy 182.129312 -354.887095) (xy 182.151274 -354.899468)
			(xy 182.16118 -354.90531) (xy 182.183024 -354.907342) (xy 182.277766 -354.873814) (xy 182.293514 -354.85832)
			(xy 182.297578 -354.847906) (xy 182.308279 -354.821132) (xy 182.336565 -354.770889) (xy 182.372094 -354.725479)
			(xy 182.414055 -354.685936) (xy 182.461492 -354.653162) (xy 182.513322 -354.627904) (xy 182.568365 -354.610738)
			(xy 182.625365 -354.602055) (xy 182.654194 -354.601526) (xy 182.681448 -354.601961) (xy 182.735402 -354.609718)
			(xy 182.787702 -354.625075) (xy 182.837285 -354.647719) (xy 182.88314 -354.67719) (xy 182.924333 -354.712887)
			(xy 182.960027 -354.754083) (xy 182.989494 -354.79994) (xy 183.012135 -354.849524) (xy 183.024857 -354.892864)
			(xy 185.165746 -354.892864) (xy 185.16624 -354.86529) (xy 185.174184 -354.810718) (xy 185.189903 -354.757858)
			(xy 185.213067 -354.707811) (xy 185.243196 -354.661621) (xy 185.27966 -354.62025) (xy 185.300366 -354.602034)
			(xy 185.308437 -354.594475) (xy 185.317791 -354.574466) (xy 185.3184 -354.563426) (xy 185.3184 -354.485702)
			(xy 185.31783 -354.474653) (xy 185.308466 -354.454632) (xy 185.300366 -354.447094) (xy 185.279642 -354.428897)
			(xy 185.243174 -354.387524) (xy 185.213044 -354.341331) (xy 185.189881 -354.291281) (xy 185.174167 -354.238416)
			(xy 185.16623 -354.183839) (xy 185.165746 -354.156264) (xy 185.166244 -354.129014) (xy 185.174004 -354.075069)
			(xy 185.189362 -354.022777) (xy 185.212004 -353.973203) (xy 185.241469 -353.927355) (xy 185.277159 -353.886166)
			(xy 185.318347 -353.850476) (xy 185.364194 -353.821009) (xy 185.413768 -353.798365) (xy 185.466059 -353.783007)
			(xy 185.520004 -353.775245) (xy 185.547254 -353.774756) (xy 185.547762 -353.774756) (xy 185.581544 -353.77628)
			(xy 185.591704 -353.777296) (xy 185.611008 -353.7712) (xy 185.674 -353.718368) (xy 185.681282 -353.711637)
			(xy 185.690568 -353.694138) (xy 185.692034 -353.684332) (xy 185.692034 -353.68357) (xy 185.695048 -353.65543)
			(xy 185.708241 -353.600398) (xy 185.729422 -353.547919) (xy 185.758125 -353.499147) (xy 185.793721 -353.455152)
			(xy 185.835427 -353.4169) (xy 185.882328 -353.385232) (xy 185.933394 -353.360842) (xy 185.987504 -353.344266)
			(xy 186.043469 -353.335869) (xy 186.071764 -353.335336) (xy 186.072018 -353.335336) (xy 186.090037 -353.335559)
			(xy 186.125912 -353.338992) (xy 186.143646 -353.342194) (xy 186.153298 -353.343972) (xy 186.172348 -353.340416)
			(xy 186.247278 -353.29241) (xy 186.258708 -353.276662) (xy 186.260994 -353.267264) (xy 186.268418 -353.240228)
			(xy 186.290044 -353.188502) (xy 186.319005 -353.140498) (xy 186.354678 -353.097246) (xy 186.396293 -353.059678)
			(xy 186.442958 -353.028603) (xy 186.493666 -353.004689) (xy 186.547327 -352.98845) (xy 186.602786 -352.980236)
			(xy 186.630818 -352.979736) (xy 186.658073 -352.980138) (xy 186.712029 -352.987899) (xy 186.764331 -353.003259)
			(xy 186.813914 -353.025907) (xy 186.859769 -353.055381) (xy 186.900963 -353.091081) (xy 186.936656 -353.132281)
			(xy 186.966123 -353.178141) (xy 186.988762 -353.227728) (xy 187.004114 -353.280032) (xy 187.011866 -353.333989)
			(xy 187.012326 -353.361244) (xy 187.011813 -353.388817) (xy 187.003869 -353.443387) (xy 186.988152 -353.496246)
			(xy 186.964991 -353.546292) (xy 186.934868 -353.592482) (xy 186.898409 -353.633856) (xy 186.877706 -353.652074)
			(xy 186.869643 -353.65964) (xy 186.860282 -353.679643) (xy 186.859672 -353.690682) (xy 186.859672 -353.768406)
			(xy 186.86027 -353.779452) (xy 186.869612 -353.799475) (xy 186.877706 -353.807014) (xy 186.898428 -353.825213)
			(xy 186.934897 -353.866584) (xy 186.965028 -353.912777) (xy 186.988192 -353.962827) (xy 187.003906 -354.015692)
			(xy 187.011842 -354.070269) (xy 187.012326 -354.097844) (xy 187.011813 -354.125417) (xy 187.003869 -354.179987)
			(xy 186.995742 -354.207318) (xy 188.13983 -354.207318) (xy 188.143901 -354.151696) (xy 188.156027 -354.097259)
			(xy 188.17595 -354.045168) (xy 188.203246 -353.996533) (xy 188.237332 -353.95239) (xy 188.277481 -353.913681)
			(xy 188.322839 -353.88123) (xy 188.372439 -353.855729) (xy 188.425223 -353.837722) (xy 188.480066 -353.827592)
			(xy 188.5358 -353.825555) (xy 188.591237 -353.831655) (xy 188.645194 -353.845761) (xy 188.696523 -353.867573)
			(xy 188.744129 -353.896627) (xy 188.786997 -353.932302) (xy 188.824214 -353.973839) (xy 188.854987 -354.020352)
			(xy 188.878659 -354.070849) (xy 188.894727 -354.124256) (xy 188.902847 -354.179432) (xy 188.903356 -354.207318)
			(xy 188.902847 -354.235204) (xy 188.894727 -354.29038) (xy 188.878659 -354.343787) (xy 188.854987 -354.394284)
			(xy 188.824214 -354.440797) (xy 188.786997 -354.482334) (xy 188.744129 -354.518009) (xy 188.696523 -354.547063)
			(xy 188.645194 -354.568875) (xy 188.591237 -354.582981) (xy 188.5358 -354.589081) (xy 188.480066 -354.587044)
			(xy 188.425223 -354.576914) (xy 188.372439 -354.558907) (xy 188.322839 -354.533406) (xy 188.277481 -354.500955)
			(xy 188.237332 -354.462246) (xy 188.203246 -354.418103) (xy 188.17595 -354.369468) (xy 188.156027 -354.317377)
			(xy 188.143901 -354.26294) (xy 188.13983 -354.207318) (xy 186.995742 -354.207318) (xy 186.988152 -354.232846)
			(xy 186.964991 -354.282892) (xy 186.934868 -354.329082) (xy 186.898409 -354.370456) (xy 186.877706 -354.388674)
			(xy 186.869643 -354.39624) (xy 186.860282 -354.416243) (xy 186.859672 -354.427282) (xy 186.859672 -354.505006)
			(xy 186.86027 -354.516052) (xy 186.869612 -354.536075) (xy 186.877706 -354.543614) (xy 186.898428 -354.561813)
			(xy 186.934897 -354.603184) (xy 186.965028 -354.649377) (xy 186.988192 -354.699427) (xy 187.003906 -354.752292)
			(xy 187.011842 -354.806869) (xy 187.012326 -354.834444) (xy 187.011863 -354.861696) (xy 187.004101 -354.915643)
			(xy 186.988741 -354.967937) (xy 186.966096 -355.017513) (xy 186.936627 -355.063363) (xy 186.902567 -355.102668)
			(xy 187.56071 -355.102668) (xy 187.564781 -355.047046) (xy 187.576907 -354.992609) (xy 187.59683 -354.940518)
			(xy 187.624126 -354.891883) (xy 187.658212 -354.84774) (xy 187.698361 -354.809031) (xy 187.743719 -354.77658)
			(xy 187.793319 -354.751079) (xy 187.846103 -354.733072) (xy 187.900946 -354.722942) (xy 187.95668 -354.720905)
			(xy 188.012117 -354.727005) (xy 188.066074 -354.741111) (xy 188.117403 -354.762923) (xy 188.165009 -354.791977)
			(xy 188.207877 -354.827652) (xy 188.245094 -354.869189) (xy 188.275867 -354.915702) (xy 188.299539 -354.966199)
			(xy 188.315607 -355.019606) (xy 188.323727 -355.074782) (xy 188.324236 -355.102668) (xy 188.323727 -355.130554)
			(xy 188.315607 -355.18573) (xy 188.299539 -355.239137) (xy 188.275867 -355.289634) (xy 188.245094 -355.336147)
			(xy 188.207877 -355.377684) (xy 188.165009 -355.413359) (xy 188.117403 -355.442413) (xy 188.066074 -355.464225)
			(xy 188.012117 -355.478331) (xy 187.95668 -355.484431) (xy 187.900946 -355.482394) (xy 187.846103 -355.472264)
			(xy 187.793319 -355.454257) (xy 187.743719 -355.428756) (xy 187.698361 -355.396305) (xy 187.658212 -355.357596)
			(xy 187.624126 -355.313453) (xy 187.59683 -355.264818) (xy 187.576907 -355.212727) (xy 187.564781 -355.15829)
			(xy 187.56071 -355.102668) (xy 186.902567 -355.102668) (xy 186.900934 -355.104552) (xy 186.859742 -355.140243)
			(xy 186.813891 -355.169709) (xy 186.764313 -355.19235) (xy 186.712018 -355.207707) (xy 186.65807 -355.215465)
			(xy 186.630818 -355.215952) (xy 186.602962 -355.215448) (xy 186.547844 -355.207326) (xy 186.494491 -355.19128)
			(xy 186.444036 -355.167652) (xy 186.397551 -355.136943) (xy 186.356021 -355.099805) (xy 186.320329 -355.057026)
			(xy 186.291232 -355.009514) (xy 186.269348 -354.958279) (xy 186.261756 -354.931472) (xy 186.25947 -354.922582)
			(xy 186.248802 -354.907342) (xy 186.17692 -354.85959) (xy 186.158886 -354.855526) (xy 186.149742 -354.856796)
			(xy 186.136726 -354.858469) (xy 186.110541 -354.860246) (xy 186.097418 -354.860352) (xy 186.083269 -354.860256)
			(xy 186.055046 -354.858223) (xy 186.04103 -354.856288) (xy 186.031124 -354.854764) (xy 186.011312 -354.85959)
			(xy 185.93689 -354.91547) (xy 185.92673 -354.932996) (xy 185.92546 -354.943156) (xy 185.921339 -354.970304)
			(xy 185.906367 -355.023131) (xy 185.883977 -355.073266) (xy 185.854633 -355.119675) (xy 185.818939 -355.161398)
			(xy 185.777633 -355.197574) (xy 185.731569 -355.227457) (xy 185.681697 -355.250428) (xy 185.629048 -355.266013)
			(xy 185.574708 -355.273891) (xy 185.547254 -355.274372) (xy 185.52 -355.273965) (xy 185.466048 -355.266201)
			(xy 185.413749 -355.250838) (xy 185.364169 -355.228189) (xy 185.318317 -355.198715) (xy 185.277127 -355.163015)
			(xy 185.241436 -355.121817) (xy 185.211971 -355.075959) (xy 185.189333 -355.026374) (xy 185.173981 -354.974072)
			(xy 185.166229 -354.920118) (xy 185.165746 -354.892864) (xy 183.024857 -354.892864) (xy 183.027488 -354.901825)
			(xy 183.035241 -354.95578) (xy 183.035702 -354.983034) (xy 183.03504 -355.014597) (xy 183.024654 -355.076862)
			(xy 183.004169 -355.136571) (xy 182.989728 -355.164644) (xy 182.984902 -355.173534) (xy 182.98287 -355.193092)
			(xy 183.00573 -355.271578) (xy 183.008976 -355.280999) (xy 183.021387 -355.29656) (xy 183.02986 -355.301804)
			(xy 183.054938 -355.31639) (xy 183.100822 -355.351886) (xy 183.140799 -355.393923) (xy 183.173948 -355.44153)
			(xy 183.199503 -355.493609) (xy 183.216874 -355.548959) (xy 183.22566 -355.6063) (xy 183.226202 -355.635306)
			(xy 183.225716 -355.662557) (xy 183.21796 -355.716505) (xy 183.202605 -355.7688) (xy 183.179963 -355.818377)
			(xy 183.150497 -355.864227) (xy 183.114806 -355.905418) (xy 183.073615 -355.941109) (xy 183.027765 -355.970575)
			(xy 182.978188 -355.993217) (xy 182.925893 -356.008572) (xy 182.871945 -356.016328) (xy 182.817443 -356.016328)
			(xy 182.763495 -356.008572) (xy 182.7112 -355.993217) (xy 182.661623 -355.970575) (xy 182.615773 -355.941109)
			(xy 182.574582 -355.905418) (xy 182.538891 -355.864227) (xy 182.509425 -355.818377) (xy 182.486783 -355.7688)
			(xy 182.471428 -355.716505) (xy 182.463672 -355.662557) (xy 182.463186 -355.635306) (xy 182.463826 -355.603742)
			(xy 182.474222 -355.541477) (xy 182.494715 -355.481768) (xy 182.50916 -355.453696) (xy 182.513986 -355.444806)
			(xy 182.516018 -355.425248) (xy 182.493158 -355.346762) (xy 182.48994 -355.337329) (xy 182.477508 -355.321774)
			(xy 182.469028 -355.316536) (xy 182.461662 -355.312472) (xy 182.451756 -355.30663) (xy 182.429912 -355.304598)
			(xy 182.33517 -355.338126) (xy 182.319422 -355.35362) (xy 182.315358 -355.364034) (xy 182.304648 -355.390804)
			(xy 182.276361 -355.441044) (xy 182.240832 -355.486452) (xy 182.198872 -355.525994) (xy 182.151437 -355.558768)
			(xy 182.099608 -355.584027) (xy 182.044568 -355.601196) (xy 181.98757 -355.609882) (xy 181.958742 -355.610414)
			(xy 181.931488 -355.609942) (xy 181.877533 -355.60219) (xy 181.825231 -355.586837) (xy 181.775646 -355.564198)
			(xy 181.729789 -355.534731) (xy 181.688592 -355.499038) (xy 181.652894 -355.457845) (xy 181.623423 -355.411991)
			(xy 181.600777 -355.362408) (xy 181.585419 -355.310108) (xy 181.577661 -355.256154) (xy 181.309272 -355.256154)
			(xy 181.288903 -355.300303) (xy 181.258957 -355.346373) (xy 181.241192 -355.367336) (xy 181.240938 -355.36759)
			(xy 181.235342 -355.37467) (xy 181.229103 -355.391592) (xy 181.228746 -355.40061) (xy 181.228746 -355.468174)
			(xy 181.229106 -355.477191) (xy 181.23535 -355.494108) (xy 181.240938 -355.501194) (xy 181.241446 -355.501702)
			(xy 181.259168 -355.522658) (xy 181.289054 -355.568687) (xy 181.312023 -355.61853) (xy 181.327601 -355.671153)
			(xy 181.335463 -355.725468) (xy 181.335934 -355.752908) (xy 181.33543 -355.780158) (xy 181.327673 -355.834104)
			(xy 181.312318 -355.886397) (xy 181.289678 -355.935972) (xy 181.260213 -355.981821) (xy 181.224524 -356.023011)
			(xy 181.183336 -356.058702) (xy 181.137488 -356.088169) (xy 181.087914 -356.110812) (xy 181.035622 -356.126169)
			(xy 180.981676 -356.133928) (xy 180.954426 -356.134416) (xy 180.954172 -356.134416) (xy 180.926158 -356.133892)
			(xy 180.870735 -356.125673) (xy 180.817108 -356.109443) (xy 180.766428 -356.085553) (xy 180.719782 -356.054513)
			(xy 180.698648 -356.036118) (xy 180.691461 -356.030118) (xy 180.67397 -356.02347) (xy 180.664612 -356.023164)
			(xy 180.352954 -356.023164) (xy 180.342886 -356.0236) (xy 180.324287 -356.031311) (xy 180.316886 -356.03815)
			(xy 179.870354 -356.484428) (xy 179.852276 -356.501703) (xy 179.810724 -356.529509) (xy 179.764548 -356.548676)
			(xy 179.71552 -356.55847) (xy 179.690522 -356.559104) (xy 179.446174 -356.559104) (xy 179.4361 -356.559488)
			(xy 179.417501 -356.567235) (xy 179.410106 -356.57409) (xy 179.000404 -356.983538) (xy 178.982303 -357.00077)
			(xy 178.940741 -357.02851) (xy 178.894568 -357.047615) (xy 178.845557 -357.057352) (xy 178.820572 -357.05796)
			(xy 158.374334 -357.05796) (xy 158.34935 -357.057368) (xy 158.300341 -357.047618) (xy 158.254171 -357.028505)
			(xy 158.212612 -357.000761) (xy 158.194502 -356.983538) (xy 152.605486 -351.394522) (xy 152.588266 -351.37641)
			(xy 152.560523 -351.334852) (xy 152.541414 -351.288683) (xy 152.531674 -351.239674) (xy 152.531064 -351.21469)
			(xy 152.531064 -346.140278) (xy 152.531676 -346.115294) (xy 152.541419 -346.066286) (xy 152.560526 -346.020117)
			(xy 152.588264 -345.978556) (xy 152.605486 -345.960446) (xy 154.307032 -344.2589) (xy 154.32512 -344.241636)
			(xy 154.366668 -344.213827) (xy 154.412841 -344.194656) (xy 154.461867 -344.184859) (xy 154.486864 -344.184224)
			(xy 160.064704 -344.184224) (xy 160.074776 -344.183821) (xy 160.093375 -344.176087) (xy 160.100772 -344.169238)
			(xy 160.11652 -344.15349) (xy 160.123233 -344.1461) (xy 160.130834 -344.127657) (xy 160.130827 -344.107709)
			(xy 160.123214 -344.089272) (xy 160.11652 -344.081862) (xy 160.116266 -344.081608) (xy 160.110373 -344.076113)
			(xy 160.095992 -344.068866) (xy 160.088072 -344.067384) (xy 160.087564 -344.067384) (xy 160.060613 -344.063084)
			(xy 160.008222 -344.047802) (xy 159.958543 -344.025209) (xy 159.912592 -343.995768) (xy 159.871305 -343.960077)
			(xy 159.835526 -343.918868) (xy 159.805985 -343.872979) (xy 159.783285 -343.823349) (xy 159.767891 -343.770991)
			(xy 159.760115 -343.716973) (xy 159.75965 -343.689686) (xy 159.760211 -343.66077) (xy 159.768929 -343.6036)
			(xy 159.786177 -343.548402) (xy 159.81156 -343.496439) (xy 159.844498 -343.448905) (xy 159.884233 -343.406887)
			(xy 159.906716 -343.388696) (xy 159.915518 -343.381084) (xy 159.925704 -343.360187) (xy 159.926274 -343.348564)
			(xy 159.926274 -343.268808) (xy 159.925725 -343.257177) (xy 159.915544 -343.236267) (xy 159.906716 -343.228676)
			(xy 159.884224 -343.210494) (xy 159.844489 -343.168473) (xy 159.81155 -343.120937) (xy 159.786163 -343.068973)
			(xy 159.768909 -343.013774) (xy 159.760183 -342.956603) (xy 159.75965 -342.927686) (xy 159.760136 -342.900435)
			(xy 159.767892 -342.846487) (xy 159.783247 -342.794192) (xy 159.805889 -342.744615) (xy 159.835355 -342.698765)
			(xy 159.871046 -342.657574) (xy 159.912237 -342.621883) (xy 159.958087 -342.592417) (xy 160.007664 -342.569775)
			(xy 160.059959 -342.55442) (xy 160.113907 -342.546664) (xy 160.168409 -342.546664) (xy 160.222357 -342.55442)
			(xy 160.274652 -342.569775) (xy 160.324229 -342.592417) (xy 160.370079 -342.621883) (xy 160.41127 -342.657574)
			(xy 160.446961 -342.698765) (xy 160.476427 -342.744615) (xy 160.499069 -342.794192) (xy 160.514424 -342.846487)
			(xy 160.52218 -342.900435) (xy 160.522666 -342.927686) (xy 160.52215 -342.956603) (xy 160.513423 -343.013775)
			(xy 160.496165 -343.068975) (xy 160.470773 -343.120936) (xy 160.437828 -343.16847) (xy 160.398086 -343.210486)
			(xy 160.3756 -343.228676) (xy 160.366814 -343.236303) (xy 160.356619 -343.257189) (xy 160.356042 -343.268808)
			(xy 160.356042 -343.348564) (xy 160.356544 -343.360201) (xy 160.366758 -343.381111) (xy 160.3756 -343.388696)
			(xy 160.396798 -343.40582) (xy 160.434576 -343.445091) (xy 160.466387 -343.489334) (xy 160.491583 -343.53765)
			(xy 160.501076 -343.563194) (xy 160.504247 -343.571129) (xy 160.514914 -343.584463) (xy 160.529395 -343.59351)
			(xy 160.537652 -343.595706) (xy 160.621472 -343.614756) (xy 160.629898 -343.616352) (xy 160.646935 -343.614481)
			(xy 160.662401 -343.607096) (xy 160.668716 -343.601294) (xy 160.836864 -343.433146) (xy 160.844288 -343.426336)
			(xy 160.862869 -343.418597) (xy 160.872932 -343.41816) (xy 160.927796 -343.41816) (xy 160.937822 -343.417776)
			(xy 160.956347 -343.4101) (xy 160.97052 -343.395916) (xy 160.978183 -343.377386) (xy 160.978596 -343.36736)
			(xy 160.978596 -343.019634) (xy 160.97818 -343.009563) (xy 160.970456 -342.990964) (xy 160.96361 -342.983566)
			(xy 160.03905 -342.059006) (xy 160.031626 -342.052196) (xy 160.013045 -342.044459) (xy 160.002982 -342.04402)
			(xy 155.090114 -342.04402) (xy 155.080045 -342.044447) (xy 155.061447 -342.052166) (xy 155.054046 -342.059006)
			(xy 151.64181 -345.470988) (xy 151.634984 -345.478399) (xy 151.627256 -345.49699) (xy 151.626824 -345.507056)
			(xy 151.626824 -351.610676) (xy 151.627255 -351.620745) (xy 151.634971 -351.639343) (xy 151.64181 -351.646744)
			(xy 157.56128 -357.566214) (xy 157.568691 -357.57304) (xy 157.587282 -357.580767) (xy 157.597348 -357.5812)
			(xy 182.795164 -357.5812) (xy 182.820148 -357.581805) (xy 182.869155 -357.591553) (xy 182.915324 -357.610662)
			(xy 182.956885 -357.638401) (xy 182.974996 -357.655622) (xy 183.36387 -358.044242) (xy 183.371281 -358.051067)
			(xy 183.389872 -358.058794) (xy 183.399938 -358.059228) (xy 187.52312 -358.059228) (xy 187.533193 -358.058832)
			(xy 187.551792 -358.051093) (xy 187.559188 -358.044242) (xy 188.402722 -357.200962) (xy 188.409574 -357.193572)
			(xy 188.417286 -357.174965) (xy 188.417708 -357.164894) (xy 188.417708 -355.426772) (xy 188.418333 -355.401789)
			(xy 188.428074 -355.352783) (xy 188.447178 -355.306613) (xy 188.474911 -355.265051) (xy 188.49213 -355.24694)
			(xy 188.777626 -354.961444) (xy 188.795724 -354.94419) (xy 188.837267 -354.916377) (xy 188.883438 -354.897203)
			(xy 188.932462 -354.887404) (xy 188.957458 -354.886768) (xy 188.985144 -354.886768) (xy 189.003686 -354.879148)
			(xy 189.010798 -354.872036) (xy 189.032395 -354.851129) (xy 189.080963 -354.815719) (xy 189.134486 -354.788366)
			(xy 189.191637 -354.769749) (xy 189.251001 -354.760327) (xy 189.281054 -354.759768) (xy 189.308305 -354.760298)
			(xy 189.362252 -354.768048) (xy 189.414547 -354.783397) (xy 189.464125 -354.806032) (xy 189.509978 -354.835493)
			(xy 189.55117 -354.87118) (xy 189.586865 -354.912366) (xy 189.616334 -354.958213) (xy 189.638978 -355.007787)
			(xy 189.654337 -355.06008) (xy 189.662097 -355.114025) (xy 189.662562 -355.141276) (xy 189.662071 -355.168751)
			(xy 189.654182 -355.22313) (xy 189.638563 -355.275813) (xy 189.635916 -355.281549) (xy 189.904384 -355.281549)
			(xy 189.904384 -355.227051) (xy 189.912139 -355.173106) (xy 189.927493 -355.120815) (xy 189.950131 -355.07124)
			(xy 189.979594 -355.025392) (xy 190.015282 -354.984203) (xy 190.056468 -354.948512) (xy 190.102314 -354.919046)
			(xy 190.151887 -354.896403) (xy 190.204177 -354.881046) (xy 190.258121 -354.873286) (xy 190.28537 -354.872798)
			(xy 190.285624 -354.872798) (xy 190.310828 -354.873179) (xy 190.360797 -354.879823) (xy 190.409452 -354.893005)
			(xy 190.455941 -354.912493) (xy 190.477902 -354.924868) (xy 190.487808 -354.93071) (xy 190.509652 -354.932742)
			(xy 190.604394 -354.899214) (xy 190.620142 -354.88372) (xy 190.624206 -354.873306) (xy 190.634884 -354.846522)
			(xy 190.663173 -354.796278) (xy 190.698704 -354.750867) (xy 190.740669 -354.711325) (xy 190.788109 -354.678551)
			(xy 190.839943 -354.653295) (xy 190.894989 -354.636132) (xy 190.951992 -354.627453) (xy 190.980822 -354.626926)
			(xy 191.008077 -354.627335) (xy 191.062032 -354.635095) (xy 191.114333 -354.650456) (xy 191.163915 -354.673103)
			(xy 191.20977 -354.702577) (xy 191.250963 -354.738276) (xy 191.286657 -354.779475) (xy 191.316123 -354.825334)
			(xy 191.338764 -354.87492) (xy 191.351487 -354.918264) (xy 193.492374 -354.918264) (xy 193.492893 -354.890691)
			(xy 193.500836 -354.836121) (xy 193.516551 -354.783263) (xy 193.539711 -354.733217) (xy 193.569834 -354.687026)
			(xy 193.606292 -354.645652) (xy 193.626994 -354.627434) (xy 193.635054 -354.619864) (xy 193.644417 -354.599864)
			(xy 193.645028 -354.588826) (xy 193.645028 -354.511102) (xy 193.644481 -354.500049) (xy 193.635103 -354.480027)
			(xy 193.626994 -354.472494) (xy 193.606276 -354.454291) (xy 193.569806 -354.41292) (xy 193.539675 -354.366729)
			(xy 193.516511 -354.316679) (xy 193.500796 -354.263815) (xy 193.492858 -354.209239) (xy 193.492374 -354.181664)
			(xy 193.492844 -354.154413) (xy 193.500605 -354.100465) (xy 193.515964 -354.048171) (xy 193.538608 -353.998595)
			(xy 193.568076 -353.952746) (xy 193.603769 -353.911557) (xy 193.64496 -353.875866) (xy 193.690811 -353.846399)
			(xy 193.740388 -353.823758) (xy 193.792683 -353.808401) (xy 193.846631 -353.800643) (xy 193.873882 -353.800156)
			(xy 193.87439 -353.800156) (xy 193.908172 -353.80168) (xy 193.918332 -353.802696) (xy 193.937636 -353.7966)
			(xy 194.000628 -353.743768) (xy 194.007915 -353.737041) (xy 194.017198 -353.719539) (xy 194.018662 -353.709732)
			(xy 194.018662 -353.70897) (xy 194.021649 -353.680826) (xy 194.034843 -353.625792) (xy 194.056026 -353.573311)
			(xy 194.084732 -353.524538) (xy 194.120331 -353.480542) (xy 194.16204 -353.44229) (xy 194.208945 -353.410622)
			(xy 194.260014 -353.386234) (xy 194.314127 -353.369661) (xy 194.370095 -353.361267) (xy 194.398392 -353.360736)
			(xy 194.398646 -353.360736) (xy 194.416665 -353.360955) (xy 194.45254 -353.364391) (xy 194.470274 -353.367594)
			(xy 194.479926 -353.369372) (xy 194.498976 -353.365816) (xy 194.573906 -353.31781) (xy 194.585336 -353.302062)
			(xy 194.587622 -353.292664) (xy 194.59502 -353.26562) (xy 194.616649 -353.213893) (xy 194.645613 -353.165887)
			(xy 194.681288 -353.122635) (xy 194.722907 -353.085068) (xy 194.769575 -353.053993) (xy 194.820286 -353.030081)
			(xy 194.873951 -353.013845) (xy 194.929413 -353.005634) (xy 194.957446 -353.005136) (xy 194.9847 -353.005535)
			(xy 195.038654 -353.013299) (xy 195.090953 -353.028662) (xy 195.140533 -353.051312) (xy 195.186385 -353.080787)
			(xy 195.227576 -353.116488) (xy 195.263267 -353.157687) (xy 195.292731 -353.203546) (xy 195.315369 -353.253132)
			(xy 195.33072 -353.305435) (xy 195.338471 -353.35939) (xy 195.338954 -353.386644) (xy 195.338466 -353.414218)
			(xy 195.33052 -353.46879) (xy 195.314801 -353.521651) (xy 195.291635 -353.571697) (xy 195.261506 -353.617887)
			(xy 195.22504 -353.659258) (xy 195.204334 -353.677474) (xy 195.196259 -353.685029) (xy 195.186907 -353.705041)
			(xy 195.1863 -353.716082) (xy 195.1863 -353.793806) (xy 195.18692 -353.804849) (xy 195.196249 -353.824871)
			(xy 195.204334 -353.832414) (xy 195.225062 -353.850607) (xy 195.261529 -353.89198) (xy 195.291659 -353.938174)
			(xy 195.314821 -353.988226) (xy 195.330534 -354.041091) (xy 195.33847 -354.095668) (xy 195.338954 -354.123244)
			(xy 195.338466 -354.150818) (xy 195.33052 -354.20539) (xy 195.314801 -354.258251) (xy 195.291635 -354.308297)
			(xy 195.261506 -354.354487) (xy 195.22504 -354.395858) (xy 195.204334 -354.414074) (xy 195.196259 -354.421629)
			(xy 195.186907 -354.441641) (xy 195.1863 -354.452682) (xy 195.1863 -354.530406) (xy 195.18692 -354.541449)
			(xy 195.196249 -354.561471) (xy 195.204334 -354.569014) (xy 195.225062 -354.587207) (xy 195.261529 -354.62858)
			(xy 195.291659 -354.674774) (xy 195.314821 -354.724826) (xy 195.330534 -354.777691) (xy 195.33847 -354.832268)
			(xy 195.338954 -354.859844) (xy 195.338463 -354.887094) (xy 195.330702 -354.941039) (xy 195.315344 -354.993331)
			(xy 195.292701 -355.042906) (xy 195.263234 -355.088753) (xy 195.227543 -355.129942) (xy 195.186355 -355.165633)
			(xy 195.140507 -355.1951) (xy 195.090933 -355.217743) (xy 195.038641 -355.233102) (xy 194.984696 -355.240863)
			(xy 194.957446 -355.241352) (xy 194.92959 -355.240823) (xy 194.874473 -355.232705) (xy 194.821121 -355.216663)
			(xy 194.770667 -355.193038) (xy 194.724181 -355.162332) (xy 194.682651 -355.125197) (xy 194.646958 -355.082421)
			(xy 194.617861 -355.034911) (xy 194.595976 -354.983678) (xy 194.588384 -354.956872) (xy 194.586098 -354.947982)
			(xy 194.57543 -354.932742) (xy 194.503548 -354.88499) (xy 194.485514 -354.880926) (xy 194.47637 -354.882196)
			(xy 194.463354 -354.883866) (xy 194.437169 -354.885645) (xy 194.424046 -354.885752) (xy 194.409897 -354.885653)
			(xy 194.381674 -354.883622) (xy 194.367658 -354.881688) (xy 194.357752 -354.880164) (xy 194.33794 -354.88499)
			(xy 194.263518 -354.94087) (xy 194.253358 -354.958396) (xy 194.252088 -354.968556) (xy 194.248037 -354.995716)
			(xy 194.233061 -355.048548) (xy 194.210665 -355.098688) (xy 194.181314 -355.1451) (xy 194.145612 -355.186825)
			(xy 194.104298 -355.223001) (xy 194.058225 -355.252881) (xy 194.008344 -355.275848) (xy 193.955686 -355.291427)
			(xy 193.901339 -355.299296) (xy 193.873882 -355.299772) (xy 193.846627 -355.299362) (xy 193.792672 -355.291601)
			(xy 193.740371 -355.276241) (xy 193.690789 -355.253594) (xy 193.644934 -355.224121) (xy 193.60374 -355.188421)
			(xy 193.568047 -355.147223) (xy 193.53858 -355.101364) (xy 193.51594 -355.051778) (xy 193.500587 -354.999475)
			(xy 193.492834 -354.945519) (xy 193.492374 -354.918264) (xy 191.351487 -354.918264) (xy 191.354117 -354.927223)
			(xy 191.361869 -354.981179) (xy 191.36233 -355.008434) (xy 191.361665 -355.039996) (xy 191.351279 -355.102261)
			(xy 191.330796 -355.161971) (xy 191.316356 -355.190044) (xy 191.31153 -355.198934) (xy 191.309498 -355.218492)
			(xy 191.332358 -355.296978) (xy 191.335594 -355.306404) (xy 191.348012 -355.321963) (xy 191.356488 -355.327204)
			(xy 191.381573 -355.34178) (xy 191.427455 -355.377278) (xy 191.467431 -355.419317) (xy 191.500578 -355.466927)
			(xy 191.526132 -355.519007) (xy 191.543502 -355.574357) (xy 191.552288 -355.6317) (xy 191.55283 -355.660706)
			(xy 191.552344 -355.687957) (xy 191.544588 -355.741905) (xy 191.529233 -355.7942) (xy 191.506591 -355.843777)
			(xy 191.477125 -355.889627) (xy 191.441434 -355.930818) (xy 191.400243 -355.966509) (xy 191.354393 -355.995975)
			(xy 191.304816 -356.018617) (xy 191.252521 -356.033972) (xy 191.198573 -356.041728) (xy 191.144071 -356.041728)
			(xy 191.090123 -356.033972) (xy 191.037828 -356.018617) (xy 190.988251 -355.995975) (xy 190.942401 -355.966509)
			(xy 190.90121 -355.930818) (xy 190.865519 -355.889627) (xy 190.836053 -355.843777) (xy 190.813411 -355.7942)
			(xy 190.798056 -355.741905) (xy 190.7903 -355.687957) (xy 190.789814 -355.660706) (xy 190.79045 -355.629142)
			(xy 190.800847 -355.566876) (xy 190.821342 -355.507168) (xy 190.835788 -355.479096) (xy 190.840614 -355.470206)
			(xy 190.842646 -355.450648) (xy 190.819786 -355.372162) (xy 190.816558 -355.362734) (xy 190.804133 -355.347177)
			(xy 190.795656 -355.341936) (xy 190.78829 -355.337872) (xy 190.778384 -355.33203) (xy 190.75654 -355.329998)
			(xy 190.661798 -355.363526) (xy 190.64605 -355.37902) (xy 190.641986 -355.389434) (xy 190.631336 -355.41623)
			(xy 190.603042 -355.466472) (xy 190.567505 -355.511882) (xy 190.525536 -355.551423) (xy 190.478092 -355.584194)
			(xy 190.426255 -355.609449) (xy 190.371206 -355.62661) (xy 190.314201 -355.635287) (xy 190.28537 -355.635814)
			(xy 190.258121 -355.635314) (xy 190.204177 -355.627554) (xy 190.151887 -355.612197) (xy 190.102314 -355.589554)
			(xy 190.056468 -355.560088) (xy 190.015282 -355.524397) (xy 189.979594 -355.483208) (xy 189.950131 -355.43736)
			(xy 189.927493 -355.387785) (xy 189.912139 -355.335494) (xy 189.904384 -355.281549) (xy 189.635916 -355.281549)
			(xy 189.615539 -355.325706) (xy 189.585588 -355.371774) (xy 189.56782 -355.392736) (xy 189.567566 -355.39299)
			(xy 189.561974 -355.400072) (xy 189.555732 -355.416993) (xy 189.555374 -355.42601) (xy 189.555374 -355.493574)
			(xy 189.555749 -355.502589) (xy 189.561985 -355.519506) (xy 189.567566 -355.526594) (xy 189.568074 -355.527102)
			(xy 189.5858 -355.548054) (xy 189.615685 -355.594085) (xy 189.638653 -355.643928) (xy 189.654229 -355.696553)
			(xy 189.662091 -355.750867) (xy 189.662562 -355.778308) (xy 189.662083 -355.804862) (xy 189.654728 -355.857458)
			(xy 189.640148 -355.908525) (xy 189.618625 -355.957075) (xy 189.590575 -356.002171) (xy 189.55654 -356.042939)
			(xy 189.517178 -356.078592) (xy 189.473252 -356.108439) (xy 189.425609 -356.131904) (xy 189.375172 -356.148533)
			(xy 189.349126 -356.15372) (xy 189.348872 -356.15372) (xy 189.33733 -356.156448) (xy 189.318414 -356.170712)
			(xy 189.307837 -356.191912) (xy 189.307216 -356.203758) (xy 189.307216 -357.449374) (xy 189.306641 -357.474359)
			(xy 189.296888 -357.52337) (xy 189.27777 -357.569539) (xy 189.250021 -357.611098) (xy 189.232794 -357.629206)
			(xy 187.984638 -358.877362) (xy 187.966527 -358.894582) (xy 187.924968 -358.922323) (xy 187.878798 -358.941431)
			(xy 187.82979 -358.951173) (xy 187.804806 -358.951784) (xy 183.100472 -358.951784) (xy 183.075489 -358.951161)
			(xy 183.026482 -358.94142) (xy 182.980313 -358.922316) (xy 182.938751 -358.894581) (xy 182.92064 -358.877362)
			(xy 182.528972 -358.485694) (xy 182.521576 -358.478848) (xy 182.502974 -358.471132) (xy 182.492904 -358.470708)
			(xy 157.312868 -358.470708) (xy 157.287884 -358.47011) (xy 157.238874 -358.460364) (xy 157.192704 -358.441253)
			(xy 157.151145 -358.41351) (xy 157.133036 -358.396286) (xy 150.811738 -352.074988) (xy 150.794494 -352.056898)
			(xy 150.766757 -352.015331) (xy 150.747656 -351.969155) (xy 150.737923 -351.920142) (xy 150.737316 -351.895156)
			(xy 148.56333 -351.895156) (xy 148.56333 -357.0605) (xy 148.563754 -357.07057) (xy 148.571472 -357.089171)
			(xy 148.578316 -357.096568) (xy 150.769828 -359.28808) (xy 150.777227 -359.294924) (xy 150.795825 -359.302652)
			(xy 150.805896 -359.303066) (xy 154.546808 -359.303066) (xy 154.553168 -359.302906) (xy 154.565508 -359.299828)
			(xy 154.571192 -359.29697) (xy 154.603105 -359.280236) (xy 154.670188 -359.253925) (xy 154.740018 -359.23614)
			(xy 154.811515 -359.227156) (xy 154.847544 -359.226612) (xy 169.164254 -359.226612) (xy 169.196776 -359.22706)
			(xy 169.261409 -359.234362) (xy 169.324817 -359.248857) (xy 169.386203 -359.270361) (xy 169.444795 -359.298605)
			(xy 169.499855 -359.333234) (xy 169.55069 -359.373811) (xy 169.573956 -359.396538) (xy 170.450571 -360.273153)
			(xy 172.666349 -360.273153) (xy 172.666349 -360.218646) (xy 172.674107 -360.164693) (xy 172.689463 -360.112394)
			(xy 172.712107 -360.062813) (xy 172.741576 -360.016959) (xy 172.777271 -359.975765) (xy 172.818465 -359.940071)
			(xy 172.86432 -359.910603) (xy 172.913902 -359.887961) (xy 172.966201 -359.872605) (xy 173.020154 -359.864849)
			(xy 173.074661 -359.86485) (xy 173.128613 -359.872608) (xy 173.180912 -359.887966) (xy 173.230493 -359.91061)
			(xy 173.276347 -359.94008) (xy 173.317539 -359.975776) (xy 173.353233 -360.016971) (xy 173.3827 -360.062826)
			(xy 173.405342 -360.112408) (xy 173.420696 -360.164708) (xy 173.428452 -360.21866) (xy 173.428914 -360.245914)
			(xy 173.428704 -360.263673) (xy 173.425396 -360.299036) (xy 173.42231 -360.316526) (xy 173.420715 -360.328459)
			(xy 173.427489 -360.351528) (xy 173.435264 -360.360722) (xy 173.499526 -360.429556) (xy 173.52264 -360.437684)
			(xy 173.534578 -360.43616) (xy 173.546215 -360.434823) (xy 173.5696 -360.433428) (xy 173.581314 -360.433366)
			(xy 173.608564 -360.433865) (xy 173.66251 -360.441622) (xy 173.714803 -360.456978) (xy 173.764379 -360.479619)
			(xy 173.810228 -360.509084) (xy 173.851417 -360.544774) (xy 173.887109 -360.585963) (xy 173.916575 -360.631811)
			(xy 173.939218 -360.681385) (xy 173.954575 -360.733678) (xy 173.962334 -360.787624) (xy 173.962822 -360.814874)
			(xy 173.962822 -360.815382) (xy 173.962411 -360.840282) (xy 173.955895 -360.889655) (xy 173.943011 -360.93776)
			(xy 173.933866 -360.960924) (xy 173.928532 -360.973624) (xy 173.932342 -361.000802) (xy 173.995842 -361.08132)
			(xy 174.001647 -361.088146) (xy 174.016888 -361.097548) (xy 174.034436 -361.101118) (xy 174.04334 -361.100116)
			(xy 174.043594 -361.100116) (xy 174.058542 -361.097863) (xy 174.088676 -361.095448) (xy 174.103792 -361.09529)
			(xy 174.131046 -361.095747) (xy 174.184998 -361.103503) (xy 174.237298 -361.118858) (xy 174.286879 -361.1415)
			(xy 174.332734 -361.170968) (xy 174.373929 -361.206662) (xy 174.409624 -361.247856) (xy 174.439093 -361.293709)
			(xy 174.461737 -361.343291) (xy 174.477094 -361.39559) (xy 174.484852 -361.449542) (xy 174.484853 -361.504049)
			(xy 174.477096 -361.558001) (xy 174.461741 -361.610301) (xy 174.439098 -361.659882) (xy 174.40963 -361.705737)
			(xy 174.373935 -361.746931) (xy 174.332742 -361.782626) (xy 174.286888 -361.812095) (xy 174.237306 -361.834738)
			(xy 174.185007 -361.850095) (xy 174.131055 -361.857853) (xy 174.076548 -361.857853) (xy 174.022595 -361.850096)
			(xy 173.970296 -361.834739) (xy 173.920715 -361.812096) (xy 173.87486 -361.782628) (xy 173.833667 -361.746933)
			(xy 173.797972 -361.705739) (xy 173.768503 -361.659885) (xy 173.74586 -361.610303) (xy 173.730504 -361.558004)
			(xy 173.722747 -361.504052) (xy 173.722284 -361.476798) (xy 173.722284 -361.47629) (xy 173.722717 -361.451391)
			(xy 173.729224 -361.402018) (xy 173.7421 -361.353913) (xy 173.75124 -361.330748) (xy 173.756574 -361.318048)
			(xy 173.752764 -361.29087) (xy 173.689264 -361.210352) (xy 173.683461 -361.203525) (xy 173.668218 -361.194125)
			(xy 173.65067 -361.190554) (xy 173.641766 -361.191556) (xy 173.641512 -361.191556) (xy 173.626564 -361.193808)
			(xy 173.59643 -361.196224) (xy 173.581314 -361.196382) (xy 173.55406 -361.195932) (xy 173.500108 -361.188176)
			(xy 173.447808 -361.17282) (xy 173.398226 -361.150177) (xy 173.352372 -361.120709) (xy 173.311178 -361.085013)
			(xy 173.275484 -361.043819) (xy 173.246017 -360.997963) (xy 173.223376 -360.948381) (xy 173.208022 -360.896081)
			(xy 173.200268 -360.842128) (xy 173.199806 -360.814874) (xy 173.200014 -360.797115) (xy 173.203323 -360.761752)
			(xy 173.20641 -360.744262) (xy 173.208034 -360.73233) (xy 173.201243 -360.709255) (xy 173.193456 -360.700066)
			(xy 173.129194 -360.631232) (xy 173.10608 -360.623104) (xy 173.094142 -360.624628) (xy 173.082505 -360.625963)
			(xy 173.05912 -360.62736) (xy 173.047406 -360.627422) (xy 173.020152 -360.626951) (xy 172.9662 -360.619195)
			(xy 172.913901 -360.603839) (xy 172.864319 -360.581196) (xy 172.818464 -360.551728) (xy 172.77727 -360.516034)
			(xy 172.741575 -360.47484) (xy 172.712106 -360.428986) (xy 172.689463 -360.379404) (xy 172.674106 -360.327105)
			(xy 172.666349 -360.273153) (xy 170.450571 -360.273153) (xy 173.315376 -363.137958) (xy 173.322777 -363.144797)
			(xy 173.341375 -363.152511) (xy 173.351444 -363.152944) (xy 175.23079 -363.152944) (xy 175.240802 -363.152458)
			(xy 175.259305 -363.144802) (xy 175.273472 -363.13065) (xy 175.281148 -363.112156) (xy 175.28159 -363.102144)
			(xy 175.28159 -363.09681) (xy 175.28286 -363.066584) (xy 175.28286 -363.066076) (xy 175.283622 -363.055154)
			(xy 175.276002 -363.034326) (xy 175.213264 -362.971588) (xy 175.205083 -362.964193) (xy 175.184412 -362.956571)
			(xy 175.173386 -362.956856) (xy 175.142652 -362.958126) (xy 175.1154 -362.957637) (xy 175.061452 -362.949873)
			(xy 175.009157 -362.934511) (xy 174.959581 -362.911864) (xy 174.913733 -362.882391) (xy 174.872545 -362.846694)
			(xy 174.836857 -362.805498) (xy 174.807395 -362.759643) (xy 174.784758 -362.710062) (xy 174.769408 -362.657764)
			(xy 174.761657 -362.603814) (xy 174.761663 -362.54931) (xy 174.769425 -362.495361) (xy 174.784785 -362.443066)
			(xy 174.807431 -362.39349) (xy 174.836903 -362.347641) (xy 174.872599 -362.306452) (xy 174.913794 -362.270763)
			(xy 174.959648 -362.2413) (xy 175.009228 -362.218662) (xy 175.061526 -362.20331) (xy 175.115476 -362.195558)
			(xy 175.16998 -362.195562) (xy 175.223929 -362.203322) (xy 175.276224 -362.218682) (xy 175.325801 -362.241327)
			(xy 175.371651 -362.270797) (xy 175.412841 -362.306492) (xy 175.448531 -362.347686) (xy 175.477995 -362.393539)
			(xy 175.500635 -362.443119) (xy 175.515987 -362.495416) (xy 175.523741 -362.549366) (xy 175.52416 -362.576618)
			(xy 175.52289 -362.606844) (xy 175.52289 -362.607352) (xy 175.522128 -362.618274) (xy 175.529748 -362.639102)
			(xy 175.592486 -362.70184) (xy 175.600666 -362.70924) (xy 175.621337 -362.716878) (xy 175.632364 -362.716572)
			(xy 175.663098 -362.715302) (xy 175.690351 -362.715765) (xy 175.744301 -362.723522) (xy 175.796599 -362.738878)
			(xy 175.846179 -362.76152) (xy 175.892031 -362.790989) (xy 175.933223 -362.826682) (xy 175.968916 -362.867875)
			(xy 175.998383 -362.913728) (xy 176.021025 -362.963309) (xy 176.03638 -363.015607) (xy 176.044135 -363.069557)
			(xy 176.044606 -363.09681) (xy 176.044606 -363.102144) (xy 176.045102 -363.112145) (xy 176.052769 -363.130621)
			(xy 176.066921 -363.144759) (xy 176.085404 -363.152408) (xy 176.095406 -363.152944) (xy 177.367692 -363.152944)
			(xy 177.400205 -363.153399) (xy 177.464821 -363.160677) (xy 177.528217 -363.175141) (xy 177.589595 -363.196611)
			(xy 177.648185 -363.224816) (xy 177.703249 -363.259402) (xy 177.754096 -363.299935) (xy 177.777394 -363.322616)
			(xy 178.37912 -363.924342) (xy 179.856638 -363.924342) (xy 179.857119 -363.896972) (xy 179.864932 -363.842793)
			(xy 179.880417 -363.79029) (xy 179.903256 -363.740543) (xy 179.932978 -363.694576) (xy 179.950618 -363.673644)
			(xy 179.950872 -363.67339) (xy 179.956477 -363.666317) (xy 179.962711 -363.649389) (xy 179.963064 -363.64037)
			(xy 179.963064 -363.573314) (xy 179.962708 -363.564297) (xy 179.95646 -363.54738) (xy 179.950872 -363.540294)
			(xy 179.950618 -363.540294) (xy 179.950618 -363.54004) (xy 179.932987 -363.519101) (xy 179.903273 -363.473131)
			(xy 179.880436 -363.423385) (xy 179.864943 -363.370886) (xy 179.857113 -363.316711) (xy 179.856638 -363.289342)
			(xy 179.857119 -363.261768) (xy 179.865067 -363.207195) (xy 179.880788 -363.154335) (xy 179.903955 -363.104289)
			(xy 179.934085 -363.058099) (xy 179.970551 -363.016728) (xy 179.991258 -362.998512) (xy 179.999337 -362.990961)
			(xy 180.008687 -362.970946) (xy 180.009292 -362.959904) (xy 180.009292 -362.88218) (xy 180.008682 -362.871136)
			(xy 179.999347 -362.851114) (xy 179.991258 -362.843572) (xy 179.970522 -362.825388) (xy 179.934055 -362.784013)
			(xy 179.903927 -362.737817) (xy 179.880766 -362.687764) (xy 179.865055 -362.634897) (xy 179.857121 -362.580318)
			(xy 179.856638 -362.552742) (xy 179.857119 -362.525372) (xy 179.864932 -362.471193) (xy 179.880417 -362.41869)
			(xy 179.903256 -362.368943) (xy 179.932978 -362.322976) (xy 179.950618 -362.302044) (xy 179.950872 -362.30179)
			(xy 179.956477 -362.294717) (xy 179.962711 -362.277789) (xy 179.963064 -362.26877) (xy 179.963064 -362.201714)
			(xy 179.962708 -362.192697) (xy 179.95646 -362.17578) (xy 179.950872 -362.168694) (xy 179.950618 -362.168694)
			(xy 179.950618 -362.16844) (xy 179.933019 -362.147474) (xy 179.903293 -362.101512) (xy 179.880446 -362.051771)
			(xy 179.864947 -361.999274) (xy 179.857114 -361.9451) (xy 179.85711 -361.890363) (xy 179.864933 -361.836188)
			(xy 179.880423 -361.783689) (xy 179.903263 -361.733944) (xy 179.932981 -361.687977) (xy 179.950618 -361.667044)
			(xy 179.950872 -361.66679) (xy 179.956477 -361.659717) (xy 179.962711 -361.642789) (xy 179.963064 -361.63377)
			(xy 179.963064 -361.566714) (xy 179.962708 -361.557697) (xy 179.95646 -361.54078) (xy 179.950872 -361.533694)
			(xy 179.950618 -361.533694) (xy 179.950618 -361.53344) (xy 179.933019 -361.512474) (xy 179.903293 -361.466512)
			(xy 179.880446 -361.416771) (xy 179.864947 -361.364274) (xy 179.857114 -361.3101) (xy 179.85711 -361.255363)
			(xy 179.864933 -361.201188) (xy 179.880423 -361.148689) (xy 179.903263 -361.098944) (xy 179.932981 -361.052977)
			(xy 179.950618 -361.032044) (xy 179.950872 -361.03179) (xy 179.956477 -361.024717) (xy 179.962711 -361.007789)
			(xy 179.963064 -360.99877) (xy 179.963064 -360.931714) (xy 179.962708 -360.922697) (xy 179.95646 -360.90578)
			(xy 179.950872 -360.898694) (xy 179.950618 -360.898694) (xy 179.950618 -360.89844) (xy 179.932987 -360.877501)
			(xy 179.903273 -360.831531) (xy 179.880436 -360.781785) (xy 179.864943 -360.729286) (xy 179.857113 -360.675111)
			(xy 179.856638 -360.647742) (xy 179.857119 -360.620168) (xy 179.865067 -360.565595) (xy 179.880788 -360.512735)
			(xy 179.903955 -360.462689) (xy 179.934085 -360.416499) (xy 179.970551 -360.375128) (xy 179.991258 -360.356912)
			(xy 179.999337 -360.349361) (xy 180.008687 -360.329346) (xy 180.009292 -360.318304) (xy 180.009292 -360.24058)
			(xy 180.008682 -360.229536) (xy 179.999347 -360.209514) (xy 179.991258 -360.201972) (xy 179.970522 -360.183788)
			(xy 179.934055 -360.142413) (xy 179.903927 -360.096217) (xy 179.880766 -360.046164) (xy 179.865055 -359.993297)
			(xy 179.857121 -359.938718) (xy 179.856638 -359.911142) (xy 179.857119 -359.883772) (xy 179.864932 -359.829593)
			(xy 179.880417 -359.77709) (xy 179.903256 -359.727343) (xy 179.932978 -359.681376) (xy 179.950618 -359.660444)
			(xy 179.950872 -359.66019) (xy 179.956477 -359.653117) (xy 179.962711 -359.636189) (xy 179.963064 -359.62717)
			(xy 179.963064 -359.560114) (xy 179.962708 -359.551097) (xy 179.95646 -359.53418) (xy 179.950872 -359.527094)
			(xy 179.950618 -359.527094) (xy 179.950618 -359.52684) (xy 179.932987 -359.505901) (xy 179.903273 -359.459931)
			(xy 179.880436 -359.410185) (xy 179.864943 -359.357686) (xy 179.857113 -359.303511) (xy 179.856638 -359.276142)
			(xy 179.857095 -359.248888) (xy 179.864847 -359.194935) (xy 179.8802 -359.142634) (xy 179.902841 -359.093051)
			(xy 179.932309 -359.047195) (xy 179.968004 -359.006001) (xy 180.009198 -358.970306) (xy 180.055054 -358.940839)
			(xy 180.104637 -358.918199) (xy 180.156938 -358.902846) (xy 180.210892 -358.895094) (xy 180.238146 -358.894634)
			(xy 180.265515 -358.895123) (xy 180.319694 -358.902934) (xy 180.372197 -358.918418) (xy 180.421944 -358.941254)
			(xy 180.467912 -358.970975) (xy 180.488844 -358.988614) (xy 180.489098 -358.988868) (xy 180.496175 -358.994468)
			(xy 180.513099 -359.000705) (xy 180.522118 -359.00106) (xy 180.589174 -359.00106) (xy 180.598191 -359.000699)
			(xy 180.615108 -358.994455) (xy 180.622194 -358.988868) (xy 180.622194 -358.988614) (xy 180.622448 -358.988614)
			(xy 180.643381 -358.970973) (xy 180.689349 -358.941249) (xy 180.739095 -358.918403) (xy 180.791597 -358.902907)
			(xy 180.845775 -358.895078) (xy 180.900517 -358.895078) (xy 180.954695 -358.902907) (xy 181.007197 -358.918403)
			(xy 181.056943 -358.941249) (xy 181.102911 -358.970973) (xy 181.123844 -358.988614) (xy 181.124098 -358.988868)
			(xy 181.131175 -358.994468) (xy 181.148099 -359.000705) (xy 181.157118 -359.00106) (xy 181.224174 -359.00106)
			(xy 181.233191 -359.000699) (xy 181.250108 -358.994455) (xy 181.257194 -358.988868) (xy 181.257194 -358.988614)
			(xy 181.257448 -358.988614) (xy 181.278381 -358.970973) (xy 181.324349 -358.941249) (xy 181.374095 -358.918403)
			(xy 181.426597 -358.902907) (xy 181.480775 -358.895078) (xy 181.535517 -358.895078) (xy 181.589695 -358.902907)
			(xy 181.642197 -358.918403) (xy 181.691943 -358.941249) (xy 181.737911 -358.970973) (xy 181.758844 -358.988614)
			(xy 181.759098 -358.988868) (xy 181.766175 -358.994468) (xy 181.783099 -359.000705) (xy 181.792118 -359.00106)
			(xy 181.859174 -359.00106) (xy 181.868191 -359.000699) (xy 181.885108 -358.994455) (xy 181.892194 -358.988868)
			(xy 181.892194 -358.988614) (xy 181.892448 -358.988614) (xy 181.913391 -358.970988) (xy 181.95936 -358.941274)
			(xy 182.009105 -358.918435) (xy 182.061604 -358.902941) (xy 182.115778 -358.89511) (xy 182.143146 -358.894634)
			(xy 182.1704 -358.895035) (xy 182.224353 -358.902799) (xy 182.276652 -358.918162) (xy 182.326232 -358.940812)
			(xy 182.372085 -358.970287) (xy 182.413275 -359.005987) (xy 182.448966 -359.047186) (xy 182.478431 -359.093045)
			(xy 182.501069 -359.14263) (xy 182.51642 -359.194933) (xy 182.524171 -359.248888) (xy 182.524654 -359.276142)
			(xy 182.524165 -359.303512) (xy 182.516355 -359.35769) (xy 182.500871 -359.410193) (xy 182.478034 -359.459941)
			(xy 182.448314 -359.505908) (xy 182.430674 -359.52684) (xy 182.43042 -359.527094) (xy 182.42482 -359.534171)
			(xy 182.418584 -359.551096) (xy 182.418228 -359.560114) (xy 182.418228 -359.62717) (xy 182.418593 -359.636186)
			(xy 182.424835 -359.653103) (xy 182.43042 -359.66019) (xy 182.430674 -359.66019) (xy 182.430674 -359.660444)
			(xy 182.448296 -359.68139) (xy 182.478012 -359.727358) (xy 182.500851 -359.777102) (xy 182.516346 -359.8296)
			(xy 182.524178 -359.883774) (xy 182.524654 -359.911142) (xy 182.524161 -359.938392) (xy 182.5164 -359.992337)
			(xy 182.501042 -360.044629) (xy 182.4784 -360.094203) (xy 182.448933 -360.140051) (xy 182.413243 -360.18124)
			(xy 182.372055 -360.216931) (xy 182.326207 -360.246398) (xy 182.276633 -360.269041) (xy 182.224341 -360.2844)
			(xy 182.170396 -360.292161) (xy 182.143146 -360.29265) (xy 182.115776 -360.292169) (xy 182.061597 -360.284357)
			(xy 182.009094 -360.268872) (xy 181.959347 -360.246033) (xy 181.91338 -360.216311) (xy 181.892448 -360.19867)
			(xy 181.892194 -360.198416) (xy 181.885112 -360.192823) (xy 181.868192 -360.186579) (xy 181.859174 -360.186224)
			(xy 181.792118 -360.186224) (xy 181.783101 -360.186585) (xy 181.766184 -360.192829) (xy 181.759098 -360.198416)
			(xy 181.759098 -360.19867) (xy 181.758844 -360.19867) (xy 181.737911 -360.216311) (xy 181.691943 -360.246035)
			(xy 181.642197 -360.268881) (xy 181.589695 -360.284377) (xy 181.535517 -360.292206) (xy 181.480775 -360.292206)
			(xy 181.426597 -360.284377) (xy 181.374095 -360.268881) (xy 181.324349 -360.246035) (xy 181.278381 -360.216311)
			(xy 181.257448 -360.19867) (xy 181.257194 -360.198416) (xy 181.250112 -360.192823) (xy 181.233192 -360.186579)
			(xy 181.224174 -360.186224) (xy 181.157118 -360.186224) (xy 181.148101 -360.186585) (xy 181.131184 -360.192829)
			(xy 181.124098 -360.198416) (xy 181.124098 -360.19867) (xy 181.123844 -360.19867) (xy 181.102911 -360.216311)
			(xy 181.056943 -360.246035) (xy 181.007197 -360.268881) (xy 180.954695 -360.284377) (xy 180.900517 -360.292206)
			(xy 180.845775 -360.292206) (xy 180.791597 -360.284377) (xy 180.739095 -360.268881) (xy 180.689349 -360.246035)
			(xy 180.643381 -360.216311) (xy 180.622448 -360.19867) (xy 180.622194 -360.198416) (xy 180.615112 -360.192823)
			(xy 180.598192 -360.186579) (xy 180.589174 -360.186224) (xy 180.522118 -360.186224) (xy 180.513101 -360.186585)
			(xy 180.496184 -360.192829) (xy 180.489098 -360.198416) (xy 180.488844 -360.19867) (xy 180.485034 -360.201972)
			(xy 180.476922 -360.20958) (xy 180.467567 -360.229728) (xy 180.467 -360.240834) (xy 180.467 -360.318304)
			(xy 180.467621 -360.329347) (xy 180.476949 -360.349368) (xy 180.485034 -360.356912) (xy 180.505761 -360.375106)
			(xy 180.542229 -360.416479) (xy 180.572358 -360.462673) (xy 180.595521 -360.512724) (xy 180.611234 -360.565589)
			(xy 180.61917 -360.620166) (xy 180.619654 -360.647742) (xy 180.619165 -360.675112) (xy 180.611355 -360.72929)
			(xy 180.595871 -360.781793) (xy 180.573034 -360.831541) (xy 180.543314 -360.877508) (xy 180.525674 -360.89844)
			(xy 180.52542 -360.898694) (xy 180.51982 -360.905771) (xy 180.513584 -360.922696) (xy 180.513228 -360.931714)
			(xy 180.513228 -360.99877) (xy 180.513593 -361.007786) (xy 180.519835 -361.024703) (xy 180.52542 -361.03179)
			(xy 180.525674 -361.03179) (xy 180.525674 -361.032044) (xy 180.543356 -361.052943) (xy 180.573079 -361.098917)
			(xy 180.595922 -361.148669) (xy 180.611415 -361.201176) (xy 180.619239 -361.255359) (xy 180.619235 -361.310104)
			(xy 180.611401 -361.364286) (xy 180.595899 -361.416791) (xy 180.573048 -361.466539) (xy 180.568874 -361.472993)
			(xy 185.652165 -361.472993) (xy 185.655896 -361.419741) (xy 185.667013 -361.367529) (xy 185.685299 -361.317376)
			(xy 185.710397 -361.270262) (xy 185.741818 -361.227107) (xy 185.778948 -361.188752) (xy 185.79973 -361.171998)
			(xy 185.808533 -361.164387) (xy 185.818718 -361.143489) (xy 185.819288 -361.131866) (xy 185.819288 -361.05211)
			(xy 185.818733 -361.04048) (xy 185.808556 -361.01957) (xy 185.79973 -361.011978) (xy 185.777242 -360.993792)
			(xy 185.737506 -360.951772) (xy 185.704567 -360.904236) (xy 185.679179 -360.852274) (xy 185.661924 -360.797075)
			(xy 185.653197 -360.739904) (xy 185.652664 -360.710988) (xy 185.653167 -360.683738) (xy 185.660924 -360.629792)
			(xy 185.676279 -360.577499) (xy 185.69892 -360.527924) (xy 185.728385 -360.482075) (xy 185.764074 -360.440886)
			(xy 185.805262 -360.405194) (xy 185.85111 -360.375727) (xy 185.900684 -360.353085) (xy 185.952976 -360.337727)
			(xy 186.006922 -360.329968) (xy 186.034172 -360.32948) (xy 186.06309 -360.329988) (xy 186.120263 -360.338715)
			(xy 186.175463 -360.355973) (xy 186.227425 -360.381366) (xy 186.274959 -360.414313) (xy 186.316974 -360.454058)
			(xy 186.335162 -360.476546) (xy 186.342788 -360.485334) (xy 186.363675 -360.495526) (xy 186.375294 -360.496104)
			(xy 186.45505 -360.496104) (xy 186.466683 -360.495578) (xy 186.487593 -360.48538) (xy 186.495182 -360.476546)
			(xy 186.51337 -360.45406) (xy 186.555392 -360.414327) (xy 186.602928 -360.38139) (xy 186.654889 -360.356003)
			(xy 186.710087 -360.338746) (xy 186.767256 -360.330016) (xy 186.796172 -360.32948) (xy 186.823424 -360.329981)
			(xy 186.877373 -360.337734) (xy 186.929669 -360.353086) (xy 186.979248 -360.375724) (xy 187.025101 -360.405188)
			(xy 187.066294 -360.440878) (xy 187.101988 -360.482067) (xy 187.131456 -360.527917) (xy 187.1541 -360.577494)
			(xy 187.169457 -360.629788) (xy 187.177216 -360.683736) (xy 187.17768 -360.710988) (xy 187.177161 -360.739905)
			(xy 187.168433 -360.797076) (xy 187.151176 -360.852276) (xy 187.125784 -360.904237) (xy 187.092841 -360.951771)
			(xy 187.0531 -360.993788) (xy 187.030614 -361.011978) (xy 187.021812 -361.01959) (xy 187.011629 -361.040488)
			(xy 187.011056 -361.05211) (xy 187.011056 -361.131866) (xy 187.011609 -361.143497) (xy 187.021786 -361.164408)
			(xy 187.030614 -361.171998) (xy 187.051386 -361.188765) (xy 187.088519 -361.227115) (xy 187.119942 -361.270268)
			(xy 187.145044 -361.31738) (xy 187.163332 -361.367531) (xy 187.17445 -361.419742) (xy 187.178181 -361.472993)
			(xy 187.174452 -361.526244) (xy 187.163336 -361.578455) (xy 187.14505 -361.628607) (xy 187.11995 -361.67572)
			(xy 187.088528 -361.718873) (xy 187.051397 -361.757225) (xy 187.030614 -361.773978) (xy 187.021812 -361.78159)
			(xy 187.011629 -361.802488) (xy 187.011056 -361.81411) (xy 187.011056 -361.893866) (xy 187.011609 -361.905497)
			(xy 187.021786 -361.926408) (xy 187.030614 -361.933998) (xy 187.053099 -361.952187) (xy 187.092834 -361.994207)
			(xy 187.125772 -362.041743) (xy 187.15116 -362.093704) (xy 187.168416 -362.148902) (xy 187.177145 -362.206072)
			(xy 187.17768 -362.234988) (xy 187.177233 -362.262242) (xy 187.169477 -362.316195) (xy 187.154121 -362.368495)
			(xy 187.131478 -362.418077) (xy 187.102009 -362.463931) (xy 187.094223 -362.472916) (xy 190.790826 -362.472916)
			(xy 190.790826 -362.38822) (xy 190.798877 -362.303906) (xy 190.814906 -362.22074) (xy 190.838767 -362.139473)
			(xy 190.870246 -362.060843) (xy 190.909057 -361.985562) (xy 190.954847 -361.91431) (xy 191.007203 -361.847734)
			(xy 191.065651 -361.786436) (xy 191.129661 -361.730971) (xy 191.198653 -361.681842) (xy 191.272003 -361.639493)
			(xy 191.349046 -361.604309) (xy 191.429085 -361.576607) (xy 191.511394 -361.556639) (xy 191.595229 -361.544586)
			(xy 191.67983 -361.540556) (xy 191.764431 -361.544586) (xy 191.848266 -361.556639) (xy 191.930575 -361.576607)
			(xy 192.010614 -361.604309) (xy 192.087657 -361.639493) (xy 192.161007 -361.681842) (xy 192.229999 -361.730971)
			(xy 192.294009 -361.786436) (xy 192.352457 -361.847734) (xy 192.404813 -361.91431) (xy 192.450603 -361.985562)
			(xy 192.489414 -362.060843) (xy 192.520893 -362.139473) (xy 192.544754 -362.22074) (xy 192.560783 -362.303906)
			(xy 192.568834 -362.38822) (xy 192.569338 -362.430568) (xy 192.568834 -362.472916) (xy 192.560783 -362.55723)
			(xy 192.544754 -362.640396) (xy 192.520893 -362.721663) (xy 192.489414 -362.800293) (xy 192.450603 -362.875574)
			(xy 192.404813 -362.946826) (xy 192.352457 -363.013402) (xy 192.294009 -363.0747) (xy 192.229999 -363.130165)
			(xy 192.161007 -363.179294) (xy 192.087657 -363.221643) (xy 192.010614 -363.256827) (xy 191.930575 -363.284529)
			(xy 191.848266 -363.304497) (xy 191.764431 -363.31655) (xy 191.67983 -363.320581) (xy 191.595229 -363.31655)
			(xy 191.511394 -363.304497) (xy 191.429085 -363.284529) (xy 191.349046 -363.256827) (xy 191.272003 -363.221643)
			(xy 191.198653 -363.179294) (xy 191.129661 -363.130165) (xy 191.065651 -363.0747) (xy 191.007203 -363.013402)
			(xy 190.954847 -362.946826) (xy 190.909057 -362.875574) (xy 190.870246 -362.800293) (xy 190.838767 -362.721663)
			(xy 190.814906 -362.640396) (xy 190.798877 -362.55723) (xy 190.790826 -362.472916) (xy 187.094223 -362.472916)
			(xy 187.066313 -362.505125) (xy 187.025118 -362.540819) (xy 186.979263 -362.570286) (xy 186.92968 -362.592927)
			(xy 186.877379 -362.608281) (xy 186.823426 -362.616035) (xy 186.796172 -362.616496) (xy 186.767257 -362.615928)
			(xy 186.710088 -362.607209) (xy 186.65489 -362.589961) (xy 186.602928 -362.564579) (xy 186.555393 -362.531644)
			(xy 186.513374 -362.491912) (xy 186.495182 -362.46943) (xy 186.487585 -362.460613) (xy 186.466676 -362.450438)
			(xy 186.45505 -362.449872) (xy 186.375294 -362.449872) (xy 186.36366 -362.450397) (xy 186.342749 -362.460593)
			(xy 186.335162 -362.46943) (xy 186.317 -362.491938) (xy 186.274973 -362.53167) (xy 186.227432 -362.564605)
			(xy 186.175465 -362.589989) (xy 186.120263 -362.607241) (xy 186.06309 -362.615964) (xy 186.034172 -362.616496)
			(xy 186.00692 -362.616048) (xy 185.95297 -362.608288) (xy 185.900674 -362.592928) (xy 185.851095 -362.570283)
			(xy 185.805245 -362.540813) (xy 185.764054 -362.505117) (xy 185.728363 -362.463923) (xy 185.698898 -362.418069)
			(xy 185.676258 -362.368489) (xy 185.660904 -362.316191) (xy 185.653149 -362.262241) (xy 185.652664 -362.234988)
			(xy 185.653221 -362.206072) (xy 185.661939 -362.148902) (xy 185.679187 -362.093703) (xy 185.704572 -362.04174)
			(xy 185.73751 -361.994206) (xy 185.777246 -361.952188) (xy 185.79973 -361.933998) (xy 185.808533 -361.926387)
			(xy 185.818718 -361.905489) (xy 185.819288 -361.893866) (xy 185.819288 -361.81411) (xy 185.818733 -361.80248)
			(xy 185.808556 -361.78157) (xy 185.79973 -361.773978) (xy 185.778937 -361.757238) (xy 185.741809 -361.718882)
			(xy 185.71039 -361.675725) (xy 185.685293 -361.62861) (xy 185.667009 -361.578457) (xy 185.655894 -361.526245)
			(xy 185.652165 -361.472993) (xy 180.568874 -361.472993) (xy 180.543318 -361.512507) (xy 180.525674 -361.53344)
			(xy 180.52542 -361.533694) (xy 180.51982 -361.540771) (xy 180.513584 -361.557696) (xy 180.513228 -361.566714)
			(xy 180.513228 -361.63377) (xy 180.513593 -361.642786) (xy 180.519835 -361.659703) (xy 180.52542 -361.66679)
			(xy 180.525674 -361.66679) (xy 180.525674 -361.667044) (xy 180.543356 -361.687943) (xy 180.573079 -361.733917)
			(xy 180.595922 -361.783669) (xy 180.611415 -361.836176) (xy 180.619239 -361.890359) (xy 180.619235 -361.945104)
			(xy 180.611401 -361.999286) (xy 180.595899 -362.051791) (xy 180.573048 -362.101539) (xy 180.543318 -362.147507)
			(xy 180.525674 -362.16844) (xy 180.52542 -362.168694) (xy 180.51982 -362.175771) (xy 180.513584 -362.192696)
			(xy 180.513228 -362.201714) (xy 180.513228 -362.26877) (xy 180.513593 -362.277786) (xy 180.519835 -362.294703)
			(xy 180.52542 -362.30179) (xy 180.525674 -362.30179) (xy 180.525674 -362.302044) (xy 180.543296 -362.32299)
			(xy 180.573012 -362.368958) (xy 180.595851 -362.418702) (xy 180.611346 -362.4712) (xy 180.619178 -362.525374)
			(xy 180.619654 -362.552742) (xy 180.619164 -362.580316) (xy 180.611219 -362.634888) (xy 180.5955 -362.687748)
			(xy 180.572334 -362.737795) (xy 180.542205 -362.783985) (xy 180.50574 -362.825356) (xy 180.485034 -362.843572)
			(xy 180.47696 -362.851128) (xy 180.467608 -362.871139) (xy 180.467 -362.88218) (xy 180.467 -362.95965)
			(xy 180.46758 -362.970758) (xy 180.47691 -362.990917) (xy 180.485034 -362.998512) (xy 180.488844 -363.001814)
			(xy 180.489098 -363.002068) (xy 180.496175 -363.007668) (xy 180.513099 -363.013905) (xy 180.522118 -363.01426)
			(xy 180.589174 -363.01426) (xy 180.598191 -363.013899) (xy 180.615108 -363.007655) (xy 180.622194 -363.002068)
			(xy 180.622194 -363.001814) (xy 180.622448 -363.001814) (xy 180.643381 -362.984173) (xy 180.689349 -362.954449)
			(xy 180.739095 -362.931603) (xy 180.791597 -362.916107) (xy 180.845775 -362.908278) (xy 180.900517 -362.908278)
			(xy 180.954695 -362.916107) (xy 181.007197 -362.931603) (xy 181.056943 -362.954449) (xy 181.102911 -362.984173)
			(xy 181.123844 -363.001814) (xy 181.124098 -363.002068) (xy 181.131175 -363.007668) (xy 181.148099 -363.013905)
			(xy 181.157118 -363.01426) (xy 181.224174 -363.01426) (xy 181.233191 -363.013899) (xy 181.250108 -363.007655)
			(xy 181.257194 -363.002068) (xy 181.257194 -363.001814) (xy 181.257448 -363.001814) (xy 181.278381 -362.984173)
			(xy 181.324349 -362.954449) (xy 181.374095 -362.931603) (xy 181.426597 -362.916107) (xy 181.480775 -362.908278)
			(xy 181.535517 -362.908278) (xy 181.589695 -362.916107) (xy 181.642197 -362.931603) (xy 181.691943 -362.954449)
			(xy 181.737911 -362.984173) (xy 181.758844 -363.001814) (xy 181.759098 -363.002068) (xy 181.766175 -363.007668)
			(xy 181.783099 -363.013905) (xy 181.792118 -363.01426) (xy 181.859174 -363.01426) (xy 181.868191 -363.013899)
			(xy 181.885108 -363.007655) (xy 181.892194 -363.002068) (xy 181.892194 -363.001814) (xy 181.892448 -363.001814)
			(xy 181.913391 -362.984188) (xy 181.95936 -362.954474) (xy 182.009105 -362.931635) (xy 182.061604 -362.916141)
			(xy 182.115778 -362.90831) (xy 182.143146 -362.907834) (xy 182.1704 -362.908235) (xy 182.224353 -362.915999)
			(xy 182.276652 -362.931362) (xy 182.326232 -362.954012) (xy 182.372085 -362.983487) (xy 182.413275 -363.019187)
			(xy 182.448966 -363.060386) (xy 182.478431 -363.106245) (xy 182.501069 -363.15583) (xy 182.51642 -363.208133)
			(xy 182.524171 -363.262088) (xy 182.524654 -363.289342) (xy 182.524165 -363.316712) (xy 182.516355 -363.37089)
			(xy 182.500871 -363.423393) (xy 182.478034 -363.473141) (xy 182.448314 -363.519108) (xy 182.430674 -363.54004)
			(xy 182.43042 -363.540294) (xy 182.42482 -363.547371) (xy 182.418584 -363.564296) (xy 182.418228 -363.573314)
			(xy 182.418228 -363.64037) (xy 182.418593 -363.649386) (xy 182.424835 -363.666303) (xy 182.43042 -363.67339)
			(xy 182.430674 -363.67339) (xy 182.430674 -363.673644) (xy 182.448296 -363.69459) (xy 182.478012 -363.740558)
			(xy 182.500851 -363.790302) (xy 182.516346 -363.8428) (xy 182.524178 -363.896974) (xy 182.524654 -363.924342)
			(xy 182.524161 -363.951592) (xy 182.5164 -364.005537) (xy 182.501042 -364.057829) (xy 182.4784 -364.107403)
			(xy 182.448933 -364.153251) (xy 182.413243 -364.19444) (xy 182.372055 -364.230131) (xy 182.326207 -364.259598)
			(xy 182.276633 -364.282241) (xy 182.224341 -364.2976) (xy 182.170396 -364.305361) (xy 182.143146 -364.30585)
			(xy 182.115776 -364.305369) (xy 182.061597 -364.297557) (xy 182.009094 -364.282072) (xy 181.959347 -364.259233)
			(xy 181.91338 -364.229511) (xy 181.892448 -364.21187) (xy 181.892194 -364.211616) (xy 181.885112 -364.206023)
			(xy 181.868192 -364.199779) (xy 181.859174 -364.199424) (xy 181.792118 -364.199424) (xy 181.783101 -364.199785)
			(xy 181.766184 -364.206029) (xy 181.759098 -364.211616) (xy 181.758844 -364.21187) (xy 181.737911 -364.229511)
			(xy 181.691943 -364.259235) (xy 181.642197 -364.282081) (xy 181.589695 -364.297577) (xy 181.535517 -364.305406)
			(xy 181.480775 -364.305406) (xy 181.426597 -364.297577) (xy 181.374095 -364.282081) (xy 181.324349 -364.259235)
			(xy 181.278381 -364.229511) (xy 181.257448 -364.21187) (xy 181.257194 -364.211616) (xy 181.250112 -364.206023)
			(xy 181.233192 -364.199779) (xy 181.224174 -364.199424) (xy 181.157118 -364.199424) (xy 181.148101 -364.199785)
			(xy 181.131184 -364.206029) (xy 181.124098 -364.211616) (xy 181.124098 -364.21187) (xy 181.123844 -364.21187)
			(xy 181.102911 -364.229511) (xy 181.056943 -364.259235) (xy 181.007197 -364.282081) (xy 180.954695 -364.297577)
			(xy 180.900517 -364.305406) (xy 180.845775 -364.305406) (xy 180.791597 -364.297577) (xy 180.739095 -364.282081)
			(xy 180.689349 -364.259235) (xy 180.643381 -364.229511) (xy 180.622448 -364.21187) (xy 180.622194 -364.211616)
			(xy 180.615112 -364.206023) (xy 180.598192 -364.199779) (xy 180.589174 -364.199424) (xy 180.522118 -364.199424)
			(xy 180.513101 -364.199785) (xy 180.496184 -364.206029) (xy 180.489098 -364.211616) (xy 180.489098 -364.21187)
			(xy 180.488844 -364.21187) (xy 180.467902 -364.229497) (xy 180.421933 -364.259212) (xy 180.372188 -364.282051)
			(xy 180.319689 -364.297544) (xy 180.265515 -364.305375) (xy 180.238146 -364.30585) (xy 180.210896 -364.305302)
			(xy 180.15695 -364.297552) (xy 180.104657 -364.282204) (xy 180.05508 -364.25957) (xy 180.009228 -364.230111)
			(xy 179.968036 -364.194426) (xy 179.932342 -364.153242) (xy 179.902872 -364.107398) (xy 179.880226 -364.057826)
			(xy 179.864866 -364.005536) (xy 179.857104 -363.951592) (xy 179.856638 -363.924342) (xy 178.37912 -363.924342)
			(xy 180.099208 -365.64443) (xy 180.106604 -365.651283) (xy 180.125202 -365.659025) (xy 180.135276 -365.659416)
			(xy 191.10071 -365.659416) (xy 191.126364 -365.64189) (xy 191.130936 -365.630714) (xy 191.099513 -365.605487)
			(xy 191.040866 -365.550215) (xy 190.987457 -365.489867) (xy 190.939723 -365.424937) (xy 190.898054 -365.355957)
			(xy 190.862793 -365.283493) (xy 190.834227 -365.208138) (xy 190.812591 -365.130508) (xy 190.798062 -365.05124)
			(xy 190.790759 -364.970984) (xy 190.790322 -364.93069) (xy 190.790826 -364.888342) (xy 190.798877 -364.804028)
			(xy 190.814906 -364.720862) (xy 190.838767 -364.639595) (xy 190.870246 -364.560965) (xy 190.909057 -364.485684)
			(xy 190.954847 -364.414432) (xy 191.007203 -364.347856) (xy 191.065651 -364.286558) (xy 191.129661 -364.231093)
			(xy 191.198653 -364.181964) (xy 191.272003 -364.139615) (xy 191.349046 -364.104431) (xy 191.429085 -364.076729)
			(xy 191.511394 -364.056761) (xy 191.595229 -364.044708) (xy 191.67983 -364.040678) (xy 191.764431 -364.044708)
			(xy 191.848266 -364.056761) (xy 191.930575 -364.076729) (xy 192.010614 -364.104431) (xy 192.087657 -364.139615)
			(xy 192.161007 -364.181964) (xy 192.229999 -364.231093) (xy 192.294009 -364.286558) (xy 192.352457 -364.347856)
			(xy 192.404813 -364.414432) (xy 192.450603 -364.485684) (xy 192.489414 -364.560965) (xy 192.520893 -364.639595)
			(xy 192.544754 -364.720862) (xy 192.560783 -364.804028) (xy 192.568834 -364.888342) (xy 192.569338 -364.93069)
			(xy 192.568887 -364.970984) (xy 192.561599 -365.051242) (xy 192.54708 -365.130512) (xy 192.52545 -365.208144)
			(xy 192.496887 -365.283501) (xy 192.461624 -365.355965) (xy 192.419951 -365.424942) (xy 192.37221 -365.489867)
			(xy 192.318791 -365.550208) (xy 192.260133 -365.605469) (xy 192.228724 -365.630714) (xy 192.233296 -365.64189)
			(xy 192.25895 -365.659416) (xy 193.047366 -365.659416) (xy 193.052385 -365.659322) (xy 193.062236 -365.6574)
			(xy 193.066924 -365.655606) (xy 197.733158 -363.724698) (xy 197.73772 -363.722688) (xy 197.746029 -363.717184)
			(xy 197.749668 -363.713776) (xy 199.18045 -362.283248) (xy 199.183881 -362.279629) (xy 199.189378 -362.271309)
			(xy 199.191372 -362.266738) (xy 202.487276 -354.31222) (xy 202.502392 -354.27741) (xy 202.540377 -354.21171)
			(xy 202.586611 -354.151528) (xy 202.613006 -354.12426) (xy 205.297278 -351.439988) (xy 205.320577 -351.417304)
			(xy 205.371415 -351.376754) (xy 205.426475 -351.342154) (xy 205.485064 -351.313938) (xy 205.546444 -351.292461)
			(xy 205.609844 -351.277994) (xy 205.674465 -351.27072) (xy 205.70698 -351.270316) (xy 206.267812 -351.270316)
			(xy 206.277882 -351.269891) (xy 206.296484 -351.262176) (xy 206.30388 -351.25533) (xy 206.421482 -351.137728)
			(xy 206.444782 -351.115047) (xy 206.495622 -351.074501) (xy 206.550683 -351.039904) (xy 206.609272 -351.011691)
			(xy 206.670652 -350.990218) (xy 206.73405 -350.975753) (xy 206.79867 -350.96848) (xy 206.831184 -350.968056)
			(xy 206.866204 -350.968583) (xy 206.935735 -350.977022) (xy 207.003741 -350.993777) (xy 207.069234 -351.018605)
			(xy 207.131257 -351.051145) (xy 207.188907 -351.090921) (xy 207.241343 -351.137354) (xy 207.287803 -351.189768)
			(xy 207.327607 -351.247398) (xy 207.360177 -351.309405) (xy 207.385038 -351.374885) (xy 207.401827 -351.442884)
			(xy 207.410299 -351.51241) (xy 207.410812 -351.54743) (xy 207.410273 -351.582315) (xy 207.40186 -351.651577)
			(xy 207.385197 -351.719329) (xy 207.360523 -351.784591) (xy 207.328196 -351.846421) (xy 207.288683 -351.903924)
			(xy 207.266032 -351.930462) (xy 207.260261 -351.937621) (xy 207.253753 -351.954804) (xy 207.253332 -351.96399)
			(xy 207.253332 -351.99447) (xy 207.253726 -352.003661) (xy 207.260244 -352.020847) (xy 207.266032 -352.027998)
			(xy 207.288714 -352.054512) (xy 207.32824 -352.112014) (xy 207.360575 -352.173846) (xy 207.385249 -352.239114)
			(xy 207.401907 -352.306873) (xy 207.410307 -352.376142) (xy 207.410812 -352.41103) (xy 207.410282 -352.446034)
			(xy 207.401843 -352.51553) (xy 207.385092 -352.583504) (xy 207.360272 -352.648964) (xy 207.327745 -352.710956)
			(xy 207.287986 -352.768577) (xy 207.241573 -352.820988) (xy 207.189184 -352.867424) (xy 207.13158 -352.90721)
			(xy 207.069603 -352.939764) (xy 207.004154 -352.964614) (xy 206.936188 -352.981396) (xy 206.866695 -352.989866)
			(xy 206.831692 -352.990404) (xy 206.831184 -352.990404) (xy 206.795229 -352.989866) (xy 206.723871 -352.980974)
			(xy 206.654163 -352.963318) (xy 206.587176 -352.937168) (xy 206.523942 -352.902926) (xy 206.49438 -352.882454)
			(xy 206.484947 -352.876456) (xy 206.462984 -352.872438) (xy 206.441379 -352.878075) (xy 206.432404 -352.88474)
			(xy 206.411774 -352.90127) (xy 206.366819 -352.929083) (xy 206.318454 -352.950423) (xy 206.267607 -352.964882)
			(xy 206.21525 -352.972182) (xy 206.188818 -352.972624) (xy 206.163013 -352.972217) (xy 206.111871 -352.965293)
			(xy 206.062131 -352.95153) (xy 206.014704 -352.931179) (xy 205.970458 -352.904612) (xy 205.950058 -352.888804)
			(xy 205.94256 -352.883325) (xy 205.924893 -352.877649) (xy 205.906364 -352.878632) (xy 205.889397 -352.886145)
			(xy 205.882494 -352.89236) (xy 205.509876 -353.265232) (xy 205.50251 -353.280472) (xy 205.501494 -353.289108)
			(xy 205.497365 -353.321329) (xy 205.48284 -353.384647) (xy 205.461331 -353.445945) (xy 205.433108 -353.504456)
			(xy 205.398523 -353.559447) (xy 205.358011 -353.61023) (xy 205.335378 -353.633532) (xy 205.033372 -353.935538)
			(xy 205.010091 -353.958195) (xy 204.959316 -353.998724) (xy 204.904325 -354.033317) (xy 204.845808 -354.061537)
			(xy 204.7845 -354.083031) (xy 204.721172 -354.097529) (xy 204.688948 -354.101654) (xy 204.680312 -354.10267)
			(xy 204.665072 -354.110036) (xy 203.76007 -355.014784) (xy 203.75664 -355.018404) (xy 203.751146 -355.026725)
			(xy 203.749148 -355.031294) (xy 200.453244 -362.985812) (xy 200.438132 -363.020625) (xy 200.400153 -363.086331)
			(xy 200.353925 -363.146519) (xy 200.327514 -363.173772) (xy 198.640192 -364.861348) (xy 198.612894 -364.887764)
			(xy 198.552625 -364.934004) (xy 198.486837 -364.971982) (xy 198.451978 -364.987078) (xy 195.364608 -366.26419)
			(xy 195.353973 -366.269187) (xy 195.33846 -366.286798) (xy 195.332383 -366.309467) (xy 195.334128 -366.321086)
			(xy 195.337684 -366.33912) (xy 195.365624 -366.36198) (xy 199.226678 -366.36198)
		)
		(stroke
			(width 0)
			(type solid)
		)
		(fill yes)
		(layer "In4.Cu")
		(net "GND")
	)
	(gr_poly
		(pts
			(xy 183.131714 -412.24708) (xy 183.142202 -412.246613) (xy 183.161475 -412.238345) (xy 183.169052 -412.231078)
			(xy 183.226964 -412.168848) (xy 183.233822 -412.14929) (xy 183.23306 -412.138622) (xy 183.232298 -412.112714)
			(xy 183.232784 -412.085463) (xy 183.24054 -412.031515) (xy 183.255895 -411.97922) (xy 183.278537 -411.929643)
			(xy 183.308003 -411.883793) (xy 183.343694 -411.842602) (xy 183.384885 -411.806911) (xy 183.430735 -411.777445)
			(xy 183.480312 -411.754803) (xy 183.532607 -411.739448) (xy 183.586555 -411.731692) (xy 183.641057 -411.731692)
			(xy 183.695005 -411.739448) (xy 183.7473 -411.754803) (xy 183.796877 -411.777445) (xy 183.842727 -411.806911)
			(xy 183.883918 -411.842602) (xy 183.919609 -411.883793) (xy 183.949075 -411.929643) (xy 183.971717 -411.97922)
			(xy 183.987072 -412.031515) (xy 183.994828 -412.085463) (xy 183.995314 -412.112714) (xy 183.994552 -412.138622)
			(xy 183.99379 -412.14929) (xy 184.000648 -412.168848) (xy 184.05856 -412.231078) (xy 184.066113 -412.238382)
			(xy 184.085401 -412.246657) (xy 184.095898 -412.24708) (xy 184.368948 -412.24708) (xy 184.377676 -412.246724)
			(xy 184.394111 -412.24084) (xy 184.407588 -412.229746) (xy 184.412382 -412.222442) (xy 184.42729 -412.198677)
			(xy 184.462975 -412.155393) (xy 184.504612 -412.117798) (xy 184.551303 -412.086701) (xy 184.602042 -412.062773)
			(xy 184.655737 -412.046529) (xy 184.711231 -412.038319) (xy 184.767329 -412.038319) (xy 184.822823 -412.046529)
			(xy 184.876518 -412.062773) (xy 184.927257 -412.086701) (xy 184.973948 -412.117798) (xy 185.015585 -412.155393)
			(xy 185.05127 -412.198677) (xy 185.066178 -412.222442) (xy 185.070991 -412.229724) (xy 185.084483 -412.240779)
			(xy 185.100892 -412.246696) (xy 185.109612 -412.24708) (xy 185.2041 -412.24708) (xy 185.213238 -412.246698)
			(xy 185.23035 -412.240282) (xy 185.244121 -412.228266) (xy 185.248804 -412.22041) (xy 185.262215 -412.196557)
			(xy 185.294823 -412.152612) (xy 185.333378 -412.11378) (xy 185.377089 -412.080859) (xy 185.425057 -412.054525)
			(xy 185.476298 -412.035318) (xy 185.529757 -412.023634) (xy 185.584338 -412.019713) (xy 185.638919 -412.023634)
			(xy 185.692378 -412.035318) (xy 185.743619 -412.054525) (xy 185.791587 -412.080859) (xy 185.835298 -412.11378)
			(xy 185.873853 -412.152612) (xy 185.906461 -412.196557) (xy 185.919872 -412.22041) (xy 185.924546 -412.228276)
			(xy 185.938318 -412.240301) (xy 185.955435 -412.246726) (xy 185.964576 -412.24708) (xy 186.80176 -412.24708)
			(xy 186.81262 -412.246513) (xy 186.832354 -412.237425) (xy 186.83986 -412.229554) (xy 186.858081 -412.20939)
			(xy 186.899249 -412.173913) (xy 186.945033 -412.144634) (xy 186.994507 -412.122146) (xy 187.046671 -412.106904)
			(xy 187.100469 -412.099215) (xy 187.127642 -412.098744) (xy 187.154816 -412.099207) (xy 187.208617 -412.106886)
			(xy 187.260784 -412.122125) (xy 187.310259 -412.144616) (xy 187.356039 -412.173903) (xy 187.397199 -412.209393)
			(xy 187.415424 -412.229554) (xy 187.422922 -412.237436) (xy 187.44266 -412.246536) (xy 187.453524 -412.24708)
			(xy 226.87788 -412.24708) (xy 226.887943 -412.246642) (xy 226.906525 -412.238905) (xy 226.913948 -412.232094)
			(xy 229.402386 -409.743656) (xy 229.409787 -409.736817) (xy 229.428385 -409.729105) (xy 229.438454 -409.72867)
			(xy 234.17403 -409.72867) (xy 234.184097 -409.728241) (xy 234.202691 -409.720515) (xy 234.210098 -409.713684)
			(xy 239.151414 -404.772368) (xy 239.158265 -404.764972) (xy 239.166001 -404.746373) (xy 239.1664 -404.7363)
			(xy 239.1664 -398.705578) (xy 239.165973 -398.69551) (xy 239.158253 -398.676911) (xy 239.151414 -398.66951)
			(xy 234.690666 -394.208762) (xy 234.683269 -394.201914) (xy 234.66467 -394.194182) (xy 234.654598 -394.193776)
			(xy 234.653582 -394.193776) (xy 229.922578 -389.462772) (xy 229.915182 -389.455921) (xy 229.896583 -389.448183)
			(xy 229.88651 -389.447786) (xy 229.38867 -389.447786) (xy 229.37808 -389.448339) (xy 229.358697 -389.456886)
			(xy 229.344371 -389.472491) (xy 229.34041 -389.48233) (xy 229.310897 -389.568108) (xy 229.245306 -389.737262)
			(xy 229.172348 -389.90337) (xy 229.092163 -390.066113) (xy 229.004905 -390.225176) (xy 228.910744 -390.380253)
			(xy 228.809861 -390.531042) (xy 228.70245 -390.677255) (xy 228.588721 -390.818607) (xy 228.468891 -390.954827)
			(xy 228.343192 -391.08565) (xy 228.211868 -391.210825) (xy 228.075171 -391.33011) (xy 227.933365 -391.443275)
			(xy 227.786725 -391.5501) (xy 227.635534 -391.65038) (xy 227.480083 -391.743922) (xy 227.320673 -391.830543)
			(xy 227.157611 -391.910078) (xy 226.991212 -391.982373) (xy 226.821798 -392.047287) (xy 226.735894 -392.076432)
			(xy 226.718114 -392.082528) (xy 226.69881 -392.114278) (xy 226.71786 -392.23188) (xy 226.719636 -392.24072)
			(xy 226.728473 -392.256424) (xy 226.74221 -392.268086) (xy 226.759141 -392.274255) (xy 226.768152 -392.274552)
			(xy 226.78771 -392.274552) (xy 226.807711 -392.275022) (xy 226.846951 -392.282782) (xy 226.883926 -392.298041)
			(xy 226.917219 -392.320214) (xy 226.931728 -392.333988) (xy 228.020118 -393.422378) (xy 228.033918 -393.436878)
			(xy 228.056149 -393.470159) (xy 228.071469 -393.507133) (xy 228.079288 -393.546385) (xy 228.079808 -393.566396)
			(xy 228.079808 -398.305789) (xy 229.449878 -398.305789) (xy 229.453609 -398.252536) (xy 229.464728 -398.200322)
			(xy 229.483016 -398.150169) (xy 229.508117 -398.103054) (xy 229.539541 -398.059899) (xy 229.576674 -398.021545)
			(xy 229.597458 -398.004792) (xy 229.606229 -397.997239) (xy 229.616405 -397.976473) (xy 229.617016 -397.964914)
			(xy 229.617016 -397.88465) (xy 229.616411 -397.873087) (xy 229.60624 -397.852316) (xy 229.597458 -397.844772)
			(xy 229.576657 -397.82804) (xy 229.539527 -397.789684) (xy 229.508105 -397.746527) (xy 229.483007 -397.699411)
			(xy 229.464721 -397.649256) (xy 229.453606 -397.597042) (xy 229.449878 -397.543789) (xy 229.453609 -397.490536)
			(xy 229.464728 -397.438322) (xy 229.483016 -397.388169) (xy 229.508117 -397.341054) (xy 229.539541 -397.297899)
			(xy 229.576674 -397.259545) (xy 229.597458 -397.242792) (xy 229.606229 -397.235239) (xy 229.616405 -397.214473)
			(xy 229.617016 -397.202914) (xy 229.617016 -397.12265) (xy 229.616411 -397.111087) (xy 229.60624 -397.090316)
			(xy 229.597458 -397.082772) (xy 229.576657 -397.06604) (xy 229.539527 -397.027684) (xy 229.508105 -396.984527)
			(xy 229.483007 -396.937411) (xy 229.464721 -396.887256) (xy 229.453606 -396.835042) (xy 229.449878 -396.781789)
			(xy 229.453609 -396.728536) (xy 229.464728 -396.676322) (xy 229.483016 -396.626169) (xy 229.508117 -396.579054)
			(xy 229.539541 -396.535899) (xy 229.576674 -396.497545) (xy 229.597458 -396.480792) (xy 229.606229 -396.473239)
			(xy 229.616405 -396.452473) (xy 229.617016 -396.440914) (xy 229.617016 -396.36065) (xy 229.616411 -396.349087)
			(xy 229.60624 -396.328316) (xy 229.597458 -396.320772) (xy 229.576657 -396.30404) (xy 229.539527 -396.265684)
			(xy 229.508105 -396.222527) (xy 229.483007 -396.175411) (xy 229.464721 -396.125256) (xy 229.453606 -396.073042)
			(xy 229.449878 -396.019789) (xy 229.453609 -395.966536) (xy 229.464728 -395.914322) (xy 229.483016 -395.864169)
			(xy 229.508117 -395.817054) (xy 229.539541 -395.773899) (xy 229.576674 -395.735545) (xy 229.597458 -395.718792)
			(xy 229.606229 -395.711239) (xy 229.616405 -395.690473) (xy 229.617016 -395.678914) (xy 229.617016 -395.59865)
			(xy 229.616411 -395.587087) (xy 229.60624 -395.566316) (xy 229.597458 -395.558772) (xy 229.574952 -395.540607)
			(xy 229.53522 -395.498581) (xy 229.502285 -395.45104) (xy 229.476901 -395.399074) (xy 229.459649 -395.343872)
			(xy 229.450925 -395.286699) (xy 229.450392 -395.257782) (xy 229.450861 -395.23053) (xy 229.45862 -395.176582)
			(xy 229.473977 -395.124287) (xy 229.496621 -395.07471) (xy 229.526089 -395.028859) (xy 229.561782 -394.987669)
			(xy 229.602974 -394.951978) (xy 229.648825 -394.922512) (xy 229.698404 -394.899871) (xy 229.7507 -394.884516)
			(xy 229.804648 -394.87676) (xy 229.8319 -394.876274) (xy 229.860818 -394.876764) (xy 229.917992 -394.885495)
			(xy 229.973193 -394.902757) (xy 230.025155 -394.928154) (xy 230.072688 -394.961103) (xy 230.114702 -395.000851)
			(xy 230.13289 -395.02334) (xy 230.140454 -395.0321) (xy 230.161211 -395.042283) (xy 230.172768 -395.042898)
			(xy 230.253032 -395.042898) (xy 230.264595 -395.042289) (xy 230.285366 -395.032122) (xy 230.29291 -395.02334)
			(xy 230.309663 -395.002557) (xy 230.348017 -394.965427) (xy 230.391171 -394.934005) (xy 230.438285 -394.908906)
			(xy 230.488437 -394.89062) (xy 230.540648 -394.879503) (xy 230.5939 -394.875773) (xy 230.647152 -394.879503)
			(xy 230.699363 -394.89062) (xy 230.749515 -394.908906) (xy 230.796629 -394.934005) (xy 230.839783 -394.965427)
			(xy 230.878137 -395.002557) (xy 230.89489 -395.02334) (xy 230.902454 -395.0321) (xy 230.923211 -395.042283)
			(xy 230.934768 -395.042898) (xy 231.015032 -395.042898) (xy 231.026595 -395.042289) (xy 231.047366 -395.032122)
			(xy 231.05491 -395.02334) (xy 231.071663 -395.002557) (xy 231.110017 -394.965427) (xy 231.153171 -394.934005)
			(xy 231.200285 -394.908906) (xy 231.250437 -394.89062) (xy 231.302648 -394.879503) (xy 231.3559 -394.875773)
			(xy 231.409152 -394.879503) (xy 231.461363 -394.89062) (xy 231.511515 -394.908906) (xy 231.558629 -394.934005)
			(xy 231.601783 -394.965427) (xy 231.640137 -395.002557) (xy 231.65689 -395.02334) (xy 231.664454 -395.0321)
			(xy 231.685211 -395.042283) (xy 231.696768 -395.042898) (xy 231.777032 -395.042898) (xy 231.788595 -395.042289)
			(xy 231.809366 -395.032122) (xy 231.81691 -395.02334) (xy 231.833663 -395.002557) (xy 231.872017 -394.965427)
			(xy 231.915171 -394.934005) (xy 231.962285 -394.908906) (xy 232.012437 -394.89062) (xy 232.064648 -394.879503)
			(xy 232.1179 -394.875773) (xy 232.171152 -394.879503) (xy 232.223363 -394.89062) (xy 232.273515 -394.908906)
			(xy 232.320629 -394.934005) (xy 232.363783 -394.965427) (xy 232.402137 -395.002557) (xy 232.41889 -395.02334)
			(xy 232.426454 -395.0321) (xy 232.447211 -395.042283) (xy 232.458768 -395.042898) (xy 232.539032 -395.042898)
			(xy 232.550595 -395.042289) (xy 232.571366 -395.032122) (xy 232.57891 -395.02334) (xy 232.595663 -395.002557)
			(xy 232.634017 -394.965427) (xy 232.677171 -394.934005) (xy 232.724285 -394.908906) (xy 232.774437 -394.89062)
			(xy 232.826648 -394.879503) (xy 232.8799 -394.875773) (xy 232.933152 -394.879503) (xy 232.985363 -394.89062)
			(xy 233.035515 -394.908906) (xy 233.082629 -394.934005) (xy 233.125783 -394.965427) (xy 233.164137 -395.002557)
			(xy 233.18089 -395.02334) (xy 233.188454 -395.0321) (xy 233.209211 -395.042283) (xy 233.220768 -395.042898)
			(xy 233.301032 -395.042898) (xy 233.312595 -395.042289) (xy 233.333366 -395.032122) (xy 233.34091 -395.02334)
			(xy 233.357663 -395.002557) (xy 233.396017 -394.965427) (xy 233.439171 -394.934005) (xy 233.486285 -394.908906)
			(xy 233.536437 -394.89062) (xy 233.588648 -394.879503) (xy 233.6419 -394.875773) (xy 233.695152 -394.879503)
			(xy 233.747363 -394.89062) (xy 233.797515 -394.908906) (xy 233.844629 -394.934005) (xy 233.887783 -394.965427)
			(xy 233.926137 -395.002557) (xy 233.94289 -395.02334) (xy 233.950454 -395.0321) (xy 233.971211 -395.042283)
			(xy 233.982768 -395.042898) (xy 234.063032 -395.042898) (xy 234.074595 -395.042289) (xy 234.095366 -395.032122)
			(xy 234.10291 -395.02334) (xy 234.121105 -395.00086) (xy 234.163123 -394.961123) (xy 234.210657 -394.928182)
			(xy 234.262617 -394.902793) (xy 234.317815 -394.885536) (xy 234.374984 -394.876808) (xy 234.4039 -394.876274)
			(xy 234.43115 -394.876778) (xy 234.485097 -394.884534) (xy 234.53739 -394.899888) (xy 234.586966 -394.922528)
			(xy 234.632815 -394.951992) (xy 234.674005 -394.987682) (xy 234.709697 -395.02887) (xy 234.739164 -395.074718)
			(xy 234.761806 -395.124293) (xy 234.777162 -395.176586) (xy 234.784921 -395.230532) (xy 234.785408 -395.257782)
			(xy 234.784912 -395.2867) (xy 234.776183 -395.343874) (xy 234.758923 -395.399075) (xy 234.733527 -395.451037)
			(xy 234.700578 -395.49857) (xy 234.660831 -395.540584) (xy 234.638342 -395.558772) (xy 234.629587 -395.56634)
			(xy 234.619402 -395.587095) (xy 234.618784 -395.59865) (xy 234.618784 -395.678914) (xy 234.619352 -395.690482)
			(xy 234.629549 -395.711252) (xy 234.638342 -395.718792) (xy 234.659107 -395.735567) (xy 234.696237 -395.773917)
			(xy 234.727659 -395.817069) (xy 234.752758 -395.86418) (xy 234.771045 -395.91433) (xy 234.782163 -395.96654)
			(xy 234.785894 -396.019789) (xy 234.782166 -396.073039) (xy 234.771051 -396.125249) (xy 234.752767 -396.175399)
			(xy 234.72767 -396.222512) (xy 234.696252 -396.265666) (xy 234.659124 -396.304019) (xy 234.638342 -396.320772)
			(xy 234.629587 -396.32834) (xy 234.619402 -396.349095) (xy 234.618784 -396.36065) (xy 234.618784 -396.440914)
			(xy 234.619352 -396.452482) (xy 234.629549 -396.473252) (xy 234.638342 -396.480792) (xy 234.659107 -396.497567)
			(xy 234.696237 -396.535917) (xy 234.727659 -396.579069) (xy 234.752758 -396.62618) (xy 234.771045 -396.67633)
			(xy 234.782163 -396.72854) (xy 234.785894 -396.781789) (xy 234.782166 -396.835039) (xy 234.771051 -396.887249)
			(xy 234.752767 -396.937399) (xy 234.72767 -396.984512) (xy 234.696252 -397.027666) (xy 234.659124 -397.066019)
			(xy 234.638342 -397.082772) (xy 234.629587 -397.09034) (xy 234.619402 -397.111095) (xy 234.618784 -397.12265)
			(xy 234.618784 -397.202914) (xy 234.619352 -397.214482) (xy 234.629549 -397.235252) (xy 234.638342 -397.242792)
			(xy 234.66083 -397.260977) (xy 234.700563 -397.302999) (xy 234.733501 -397.350536) (xy 234.758888 -397.402498)
			(xy 234.776143 -397.457696) (xy 234.784873 -397.514866) (xy 234.785408 -397.543782) (xy 234.784928 -397.571034)
			(xy 234.777173 -397.624985) (xy 234.76182 -397.677282) (xy 234.739179 -397.726862) (xy 234.709713 -397.772716)
			(xy 234.674021 -397.813908) (xy 234.63283 -397.849602) (xy 234.586978 -397.879071) (xy 234.537399 -397.901713)
			(xy 234.485102 -397.91707) (xy 234.431152 -397.924827) (xy 234.4039 -397.92529) (xy 234.374983 -397.924775)
			(xy 234.317811 -397.916046) (xy 234.262612 -397.898788) (xy 234.210651 -397.873395) (xy 234.163117 -397.840451)
			(xy 234.1211 -397.80071) (xy 234.10291 -397.778224) (xy 234.095352 -397.769458) (xy 234.07459 -397.75928)
			(xy 234.063032 -397.758666) (xy 233.982768 -397.758666) (xy 233.971202 -397.759252) (xy 233.950429 -397.769433)
			(xy 233.94289 -397.778224) (xy 233.92811 -397.796622) (xy 233.894741 -397.829993) (xy 233.876342 -397.844772)
			(xy 233.867587 -397.85234) (xy 233.857402 -397.873095) (xy 233.856784 -397.88465) (xy 233.856784 -397.964914)
			(xy 233.857352 -397.976482) (xy 233.867549 -397.997252) (xy 233.876342 -398.004792) (xy 233.897107 -398.021567)
			(xy 233.934237 -398.059917) (xy 233.965659 -398.103069) (xy 233.990758 -398.15018) (xy 234.009045 -398.20033)
			(xy 234.020163 -398.25254) (xy 234.023894 -398.305789) (xy 234.020166 -398.359039) (xy 234.009051 -398.411249)
			(xy 233.990767 -398.461399) (xy 233.96567 -398.508512) (xy 233.934252 -398.551666) (xy 233.897124 -398.590019)
			(xy 233.876342 -398.606772) (xy 233.867587 -398.61434) (xy 233.857402 -398.635095) (xy 233.856784 -398.64665)
			(xy 233.856784 -398.726914) (xy 233.857352 -398.738482) (xy 233.867549 -398.759252) (xy 233.876342 -398.766792)
			(xy 233.89883 -398.784977) (xy 233.938563 -398.826999) (xy 233.971501 -398.874536) (xy 233.996888 -398.926498)
			(xy 234.014143 -398.981696) (xy 234.022873 -399.038866) (xy 234.023408 -399.067782) (xy 234.022928 -399.095034)
			(xy 234.015173 -399.148985) (xy 233.99982 -399.201282) (xy 233.977179 -399.250862) (xy 233.947713 -399.296716)
			(xy 233.912021 -399.337908) (xy 233.87083 -399.373602) (xy 233.824978 -399.403071) (xy 233.775399 -399.425713)
			(xy 233.723102 -399.44107) (xy 233.669152 -399.448827) (xy 233.6419 -399.44929) (xy 233.612983 -399.448775)
			(xy 233.555811 -399.440046) (xy 233.500612 -399.422788) (xy 233.448651 -399.397395) (xy 233.401117 -399.364451)
			(xy 233.3591 -399.32471) (xy 233.34091 -399.302224) (xy 233.333352 -399.293458) (xy 233.31259 -399.28328)
			(xy 233.301032 -399.282666) (xy 233.220768 -399.282666) (xy 233.209202 -399.283252) (xy 233.188429 -399.293433)
			(xy 233.18089 -399.302224) (xy 233.164137 -399.323007) (xy 233.125783 -399.360137) (xy 233.082629 -399.391559)
			(xy 233.035515 -399.416658) (xy 232.985363 -399.434944) (xy 232.933152 -399.446061) (xy 232.8799 -399.449791)
			(xy 232.826648 -399.446061) (xy 232.774437 -399.434944) (xy 232.724285 -399.416658) (xy 232.677171 -399.391559)
			(xy 232.634017 -399.360137) (xy 232.595663 -399.323007) (xy 232.57891 -399.302224) (xy 232.571352 -399.293458)
			(xy 232.55059 -399.28328) (xy 232.539032 -399.282666) (xy 232.458768 -399.282666) (xy 232.447202 -399.283252)
			(xy 232.426429 -399.293433) (xy 232.41889 -399.302224) (xy 232.402137 -399.323007) (xy 232.363783 -399.360137)
			(xy 232.320629 -399.391559) (xy 232.273515 -399.416658) (xy 232.223363 -399.434944) (xy 232.171152 -399.446061)
			(xy 232.1179 -399.449791) (xy 232.064648 -399.446061) (xy 232.012437 -399.434944) (xy 231.962285 -399.416658)
			(xy 231.915171 -399.391559) (xy 231.872017 -399.360137) (xy 231.833663 -399.323007) (xy 231.81691 -399.302224)
			(xy 231.809352 -399.293458) (xy 231.78859 -399.28328) (xy 231.777032 -399.282666) (xy 231.696768 -399.282666)
			(xy 231.685202 -399.283252) (xy 231.664429 -399.293433) (xy 231.65689 -399.302224) (xy 231.640137 -399.323007)
			(xy 231.601783 -399.360137) (xy 231.558629 -399.391559) (xy 231.511515 -399.416658) (xy 231.461363 -399.434944)
			(xy 231.409152 -399.446061) (xy 231.3559 -399.449791) (xy 231.302648 -399.446061) (xy 231.250437 -399.434944)
			(xy 231.200285 -399.416658) (xy 231.153171 -399.391559) (xy 231.110017 -399.360137) (xy 231.071663 -399.323007)
			(xy 231.05491 -399.302224) (xy 231.047352 -399.293458) (xy 231.02659 -399.28328) (xy 231.015032 -399.282666)
			(xy 230.934768 -399.282666) (xy 230.923202 -399.283252) (xy 230.902429 -399.293433) (xy 230.89489 -399.302224)
			(xy 230.878137 -399.323007) (xy 230.839783 -399.360137) (xy 230.796629 -399.391559) (xy 230.749515 -399.416658)
			(xy 230.699363 -399.434944) (xy 230.647152 -399.446061) (xy 230.5939 -399.449791) (xy 230.540648 -399.446061)
			(xy 230.488437 -399.434944) (xy 230.438285 -399.416658) (xy 230.391171 -399.391559) (xy 230.348017 -399.360137)
			(xy 230.309663 -399.323007) (xy 230.29291 -399.302224) (xy 230.285352 -399.293458) (xy 230.26459 -399.28328)
			(xy 230.253032 -399.282666) (xy 230.172768 -399.282666) (xy 230.161202 -399.283252) (xy 230.140429 -399.293433)
			(xy 230.13289 -399.302224) (xy 230.114711 -399.324717) (xy 230.072688 -399.364451) (xy 230.02515 -399.397388)
			(xy 229.973187 -399.422774) (xy 229.917987 -399.440029) (xy 229.860817 -399.448756) (xy 229.8319 -399.44929)
			(xy 229.804646 -399.448845) (xy 229.750694 -399.441087) (xy 229.698395 -399.42573) (xy 229.648813 -399.403086)
			(xy 229.602959 -399.373617) (xy 229.561766 -399.337921) (xy 229.526072 -399.296726) (xy 229.496605 -399.250871)
			(xy 229.473963 -399.201289) (xy 229.458609 -399.148989) (xy 229.450854 -399.095036) (xy 229.450392 -399.067782)
			(xy 229.450934 -399.038866) (xy 229.459654 -398.981694) (xy 229.476904 -398.926494) (xy 229.502291 -398.874531)
			(xy 229.535233 -398.826997) (xy 229.574973 -398.784981) (xy 229.597458 -398.766792) (xy 229.606229 -398.759239)
			(xy 229.616405 -398.738473) (xy 229.617016 -398.726914) (xy 229.617016 -398.64665) (xy 229.616411 -398.635087)
			(xy 229.60624 -398.614316) (xy 229.597458 -398.606772) (xy 229.576657 -398.59004) (xy 229.539527 -398.551684)
			(xy 229.508105 -398.508527) (xy 229.483007 -398.461411) (xy 229.464721 -398.411256) (xy 229.453606 -398.359042)
			(xy 229.449878 -398.305789) (xy 228.079808 -398.305789) (xy 228.079808 -398.591278) (xy 228.080414 -398.603321)
			(xy 228.091294 -398.624801) (xy 228.100636 -398.632426) (xy 228.121149 -398.647858) (xy 228.158239 -398.683343)
			(xy 228.190231 -398.723485) (xy 228.216546 -398.767558) (xy 228.236708 -398.814763) (xy 228.250351 -398.864248)
			(xy 228.25723 -398.915116) (xy 228.257608 -398.940782) (xy 228.257161 -398.967188) (xy 228.249877 -399.019495)
			(xy 228.235446 -399.070297) (xy 228.214145 -399.118622) (xy 228.18638 -399.163546) (xy 228.152682 -399.20421)
			(xy 228.113697 -399.239836) (xy 228.070169 -399.269743) (xy 228.022932 -399.293358) (xy 227.972888 -399.31023)
			(xy 227.920994 -399.320037) (xy 227.894642 -399.321782) (xy 227.879148 -399.322544) (xy 227.855018 -399.34007)
			(xy 227.816156 -399.440908) (xy 227.812983 -399.450229) (xy 227.813244 -399.469897) (xy 227.820937 -399.488001)
			(xy 227.827586 -399.495264) (xy 228.020118 -399.687542) (xy 228.033921 -399.702041) (xy 228.056158 -399.735321)
			(xy 228.071484 -399.772295) (xy 228.07931 -399.811548) (xy 228.079808 -399.83156) (xy 228.079808 -400.820636)
			(xy 228.080405 -400.832684) (xy 228.091274 -400.854179) (xy 228.100636 -400.861784) (xy 228.121146 -400.877217)
			(xy 228.15823 -400.912704) (xy 228.190216 -400.952847) (xy 228.216525 -400.99692) (xy 228.236679 -401.044126)
			(xy 228.250315 -401.09361) (xy 228.257186 -401.144476) (xy 228.257608 -401.17014) (xy 228.257122 -401.197391)
			(xy 228.249366 -401.251339) (xy 228.234011 -401.303634) (xy 228.211369 -401.353211) (xy 228.181903 -401.399061)
			(xy 228.146212 -401.440252) (xy 228.105021 -401.475943) (xy 228.059171 -401.505409) (xy 228.009594 -401.528051)
			(xy 227.957299 -401.543406) (xy 227.903351 -401.551162) (xy 227.848849 -401.551162) (xy 227.794901 -401.543406)
			(xy 227.742606 -401.528051) (xy 227.693029 -401.505409) (xy 227.647179 -401.475943) (xy 227.605988 -401.440252)
			(xy 227.570297 -401.399061) (xy 227.540831 -401.353211) (xy 227.518189 -401.303634) (xy 227.502834 -401.251339)
			(xy 227.495078 -401.197391) (xy 227.494592 -401.17014) (xy 227.495182 -401.140198) (xy 227.504551 -401.081051)
			(xy 227.523047 -401.024095) (xy 227.550218 -400.97073) (xy 227.585395 -400.922267) (xy 227.627714 -400.879897)
			(xy 227.651564 -400.861784) (xy 227.66086 -400.854127) (xy 227.671713 -400.832662) (xy 227.672392 -400.820636)
			(xy 227.672392 -399.93697) (xy 227.67194 -399.926944) (xy 227.664345 -399.90839) (xy 227.65766 -399.900902)
			(xy 227.568252 -399.811748) (xy 227.560818 -399.805032) (xy 227.542318 -399.797396) (xy 227.522304 -399.797396)
			(xy 227.503804 -399.805032) (xy 227.49637 -399.811748) (xy 227.486718 -399.8214) (xy 227.47986 -399.847308)
			(xy 227.483162 -399.860516) (xy 227.488946 -399.884162) (xy 227.495185 -399.932442) (xy 227.495608 -399.956782)
			(xy 227.495016 -399.986723) (xy 227.485645 -400.045868) (xy 227.467146 -400.102822) (xy 227.439973 -400.156184)
			(xy 227.404795 -400.204645) (xy 227.362476 -400.247012) (xy 227.338636 -400.265138) (xy 227.329343 -400.272796)
			(xy 227.3185 -400.294262) (xy 227.317808 -400.306286) (xy 227.317808 -401.410678) (xy 227.318251 -401.420708)
			(xy 227.325832 -401.439276) (xy 227.33254 -401.446746) (xy 227.647754 -401.76196) (xy 227.655179 -401.768739)
			(xy 227.673775 -401.77634) (xy 227.683822 -401.776692) (xy 228.47173 -401.776692) (xy 228.481756 -401.77624)
			(xy 228.50031 -401.768645) (xy 228.507798 -401.76196) (xy 228.74478 -401.524978) (xy 228.751556 -401.517553)
			(xy 228.759145 -401.498956) (xy 228.759512 -401.48891) (xy 228.759512 -400.36242) (xy 228.75997 -400.342403)
			(xy 228.767784 -400.303139) (xy 228.783115 -400.266158) (xy 228.805373 -400.232882) (xy 228.819202 -400.218402)
			(xy 229.253542 -399.784062) (xy 229.268042 -399.770261) (xy 229.301322 -399.748026) (xy 229.338296 -399.732701)
			(xy 229.377548 -399.724875) (xy 229.39756 -399.724372) (xy 236.838998 -399.724372) (xy 236.859014 -399.724832)
			(xy 236.898274 -399.732651) (xy 236.93525 -399.747988) (xy 236.968519 -399.770252) (xy 236.983016 -399.784062)
			(xy 237.687612 -400.488912) (xy 237.710472 -400.496278) (xy 237.722664 -400.494246) (xy 237.737427 -400.492082)
			(xy 237.76718 -400.489791) (xy 237.7821 -400.489674) (xy 237.809354 -400.490137) (xy 237.863308 -400.497894)
			(xy 237.915609 -400.513251) (xy 237.965192 -400.535896) (xy 238.011048 -400.565365) (xy 238.052243 -400.601062)
			(xy 238.087938 -400.642257) (xy 238.117407 -400.688113) (xy 238.140051 -400.737696) (xy 238.155407 -400.789997)
			(xy 238.163164 -400.843952) (xy 238.163163 -400.89846) (xy 238.155404 -400.952414) (xy 238.140046 -401.004715)
			(xy 238.117402 -401.054298) (xy 238.087931 -401.100153) (xy 238.052234 -401.141347) (xy 238.011038 -401.177042)
			(xy 237.965182 -401.20651) (xy 237.915598 -401.229153) (xy 237.863297 -401.244508) (xy 237.809342 -401.252264)
			(xy 237.754834 -401.252262) (xy 237.70088 -401.244503) (xy 237.648579 -401.229144) (xy 237.598997 -401.206499)
			(xy 237.553142 -401.177027) (xy 237.511949 -401.14133) (xy 237.476255 -401.100133) (xy 237.446787 -401.054276)
			(xy 237.424145 -401.004692) (xy 237.408791 -400.952391) (xy 237.401036 -400.898436) (xy 237.400592 -400.871182)
			(xy 237.400717 -400.856262) (xy 237.403005 -400.82651) (xy 237.405164 -400.811746) (xy 237.407196 -400.799554)
			(xy 237.39983 -400.776694) (xy 236.769656 -400.14652) (xy 236.762235 -400.139731) (xy 236.743638 -400.132114)
			(xy 236.733588 -400.131788) (xy 229.50297 -400.131788) (xy 229.492944 -400.13224) (xy 229.474388 -400.139833)
			(xy 229.466902 -400.14652) (xy 229.18166 -400.431762) (xy 229.174881 -400.439187) (xy 229.167279 -400.457783)
			(xy 229.166928 -400.46783) (xy 229.166928 -400.617182) (xy 229.73614 -400.617182) (xy 229.740211 -400.56156)
			(xy 229.752337 -400.507123) (xy 229.77226 -400.455032) (xy 229.799556 -400.406397) (xy 229.833642 -400.362254)
			(xy 229.873791 -400.323545) (xy 229.919149 -400.291094) (xy 229.968749 -400.265593) (xy 230.021533 -400.247586)
			(xy 230.076376 -400.237456) (xy 230.13211 -400.235419) (xy 230.187547 -400.241519) (xy 230.241504 -400.255625)
			(xy 230.292833 -400.277437) (xy 230.340439 -400.306491) (xy 230.383307 -400.342166) (xy 230.420524 -400.383703)
			(xy 230.451297 -400.430216) (xy 230.474969 -400.480713) (xy 230.491037 -400.53412) (xy 230.499157 -400.589296)
			(xy 230.499666 -400.617182) (xy 231.15854 -400.617182) (xy 231.162611 -400.56156) (xy 231.174737 -400.507123)
			(xy 231.19466 -400.455032) (xy 231.221956 -400.406397) (xy 231.256042 -400.362254) (xy 231.296191 -400.323545)
			(xy 231.341549 -400.291094) (xy 231.391149 -400.265593) (xy 231.443933 -400.247586) (xy 231.498776 -400.237456)
			(xy 231.55451 -400.235419) (xy 231.609947 -400.241519) (xy 231.663904 -400.255625) (xy 231.715233 -400.277437)
			(xy 231.762839 -400.306491) (xy 231.805707 -400.342166) (xy 231.842924 -400.383703) (xy 231.873697 -400.430216)
			(xy 231.897369 -400.480713) (xy 231.913437 -400.53412) (xy 231.921557 -400.589296) (xy 231.922066 -400.617182)
			(xy 232.55554 -400.617182) (xy 232.559611 -400.56156) (xy 232.571737 -400.507123) (xy 232.59166 -400.455032)
			(xy 232.618956 -400.406397) (xy 232.653042 -400.362254) (xy 232.693191 -400.323545) (xy 232.738549 -400.291094)
			(xy 232.788149 -400.265593) (xy 232.840933 -400.247586) (xy 232.895776 -400.237456) (xy 232.95151 -400.235419)
			(xy 233.006947 -400.241519) (xy 233.060904 -400.255625) (xy 233.112233 -400.277437) (xy 233.159839 -400.306491)
			(xy 233.202707 -400.342166) (xy 233.239924 -400.383703) (xy 233.270697 -400.430216) (xy 233.294369 -400.480713)
			(xy 233.310437 -400.53412) (xy 233.318557 -400.589296) (xy 233.319066 -400.617182) (xy 233.318557 -400.645068)
			(xy 233.310437 -400.700244) (xy 233.294369 -400.753651) (xy 233.270697 -400.804148) (xy 233.239924 -400.850661)
			(xy 233.202707 -400.892198) (xy 233.159839 -400.927873) (xy 233.112233 -400.956927) (xy 233.060904 -400.978739)
			(xy 233.006947 -400.992845) (xy 232.95151 -400.998945) (xy 232.895776 -400.996908) (xy 232.840933 -400.986778)
			(xy 232.788149 -400.968771) (xy 232.738549 -400.94327) (xy 232.693191 -400.910819) (xy 232.653042 -400.87211)
			(xy 232.618956 -400.827967) (xy 232.59166 -400.779332) (xy 232.571737 -400.727241) (xy 232.559611 -400.672804)
			(xy 232.55554 -400.617182) (xy 231.922066 -400.617182) (xy 231.921557 -400.645068) (xy 231.913437 -400.700244)
			(xy 231.897369 -400.753651) (xy 231.873697 -400.804148) (xy 231.842924 -400.850661) (xy 231.805707 -400.892198)
			(xy 231.762839 -400.927873) (xy 231.715233 -400.956927) (xy 231.663904 -400.978739) (xy 231.609947 -400.992845)
			(xy 231.55451 -400.998945) (xy 231.498776 -400.996908) (xy 231.443933 -400.986778) (xy 231.391149 -400.968771)
			(xy 231.341549 -400.94327) (xy 231.296191 -400.910819) (xy 231.256042 -400.87211) (xy 231.221956 -400.827967)
			(xy 231.19466 -400.779332) (xy 231.174737 -400.727241) (xy 231.162611 -400.672804) (xy 231.15854 -400.617182)
			(xy 230.499666 -400.617182) (xy 230.499157 -400.645068) (xy 230.491037 -400.700244) (xy 230.474969 -400.753651)
			(xy 230.451297 -400.804148) (xy 230.420524 -400.850661) (xy 230.383307 -400.892198) (xy 230.340439 -400.927873)
			(xy 230.292833 -400.956927) (xy 230.241504 -400.978739) (xy 230.187547 -400.992845) (xy 230.13211 -400.998945)
			(xy 230.076376 -400.996908) (xy 230.021533 -400.986778) (xy 229.968749 -400.968771) (xy 229.919149 -400.94327)
			(xy 229.873791 -400.910819) (xy 229.833642 -400.87211) (xy 229.799556 -400.827967) (xy 229.77226 -400.779332)
			(xy 229.752337 -400.727241) (xy 229.740211 -400.672804) (xy 229.73614 -400.617182) (xy 229.166928 -400.617182)
			(xy 229.166928 -401.59432) (xy 229.166476 -401.614339) (xy 229.15867 -401.653607) (xy 229.143342 -401.690594)
			(xy 229.121085 -401.723874) (xy 229.107238 -401.738338) (xy 228.925374 -401.920202) (xy 229.73614 -401.920202)
			(xy 229.740211 -401.86458) (xy 229.752337 -401.810143) (xy 229.77226 -401.758052) (xy 229.799556 -401.709417)
			(xy 229.833642 -401.665274) (xy 229.873791 -401.626565) (xy 229.919149 -401.594114) (xy 229.968749 -401.568613)
			(xy 230.021533 -401.550606) (xy 230.076376 -401.540476) (xy 230.13211 -401.538439) (xy 230.187547 -401.544539)
			(xy 230.241504 -401.558645) (xy 230.292833 -401.580457) (xy 230.340439 -401.609511) (xy 230.383307 -401.645186)
			(xy 230.420524 -401.686723) (xy 230.451297 -401.733236) (xy 230.474969 -401.783733) (xy 230.491037 -401.83714)
			(xy 230.499157 -401.892316) (xy 230.499666 -401.920202) (xy 232.55554 -401.920202) (xy 232.559611 -401.86458)
			(xy 232.571737 -401.810143) (xy 232.59166 -401.758052) (xy 232.618956 -401.709417) (xy 232.653042 -401.665274)
			(xy 232.693191 -401.626565) (xy 232.738549 -401.594114) (xy 232.788149 -401.568613) (xy 232.840933 -401.550606)
			(xy 232.895776 -401.540476) (xy 232.95151 -401.538439) (xy 233.006947 -401.544539) (xy 233.060904 -401.558645)
			(xy 233.112233 -401.580457) (xy 233.159839 -401.609511) (xy 233.202707 -401.645186) (xy 233.225179 -401.670266)
			(xy 234.733082 -401.670266) (xy 234.737153 -401.614644) (xy 234.749279 -401.560207) (xy 234.769202 -401.508116)
			(xy 234.796498 -401.459481) (xy 234.830584 -401.415338) (xy 234.870733 -401.376629) (xy 234.916091 -401.344178)
			(xy 234.965691 -401.318677) (xy 235.018475 -401.30067) (xy 235.073318 -401.29054) (xy 235.129052 -401.288503)
			(xy 235.184489 -401.294603) (xy 235.238446 -401.308709) (xy 235.289775 -401.330521) (xy 235.337381 -401.359575)
			(xy 235.380249 -401.39525) (xy 235.417466 -401.436787) (xy 235.448239 -401.4833) (xy 235.471911 -401.533797)
			(xy 235.487979 -401.587204) (xy 235.496099 -401.64238) (xy 235.496608 -401.670266) (xy 235.496099 -401.698152)
			(xy 235.487979 -401.753328) (xy 235.471911 -401.806735) (xy 235.448239 -401.857232) (xy 235.417466 -401.903745)
			(xy 235.380249 -401.945282) (xy 235.337381 -401.980957) (xy 235.289775 -402.010011) (xy 235.238446 -402.031823)
			(xy 235.184489 -402.045929) (xy 235.129052 -402.052029) (xy 235.073318 -402.049992) (xy 235.018475 -402.039862)
			(xy 234.965691 -402.021855) (xy 234.916091 -401.996354) (xy 234.870733 -401.963903) (xy 234.830584 -401.925194)
			(xy 234.796498 -401.881051) (xy 234.769202 -401.832416) (xy 234.749279 -401.780325) (xy 234.737153 -401.725888)
			(xy 234.733082 -401.670266) (xy 233.225179 -401.670266) (xy 233.239924 -401.686723) (xy 233.270697 -401.733236)
			(xy 233.294369 -401.783733) (xy 233.310437 -401.83714) (xy 233.318557 -401.892316) (xy 233.319066 -401.920202)
			(xy 233.318557 -401.948088) (xy 233.310437 -402.003264) (xy 233.294369 -402.056671) (xy 233.270697 -402.107168)
			(xy 233.239924 -402.153681) (xy 233.202707 -402.195218) (xy 233.159839 -402.230893) (xy 233.112233 -402.259947)
			(xy 233.060904 -402.281759) (xy 233.006947 -402.295865) (xy 232.95151 -402.301965) (xy 232.895776 -402.299928)
			(xy 232.840933 -402.289798) (xy 232.788149 -402.271791) (xy 232.738549 -402.24629) (xy 232.693191 -402.213839)
			(xy 232.653042 -402.17513) (xy 232.618956 -402.130987) (xy 232.59166 -402.082352) (xy 232.571737 -402.030261)
			(xy 232.559611 -401.975824) (xy 232.55554 -401.920202) (xy 230.499666 -401.920202) (xy 230.499157 -401.948088)
			(xy 230.491037 -402.003264) (xy 230.474969 -402.056671) (xy 230.451297 -402.107168) (xy 230.420524 -402.153681)
			(xy 230.383307 -402.195218) (xy 230.340439 -402.230893) (xy 230.292833 -402.259947) (xy 230.241504 -402.281759)
			(xy 230.187547 -402.295865) (xy 230.13211 -402.301965) (xy 230.076376 -402.299928) (xy 230.021533 -402.289798)
			(xy 229.968749 -402.271791) (xy 229.919149 -402.24629) (xy 229.873791 -402.213839) (xy 229.833642 -402.17513)
			(xy 229.799556 -402.130987) (xy 229.77226 -402.082352) (xy 229.752337 -402.030261) (xy 229.740211 -401.975824)
			(xy 229.73614 -401.920202) (xy 228.925374 -401.920202) (xy 228.721158 -402.124418) (xy 228.706659 -402.138221)
			(xy 228.673379 -402.160458) (xy 228.636405 -402.175784) (xy 228.597152 -402.18361) (xy 228.57714 -402.184108)
			(xy 227.578412 -402.184108) (xy 227.571554 -402.183854) (xy 227.560378 -402.1836) (xy 227.540058 -402.191982)
			(xy 227.472748 -402.265642) (xy 227.46589 -402.286724) (xy 227.467414 -402.2979) (xy 227.468728 -402.309475)
			(xy 227.470125 -402.332732) (xy 227.470208 -402.344382) (xy 227.469722 -402.371633) (xy 227.461966 -402.425581)
			(xy 227.446611 -402.477876) (xy 227.423969 -402.527453) (xy 227.394503 -402.573303) (xy 227.358812 -402.614494)
			(xy 227.317621 -402.650185) (xy 227.271771 -402.679651) (xy 227.222194 -402.702293) (xy 227.169899 -402.717648)
			(xy 227.115951 -402.725404) (xy 227.061449 -402.725404) (xy 227.007501 -402.717648) (xy 226.955206 -402.702293)
			(xy 226.905629 -402.679651) (xy 226.859779 -402.650185) (xy 226.818588 -402.614494) (xy 226.782897 -402.573303)
			(xy 226.753431 -402.527453) (xy 226.730789 -402.477876) (xy 226.715434 -402.425581) (xy 226.707678 -402.371633)
			(xy 226.707192 -402.344382) (xy 226.707682 -402.316683) (xy 226.715684 -402.261868) (xy 226.731532 -402.208786)
			(xy 226.754893 -402.158556) (xy 226.785274 -402.112233) (xy 226.822038 -402.070793) (xy 226.864409 -402.035108)
			(xy 226.911497 -402.005927) (xy 226.962312 -401.983866) (xy 227.015783 -401.969388) (xy 227.043234 -401.965668)
			(xy 227.057966 -401.96389) (xy 227.080318 -401.945602) (xy 227.115116 -401.845526) (xy 227.117835 -401.836396)
			(xy 227.117039 -401.817377) (xy 227.109385 -401.799947) (xy 227.102924 -401.792948) (xy 226.970082 -401.660106)
			(xy 226.956284 -401.645605) (xy 226.934055 -401.612324) (xy 226.918739 -401.575349) (xy 226.910922 -401.536099)
			(xy 226.910392 -401.516088) (xy 226.910392 -400.306286) (xy 226.9098 -400.294236) (xy 226.898936 -400.272733)
			(xy 226.889564 -400.265138) (xy 226.865835 -400.24715) (xy 226.823734 -400.205046) (xy 226.805744 -400.181318)
			(xy 226.79813 -400.171941) (xy 226.776655 -400.160956) (xy 226.764596 -400.160236) (xy 222.596964 -400.160236)
			(xy 222.586773 -400.160749) (xy 222.568025 -400.168765) (xy 222.553842 -400.183413) (xy 222.54972 -400.192748)
			(xy 222.509334 -400.295618) (xy 222.516446 -400.325844) (xy 222.52813 -400.336766) (xy 222.547157 -400.354884)
			(xy 222.580552 -400.395442) (xy 222.608061 -400.440203) (xy 222.629163 -400.488317) (xy 222.643458 -400.538873)
			(xy 222.650676 -400.590913) (xy 222.651066 -400.617182) (xy 222.65058 -400.644433) (xy 222.642824 -400.698381)
			(xy 222.627469 -400.750676) (xy 222.604827 -400.800253) (xy 222.575361 -400.846103) (xy 222.53967 -400.887294)
			(xy 222.498479 -400.922985) (xy 222.452629 -400.952451) (xy 222.403052 -400.975093) (xy 222.350757 -400.990448)
			(xy 222.296809 -400.998204) (xy 222.242307 -400.998204) (xy 222.188359 -400.990448) (xy 222.136064 -400.975093)
			(xy 222.086487 -400.952451) (xy 222.040637 -400.922985) (xy 221.999446 -400.887294) (xy 221.963755 -400.846103)
			(xy 221.934289 -400.800253) (xy 221.911647 -400.750676) (xy 221.896292 -400.698381) (xy 221.888536 -400.644433)
			(xy 221.88805 -400.617182) (xy 221.88849 -400.590915) (xy 221.895704 -400.538879) (xy 221.909992 -400.488325)
			(xy 221.931084 -400.440211) (xy 221.95858 -400.395447) (xy 221.991961 -400.354882) (xy 222.010986 -400.336766)
			(xy 222.02267 -400.325844) (xy 222.029782 -400.295618) (xy 221.989396 -400.192748) (xy 221.985309 -400.183386)
			(xy 221.971137 -400.168699) (xy 221.952356 -400.160712) (xy 221.942152 -400.160236) (xy 221.199964 -400.160236)
			(xy 221.189773 -400.160749) (xy 221.171025 -400.168765) (xy 221.156842 -400.183413) (xy 221.15272 -400.192748)
			(xy 221.112334 -400.295618) (xy 221.119446 -400.325844) (xy 221.13113 -400.336766) (xy 221.150157 -400.354884)
			(xy 221.183552 -400.395442) (xy 221.211061 -400.440203) (xy 221.232163 -400.488317) (xy 221.246458 -400.538873)
			(xy 221.253676 -400.590913) (xy 221.254066 -400.617182) (xy 221.25358 -400.644433) (xy 221.245824 -400.698381)
			(xy 221.230469 -400.750676) (xy 221.207827 -400.800253) (xy 221.178361 -400.846103) (xy 221.14267 -400.887294)
			(xy 221.101479 -400.922985) (xy 221.055629 -400.952451) (xy 221.006052 -400.975093) (xy 220.953757 -400.990448)
			(xy 220.899809 -400.998204) (xy 220.845307 -400.998204) (xy 220.791359 -400.990448) (xy 220.739064 -400.975093)
			(xy 220.689487 -400.952451) (xy 220.643637 -400.922985) (xy 220.602446 -400.887294) (xy 220.566755 -400.846103)
			(xy 220.537289 -400.800253) (xy 220.514647 -400.750676) (xy 220.499292 -400.698381) (xy 220.491536 -400.644433)
			(xy 220.49105 -400.617182) (xy 220.49149 -400.590915) (xy 220.498704 -400.538879) (xy 220.512992 -400.488325)
			(xy 220.534084 -400.440211) (xy 220.56158 -400.395447) (xy 220.594961 -400.354882) (xy 220.613986 -400.336766)
			(xy 220.62567 -400.325844) (xy 220.632782 -400.295618) (xy 220.592396 -400.192748) (xy 220.588309 -400.183386)
			(xy 220.574137 -400.168699) (xy 220.555356 -400.160712) (xy 220.545152 -400.160236) (xy 219.777564 -400.160236)
			(xy 219.767373 -400.160749) (xy 219.748625 -400.168765) (xy 219.734442 -400.183413) (xy 219.73032 -400.192748)
			(xy 219.689934 -400.295618) (xy 219.697046 -400.325844) (xy 219.70873 -400.336766) (xy 219.727757 -400.354884)
			(xy 219.761152 -400.395442) (xy 219.788661 -400.440203) (xy 219.809763 -400.488317) (xy 219.824058 -400.538873)
			(xy 219.831276 -400.590913) (xy 219.831666 -400.617182) (xy 219.83118 -400.644433) (xy 219.823424 -400.698381)
			(xy 219.808069 -400.750676) (xy 219.785427 -400.800253) (xy 219.755961 -400.846103) (xy 219.72027 -400.887294)
			(xy 219.679079 -400.922985) (xy 219.633229 -400.952451) (xy 219.583652 -400.975093) (xy 219.531357 -400.990448)
			(xy 219.477409 -400.998204) (xy 219.422907 -400.998204) (xy 219.368959 -400.990448) (xy 219.316664 -400.975093)
			(xy 219.267087 -400.952451) (xy 219.221237 -400.922985) (xy 219.180046 -400.887294) (xy 219.144355 -400.846103)
			(xy 219.114889 -400.800253) (xy 219.092247 -400.750676) (xy 219.076892 -400.698381) (xy 219.069136 -400.644433)
			(xy 219.06865 -400.617182) (xy 219.06909 -400.590915) (xy 219.076304 -400.538879) (xy 219.090592 -400.488325)
			(xy 219.111684 -400.440211) (xy 219.13918 -400.395447) (xy 219.172561 -400.354882) (xy 219.191586 -400.336766)
			(xy 219.20327 -400.325844) (xy 219.210382 -400.295618) (xy 219.169996 -400.192748) (xy 219.165909 -400.183386)
			(xy 219.151737 -400.168699) (xy 219.132956 -400.160712) (xy 219.122752 -400.160236) (xy 219.001848 -400.160236)
			(xy 218.991783 -400.160669) (xy 218.973195 -400.168401) (xy 218.96578 -400.175222) (xy 218.72448 -400.416522)
			(xy 218.717708 -400.423949) (xy 218.710125 -400.442545) (xy 218.709748 -400.45259) (xy 218.709748 -401.2311)
			(xy 218.709288 -401.251116) (xy 218.701469 -401.290376) (xy 218.686133 -401.327354) (xy 218.663871 -401.360623)
			(xy 218.650058 -401.375118) (xy 218.104974 -401.920202) (xy 219.06814 -401.920202) (xy 219.072211 -401.86458)
			(xy 219.084337 -401.810143) (xy 219.10426 -401.758052) (xy 219.131556 -401.709417) (xy 219.165642 -401.665274)
			(xy 219.205791 -401.626565) (xy 219.251149 -401.594114) (xy 219.300749 -401.568613) (xy 219.353533 -401.550606)
			(xy 219.408376 -401.540476) (xy 219.46411 -401.538439) (xy 219.519547 -401.544539) (xy 219.573504 -401.558645)
			(xy 219.624833 -401.580457) (xy 219.672439 -401.609511) (xy 219.715307 -401.645186) (xy 219.752524 -401.686723)
			(xy 219.783297 -401.733236) (xy 219.806969 -401.783733) (xy 219.823037 -401.83714) (xy 219.831157 -401.892316)
			(xy 219.831666 -401.920202) (xy 221.88754 -401.920202) (xy 221.891611 -401.86458) (xy 221.903737 -401.810143)
			(xy 221.92366 -401.758052) (xy 221.950956 -401.709417) (xy 221.985042 -401.665274) (xy 222.025191 -401.626565)
			(xy 222.070549 -401.594114) (xy 222.120149 -401.568613) (xy 222.172933 -401.550606) (xy 222.227776 -401.540476)
			(xy 222.28351 -401.538439) (xy 222.338947 -401.544539) (xy 222.392904 -401.558645) (xy 222.444233 -401.580457)
			(xy 222.491839 -401.609511) (xy 222.534707 -401.645186) (xy 222.571924 -401.686723) (xy 222.602697 -401.733236)
			(xy 222.626369 -401.783733) (xy 222.642437 -401.83714) (xy 222.650557 -401.892316) (xy 222.651066 -401.920202)
			(xy 222.650557 -401.948088) (xy 222.642437 -402.003264) (xy 222.626369 -402.056671) (xy 222.602697 -402.107168)
			(xy 222.571924 -402.153681) (xy 222.534707 -402.195218) (xy 222.491839 -402.230893) (xy 222.444233 -402.259947)
			(xy 222.392904 -402.281759) (xy 222.338947 -402.295865) (xy 222.28351 -402.301965) (xy 222.227776 -402.299928)
			(xy 222.172933 -402.289798) (xy 222.120149 -402.271791) (xy 222.070549 -402.24629) (xy 222.025191 -402.213839)
			(xy 221.985042 -402.17513) (xy 221.950956 -402.130987) (xy 221.92366 -402.082352) (xy 221.903737 -402.030261)
			(xy 221.891611 -401.975824) (xy 221.88754 -401.920202) (xy 219.831666 -401.920202) (xy 219.831157 -401.948088)
			(xy 219.823037 -402.003264) (xy 219.806969 -402.056671) (xy 219.783297 -402.107168) (xy 219.752524 -402.153681)
			(xy 219.715307 -402.195218) (xy 219.672439 -402.230893) (xy 219.624833 -402.259947) (xy 219.573504 -402.281759)
			(xy 219.519547 -402.295865) (xy 219.46411 -402.301965) (xy 219.408376 -402.299928) (xy 219.353533 -402.289798)
			(xy 219.300749 -402.271791) (xy 219.251149 -402.24629) (xy 219.205791 -402.213839) (xy 219.165642 -402.17513)
			(xy 219.131556 -402.130987) (xy 219.10426 -402.082352) (xy 219.084337 -402.030261) (xy 219.072211 -401.975824)
			(xy 219.06814 -401.920202) (xy 218.104974 -401.920202) (xy 218.020138 -402.005038) (xy 218.005638 -402.018838)
			(xy 217.972357 -402.04107) (xy 217.935382 -402.05639) (xy 217.896131 -402.064212) (xy 217.87612 -402.064728)
			(xy 216.8144 -402.064728) (xy 216.792048 -402.063458) (xy 216.782541 -402.062792) (xy 216.764152 -402.067738)
			(xy 216.748845 -402.079067) (xy 216.738743 -402.095211) (xy 216.735246 -402.11393) (xy 216.738839 -402.132631)
			(xy 216.743534 -402.140928) (xy 216.757437 -402.163881) (xy 216.779376 -402.212854) (xy 216.794247 -402.264416)
			(xy 216.801758 -402.317551) (xy 216.802208 -402.344382) (xy 216.801722 -402.371633) (xy 216.793966 -402.425581)
			(xy 216.778611 -402.477876) (xy 216.755969 -402.527453) (xy 216.726503 -402.573303) (xy 216.690812 -402.614494)
			(xy 216.649621 -402.650185) (xy 216.603771 -402.679651) (xy 216.554194 -402.702293) (xy 216.501899 -402.717648)
			(xy 216.447951 -402.725404) (xy 216.393449 -402.725404) (xy 216.339501 -402.717648) (xy 216.287206 -402.702293)
			(xy 216.237629 -402.679651) (xy 216.191779 -402.650185) (xy 216.150588 -402.614494) (xy 216.114897 -402.573303)
			(xy 216.085431 -402.527453) (xy 216.062789 -402.477876) (xy 216.047434 -402.425581) (xy 216.039678 -402.371633)
			(xy 216.039192 -402.344382) (xy 216.039726 -402.31584) (xy 216.048232 -402.259392) (xy 216.065052 -402.204842)
			(xy 216.08981 -402.153405) (xy 216.121954 -402.106231) (xy 216.160767 -402.064371) (xy 216.205383 -402.02876)
			(xy 216.254805 -402.000192) (xy 216.307931 -401.979306) (xy 216.363576 -401.966566) (xy 216.391998 -401.96389)
			(xy 216.406984 -401.962874) (xy 216.430606 -401.945094) (xy 216.467944 -401.84451) (xy 216.470958 -401.835275)
			(xy 216.470521 -401.815872) (xy 216.462864 -401.798037) (xy 216.45626 -401.790916) (xy 216.302082 -401.636738)
			(xy 216.288281 -401.622238) (xy 216.266047 -401.588958) (xy 216.250725 -401.551983) (xy 216.242902 -401.512732)
			(xy 216.242392 -401.49272) (xy 216.242392 -400.306286) (xy 216.2418 -400.294236) (xy 216.230936 -400.272733)
			(xy 216.221564 -400.265138) (xy 216.197835 -400.24715) (xy 216.155734 -400.205046) (xy 216.137744 -400.181318)
			(xy 216.13013 -400.171941) (xy 216.108655 -400.160956) (xy 216.096596 -400.160236) (xy 211.928964 -400.160236)
			(xy 211.918773 -400.160749) (xy 211.900025 -400.168765) (xy 211.885842 -400.183413) (xy 211.88172 -400.192748)
			(xy 211.841334 -400.295618) (xy 211.848446 -400.325844) (xy 211.86013 -400.336766) (xy 211.879157 -400.354884)
			(xy 211.912552 -400.395442) (xy 211.940061 -400.440203) (xy 211.961163 -400.488317) (xy 211.975458 -400.538873)
			(xy 211.982676 -400.590913) (xy 211.983066 -400.617182) (xy 211.98258 -400.644433) (xy 211.974824 -400.698381)
			(xy 211.959469 -400.750676) (xy 211.936827 -400.800253) (xy 211.907361 -400.846103) (xy 211.87167 -400.887294)
			(xy 211.830479 -400.922985) (xy 211.784629 -400.952451) (xy 211.735052 -400.975093) (xy 211.682757 -400.990448)
			(xy 211.628809 -400.998204) (xy 211.574307 -400.998204) (xy 211.520359 -400.990448) (xy 211.468064 -400.975093)
			(xy 211.418487 -400.952451) (xy 211.372637 -400.922985) (xy 211.331446 -400.887294) (xy 211.295755 -400.846103)
			(xy 211.266289 -400.800253) (xy 211.243647 -400.750676) (xy 211.228292 -400.698381) (xy 211.220536 -400.644433)
			(xy 211.22005 -400.617182) (xy 211.22049 -400.590915) (xy 211.227704 -400.538879) (xy 211.241992 -400.488325)
			(xy 211.263084 -400.440211) (xy 211.29058 -400.395447) (xy 211.323961 -400.354882) (xy 211.342986 -400.336766)
			(xy 211.35467 -400.325844) (xy 211.361782 -400.295618) (xy 211.321396 -400.192748) (xy 211.317309 -400.183386)
			(xy 211.303137 -400.168699) (xy 211.284356 -400.160712) (xy 211.274152 -400.160236) (xy 210.531964 -400.160236)
			(xy 210.521773 -400.160749) (xy 210.503025 -400.168765) (xy 210.488842 -400.183413) (xy 210.48472 -400.192748)
			(xy 210.444334 -400.295618) (xy 210.451446 -400.325844) (xy 210.46313 -400.336766) (xy 210.482157 -400.354884)
			(xy 210.515552 -400.395442) (xy 210.543061 -400.440203) (xy 210.564163 -400.488317) (xy 210.578458 -400.538873)
			(xy 210.585676 -400.590913) (xy 210.586066 -400.617182) (xy 210.58558 -400.644433) (xy 210.577824 -400.698381)
			(xy 210.562469 -400.750676) (xy 210.539827 -400.800253) (xy 210.510361 -400.846103) (xy 210.47467 -400.887294)
			(xy 210.433479 -400.922985) (xy 210.387629 -400.952451) (xy 210.338052 -400.975093) (xy 210.285757 -400.990448)
			(xy 210.231809 -400.998204) (xy 210.177307 -400.998204) (xy 210.123359 -400.990448) (xy 210.071064 -400.975093)
			(xy 210.021487 -400.952451) (xy 209.975637 -400.922985) (xy 209.934446 -400.887294) (xy 209.898755 -400.846103)
			(xy 209.869289 -400.800253) (xy 209.846647 -400.750676) (xy 209.831292 -400.698381) (xy 209.823536 -400.644433)
			(xy 209.82305 -400.617182) (xy 209.82349 -400.590915) (xy 209.830704 -400.538879) (xy 209.844992 -400.488325)
			(xy 209.866084 -400.440211) (xy 209.89358 -400.395447) (xy 209.926961 -400.354882) (xy 209.945986 -400.336766)
			(xy 209.95767 -400.325844) (xy 209.964782 -400.295618) (xy 209.924396 -400.192748) (xy 209.920309 -400.183386)
			(xy 209.906137 -400.168699) (xy 209.887356 -400.160712) (xy 209.877152 -400.160236) (xy 209.109564 -400.160236)
			(xy 209.099373 -400.160749) (xy 209.080625 -400.168765) (xy 209.066442 -400.183413) (xy 209.06232 -400.192748)
			(xy 209.021934 -400.295618) (xy 209.029046 -400.325844) (xy 209.04073 -400.336766) (xy 209.059757 -400.354884)
			(xy 209.093152 -400.395442) (xy 209.120661 -400.440203) (xy 209.141763 -400.488317) (xy 209.156058 -400.538873)
			(xy 209.163276 -400.590913) (xy 209.163666 -400.617182) (xy 209.16318 -400.644433) (xy 209.155424 -400.698381)
			(xy 209.140069 -400.750676) (xy 209.117427 -400.800253) (xy 209.087961 -400.846103) (xy 209.05227 -400.887294)
			(xy 209.011079 -400.922985) (xy 208.965229 -400.952451) (xy 208.915652 -400.975093) (xy 208.863357 -400.990448)
			(xy 208.809409 -400.998204) (xy 208.754907 -400.998204) (xy 208.700959 -400.990448) (xy 208.648664 -400.975093)
			(xy 208.599087 -400.952451) (xy 208.553237 -400.922985) (xy 208.512046 -400.887294) (xy 208.476355 -400.846103)
			(xy 208.446889 -400.800253) (xy 208.424247 -400.750676) (xy 208.408892 -400.698381) (xy 208.401136 -400.644433)
			(xy 208.40065 -400.617182) (xy 208.40109 -400.590915) (xy 208.408304 -400.538879) (xy 208.422592 -400.488325)
			(xy 208.443684 -400.440211) (xy 208.47118 -400.395447) (xy 208.504561 -400.354882) (xy 208.523586 -400.336766)
			(xy 208.53527 -400.325844) (xy 208.542382 -400.295618) (xy 208.501996 -400.192748) (xy 208.497909 -400.183386)
			(xy 208.483737 -400.168699) (xy 208.464956 -400.160712) (xy 208.454752 -400.160236) (xy 208.412588 -400.160236)
			(xy 208.40252 -400.160662) (xy 208.383922 -400.168384) (xy 208.37652 -400.175222) (xy 208.05902 -400.492722)
			(xy 208.052244 -400.500147) (xy 208.044655 -400.518744) (xy 208.044288 -400.52879) (xy 208.044288 -401.2438)
			(xy 208.043828 -401.263816) (xy 208.036011 -401.303078) (xy 208.020677 -401.340057) (xy 207.998417 -401.37333)
			(xy 207.984598 -401.387818) (xy 207.452214 -401.920202) (xy 208.40014 -401.920202) (xy 208.404211 -401.86458)
			(xy 208.416337 -401.810143) (xy 208.43626 -401.758052) (xy 208.463556 -401.709417) (xy 208.497642 -401.665274)
			(xy 208.537791 -401.626565) (xy 208.583149 -401.594114) (xy 208.632749 -401.568613) (xy 208.685533 -401.550606)
			(xy 208.740376 -401.540476) (xy 208.79611 -401.538439) (xy 208.851547 -401.544539) (xy 208.905504 -401.558645)
			(xy 208.956833 -401.580457) (xy 209.004439 -401.609511) (xy 209.047307 -401.645186) (xy 209.084524 -401.686723)
			(xy 209.115297 -401.733236) (xy 209.138969 -401.783733) (xy 209.155037 -401.83714) (xy 209.163157 -401.892316)
			(xy 209.163666 -401.920202) (xy 211.21954 -401.920202) (xy 211.223611 -401.86458) (xy 211.235737 -401.810143)
			(xy 211.25566 -401.758052) (xy 211.282956 -401.709417) (xy 211.317042 -401.665274) (xy 211.357191 -401.626565)
			(xy 211.402549 -401.594114) (xy 211.452149 -401.568613) (xy 211.504933 -401.550606) (xy 211.559776 -401.540476)
			(xy 211.61551 -401.538439) (xy 211.670947 -401.544539) (xy 211.724904 -401.558645) (xy 211.776233 -401.580457)
			(xy 211.823839 -401.609511) (xy 211.866707 -401.645186) (xy 211.903924 -401.686723) (xy 211.934697 -401.733236)
			(xy 211.958369 -401.783733) (xy 211.974437 -401.83714) (xy 211.982557 -401.892316) (xy 211.983066 -401.920202)
			(xy 211.982557 -401.948088) (xy 211.974437 -402.003264) (xy 211.958369 -402.056671) (xy 211.934697 -402.107168)
			(xy 211.903924 -402.153681) (xy 211.866707 -402.195218) (xy 211.823839 -402.230893) (xy 211.776233 -402.259947)
			(xy 211.724904 -402.281759) (xy 211.670947 -402.295865) (xy 211.61551 -402.301965) (xy 211.559776 -402.299928)
			(xy 211.504933 -402.289798) (xy 211.452149 -402.271791) (xy 211.402549 -402.24629) (xy 211.357191 -402.213839)
			(xy 211.317042 -402.17513) (xy 211.282956 -402.130987) (xy 211.25566 -402.082352) (xy 211.235737 -402.030261)
			(xy 211.223611 -401.975824) (xy 211.21954 -401.920202) (xy 209.163666 -401.920202) (xy 209.163157 -401.948088)
			(xy 209.155037 -402.003264) (xy 209.138969 -402.056671) (xy 209.115297 -402.107168) (xy 209.084524 -402.153681)
			(xy 209.047307 -402.195218) (xy 209.004439 -402.230893) (xy 208.956833 -402.259947) (xy 208.905504 -402.281759)
			(xy 208.851547 -402.295865) (xy 208.79611 -402.301965) (xy 208.740376 -402.299928) (xy 208.685533 -402.289798)
			(xy 208.632749 -402.271791) (xy 208.583149 -402.24629) (xy 208.537791 -402.213839) (xy 208.497642 -402.17513)
			(xy 208.463556 -402.130987) (xy 208.43626 -402.082352) (xy 208.416337 -402.030261) (xy 208.404211 -401.975824)
			(xy 208.40014 -401.920202) (xy 207.452214 -401.920202) (xy 207.331818 -402.040598) (xy 207.317318 -402.054398)
			(xy 207.284038 -402.076631) (xy 207.247063 -402.091951) (xy 207.207811 -402.099771) (xy 207.1878 -402.100288)
			(xy 206.2226 -402.100288) (xy 206.217012 -402.100034) (xy 206.204566 -402.09978) (xy 206.182722 -402.110194)
			(xy 206.117698 -402.195792) (xy 206.113634 -402.219922) (xy 206.11719 -402.231606) (xy 206.125167 -402.259114)
			(xy 206.133715 -402.315745) (xy 206.134208 -402.344382) (xy 206.133746 -402.371635) (xy 206.125991 -402.425587)
			(xy 206.110637 -402.477886) (xy 206.087997 -402.527468) (xy 206.05853 -402.573322) (xy 206.022838 -402.614517)
			(xy 205.981646 -402.650212) (xy 205.935794 -402.679682) (xy 205.886214 -402.702327) (xy 205.833916 -402.717685)
			(xy 205.779965 -402.725444) (xy 205.725459 -402.725445) (xy 205.671507 -402.71769) (xy 205.619208 -402.702335)
			(xy 205.569627 -402.679694) (xy 205.523773 -402.650227) (xy 205.482579 -402.614534) (xy 205.446884 -402.573342)
			(xy 205.417415 -402.527489) (xy 205.394771 -402.477909) (xy 205.379414 -402.42561) (xy 205.371656 -402.371659)
			(xy 205.371655 -402.317153) (xy 205.379411 -402.263201) (xy 205.394767 -402.210903) (xy 205.417409 -402.161322)
			(xy 205.446877 -402.115468) (xy 205.48257 -402.074275) (xy 205.523763 -402.03858) (xy 205.569617 -402.009112)
			(xy 205.619197 -401.986469) (xy 205.671495 -401.971112) (xy 205.725447 -401.963355) (xy 205.7527 -401.962874)
			(xy 205.770734 -401.962874) (xy 205.796388 -401.94611) (xy 205.838552 -401.845018) (xy 205.841952 -401.83555)
			(xy 205.841992 -401.815453) (xy 205.834374 -401.796855) (xy 205.82763 -401.789392) (xy 205.634082 -401.596098)
			(xy 205.620277 -401.5816) (xy 205.598033 -401.548322) (xy 205.5827 -401.511347) (xy 205.574865 -401.472093)
			(xy 205.574392 -401.45208) (xy 205.574392 -400.306286) (xy 205.5738 -400.294236) (xy 205.562936 -400.272733)
			(xy 205.553564 -400.265138) (xy 205.529835 -400.24715) (xy 205.487734 -400.205046) (xy 205.469744 -400.181318)
			(xy 205.46213 -400.171941) (xy 205.440655 -400.160956) (xy 205.428596 -400.160236) (xy 201.260964 -400.160236)
			(xy 201.250773 -400.160749) (xy 201.232025 -400.168765) (xy 201.217842 -400.183413) (xy 201.21372 -400.192748)
			(xy 201.173334 -400.295618) (xy 201.180446 -400.325844) (xy 201.19213 -400.336766) (xy 201.211157 -400.354884)
			(xy 201.244552 -400.395442) (xy 201.272061 -400.440203) (xy 201.293163 -400.488317) (xy 201.307458 -400.538873)
			(xy 201.314676 -400.590913) (xy 201.315066 -400.617182) (xy 201.31458 -400.644433) (xy 201.306824 -400.698381)
			(xy 201.291469 -400.750676) (xy 201.268827 -400.800253) (xy 201.239361 -400.846103) (xy 201.20367 -400.887294)
			(xy 201.162479 -400.922985) (xy 201.116629 -400.952451) (xy 201.067052 -400.975093) (xy 201.014757 -400.990448)
			(xy 200.960809 -400.998204) (xy 200.906307 -400.998204) (xy 200.852359 -400.990448) (xy 200.800064 -400.975093)
			(xy 200.750487 -400.952451) (xy 200.704637 -400.922985) (xy 200.663446 -400.887294) (xy 200.627755 -400.846103)
			(xy 200.598289 -400.800253) (xy 200.575647 -400.750676) (xy 200.560292 -400.698381) (xy 200.552536 -400.644433)
			(xy 200.55205 -400.617182) (xy 200.55249 -400.590915) (xy 200.559704 -400.538879) (xy 200.573992 -400.488325)
			(xy 200.595084 -400.440211) (xy 200.62258 -400.395447) (xy 200.655961 -400.354882) (xy 200.674986 -400.336766)
			(xy 200.68667 -400.325844) (xy 200.693782 -400.295618) (xy 200.653396 -400.192748) (xy 200.649309 -400.183386)
			(xy 200.635137 -400.168699) (xy 200.616356 -400.160712) (xy 200.606152 -400.160236) (xy 199.863964 -400.160236)
			(xy 199.853773 -400.160749) (xy 199.835025 -400.168765) (xy 199.820842 -400.183413) (xy 199.81672 -400.192748)
			(xy 199.776334 -400.295618) (xy 199.783446 -400.325844) (xy 199.79513 -400.336766) (xy 199.814157 -400.354884)
			(xy 199.847552 -400.395442) (xy 199.875061 -400.440203) (xy 199.896163 -400.488317) (xy 199.910458 -400.538873)
			(xy 199.917676 -400.590913) (xy 199.918066 -400.617182) (xy 199.91758 -400.644433) (xy 199.909824 -400.698381)
			(xy 199.894469 -400.750676) (xy 199.871827 -400.800253) (xy 199.842361 -400.846103) (xy 199.80667 -400.887294)
			(xy 199.765479 -400.922985) (xy 199.719629 -400.952451) (xy 199.670052 -400.975093) (xy 199.617757 -400.990448)
			(xy 199.563809 -400.998204) (xy 199.509307 -400.998204) (xy 199.455359 -400.990448) (xy 199.403064 -400.975093)
			(xy 199.353487 -400.952451) (xy 199.307637 -400.922985) (xy 199.266446 -400.887294) (xy 199.230755 -400.846103)
			(xy 199.201289 -400.800253) (xy 199.178647 -400.750676) (xy 199.163292 -400.698381) (xy 199.155536 -400.644433)
			(xy 199.15505 -400.617182) (xy 199.15549 -400.590915) (xy 199.162704 -400.538879) (xy 199.176992 -400.488325)
			(xy 199.198084 -400.440211) (xy 199.22558 -400.395447) (xy 199.258961 -400.354882) (xy 199.277986 -400.336766)
			(xy 199.28967 -400.325844) (xy 199.296782 -400.295618) (xy 199.256396 -400.192748) (xy 199.252309 -400.183386)
			(xy 199.238137 -400.168699) (xy 199.219356 -400.160712) (xy 199.209152 -400.160236) (xy 198.441564 -400.160236)
			(xy 198.431373 -400.160749) (xy 198.412625 -400.168765) (xy 198.398442 -400.183413) (xy 198.39432 -400.192748)
			(xy 198.353934 -400.295618) (xy 198.361046 -400.325844) (xy 198.37273 -400.336766) (xy 198.391757 -400.354884)
			(xy 198.425152 -400.395442) (xy 198.452661 -400.440203) (xy 198.473763 -400.488317) (xy 198.488058 -400.538873)
			(xy 198.495276 -400.590913) (xy 198.495666 -400.617182) (xy 198.49518 -400.644433) (xy 198.487424 -400.698381)
			(xy 198.472069 -400.750676) (xy 198.449427 -400.800253) (xy 198.419961 -400.846103) (xy 198.38427 -400.887294)
			(xy 198.343079 -400.922985) (xy 198.297229 -400.952451) (xy 198.247652 -400.975093) (xy 198.195357 -400.990448)
			(xy 198.141409 -400.998204) (xy 198.086907 -400.998204) (xy 198.032959 -400.990448) (xy 197.980664 -400.975093)
			(xy 197.931087 -400.952451) (xy 197.885237 -400.922985) (xy 197.844046 -400.887294) (xy 197.808355 -400.846103)
			(xy 197.778889 -400.800253) (xy 197.756247 -400.750676) (xy 197.740892 -400.698381) (xy 197.733136 -400.644433)
			(xy 197.73265 -400.617182) (xy 197.73309 -400.590915) (xy 197.740304 -400.538879) (xy 197.754592 -400.488325)
			(xy 197.775684 -400.440211) (xy 197.80318 -400.395447) (xy 197.836561 -400.354882) (xy 197.855586 -400.336766)
			(xy 197.86727 -400.325844) (xy 197.874382 -400.295618) (xy 197.833996 -400.192748) (xy 197.829909 -400.183386)
			(xy 197.815737 -400.168699) (xy 197.796956 -400.160712) (xy 197.786752 -400.160236) (xy 197.363588 -400.160236)
			(xy 197.35352 -400.160662) (xy 197.334922 -400.168384) (xy 197.32752 -400.175222) (xy 197.05828 -400.444462)
			(xy 197.051498 -400.451886) (xy 197.043894 -400.470482) (xy 197.043548 -400.48053) (xy 197.043548 -401.02536)
			(xy 197.043092 -401.045377) (xy 197.03528 -401.084642) (xy 197.019949 -401.121625) (xy 196.997689 -401.1549)
			(xy 196.983858 -401.169378) (xy 196.450458 -401.702778) (xy 196.43596 -401.716583) (xy 196.402682 -401.738825)
			(xy 196.365707 -401.754153) (xy 196.326453 -401.761982) (xy 196.30644 -401.762468) (xy 195.6689 -401.762468)
			(xy 195.648884 -401.762008) (xy 195.609623 -401.75419) (xy 195.572645 -401.738855) (xy 195.539373 -401.716594)
			(xy 195.524882 -401.702778) (xy 195.359528 -401.537424) (xy 195.351971 -401.530559) (xy 195.333045 -401.522944)
			(xy 195.312648 -401.52329) (xy 195.30314 -401.52701) (xy 195.202048 -401.571714) (xy 195.185538 -401.598384)
			(xy 195.1863 -401.614386) (xy 195.186808 -401.633182) (xy 195.186346 -401.660435) (xy 195.178591 -401.714387)
			(xy 195.163237 -401.766686) (xy 195.140597 -401.816268) (xy 195.11113 -401.862122) (xy 195.075438 -401.903317)
			(xy 195.055953 -401.920202) (xy 197.73214 -401.920202) (xy 197.736211 -401.86458) (xy 197.748337 -401.810143)
			(xy 197.76826 -401.758052) (xy 197.795556 -401.709417) (xy 197.829642 -401.665274) (xy 197.869791 -401.626565)
			(xy 197.915149 -401.594114) (xy 197.964749 -401.568613) (xy 198.017533 -401.550606) (xy 198.072376 -401.540476)
			(xy 198.12811 -401.538439) (xy 198.183547 -401.544539) (xy 198.237504 -401.558645) (xy 198.288833 -401.580457)
			(xy 198.336439 -401.609511) (xy 198.379307 -401.645186) (xy 198.416524 -401.686723) (xy 198.447297 -401.733236)
			(xy 198.470969 -401.783733) (xy 198.487037 -401.83714) (xy 198.495157 -401.892316) (xy 198.495666 -401.920202)
			(xy 200.55154 -401.920202) (xy 200.555611 -401.86458) (xy 200.567737 -401.810143) (xy 200.58766 -401.758052)
			(xy 200.614956 -401.709417) (xy 200.649042 -401.665274) (xy 200.689191 -401.626565) (xy 200.734549 -401.594114)
			(xy 200.784149 -401.568613) (xy 200.836933 -401.550606) (xy 200.891776 -401.540476) (xy 200.94751 -401.538439)
			(xy 201.002947 -401.544539) (xy 201.056904 -401.558645) (xy 201.108233 -401.580457) (xy 201.155839 -401.609511)
			(xy 201.198707 -401.645186) (xy 201.235924 -401.686723) (xy 201.266697 -401.733236) (xy 201.290369 -401.783733)
			(xy 201.306437 -401.83714) (xy 201.314557 -401.892316) (xy 201.315066 -401.920202) (xy 201.314557 -401.948088)
			(xy 201.306437 -402.003264) (xy 201.290369 -402.056671) (xy 201.266697 -402.107168) (xy 201.235924 -402.153681)
			(xy 201.198707 -402.195218) (xy 201.155839 -402.230893) (xy 201.108233 -402.259947) (xy 201.056904 -402.281759)
			(xy 201.002947 -402.295865) (xy 200.94751 -402.301965) (xy 200.891776 -402.299928) (xy 200.836933 -402.289798)
			(xy 200.784149 -402.271791) (xy 200.734549 -402.24629) (xy 200.689191 -402.213839) (xy 200.649042 -402.17513)
			(xy 200.614956 -402.130987) (xy 200.58766 -402.082352) (xy 200.567737 -402.030261) (xy 200.555611 -401.975824)
			(xy 200.55154 -401.920202) (xy 198.495666 -401.920202) (xy 198.495157 -401.948088) (xy 198.487037 -402.003264)
			(xy 198.470969 -402.056671) (xy 198.447297 -402.107168) (xy 198.416524 -402.153681) (xy 198.379307 -402.195218)
			(xy 198.336439 -402.230893) (xy 198.288833 -402.259947) (xy 198.237504 -402.281759) (xy 198.183547 -402.295865)
			(xy 198.12811 -402.301965) (xy 198.072376 -402.299928) (xy 198.017533 -402.289798) (xy 197.964749 -402.271791)
			(xy 197.915149 -402.24629) (xy 197.869791 -402.213839) (xy 197.829642 -402.17513) (xy 197.795556 -402.130987)
			(xy 197.76826 -402.082352) (xy 197.748337 -402.030261) (xy 197.736211 -401.975824) (xy 197.73214 -401.920202)
			(xy 195.055953 -401.920202) (xy 195.034246 -401.939012) (xy 194.988394 -401.968482) (xy 194.938814 -401.991127)
			(xy 194.886516 -402.006485) (xy 194.832565 -402.014244) (xy 194.778059 -402.014245) (xy 194.724107 -402.00649)
			(xy 194.671808 -401.991135) (xy 194.622227 -401.968494) (xy 194.576373 -401.939027) (xy 194.535179 -401.903334)
			(xy 194.499484 -401.862142) (xy 194.470015 -401.816289) (xy 194.447371 -401.766709) (xy 194.432014 -401.71441)
			(xy 194.424256 -401.660459) (xy 194.424255 -401.605953) (xy 194.432011 -401.552001) (xy 194.447367 -401.499703)
			(xy 194.470009 -401.450122) (xy 194.499477 -401.404268) (xy 194.53517 -401.363075) (xy 194.576363 -401.32738)
			(xy 194.622217 -401.297912) (xy 194.671797 -401.275269) (xy 194.724095 -401.259912) (xy 194.778047 -401.252155)
			(xy 194.8053 -401.251674) (xy 194.824096 -401.252182) (xy 194.840098 -401.252944) (xy 194.866768 -401.236434)
			(xy 194.911472 -401.135342) (xy 194.915179 -401.125833) (xy 194.915518 -401.105444) (xy 194.9079 -401.086529)
			(xy 194.901058 -401.078954) (xy 193.486278 -399.66392) (xy 193.478853 -399.657144) (xy 193.460256 -399.649555)
			(xy 193.45021 -399.649188) (xy 192.07861 -399.649188) (xy 192.06858 -399.649633) (xy 192.050014 -399.657215)
			(xy 192.042542 -399.66392) (xy 191.396839 -400.309842) (xy 192.050922 -400.309842) (xy 192.054993 -400.25422)
			(xy 192.067119 -400.199783) (xy 192.087042 -400.147692) (xy 192.114338 -400.099057) (xy 192.148424 -400.054914)
			(xy 192.188573 -400.016205) (xy 192.233931 -399.983754) (xy 192.283531 -399.958253) (xy 192.336315 -399.940246)
			(xy 192.391158 -399.930116) (xy 192.446892 -399.928079) (xy 192.502329 -399.934179) (xy 192.556286 -399.948285)
			(xy 192.607615 -399.970097) (xy 192.655221 -399.999151) (xy 192.698089 -400.034826) (xy 192.735306 -400.076363)
			(xy 192.766079 -400.122876) (xy 192.789751 -400.173373) (xy 192.805819 -400.22678) (xy 192.813939 -400.281956)
			(xy 192.814448 -400.309842) (xy 192.813939 -400.337728) (xy 192.805819 -400.392904) (xy 192.789751 -400.446311)
			(xy 192.766079 -400.496808) (xy 192.735306 -400.543321) (xy 192.698089 -400.584858) (xy 192.655221 -400.620533)
			(xy 192.607615 -400.649587) (xy 192.556286 -400.671399) (xy 192.502329 -400.685505) (xy 192.446892 -400.691605)
			(xy 192.391158 -400.689568) (xy 192.336315 -400.679438) (xy 192.283531 -400.661431) (xy 192.233931 -400.63593)
			(xy 192.188573 -400.603479) (xy 192.148424 -400.56477) (xy 192.114338 -400.520627) (xy 192.087042 -400.471992)
			(xy 192.067119 -400.419901) (xy 192.054993 -400.365464) (xy 192.050922 -400.309842) (xy 191.396839 -400.309842)
			(xy 191.293496 -400.41322) (xy 191.279014 -400.427029) (xy 191.245723 -400.44922) (xy 191.208738 -400.464478)
			(xy 191.169484 -400.472215) (xy 191.149478 -400.472656) (xy 190.115444 -400.472656) (xy 190.103373 -400.473325)
			(xy 190.081884 -400.484327) (xy 190.074296 -400.493738) (xy 190.058863 -400.514247) (xy 190.023375 -400.551329)
			(xy 189.983232 -400.583313) (xy 189.939158 -400.609619) (xy 189.891953 -400.629771) (xy 189.842469 -400.643404)
			(xy 189.791604 -400.650272) (xy 189.76594 -400.65071) (xy 189.738685 -400.650249) (xy 189.68473 -400.642497)
			(xy 189.632427 -400.627144) (xy 189.582841 -400.604504) (xy 189.536983 -400.575037) (xy 189.495785 -400.539343)
			(xy 189.460087 -400.498149) (xy 189.430615 -400.452294) (xy 189.40797 -400.402711) (xy 189.392612 -400.35041)
			(xy 189.384853 -400.296455) (xy 189.384853 -400.241945) (xy 189.392612 -400.18799) (xy 189.40797 -400.135689)
			(xy 189.430615 -400.086106) (xy 189.460087 -400.040251) (xy 189.495785 -399.999057) (xy 189.536983 -399.963363)
			(xy 189.582841 -399.933896) (xy 189.632427 -399.911256) (xy 189.68473 -399.895903) (xy 189.738685 -399.888151)
			(xy 189.76594 -399.887694) (xy 189.791602 -399.888114) (xy 189.842463 -399.895003) (xy 189.891941 -399.90865)
			(xy 189.939141 -399.928809) (xy 189.983211 -399.955115) (xy 190.023356 -399.987095) (xy 190.058849 -400.024169)
			(xy 190.074296 -400.044666) (xy 190.081905 -400.054055) (xy 190.103379 -400.065069) (xy 190.115444 -400.065748)
			(xy 191.044068 -400.065748) (xy 191.054132 -400.065311) (xy 191.072713 -400.057573) (xy 191.080136 -400.050762)
			(xy 191.829182 -399.301462) (xy 191.843683 -399.287664) (xy 191.876964 -399.265435) (xy 191.913939 -399.250118)
			(xy 191.953189 -399.2423) (xy 191.9732 -399.241772) (xy 193.55562 -399.241772) (xy 193.575639 -399.242224)
			(xy 193.614907 -399.25003) (xy 193.651894 -399.265358) (xy 193.685174 -399.287615) (xy 193.699638 -399.301462)
			(xy 195.738242 -401.34032) (xy 195.745665 -401.347105) (xy 195.764261 -401.354716) (xy 195.77431 -401.355052)
			(xy 196.20103 -401.355052) (xy 196.211055 -401.354599) (xy 196.229606 -401.346999) (xy 196.237098 -401.34032)
			(xy 196.6214 -400.956018) (xy 196.62818 -400.948594) (xy 196.635781 -400.929998) (xy 196.636132 -400.91995)
			(xy 196.636132 -400.37512) (xy 196.63659 -400.355103) (xy 196.644405 -400.31584) (xy 196.659737 -400.278859)
			(xy 196.681997 -400.245585) (xy 196.695822 -400.231102) (xy 197.11416 -399.812764) (xy 197.128641 -399.798953)
			(xy 197.161931 -399.776756) (xy 197.198916 -399.761492) (xy 197.238171 -399.753747) (xy 197.258178 -399.753328)
			(xy 205.428596 -399.753328) (xy 205.440662 -399.75265) (xy 205.462134 -399.741636) (xy 205.469744 -399.732246)
			(xy 205.486484 -399.710091) (xy 205.52532 -399.670404) (xy 205.569499 -399.636766) (xy 205.618088 -399.609889)
			(xy 205.67006 -399.59034) (xy 205.697074 -399.58391) (xy 205.71079 -399.581116) (xy 205.730856 -399.56232)
			(xy 205.760066 -399.463006) (xy 205.762203 -399.454188) (xy 205.760827 -399.436108) (xy 205.753278 -399.419622)
			(xy 205.747112 -399.412968) (xy 205.595982 -399.261838) (xy 205.582181 -399.247338) (xy 205.559947 -399.214058)
			(xy 205.544625 -399.177083) (xy 205.536802 -399.137832) (xy 205.536292 -399.11782) (xy 205.536292 -398.64157)
			(xy 205.53584 -398.631544) (xy 205.528245 -398.61299) (xy 205.52156 -398.605502) (xy 204.955902 -398.040098)
			(xy 204.942095 -398.0256) (xy 204.919849 -397.992323) (xy 204.904515 -397.955348) (xy 204.89668 -397.916094)
			(xy 204.896212 -397.89608) (xy 204.896212 -391.716006) (xy 204.888592 -391.697464) (xy 196.17055 -391.697464)
			(xy 196.152008 -391.705084) (xy 196.152008 -398.305789) (xy 197.445878 -398.305789) (xy 197.449609 -398.252536)
			(xy 197.460728 -398.200322) (xy 197.479016 -398.150169) (xy 197.504117 -398.103054) (xy 197.535541 -398.059899)
			(xy 197.572674 -398.021545) (xy 197.593458 -398.004792) (xy 197.602229 -397.997239) (xy 197.612405 -397.976473)
			(xy 197.613016 -397.964914) (xy 197.613016 -397.88465) (xy 197.612411 -397.873087) (xy 197.60224 -397.852316)
			(xy 197.593458 -397.844772) (xy 197.572657 -397.82804) (xy 197.535527 -397.789684) (xy 197.504105 -397.746527)
			(xy 197.479007 -397.699411) (xy 197.460721 -397.649256) (xy 197.449606 -397.597042) (xy 197.445878 -397.543789)
			(xy 197.449609 -397.490536) (xy 197.460728 -397.438322) (xy 197.479016 -397.388169) (xy 197.504117 -397.341054)
			(xy 197.535541 -397.297899) (xy 197.572674 -397.259545) (xy 197.593458 -397.242792) (xy 197.602229 -397.235239)
			(xy 197.612405 -397.214473) (xy 197.613016 -397.202914) (xy 197.613016 -397.12265) (xy 197.612411 -397.111087)
			(xy 197.60224 -397.090316) (xy 197.593458 -397.082772) (xy 197.572657 -397.06604) (xy 197.535527 -397.027684)
			(xy 197.504105 -396.984527) (xy 197.479007 -396.937411) (xy 197.460721 -396.887256) (xy 197.449606 -396.835042)
			(xy 197.445878 -396.781789) (xy 197.449609 -396.728536) (xy 197.460728 -396.676322) (xy 197.479016 -396.626169)
			(xy 197.504117 -396.579054) (xy 197.535541 -396.535899) (xy 197.572674 -396.497545) (xy 197.593458 -396.480792)
			(xy 197.602229 -396.473239) (xy 197.612405 -396.452473) (xy 197.613016 -396.440914) (xy 197.613016 -396.36065)
			(xy 197.612411 -396.349087) (xy 197.60224 -396.328316) (xy 197.593458 -396.320772) (xy 197.572657 -396.30404)
			(xy 197.535527 -396.265684) (xy 197.504105 -396.222527) (xy 197.479007 -396.175411) (xy 197.460721 -396.125256)
			(xy 197.449606 -396.073042) (xy 197.445878 -396.019789) (xy 197.449609 -395.966536) (xy 197.460728 -395.914322)
			(xy 197.479016 -395.864169) (xy 197.504117 -395.817054) (xy 197.535541 -395.773899) (xy 197.572674 -395.735545)
			(xy 197.593458 -395.718792) (xy 197.602229 -395.711239) (xy 197.612405 -395.690473) (xy 197.613016 -395.678914)
			(xy 197.613016 -395.59865) (xy 197.612411 -395.587087) (xy 197.60224 -395.566316) (xy 197.593458 -395.558772)
			(xy 197.570952 -395.540607) (xy 197.53122 -395.498581) (xy 197.498285 -395.45104) (xy 197.472901 -395.399074)
			(xy 197.455649 -395.343872) (xy 197.446925 -395.286699) (xy 197.446392 -395.257782) (xy 197.446861 -395.23053)
			(xy 197.45462 -395.176582) (xy 197.469977 -395.124287) (xy 197.492621 -395.07471) (xy 197.522089 -395.028859)
			(xy 197.557782 -394.987669) (xy 197.598974 -394.951978) (xy 197.644825 -394.922512) (xy 197.694404 -394.899871)
			(xy 197.7467 -394.884516) (xy 197.800648 -394.87676) (xy 197.8279 -394.876274) (xy 197.856818 -394.876764)
			(xy 197.913992 -394.885495) (xy 197.969193 -394.902757) (xy 198.021155 -394.928154) (xy 198.068688 -394.961103)
			(xy 198.110702 -395.000851) (xy 198.12889 -395.02334) (xy 198.136454 -395.0321) (xy 198.157211 -395.042283)
			(xy 198.168768 -395.042898) (xy 198.249032 -395.042898) (xy 198.260595 -395.042289) (xy 198.281366 -395.032122)
			(xy 198.28891 -395.02334) (xy 198.305663 -395.002557) (xy 198.344017 -394.965427) (xy 198.387171 -394.934005)
			(xy 198.434285 -394.908906) (xy 198.484437 -394.89062) (xy 198.536648 -394.879503) (xy 198.5899 -394.875773)
			(xy 198.643152 -394.879503) (xy 198.695363 -394.89062) (xy 198.745515 -394.908906) (xy 198.792629 -394.934005)
			(xy 198.835783 -394.965427) (xy 198.874137 -395.002557) (xy 198.89089 -395.02334) (xy 198.898454 -395.0321)
			(xy 198.919211 -395.042283) (xy 198.930768 -395.042898) (xy 199.011032 -395.042898) (xy 199.022595 -395.042289)
			(xy 199.043366 -395.032122) (xy 199.05091 -395.02334) (xy 199.067663 -395.002557) (xy 199.106017 -394.965427)
			(xy 199.149171 -394.934005) (xy 199.196285 -394.908906) (xy 199.246437 -394.89062) (xy 199.298648 -394.879503)
			(xy 199.3519 -394.875773) (xy 199.405152 -394.879503) (xy 199.457363 -394.89062) (xy 199.507515 -394.908906)
			(xy 199.554629 -394.934005) (xy 199.597783 -394.965427) (xy 199.636137 -395.002557) (xy 199.65289 -395.02334)
			(xy 199.660454 -395.0321) (xy 199.681211 -395.042283) (xy 199.692768 -395.042898) (xy 199.773032 -395.042898)
			(xy 199.784595 -395.042289) (xy 199.805366 -395.032122) (xy 199.81291 -395.02334) (xy 199.829663 -395.002557)
			(xy 199.868017 -394.965427) (xy 199.911171 -394.934005) (xy 199.958285 -394.908906) (xy 200.008437 -394.89062)
			(xy 200.060648 -394.879503) (xy 200.1139 -394.875773) (xy 200.167152 -394.879503) (xy 200.219363 -394.89062)
			(xy 200.269515 -394.908906) (xy 200.316629 -394.934005) (xy 200.359783 -394.965427) (xy 200.398137 -395.002557)
			(xy 200.41489 -395.02334) (xy 200.422454 -395.0321) (xy 200.443211 -395.042283) (xy 200.454768 -395.042898)
			(xy 200.535032 -395.042898) (xy 200.546595 -395.042289) (xy 200.567366 -395.032122) (xy 200.57491 -395.02334)
			(xy 200.591663 -395.002557) (xy 200.630017 -394.965427) (xy 200.673171 -394.934005) (xy 200.720285 -394.908906)
			(xy 200.770437 -394.89062) (xy 200.822648 -394.879503) (xy 200.8759 -394.875773) (xy 200.929152 -394.879503)
			(xy 200.981363 -394.89062) (xy 201.031515 -394.908906) (xy 201.078629 -394.934005) (xy 201.121783 -394.965427)
			(xy 201.160137 -395.002557) (xy 201.17689 -395.02334) (xy 201.184454 -395.0321) (xy 201.205211 -395.042283)
			(xy 201.216768 -395.042898) (xy 201.297032 -395.042898) (xy 201.308595 -395.042289) (xy 201.329366 -395.032122)
			(xy 201.33691 -395.02334) (xy 201.353663 -395.002557) (xy 201.392017 -394.965427) (xy 201.435171 -394.934005)
			(xy 201.482285 -394.908906) (xy 201.532437 -394.89062) (xy 201.584648 -394.879503) (xy 201.6379 -394.875773)
			(xy 201.691152 -394.879503) (xy 201.743363 -394.89062) (xy 201.793515 -394.908906) (xy 201.840629 -394.934005)
			(xy 201.883783 -394.965427) (xy 201.922137 -395.002557) (xy 201.93889 -395.02334) (xy 201.946454 -395.0321)
			(xy 201.967211 -395.042283) (xy 201.978768 -395.042898) (xy 202.059032 -395.042898) (xy 202.070595 -395.042289)
			(xy 202.091366 -395.032122) (xy 202.09891 -395.02334) (xy 202.117105 -395.00086) (xy 202.159123 -394.961123)
			(xy 202.206657 -394.928182) (xy 202.258617 -394.902793) (xy 202.313815 -394.885536) (xy 202.370984 -394.876808)
			(xy 202.3999 -394.876274) (xy 202.42715 -394.876778) (xy 202.481097 -394.884534) (xy 202.53339 -394.899888)
			(xy 202.582966 -394.922528) (xy 202.628815 -394.951992) (xy 202.670005 -394.987682) (xy 202.705697 -395.02887)
			(xy 202.735164 -395.074718) (xy 202.757806 -395.124293) (xy 202.773162 -395.176586) (xy 202.780921 -395.230532)
			(xy 202.781408 -395.257782) (xy 202.780912 -395.2867) (xy 202.772183 -395.343874) (xy 202.754923 -395.399075)
			(xy 202.729527 -395.451037) (xy 202.696578 -395.49857) (xy 202.656831 -395.540584) (xy 202.634342 -395.558772)
			(xy 202.625587 -395.56634) (xy 202.615402 -395.587095) (xy 202.614784 -395.59865) (xy 202.614784 -395.678914)
			(xy 202.615352 -395.690482) (xy 202.625549 -395.711252) (xy 202.634342 -395.718792) (xy 202.655107 -395.735567)
			(xy 202.692237 -395.773917) (xy 202.723659 -395.817069) (xy 202.748758 -395.86418) (xy 202.767045 -395.91433)
			(xy 202.778163 -395.96654) (xy 202.781894 -396.019789) (xy 202.778166 -396.073039) (xy 202.767051 -396.125249)
			(xy 202.748767 -396.175399) (xy 202.72367 -396.222512) (xy 202.692252 -396.265666) (xy 202.655124 -396.304019)
			(xy 202.634342 -396.320772) (xy 202.625587 -396.32834) (xy 202.615402 -396.349095) (xy 202.614784 -396.36065)
			(xy 202.614784 -396.440914) (xy 202.615352 -396.452482) (xy 202.625549 -396.473252) (xy 202.634342 -396.480792)
			(xy 202.655107 -396.497567) (xy 202.692237 -396.535917) (xy 202.723659 -396.579069) (xy 202.748758 -396.62618)
			(xy 202.767045 -396.67633) (xy 202.778163 -396.72854) (xy 202.781894 -396.781789) (xy 202.778166 -396.835039)
			(xy 202.767051 -396.887249) (xy 202.748767 -396.937399) (xy 202.72367 -396.984512) (xy 202.692252 -397.027666)
			(xy 202.655124 -397.066019) (xy 202.634342 -397.082772) (xy 202.625587 -397.09034) (xy 202.615402 -397.111095)
			(xy 202.614784 -397.12265) (xy 202.614784 -397.202914) (xy 202.615352 -397.214482) (xy 202.625549 -397.235252)
			(xy 202.634342 -397.242792) (xy 202.65683 -397.260977) (xy 202.696563 -397.302999) (xy 202.729501 -397.350536)
			(xy 202.754888 -397.402498) (xy 202.772143 -397.457696) (xy 202.780873 -397.514866) (xy 202.781408 -397.543782)
			(xy 202.780928 -397.571034) (xy 202.773173 -397.624985) (xy 202.75782 -397.677282) (xy 202.735179 -397.726862)
			(xy 202.705713 -397.772716) (xy 202.670021 -397.813908) (xy 202.62883 -397.849602) (xy 202.582978 -397.879071)
			(xy 202.533399 -397.901713) (xy 202.481102 -397.91707) (xy 202.427152 -397.924827) (xy 202.3999 -397.92529)
			(xy 202.370983 -397.924775) (xy 202.313811 -397.916046) (xy 202.258612 -397.898788) (xy 202.206651 -397.873395)
			(xy 202.159117 -397.840451) (xy 202.1171 -397.80071) (xy 202.09891 -397.778224) (xy 202.091352 -397.769458)
			(xy 202.07059 -397.75928) (xy 202.059032 -397.758666) (xy 201.978768 -397.758666) (xy 201.967202 -397.759252)
			(xy 201.946429 -397.769433) (xy 201.93889 -397.778224) (xy 201.92411 -397.796622) (xy 201.890741 -397.829993)
			(xy 201.872342 -397.844772) (xy 201.863587 -397.85234) (xy 201.853402 -397.873095) (xy 201.852784 -397.88465)
			(xy 201.852784 -397.964914) (xy 201.853352 -397.976482) (xy 201.863549 -397.997252) (xy 201.872342 -398.004792)
			(xy 201.893107 -398.021567) (xy 201.930237 -398.059917) (xy 201.961659 -398.103069) (xy 201.986758 -398.15018)
			(xy 202.005045 -398.20033) (xy 202.016163 -398.25254) (xy 202.019894 -398.305789) (xy 202.016166 -398.359039)
			(xy 202.005051 -398.411249) (xy 201.986767 -398.461399) (xy 201.96167 -398.508512) (xy 201.930252 -398.551666)
			(xy 201.893124 -398.590019) (xy 201.872342 -398.606772) (xy 201.863587 -398.61434) (xy 201.853402 -398.635095)
			(xy 201.852784 -398.64665) (xy 201.852784 -398.726914) (xy 201.853352 -398.738482) (xy 201.863549 -398.759252)
			(xy 201.872342 -398.766792) (xy 201.89483 -398.784977) (xy 201.934563 -398.826999) (xy 201.967501 -398.874536)
			(xy 201.992888 -398.926498) (xy 202.010143 -398.981696) (xy 202.018873 -399.038866) (xy 202.019408 -399.067782)
			(xy 202.018928 -399.095034) (xy 202.011173 -399.148985) (xy 201.99582 -399.201282) (xy 201.973179 -399.250862)
			(xy 201.943713 -399.296716) (xy 201.908021 -399.337908) (xy 201.86683 -399.373602) (xy 201.820978 -399.403071)
			(xy 201.771399 -399.425713) (xy 201.719102 -399.44107) (xy 201.665152 -399.448827) (xy 201.6379 -399.44929)
			(xy 201.608983 -399.448775) (xy 201.551811 -399.440046) (xy 201.496612 -399.422788) (xy 201.444651 -399.397395)
			(xy 201.397117 -399.364451) (xy 201.3551 -399.32471) (xy 201.33691 -399.302224) (xy 201.329352 -399.293458)
			(xy 201.30859 -399.28328) (xy 201.297032 -399.282666) (xy 201.216768 -399.282666) (xy 201.205202 -399.283252)
			(xy 201.184429 -399.293433) (xy 201.17689 -399.302224) (xy 201.160137 -399.323007) (xy 201.121783 -399.360137)
			(xy 201.078629 -399.391559) (xy 201.031515 -399.416658) (xy 200.981363 -399.434944) (xy 200.929152 -399.446061)
			(xy 200.8759 -399.449791) (xy 200.822648 -399.446061) (xy 200.770437 -399.434944) (xy 200.720285 -399.416658)
			(xy 200.673171 -399.391559) (xy 200.630017 -399.360137) (xy 200.591663 -399.323007) (xy 200.57491 -399.302224)
			(xy 200.567352 -399.293458) (xy 200.54659 -399.28328) (xy 200.535032 -399.282666) (xy 200.454768 -399.282666)
			(xy 200.443202 -399.283252) (xy 200.422429 -399.293433) (xy 200.41489 -399.302224) (xy 200.398137 -399.323007)
			(xy 200.359783 -399.360137) (xy 200.316629 -399.391559) (xy 200.269515 -399.416658) (xy 200.219363 -399.434944)
			(xy 200.167152 -399.446061) (xy 200.1139 -399.449791) (xy 200.060648 -399.446061) (xy 200.008437 -399.434944)
			(xy 199.958285 -399.416658) (xy 199.911171 -399.391559) (xy 199.868017 -399.360137) (xy 199.829663 -399.323007)
			(xy 199.81291 -399.302224) (xy 199.805352 -399.293458) (xy 199.78459 -399.28328) (xy 199.773032 -399.282666)
			(xy 199.692768 -399.282666) (xy 199.681202 -399.283252) (xy 199.660429 -399.293433) (xy 199.65289 -399.302224)
			(xy 199.636137 -399.323007) (xy 199.597783 -399.360137) (xy 199.554629 -399.391559) (xy 199.507515 -399.416658)
			(xy 199.457363 -399.434944) (xy 199.405152 -399.446061) (xy 199.3519 -399.449791) (xy 199.298648 -399.446061)
			(xy 199.246437 -399.434944) (xy 199.196285 -399.416658) (xy 199.149171 -399.391559) (xy 199.106017 -399.360137)
			(xy 199.067663 -399.323007) (xy 199.05091 -399.302224) (xy 199.043352 -399.293458) (xy 199.02259 -399.28328)
			(xy 199.011032 -399.282666) (xy 198.930768 -399.282666) (xy 198.919202 -399.283252) (xy 198.898429 -399.293433)
			(xy 198.89089 -399.302224) (xy 198.874137 -399.323007) (xy 198.835783 -399.360137) (xy 198.792629 -399.391559)
			(xy 198.745515 -399.416658) (xy 198.695363 -399.434944) (xy 198.643152 -399.446061) (xy 198.5899 -399.449791)
			(xy 198.536648 -399.446061) (xy 198.484437 -399.434944) (xy 198.434285 -399.416658) (xy 198.387171 -399.391559)
			(xy 198.344017 -399.360137) (xy 198.305663 -399.323007) (xy 198.28891 -399.302224) (xy 198.281352 -399.293458)
			(xy 198.26059 -399.28328) (xy 198.249032 -399.282666) (xy 198.168768 -399.282666) (xy 198.157202 -399.283252)
			(xy 198.136429 -399.293433) (xy 198.12889 -399.302224) (xy 198.110711 -399.324717) (xy 198.068688 -399.364451)
			(xy 198.02115 -399.397388) (xy 197.969187 -399.422774) (xy 197.913987 -399.440029) (xy 197.856817 -399.448756)
			(xy 197.8279 -399.44929) (xy 197.800646 -399.448845) (xy 197.746694 -399.441087) (xy 197.694395 -399.42573)
			(xy 197.644813 -399.403086) (xy 197.598959 -399.373617) (xy 197.557766 -399.337921) (xy 197.522072 -399.296726)
			(xy 197.492605 -399.250871) (xy 197.469963 -399.201289) (xy 197.454609 -399.148989) (xy 197.446854 -399.095036)
			(xy 197.446392 -399.067782) (xy 197.446934 -399.038866) (xy 197.455654 -398.981694) (xy 197.472904 -398.926494)
			(xy 197.498291 -398.874531) (xy 197.531233 -398.826997) (xy 197.570973 -398.784981) (xy 197.593458 -398.766792)
			(xy 197.602229 -398.759239) (xy 197.612405 -398.738473) (xy 197.613016 -398.726914) (xy 197.613016 -398.64665)
			(xy 197.612411 -398.635087) (xy 197.60224 -398.614316) (xy 197.593458 -398.606772) (xy 197.572657 -398.59004)
			(xy 197.535527 -398.551684) (xy 197.504105 -398.508527) (xy 197.479007 -398.461411) (xy 197.460721 -398.411256)
			(xy 197.449606 -398.359042) (xy 197.445878 -398.305789) (xy 196.152008 -398.305789) (xy 196.152008 -400.293078)
			(xy 196.152614 -400.305121) (xy 196.163494 -400.326601) (xy 196.172836 -400.334226) (xy 196.193349 -400.349658)
			(xy 196.230439 -400.385143) (xy 196.262431 -400.425285) (xy 196.288746 -400.469358) (xy 196.308908 -400.516563)
			(xy 196.322551 -400.566048) (xy 196.32943 -400.616916) (xy 196.329808 -400.642582) (xy 196.329346 -400.669836)
			(xy 196.321591 -400.723789) (xy 196.306237 -400.776089) (xy 196.283595 -400.825671) (xy 196.254128 -400.871526)
			(xy 196.218434 -400.912721) (xy 196.177241 -400.948417) (xy 196.131387 -400.977886) (xy 196.081805 -401.00053)
			(xy 196.029506 -401.015887) (xy 195.975554 -401.023645) (xy 195.9483 -401.02409) (xy 195.919658 -401.023569)
			(xy 195.863019 -401.014994) (xy 195.808297 -400.998051) (xy 195.756722 -400.97312) (xy 195.709452 -400.940762)
			(xy 195.667548 -400.901704) (xy 195.631951 -400.856821) (xy 195.603462 -400.807124) (xy 195.582719 -400.753727)
			(xy 195.575936 -400.725894) (xy 195.574412 -400.718528) (xy 195.567554 -400.706082) (xy 193.622422 -398.761204)
			(xy 193.608621 -398.746704) (xy 193.586389 -398.713424) (xy 193.57107 -398.676449) (xy 193.563252 -398.637197)
			(xy 193.562732 -398.617186) (xy 193.562732 -393.556744) (xy 193.562294 -393.546711) (xy 193.554723 -393.528134)
			(xy 193.548 -393.520676) (xy 193.257932 -393.230608) (xy 193.250509 -393.223825) (xy 193.231913 -393.216218)
			(xy 193.221864 -393.215876) (xy 183.510428 -393.215876) (xy 183.500397 -393.216317) (xy 183.481824 -393.223893)
			(xy 183.47436 -393.230608) (xy 182.623206 -394.081762) (xy 182.616369 -394.089163) (xy 182.608656 -394.107762)
			(xy 182.60822 -394.11783) (xy 182.60822 -395.821662) (xy 184.421526 -395.821662) (xy 184.422079 -395.792746)
			(xy 184.430799 -395.735576) (xy 184.44805 -395.680378) (xy 184.473435 -395.628416) (xy 184.506373 -395.580881)
			(xy 184.546109 -395.538863) (xy 184.568592 -395.520672) (xy 184.577361 -395.513117) (xy 184.587541 -395.492353)
			(xy 184.58815 -395.480794) (xy 184.58815 -395.40053) (xy 184.58758 -395.388962) (xy 184.577387 -395.36819)
			(xy 184.568592 -395.360652) (xy 184.546132 -395.342434) (xy 184.506395 -395.300419) (xy 184.473454 -395.25289)
			(xy 184.448062 -395.200934) (xy 184.4308 -395.145742) (xy 184.422065 -395.088576) (xy 184.421526 -395.059662)
			(xy 184.421943 -395.032408) (xy 184.429705 -394.978456) (xy 184.445067 -394.926158) (xy 184.467715 -394.876579)
			(xy 184.497188 -394.830727) (xy 184.532887 -394.789536) (xy 184.574084 -394.753845) (xy 184.619942 -394.72438)
			(xy 184.669526 -394.701742) (xy 184.721827 -394.68639) (xy 184.77578 -394.678637) (xy 184.803034 -394.678154)
			(xy 184.831695 -394.678653) (xy 184.888371 -394.687241) (xy 184.943126 -394.704203) (xy 184.994731 -394.729159)
			(xy 185.042026 -394.761548) (xy 185.083949 -394.800643) (xy 185.119557 -394.845564) (xy 185.13425 -394.870178)
			(xy 185.1406 -394.881608) (xy 185.162698 -394.89507) (xy 185.274966 -394.90015) (xy 185.29808 -394.88872)
			(xy 185.3057 -394.877798) (xy 185.321043 -394.856527) (xy 185.356648 -394.818014) (xy 185.397193 -394.784743)
			(xy 185.441914 -394.757342) (xy 185.489969 -394.736326) (xy 185.540449 -394.722093) (xy 185.592404 -394.71491)
			(xy 185.618628 -394.714476) (xy 185.647544 -394.715017) (xy 185.704716 -394.723738) (xy 185.759915 -394.740989)
			(xy 185.811878 -394.766376) (xy 185.859412 -394.799317) (xy 185.901428 -394.839057) (xy 185.919618 -394.861542)
			(xy 185.927169 -394.870314) (xy 185.947936 -394.88049) (xy 185.959496 -394.8811) (xy 186.03976 -394.8811)
			(xy 186.051325 -394.880507) (xy 186.072096 -394.870328) (xy 186.079638 -394.861542) (xy 186.096391 -394.840759)
			(xy 186.134745 -394.803629) (xy 186.177899 -394.772207) (xy 186.225013 -394.747108) (xy 186.275165 -394.728822)
			(xy 186.327376 -394.717705) (xy 186.380628 -394.713975) (xy 186.43388 -394.717705) (xy 186.486091 -394.728822)
			(xy 186.536243 -394.747108) (xy 186.583357 -394.772207) (xy 186.626511 -394.803629) (xy 186.664865 -394.840759)
			(xy 186.681618 -394.861542) (xy 186.689169 -394.870314) (xy 186.709936 -394.88049) (xy 186.721496 -394.8811)
			(xy 186.80176 -394.8811) (xy 186.813325 -394.880507) (xy 186.834096 -394.870328) (xy 186.841638 -394.861542)
			(xy 186.858391 -394.840759) (xy 186.896745 -394.803629) (xy 186.939899 -394.772207) (xy 186.987013 -394.747108)
			(xy 187.037165 -394.728822) (xy 187.089376 -394.717705) (xy 187.142628 -394.713975) (xy 187.19588 -394.717705)
			(xy 187.248091 -394.728822) (xy 187.298243 -394.747108) (xy 187.345357 -394.772207) (xy 187.388511 -394.803629)
			(xy 187.426865 -394.840759) (xy 187.443618 -394.861542) (xy 187.451169 -394.870314) (xy 187.471936 -394.88049)
			(xy 187.483496 -394.8811) (xy 187.56376 -394.8811) (xy 187.575325 -394.880507) (xy 187.596096 -394.870328)
			(xy 187.603638 -394.861542) (xy 187.620391 -394.840759) (xy 187.658745 -394.803629) (xy 187.701899 -394.772207)
			(xy 187.749013 -394.747108) (xy 187.799165 -394.728822) (xy 187.851376 -394.717705) (xy 187.904628 -394.713975)
			(xy 187.95788 -394.717705) (xy 188.010091 -394.728822) (xy 188.060243 -394.747108) (xy 188.107357 -394.772207)
			(xy 188.150511 -394.803629) (xy 188.188865 -394.840759) (xy 188.205618 -394.861542) (xy 188.213169 -394.870314)
			(xy 188.233936 -394.88049) (xy 188.245496 -394.8811) (xy 188.32576 -394.8811) (xy 188.337325 -394.880507)
			(xy 188.358096 -394.870328) (xy 188.365638 -394.861542) (xy 188.382391 -394.840759) (xy 188.420745 -394.803629)
			(xy 188.463899 -394.772207) (xy 188.511013 -394.747108) (xy 188.561165 -394.728822) (xy 188.613376 -394.717705)
			(xy 188.666628 -394.713975) (xy 188.71988 -394.717705) (xy 188.772091 -394.728822) (xy 188.822243 -394.747108)
			(xy 188.869357 -394.772207) (xy 188.912511 -394.803629) (xy 188.950865 -394.840759) (xy 188.967618 -394.861542)
			(xy 188.975169 -394.870314) (xy 188.995936 -394.88049) (xy 189.007496 -394.8811) (xy 189.08776 -394.8811)
			(xy 189.099325 -394.880507) (xy 189.120096 -394.870328) (xy 189.127638 -394.861542) (xy 189.144391 -394.840759)
			(xy 189.182745 -394.803629) (xy 189.225899 -394.772207) (xy 189.273013 -394.747108) (xy 189.323165 -394.728822)
			(xy 189.375376 -394.717705) (xy 189.428628 -394.713975) (xy 189.48188 -394.717705) (xy 189.534091 -394.728822)
			(xy 189.584243 -394.747108) (xy 189.631357 -394.772207) (xy 189.674511 -394.803629) (xy 189.712865 -394.840759)
			(xy 189.729618 -394.861542) (xy 189.737169 -394.870314) (xy 189.757936 -394.88049) (xy 189.769496 -394.8811)
			(xy 189.84976 -394.8811) (xy 189.861325 -394.880507) (xy 189.882096 -394.870328) (xy 189.889638 -394.861542)
			(xy 189.907818 -394.839049) (xy 189.949839 -394.799313) (xy 189.997376 -394.766373) (xy 190.049339 -394.740986)
			(xy 190.104539 -394.723733) (xy 190.161711 -394.715008) (xy 190.190628 -394.714476) (xy 190.217879 -394.714952)
			(xy 190.271826 -394.722712) (xy 190.32412 -394.738069) (xy 190.373697 -394.760713) (xy 190.419546 -394.79018)
			(xy 190.460736 -394.825873) (xy 190.496427 -394.867063) (xy 190.525893 -394.912914) (xy 190.548535 -394.962491)
			(xy 190.563891 -395.014785) (xy 190.571649 -395.068733) (xy 190.572136 -395.095984) (xy 190.57163 -395.124902)
			(xy 190.562902 -395.182075) (xy 190.545643 -395.237275) (xy 190.520249 -395.289237) (xy 190.487302 -395.33677)
			(xy 190.447558 -395.378785) (xy 190.42507 -395.396974) (xy 190.416319 -395.404546) (xy 190.406131 -395.425297)
			(xy 190.405512 -395.436852) (xy 190.405512 -395.517116) (xy 190.406069 -395.528686) (xy 190.416273 -395.549457)
			(xy 190.42507 -395.556994) (xy 190.445836 -395.573767) (xy 190.482963 -395.612119) (xy 190.514383 -395.655272)
			(xy 190.53948 -395.702383) (xy 190.557765 -395.752533) (xy 190.568882 -395.804742) (xy 190.572613 -395.85799)
			(xy 190.568885 -395.911239) (xy 190.557771 -395.963448) (xy 190.539488 -396.013599) (xy 190.514393 -396.060711)
			(xy 190.482976 -396.103866) (xy 190.445851 -396.14222) (xy 190.42507 -396.158974) (xy 190.416319 -396.166546)
			(xy 190.406131 -396.187297) (xy 190.405512 -396.198852) (xy 190.405512 -396.279116) (xy 190.406069 -396.290686)
			(xy 190.416273 -396.311457) (xy 190.42507 -396.318994) (xy 190.445836 -396.335767) (xy 190.482963 -396.374119)
			(xy 190.514383 -396.417272) (xy 190.53948 -396.464383) (xy 190.557765 -396.514533) (xy 190.568882 -396.566742)
			(xy 190.572613 -396.61999) (xy 190.568885 -396.673239) (xy 190.557771 -396.725448) (xy 190.539488 -396.775599)
			(xy 190.514393 -396.822711) (xy 190.482976 -396.865866) (xy 190.445851 -396.90422) (xy 190.42507 -396.920974)
			(xy 190.416319 -396.928546) (xy 190.406131 -396.949297) (xy 190.405512 -396.960852) (xy 190.405512 -397.041116)
			(xy 190.406069 -397.052686) (xy 190.416273 -397.073457) (xy 190.42507 -397.080994) (xy 190.447544 -397.099196)
			(xy 190.487281 -397.141213) (xy 190.520222 -397.188745) (xy 190.545613 -397.240704) (xy 190.56287 -397.2959)
			(xy 190.571601 -397.353068) (xy 190.572136 -397.381984) (xy 190.571607 -397.409234) (xy 190.563853 -397.463178)
			(xy 190.548502 -397.51547) (xy 190.525864 -397.565046) (xy 190.496402 -397.610895) (xy 190.460716 -397.652084)
			(xy 190.41953 -397.687776) (xy 190.373684 -397.717243) (xy 190.324112 -397.739886) (xy 190.271821 -397.755244)
			(xy 190.217877 -397.763004) (xy 190.190628 -397.763492) (xy 190.161712 -397.762957) (xy 190.104541 -397.754231)
			(xy 190.049343 -397.736977) (xy 189.997381 -397.711589) (xy 189.949846 -397.678648) (xy 189.907829 -397.63891)
			(xy 189.889638 -397.616426) (xy 189.882068 -397.607673) (xy 189.861315 -397.597488) (xy 189.84976 -397.596868)
			(xy 189.769496 -397.596868) (xy 189.757924 -397.597412) (xy 189.737152 -397.607623) (xy 189.729618 -397.616426)
			(xy 189.712865 -397.637209) (xy 189.674511 -397.674339) (xy 189.631357 -397.705761) (xy 189.584243 -397.73086)
			(xy 189.534091 -397.749146) (xy 189.48188 -397.760263) (xy 189.428628 -397.763993) (xy 189.375376 -397.760263)
			(xy 189.323165 -397.749146) (xy 189.273013 -397.73086) (xy 189.225899 -397.705761) (xy 189.182745 -397.674339)
			(xy 189.144391 -397.637209) (xy 189.127638 -397.616426) (xy 189.120068 -397.607673) (xy 189.099315 -397.597488)
			(xy 189.08776 -397.596868) (xy 189.007496 -397.596868) (xy 188.995924 -397.597412) (xy 188.975152 -397.607623)
			(xy 188.967618 -397.616426) (xy 188.952835 -397.634821) (xy 188.919468 -397.668194) (xy 188.90107 -397.682974)
			(xy 188.892319 -397.690546) (xy 188.882131 -397.711297) (xy 188.881512 -397.722852) (xy 188.881512 -397.803116)
			(xy 188.882069 -397.814686) (xy 188.892273 -397.835457) (xy 188.90107 -397.842994) (xy 188.921836 -397.859767)
			(xy 188.958963 -397.898119) (xy 188.990383 -397.941272) (xy 189.01548 -397.988383) (xy 189.033765 -398.038533)
			(xy 189.044882 -398.090742) (xy 189.048613 -398.14399) (xy 189.044885 -398.197239) (xy 189.033771 -398.249448)
			(xy 189.015488 -398.299599) (xy 188.990393 -398.346711) (xy 188.958976 -398.389866) (xy 188.921851 -398.42822)
			(xy 188.90107 -398.444974) (xy 188.892319 -398.452546) (xy 188.882131 -398.473297) (xy 188.881512 -398.484852)
			(xy 188.881512 -398.565116) (xy 188.882069 -398.576686) (xy 188.892273 -398.597457) (xy 188.90107 -398.604994)
			(xy 188.923544 -398.623196) (xy 188.963281 -398.665213) (xy 188.996222 -398.712745) (xy 189.021613 -398.764704)
			(xy 189.03887 -398.8199) (xy 189.047601 -398.877068) (xy 189.048136 -398.905984) (xy 189.047607 -398.933234)
			(xy 189.039853 -398.987178) (xy 189.024502 -399.03947) (xy 189.001864 -399.089046) (xy 188.972402 -399.134895)
			(xy 188.936716 -399.176084) (xy 188.89553 -399.211776) (xy 188.849684 -399.241243) (xy 188.800112 -399.263886)
			(xy 188.747821 -399.279244) (xy 188.693877 -399.287004) (xy 188.666628 -399.287492) (xy 188.637712 -399.286957)
			(xy 188.580541 -399.278231) (xy 188.525343 -399.260977) (xy 188.473381 -399.235589) (xy 188.425846 -399.202648)
			(xy 188.383829 -399.16291) (xy 188.365638 -399.140426) (xy 188.358068 -399.131673) (xy 188.337315 -399.121488)
			(xy 188.32576 -399.120868) (xy 188.245496 -399.120868) (xy 188.233924 -399.121412) (xy 188.213152 -399.131623)
			(xy 188.205618 -399.140426) (xy 188.188865 -399.161209) (xy 188.150511 -399.198339) (xy 188.107357 -399.229761)
			(xy 188.060243 -399.25486) (xy 188.010091 -399.273146) (xy 187.95788 -399.284263) (xy 187.904628 -399.287993)
			(xy 187.851376 -399.284263) (xy 187.799165 -399.273146) (xy 187.749013 -399.25486) (xy 187.701899 -399.229761)
			(xy 187.658745 -399.198339) (xy 187.620391 -399.161209) (xy 187.603638 -399.140426) (xy 187.596068 -399.131673)
			(xy 187.575315 -399.121488) (xy 187.56376 -399.120868) (xy 187.483496 -399.120868) (xy 187.471924 -399.121412)
			(xy 187.451152 -399.131623) (xy 187.443618 -399.140426) (xy 187.426865 -399.161209) (xy 187.388511 -399.198339)
			(xy 187.345357 -399.229761) (xy 187.298243 -399.25486) (xy 187.248091 -399.273146) (xy 187.19588 -399.284263)
			(xy 187.142628 -399.287993) (xy 187.089376 -399.284263) (xy 187.037165 -399.273146) (xy 186.987013 -399.25486)
			(xy 186.939899 -399.229761) (xy 186.896745 -399.198339) (xy 186.858391 -399.161209) (xy 186.841638 -399.140426)
			(xy 186.834068 -399.131673) (xy 186.813315 -399.121488) (xy 186.80176 -399.120868) (xy 186.721496 -399.120868)
			(xy 186.709924 -399.121412) (xy 186.689152 -399.131623) (xy 186.681618 -399.140426) (xy 186.664865 -399.161209)
			(xy 186.626511 -399.198339) (xy 186.583357 -399.229761) (xy 186.536243 -399.25486) (xy 186.486091 -399.273146)
			(xy 186.43388 -399.284263) (xy 186.380628 -399.287993) (xy 186.327376 -399.284263) (xy 186.275165 -399.273146)
			(xy 186.225013 -399.25486) (xy 186.177899 -399.229761) (xy 186.134745 -399.198339) (xy 186.096391 -399.161209)
			(xy 186.079638 -399.140426) (xy 186.072068 -399.131673) (xy 186.051315 -399.121488) (xy 186.03976 -399.120868)
			(xy 185.959496 -399.120868) (xy 185.947924 -399.121412) (xy 185.927152 -399.131623) (xy 185.919618 -399.140426)
			(xy 185.901423 -399.162906) (xy 185.859404 -399.20264) (xy 185.811869 -399.235579) (xy 185.759909 -399.260968)
			(xy 185.704712 -399.278225) (xy 185.647544 -399.286956) (xy 185.618628 -399.287492) (xy 185.591375 -399.287019)
			(xy 185.537424 -399.279265) (xy 185.485125 -399.263912) (xy 185.435544 -399.241271) (xy 185.38969 -399.211805)
			(xy 185.348497 -399.176112) (xy 185.312802 -399.13492) (xy 185.283334 -399.089067) (xy 185.260692 -399.039486)
			(xy 185.245338 -398.987188) (xy 185.237582 -398.933237) (xy 185.23712 -398.905984) (xy 185.237691 -398.877069)
			(xy 185.246408 -398.8199) (xy 185.263655 -398.764702) (xy 185.289037 -398.71274) (xy 185.321971 -398.665204)
			(xy 185.361704 -398.623185) (xy 185.384186 -398.604994) (xy 185.392944 -398.597428) (xy 185.40313 -398.576673)
			(xy 185.403744 -398.565116) (xy 185.403744 -398.484852) (xy 185.403163 -398.473285) (xy 185.392978 -398.452512)
			(xy 185.384186 -398.444974) (xy 185.363386 -398.42824) (xy 185.326253 -398.389886) (xy 185.294829 -398.346729)
			(xy 185.269729 -398.299614) (xy 185.251442 -398.249459) (xy 185.240325 -398.197244) (xy 185.236596 -398.14399)
			(xy 185.240328 -398.090736) (xy 185.251447 -398.038522) (xy 185.269737 -397.988368) (xy 185.29484 -397.941254)
			(xy 185.326266 -397.898099) (xy 185.363401 -397.859747) (xy 185.384186 -397.842994) (xy 185.392944 -397.835428)
			(xy 185.40313 -397.814673) (xy 185.403744 -397.803116) (xy 185.403744 -397.722852) (xy 185.403163 -397.711285)
			(xy 185.392978 -397.690512) (xy 185.384186 -397.682974) (xy 185.363386 -397.66624) (xy 185.326253 -397.627886)
			(xy 185.294829 -397.584729) (xy 185.269729 -397.537614) (xy 185.251442 -397.487459) (xy 185.240325 -397.435244)
			(xy 185.236596 -397.38199) (xy 185.240328 -397.328736) (xy 185.251447 -397.276522) (xy 185.269737 -397.226368)
			(xy 185.29484 -397.179254) (xy 185.326266 -397.136099) (xy 185.363401 -397.097747) (xy 185.384186 -397.080994)
			(xy 185.392944 -397.073428) (xy 185.40313 -397.052673) (xy 185.403744 -397.041116) (xy 185.403744 -396.960852)
			(xy 185.403163 -396.949285) (xy 185.392978 -396.928512) (xy 185.384186 -396.920974) (xy 185.363386 -396.90424)
			(xy 185.326253 -396.865886) (xy 185.294829 -396.822729) (xy 185.269729 -396.775614) (xy 185.251442 -396.725459)
			(xy 185.240325 -396.673244) (xy 185.236596 -396.61999) (xy 185.240328 -396.566736) (xy 185.251447 -396.514522)
			(xy 185.269737 -396.464368) (xy 185.29484 -396.417254) (xy 185.326266 -396.374099) (xy 185.363401 -396.335747)
			(xy 185.384186 -396.318994) (xy 185.392944 -396.311428) (xy 185.40313 -396.290673) (xy 185.403744 -396.279116)
			(xy 185.403744 -396.198852) (xy 185.403163 -396.187285) (xy 185.392978 -396.166512) (xy 185.384186 -396.158974)
			(xy 185.364866 -396.143461) (xy 185.330021 -396.108236) (xy 185.300052 -396.068779) (xy 185.287412 -396.047468)
			(xy 185.281062 -396.036038) (xy 185.258964 -396.022576) (xy 185.146696 -396.017496) (xy 185.123582 -396.028926)
			(xy 185.115962 -396.039848) (xy 185.100626 -396.061125) (xy 185.065022 -396.09964) (xy 185.024477 -396.132912)
			(xy 184.979754 -396.160314) (xy 184.931698 -396.181329) (xy 184.881215 -396.19556) (xy 184.829259 -396.202738)
			(xy 184.803034 -396.20317) (xy 184.77578 -396.202713) (xy 184.721827 -396.19496) (xy 184.669527 -396.179606)
			(xy 184.619944 -396.156965) (xy 184.574089 -396.127497) (xy 184.532895 -396.091802) (xy 184.497201 -396.050608)
			(xy 184.467733 -396.004752) (xy 184.445093 -395.955169) (xy 184.42974 -395.902869) (xy 184.421987 -395.848916)
			(xy 184.421526 -395.821662) (xy 182.60822 -395.821662) (xy 182.60822 -396.70355) (xy 183.541922 -396.70355)
			(xy 183.545993 -396.647928) (xy 183.558119 -396.593491) (xy 183.578042 -396.5414) (xy 183.605338 -396.492765)
			(xy 183.639424 -396.448622) (xy 183.679573 -396.409913) (xy 183.724931 -396.377462) (xy 183.774531 -396.351961)
			(xy 183.827315 -396.333954) (xy 183.882158 -396.323824) (xy 183.937892 -396.321787) (xy 183.993329 -396.327887)
			(xy 184.047286 -396.341993) (xy 184.098615 -396.363805) (xy 184.146221 -396.392859) (xy 184.189089 -396.428534)
			(xy 184.226306 -396.470071) (xy 184.257079 -396.516584) (xy 184.280751 -396.567081) (xy 184.296819 -396.620488)
			(xy 184.304939 -396.675664) (xy 184.305448 -396.70355) (xy 184.304939 -396.731436) (xy 184.296819 -396.786612)
			(xy 184.280751 -396.840019) (xy 184.257079 -396.890516) (xy 184.226306 -396.937029) (xy 184.189089 -396.978566)
			(xy 184.146221 -397.014241) (xy 184.098615 -397.043295) (xy 184.047286 -397.065107) (xy 183.993329 -397.079213)
			(xy 183.937892 -397.085313) (xy 183.882158 -397.083276) (xy 183.827315 -397.073146) (xy 183.774531 -397.055139)
			(xy 183.724931 -397.029638) (xy 183.679573 -396.997187) (xy 183.639424 -396.958478) (xy 183.605338 -396.914335)
			(xy 183.578042 -396.8657) (xy 183.558119 -396.813609) (xy 183.545993 -396.759172) (xy 183.541922 -396.70355)
			(xy 182.60822 -396.70355) (xy 182.60822 -397.1036) (xy 184.358532 -397.1036) (xy 184.362603 -397.047978)
			(xy 184.374729 -396.993541) (xy 184.394652 -396.94145) (xy 184.421948 -396.892815) (xy 184.456034 -396.848672)
			(xy 184.496183 -396.809963) (xy 184.541541 -396.777512) (xy 184.591141 -396.752011) (xy 184.643925 -396.734004)
			(xy 184.698768 -396.723874) (xy 184.754502 -396.721837) (xy 184.809939 -396.727937) (xy 184.863896 -396.742043)
			(xy 184.915225 -396.763855) (xy 184.962831 -396.792909) (xy 185.005699 -396.828584) (xy 185.042916 -396.870121)
			(xy 185.073689 -396.916634) (xy 185.097361 -396.967131) (xy 185.113429 -397.020538) (xy 185.121549 -397.075714)
			(xy 185.122058 -397.1036) (xy 185.121549 -397.131486) (xy 185.113429 -397.186662) (xy 185.097361 -397.240069)
			(xy 185.073689 -397.290566) (xy 185.042916 -397.337079) (xy 185.005699 -397.378616) (xy 184.962831 -397.414291)
			(xy 184.915225 -397.443345) (xy 184.863896 -397.465157) (xy 184.809939 -397.479263) (xy 184.754502 -397.485363)
			(xy 184.698768 -397.483326) (xy 184.643925 -397.473196) (xy 184.591141 -397.455189) (xy 184.541541 -397.429688)
			(xy 184.496183 -397.397237) (xy 184.456034 -397.358528) (xy 184.421948 -397.314385) (xy 184.394652 -397.26575)
			(xy 184.374729 -397.213659) (xy 184.362603 -397.159222) (xy 184.358532 -397.1036) (xy 182.60822 -397.1036)
			(xy 182.60822 -399.024602) (xy 182.863742 -399.024602) (xy 182.867813 -398.96898) (xy 182.879939 -398.914543)
			(xy 182.899862 -398.862452) (xy 182.927158 -398.813817) (xy 182.961244 -398.769674) (xy 183.001393 -398.730965)
			(xy 183.046751 -398.698514) (xy 183.096351 -398.673013) (xy 183.149135 -398.655006) (xy 183.203978 -398.644876)
			(xy 183.259712 -398.642839) (xy 183.315149 -398.648939) (xy 183.369106 -398.663045) (xy 183.420435 -398.684857)
			(xy 183.468041 -398.713911) (xy 183.510909 -398.749586) (xy 183.548126 -398.791123) (xy 183.578899 -398.837636)
			(xy 183.602571 -398.888133) (xy 183.618639 -398.94154) (xy 183.626759 -398.996716) (xy 183.627268 -399.024602)
			(xy 183.626759 -399.052488) (xy 183.618639 -399.107664) (xy 183.618411 -399.108422) (xy 184.142632 -399.108422)
			(xy 184.146703 -399.0528) (xy 184.158829 -398.998363) (xy 184.178752 -398.946272) (xy 184.206048 -398.897637)
			(xy 184.240134 -398.853494) (xy 184.280283 -398.814785) (xy 184.325641 -398.782334) (xy 184.375241 -398.756833)
			(xy 184.428025 -398.738826) (xy 184.482868 -398.728696) (xy 184.538602 -398.726659) (xy 184.594039 -398.732759)
			(xy 184.647996 -398.746865) (xy 184.699325 -398.768677) (xy 184.746931 -398.797731) (xy 184.789799 -398.833406)
			(xy 184.827016 -398.874943) (xy 184.857789 -398.921456) (xy 184.881461 -398.971953) (xy 184.897529 -399.02536)
			(xy 184.905649 -399.080536) (xy 184.906158 -399.108422) (xy 184.905649 -399.136308) (xy 184.897529 -399.191484)
			(xy 184.881461 -399.244891) (xy 184.857789 -399.295388) (xy 184.827016 -399.341901) (xy 184.789799 -399.383438)
			(xy 184.746931 -399.419113) (xy 184.699325 -399.448167) (xy 184.647996 -399.469979) (xy 184.594039 -399.484085)
			(xy 184.538602 -399.490185) (xy 184.482868 -399.488148) (xy 184.428025 -399.478018) (xy 184.375241 -399.460011)
			(xy 184.325641 -399.43451) (xy 184.280283 -399.402059) (xy 184.240134 -399.36335) (xy 184.206048 -399.319207)
			(xy 184.178752 -399.270572) (xy 184.158829 -399.218481) (xy 184.146703 -399.164044) (xy 184.142632 -399.108422)
			(xy 183.618411 -399.108422) (xy 183.602571 -399.161071) (xy 183.578899 -399.211568) (xy 183.548126 -399.258081)
			(xy 183.510909 -399.299618) (xy 183.468041 -399.335293) (xy 183.420435 -399.364347) (xy 183.369106 -399.386159)
			(xy 183.315149 -399.400265) (xy 183.259712 -399.406365) (xy 183.203978 -399.404328) (xy 183.149135 -399.394198)
			(xy 183.096351 -399.376191) (xy 183.046751 -399.35069) (xy 183.001393 -399.318239) (xy 182.961244 -399.27953)
			(xy 182.927158 -399.235387) (xy 182.899862 -399.186752) (xy 182.879939 -399.134661) (xy 182.867813 -399.080224)
			(xy 182.863742 -399.024602) (xy 182.60822 -399.024602) (xy 182.60822 -399.504154) (xy 182.607755 -399.524156)
			(xy 182.600004 -399.563402) (xy 182.58475 -399.600384) (xy 182.56258 -399.633682) (xy 182.548784 -399.648172)
			(xy 182.206138 -399.990818) (xy 182.191638 -400.004619) (xy 182.158358 -400.026853) (xy 182.121383 -400.042175)
			(xy 182.082132 -400.049998) (xy 182.06212 -400.050508) (xy 181.193186 -400.050508) (xy 181.173166 -400.050057)
			(xy 181.133895 -400.042254) (xy 181.096903 -400.026932) (xy 181.063616 -400.004682) (xy 181.049168 -399.990818)
			(xy 180.617622 -399.559272) (xy 180.603816 -399.544774) (xy 180.581572 -399.511496) (xy 180.566241 -399.474521)
			(xy 180.55841 -399.435267) (xy 180.557932 -399.415254) (xy 180.557932 -399.183352) (xy 180.557496 -399.173319)
			(xy 180.549926 -399.154739) (xy 180.5432 -399.147284) (xy 180.178964 -398.783048) (xy 180.156104 -398.775682)
			(xy 180.143912 -398.777714) (xy 180.129149 -398.779876) (xy 180.099396 -398.782166) (xy 180.084476 -398.782286)
			(xy 180.057227 -398.781798) (xy 180.003284 -398.774039) (xy 179.950995 -398.758682) (xy 179.901423 -398.736041)
			(xy 179.855578 -398.706575) (xy 179.814393 -398.670884) (xy 179.778706 -398.629696) (xy 179.749244 -398.583848)
			(xy 179.726606 -398.534274) (xy 179.711254 -398.481984) (xy 179.7035 -398.42804) (xy 179.703501 -398.373542)
			(xy 179.711258 -398.319599) (xy 179.726612 -398.267309) (xy 179.749252 -398.217736) (xy 179.778716 -398.17189)
			(xy 179.814405 -398.130704) (xy 179.855592 -398.095015) (xy 179.901438 -398.065551) (xy 179.951011 -398.042912)
			(xy 180.003301 -398.027557) (xy 180.057244 -398.019801) (xy 180.111742 -398.0198) (xy 180.165686 -398.027554)
			(xy 180.217976 -398.042907) (xy 180.26755 -398.065545) (xy 180.313398 -398.095007) (xy 180.354586 -398.130694)
			(xy 180.390276 -398.17188) (xy 180.419741 -398.217725) (xy 180.442383 -398.267297) (xy 180.457739 -398.319586)
			(xy 180.465498 -398.373529) (xy 180.465984 -398.400778) (xy 180.465861 -398.415698) (xy 180.463575 -398.445451)
			(xy 180.461412 -398.460214) (xy 180.45938 -398.472406) (xy 180.466746 -398.495266) (xy 180.905658 -398.933924)
			(xy 180.919459 -398.948424) (xy 180.941695 -398.981704) (xy 180.957021 -399.018678) (xy 180.96485 -399.05793)
			(xy 180.965348 -399.077942) (xy 180.965348 -399.309844) (xy 180.965786 -399.319876) (xy 180.973363 -399.338449)
			(xy 180.98008 -399.345912) (xy 181.262528 -399.62836) (xy 181.269957 -399.635127) (xy 181.288553 -399.642701)
			(xy 181.298596 -399.643092) (xy 181.95671 -399.643092) (xy 181.966737 -399.642643) (xy 181.985297 -399.635054)
			(xy 181.992778 -399.62836) (xy 182.186326 -399.434812) (xy 182.193182 -399.427418) (xy 182.200933 -399.408819)
			(xy 182.201312 -399.398744) (xy 182.201312 -394.01242) (xy 182.201779 -393.992419) (xy 182.209536 -393.953177)
			(xy 182.224795 -393.9162) (xy 182.24697 -393.882908) (xy 182.260748 -393.868402) (xy 183.261 -392.86815)
			(xy 183.275502 -392.854354) (xy 183.308784 -392.832129) (xy 183.345758 -392.816816) (xy 183.385008 -392.809002)
			(xy 183.405018 -392.80846) (xy 193.327274 -392.80846) (xy 193.347291 -392.808918) (xy 193.386554 -392.816732)
			(xy 193.423534 -392.832065) (xy 193.456807 -392.854327) (xy 193.471292 -392.86815) (xy 193.910458 -393.307316)
			(xy 193.92426 -393.321816) (xy 193.946497 -393.355095) (xy 193.961825 -393.39207) (xy 193.969655 -393.431322)
			(xy 193.970148 -393.451334) (xy 193.970148 -398.511776) (xy 193.970591 -398.521805) (xy 193.978177 -398.54037)
			(xy 193.98488 -398.547844) (xy 195.657978 -400.220942) (xy 195.66542 -400.227642) (xy 195.68392 -400.235252)
			(xy 195.703924 -400.235244) (xy 195.71335 -400.231864) (xy 195.727828 -400.226022) (xy 195.744592 -400.200622)
			(xy 195.744592 -391.620756) (xy 195.745046 -391.600737) (xy 195.752854 -391.561469) (xy 195.768179 -391.524482)
			(xy 195.790433 -391.491199) (xy 195.804282 -391.476738) (xy 195.931282 -391.349738) (xy 195.945784 -391.335941)
			(xy 195.979065 -391.313715) (xy 196.01604 -391.2984) (xy 196.05529 -391.290583) (xy 196.0753 -391.290048)
			(xy 204.97292 -391.290048) (xy 204.992939 -391.2905) (xy 205.032208 -391.298306) (xy 205.069196 -391.313631)
			(xy 205.102478 -391.335887) (xy 205.116938 -391.349738) (xy 205.243938 -391.476738) (xy 205.25774 -391.491238)
			(xy 205.279975 -391.524518) (xy 205.2953 -391.561492) (xy 205.303127 -391.600744) (xy 205.303628 -391.620756)
			(xy 205.303628 -397.79067) (xy 205.30407 -397.8007) (xy 205.311651 -397.819269) (xy 205.31836 -397.826738)
			(xy 205.884018 -398.392142) (xy 205.897821 -398.406641) (xy 205.920058 -398.439921) (xy 205.935384 -398.476895)
			(xy 205.94321 -398.516148) (xy 205.943708 -398.53616) (xy 205.943708 -399.01241) (xy 205.944157 -399.022437)
			(xy 205.951746 -399.040997) (xy 205.95844 -399.048478) (xy 206.684118 -399.773902) (xy 206.697923 -399.7884)
			(xy 206.720167 -399.821678) (xy 206.7355 -399.858653) (xy 206.743335 -399.897907) (xy 206.743808 -399.91792)
			(xy 206.743808 -400.555968) (xy 206.744174 -400.565993) (xy 206.751784 -400.584539) (xy 206.765958 -400.598714)
			(xy 206.77505 -400.602958) (xy 206.789528 -400.609054) (xy 206.819246 -400.602958) (xy 207.02016 -400.402298)
			(xy 207.026931 -400.39487) (xy 207.034515 -400.376274) (xy 207.034892 -400.36623) (xy 207.034892 -393.667488)
			(xy 207.035343 -393.647468) (xy 207.043145 -393.608197) (xy 207.058467 -393.571205) (xy 207.080717 -393.537918)
			(xy 207.094582 -393.52347) (xy 207.43164 -393.186412) (xy 207.446119 -393.172597) (xy 207.479407 -393.150392)
			(xy 207.516393 -393.135119) (xy 207.55565 -393.127369) (xy 207.575658 -393.126976) (xy 215.162384 -393.126976)
			(xy 215.182385 -393.127444) (xy 215.221628 -393.1352) (xy 215.258606 -393.150457) (xy 215.2919 -393.17263)
			(xy 215.306402 -393.186412) (xy 215.732868 -393.612878) (xy 215.746682 -393.627357) (xy 215.768883 -393.660646)
			(xy 215.78415 -393.697632) (xy 215.791893 -393.736889) (xy 215.792304 -393.756896) (xy 215.792304 -398.2339)
			(xy 215.792727 -398.24397) (xy 215.800442 -398.262574) (xy 215.80729 -398.269968) (xy 217.352118 -399.814542)
			(xy 217.365921 -399.829041) (xy 217.388158 -399.862321) (xy 217.403484 -399.899295) (xy 217.41131 -399.938548)
			(xy 217.411808 -399.95856) (xy 217.411808 -400.555968) (xy 217.412174 -400.565993) (xy 217.419784 -400.584539)
			(xy 217.433958 -400.598714) (xy 217.44305 -400.602958) (xy 217.457528 -400.609054) (xy 217.487246 -400.602958)
			(xy 217.72118 -400.369278) (xy 217.727956 -400.361853) (xy 217.735545 -400.343256) (xy 217.735912 -400.33321)
			(xy 217.735912 -393.695174) (xy 217.736365 -393.675155) (xy 217.74417 -393.635886) (xy 217.759494 -393.598897)
			(xy 217.781748 -393.565613) (xy 217.795602 -393.551156) (xy 218.009978 -393.33678) (xy 218.024459 -393.322969)
			(xy 218.057749 -393.300774) (xy 218.094735 -393.285511) (xy 218.13399 -393.27777) (xy 218.153996 -393.277344)
			(xy 226.527614 -393.277344) (xy 226.547615 -393.277814) (xy 226.586855 -393.285574) (xy 226.62383 -393.300834)
			(xy 226.657122 -393.323007) (xy 226.671632 -393.33678) (xy 227.127562 -393.79271) (xy 227.141364 -393.80721)
			(xy 227.163602 -393.840489) (xy 227.17893 -393.877464) (xy 227.186761 -393.916716) (xy 227.187252 -393.936728)
			(xy 227.187252 -398.833594) (xy 227.187699 -398.843622) (xy 227.195289 -398.862182) (xy 227.201984 -398.869662)
			(xy 227.321618 -398.989296) (xy 227.328909 -398.99589) (xy 227.347013 -399.00351) (xy 227.366652 -399.003845)
			(xy 227.375974 -399.000726) (xy 227.476812 -398.961864) (xy 227.494338 -398.937734) (xy 227.4951 -398.92224)
			(xy 227.497002 -398.893907) (xy 227.508143 -398.838225) (xy 227.527415 -398.78481) (xy 227.554393 -398.734843)
			(xy 227.58848 -398.689427) (xy 227.628923 -398.649566) (xy 227.651564 -398.632426) (xy 227.660867 -398.624772)
			(xy 227.671737 -398.603307) (xy 227.672392 -398.591278) (xy 227.672392 -393.671806) (xy 227.671946 -393.661777)
			(xy 227.664361 -393.643213) (xy 227.65766 -393.635738) (xy 226.718368 -392.696446) (xy 226.71097 -392.6896)
			(xy 226.692371 -392.68187) (xy 226.6823 -392.68146) (xy 217.569796 -392.68146) (xy 217.559727 -392.681885)
			(xy 217.54113 -392.689608) (xy 217.533728 -392.696446) (xy 217.42654 -392.803634) (xy 217.419774 -392.811063)
			(xy 217.412202 -392.829659) (xy 217.411808 -392.839702) (xy 217.411808 -398.591278) (xy 217.412414 -398.603321)
			(xy 217.423294 -398.624801) (xy 217.432636 -398.632426) (xy 217.453149 -398.647858) (xy 217.490239 -398.683343)
			(xy 217.522231 -398.723485) (xy 217.548546 -398.767558) (xy 217.568708 -398.814763) (xy 217.582351 -398.864248)
			(xy 217.58923 -398.915116) (xy 217.589608 -398.940782) (xy 217.589122 -398.968033) (xy 217.581366 -399.021981)
			(xy 217.566011 -399.074276) (xy 217.543369 -399.123853) (xy 217.513903 -399.169703) (xy 217.478212 -399.210894)
			(xy 217.437021 -399.246585) (xy 217.391171 -399.276051) (xy 217.341594 -399.298693) (xy 217.289299 -399.314048)
			(xy 217.235351 -399.321804) (xy 217.180849 -399.321804) (xy 217.126901 -399.314048) (xy 217.074606 -399.298693)
			(xy 217.025029 -399.276051) (xy 216.979179 -399.246585) (xy 216.937988 -399.210894) (xy 216.902297 -399.169703)
			(xy 216.872831 -399.123853) (xy 216.850189 -399.074276) (xy 216.834834 -399.021981) (xy 216.827078 -398.968033)
			(xy 216.826592 -398.940782) (xy 216.827011 -398.915119) (xy 216.833897 -398.864257) (xy 216.847542 -398.814777)
			(xy 216.867699 -398.767575) (xy 216.894004 -398.723502) (xy 216.925982 -398.683355) (xy 216.963056 -398.647859)
			(xy 216.983564 -398.632426) (xy 216.992867 -398.624772) (xy 217.003737 -398.603307) (xy 217.004392 -398.591278)
			(xy 217.004392 -392.839702) (xy 217.003946 -392.829674) (xy 216.996359 -392.811111) (xy 216.98966 -392.803634)
			(xy 216.904824 -392.718798) (xy 216.897421 -392.711964) (xy 216.878823 -392.704258) (xy 216.868756 -392.703812)
			(xy 206.99095 -392.703812) (xy 206.980884 -392.704245) (xy 206.962294 -392.711973) (xy 206.954882 -392.718798)
			(xy 206.75854 -392.91514) (xy 206.751759 -392.922564) (xy 206.744153 -392.94116) (xy 206.743808 -392.951208)
			(xy 206.743808 -398.591278) (xy 206.744414 -398.603321) (xy 206.755294 -398.624801) (xy 206.764636 -398.632426)
			(xy 206.785149 -398.647858) (xy 206.822239 -398.683343) (xy 206.854231 -398.723485) (xy 206.880546 -398.767558)
			(xy 206.900708 -398.814763) (xy 206.914351 -398.864248) (xy 206.92123 -398.915116) (xy 206.921608 -398.940782)
			(xy 206.921122 -398.968033) (xy 206.913366 -399.021981) (xy 206.898011 -399.074276) (xy 206.875369 -399.123853)
			(xy 206.845903 -399.169703) (xy 206.810212 -399.210894) (xy 206.769021 -399.246585) (xy 206.723171 -399.276051)
			(xy 206.673594 -399.298693) (xy 206.621299 -399.314048) (xy 206.567351 -399.321804) (xy 206.512849 -399.321804)
			(xy 206.458901 -399.314048) (xy 206.406606 -399.298693) (xy 206.357029 -399.276051) (xy 206.311179 -399.246585)
			(xy 206.269988 -399.210894) (xy 206.234297 -399.169703) (xy 206.204831 -399.123853) (xy 206.182189 -399.074276)
			(xy 206.166834 -399.021981) (xy 206.159078 -398.968033) (xy 206.158592 -398.940782) (xy 206.159011 -398.915119)
			(xy 206.165897 -398.864257) (xy 206.179542 -398.814777) (xy 206.199699 -398.767575) (xy 206.226004 -398.723502)
			(xy 206.257982 -398.683355) (xy 206.295056 -398.647859) (xy 206.315564 -398.632426) (xy 206.324867 -398.624772)
			(xy 206.335737 -398.603307) (xy 206.336392 -398.591278) (xy 206.336392 -391.192512) (xy 206.335947 -391.182483)
			(xy 206.328363 -391.163917) (xy 206.32166 -391.156444) (xy 205.966314 -390.801098) (xy 205.958911 -390.794265)
			(xy 205.940312 -390.786563) (xy 205.930246 -390.786112) (xy 195.387214 -390.786112) (xy 195.377151 -390.786551)
			(xy 195.35857 -390.794289) (xy 195.351146 -390.801098) (xy 194.836288 -391.315956) (xy 194.829505 -391.323379)
			(xy 194.821897 -391.341975) (xy 194.821556 -391.352024) (xy 194.821556 -397.933418) (xy 194.822151 -397.945466)
			(xy 194.833022 -397.96696) (xy 194.842384 -397.974566) (xy 194.862897 -397.989997) (xy 194.899988 -398.025481)
			(xy 194.93198 -398.065623) (xy 194.958294 -398.109696) (xy 194.978454 -398.156902) (xy 194.992095 -398.206388)
			(xy 194.998969 -398.257256) (xy 194.999356 -398.282922) (xy 194.99887 -398.310173) (xy 194.991114 -398.364121)
			(xy 194.975759 -398.416416) (xy 194.953117 -398.465993) (xy 194.923651 -398.511843) (xy 194.88796 -398.553034)
			(xy 194.846769 -398.588725) (xy 194.800919 -398.618191) (xy 194.751342 -398.640833) (xy 194.699047 -398.656188)
			(xy 194.645099 -398.663944) (xy 194.590597 -398.663944) (xy 194.536649 -398.656188) (xy 194.484354 -398.640833)
			(xy 194.434777 -398.618191) (xy 194.388927 -398.588725) (xy 194.347736 -398.553034) (xy 194.312045 -398.511843)
			(xy 194.282579 -398.465993) (xy 194.259937 -398.416416) (xy 194.244582 -398.364121) (xy 194.236826 -398.310173)
			(xy 194.23634 -398.282922) (xy 194.236931 -398.25298) (xy 194.246301 -398.193834) (xy 194.264798 -398.136878)
			(xy 194.291968 -398.083512) (xy 194.327143 -398.035047) (xy 194.369459 -397.992675) (xy 194.393312 -397.974566)
			(xy 194.402613 -397.966912) (xy 194.413469 -397.945446) (xy 194.41414 -397.933418) (xy 194.41414 -392.264392)
			(xy 194.413651 -392.254382) (xy 194.405992 -392.235887) (xy 194.39184 -392.221726) (xy 194.373349 -392.214055)
			(xy 194.36334 -392.213592) (xy 194.34556 -392.213592) (xy 194.325561 -392.213119) (xy 194.286325 -392.205353)
			(xy 194.249356 -392.190086) (xy 194.216073 -392.167906) (xy 194.201542 -392.154156) (xy 193.786252 -391.738612)
			(xy 193.778831 -391.731825) (xy 193.760234 -391.72421) (xy 193.750184 -391.72388) (xy 182.652924 -391.72388)
			(xy 182.642893 -391.724321) (xy 182.624322 -391.731899) (xy 182.616856 -391.738612) (xy 181.22646 -393.129008)
			(xy 181.219688 -393.136435) (xy 181.212103 -393.155031) (xy 181.211728 -393.165076) (xy 181.211728 -398.225264)
			(xy 181.212168 -398.235295) (xy 181.219749 -398.253865) (xy 181.22646 -398.261332) (xy 181.707028 -398.7419)
			(xy 181.717442 -398.74571) (xy 181.744427 -398.756311) (xy 181.795093 -398.784491) (xy 181.84091 -398.820013)
			(xy 181.880825 -398.86206) (xy 181.913918 -398.909662) (xy 181.939427 -398.961724) (xy 181.956765 -399.017046)
			(xy 181.965531 -399.074354) (xy 181.966108 -399.103342) (xy 181.965622 -399.130593) (xy 181.957866 -399.184541)
			(xy 181.942511 -399.236836) (xy 181.919869 -399.286413) (xy 181.890403 -399.332263) (xy 181.854712 -399.373454)
			(xy 181.813521 -399.409145) (xy 181.767671 -399.438611) (xy 181.718094 -399.461253) (xy 181.665799 -399.476608)
			(xy 181.611851 -399.484364) (xy 181.557349 -399.484364) (xy 181.503401 -399.476608) (xy 181.451106 -399.461253)
			(xy 181.401529 -399.438611) (xy 181.355679 -399.409145) (xy 181.314488 -399.373454) (xy 181.278797 -399.332263)
			(xy 181.249331 -399.286413) (xy 181.226689 -399.236836) (xy 181.211334 -399.184541) (xy 181.203578 -399.130593)
			(xy 181.203092 -399.103342) (xy 181.203452 -399.078803) (xy 181.209711 -399.030128) (xy 181.222171 -398.982659)
			(xy 181.240623 -398.937184) (xy 181.252368 -398.915636) (xy 181.261004 -398.90065) (xy 181.256432 -398.866868)
			(xy 180.864002 -398.474692) (xy 180.850196 -398.460194) (xy 180.827951 -398.426916) (xy 180.812617 -398.389942)
			(xy 180.804783 -398.350688) (xy 180.804312 -398.330674) (xy 180.804312 -393.059666) (xy 180.804766 -393.039647)
			(xy 180.812572 -393.000379) (xy 180.827898 -392.963391) (xy 180.850152 -392.930108) (xy 180.864002 -392.915648)
			(xy 182.403496 -391.376154) (xy 182.417998 -391.362357) (xy 182.451279 -391.340132) (xy 182.488254 -391.324818)
			(xy 182.527504 -391.317003) (xy 182.547514 -391.316464) (xy 193.855594 -391.316464) (xy 193.87561 -391.316923)
			(xy 193.914871 -391.324741) (xy 193.951848 -391.340077) (xy 193.985118 -391.362341) (xy 193.999612 -391.376154)
			(xy 194.327526 -391.704322) (xy 194.334968 -391.711016) (xy 194.353465 -391.718612) (xy 194.373461 -391.718587)
			(xy 194.382898 -391.715244) (xy 194.397376 -391.709402) (xy 194.41414 -391.684002) (xy 194.41414 -391.246614)
			(xy 194.414599 -391.226598) (xy 194.422415 -391.187335) (xy 194.437748 -391.150356) (xy 194.460009 -391.117083)
			(xy 194.47383 -391.102596) (xy 195.137786 -390.43864) (xy 195.152265 -390.424826) (xy 195.185554 -390.402626)
			(xy 195.22254 -390.38736) (xy 195.261797 -390.379617) (xy 195.281804 -390.379204) (xy 206.035656 -390.379204)
			(xy 206.055658 -390.379669) (xy 206.094903 -390.387421) (xy 206.131883 -390.402677) (xy 206.165179 -390.424849)
			(xy 206.179674 -390.43864) (xy 206.684118 -390.943084) (xy 206.697917 -390.957585) (xy 206.720147 -390.990865)
			(xy 206.735466 -391.02784) (xy 206.743284 -391.067091) (xy 206.743808 -391.087102) (xy 206.743808 -392.197844)
			(xy 206.744308 -392.208682) (xy 206.753264 -392.228419) (xy 206.76108 -392.235944) (xy 206.826866 -392.293856)
			(xy 206.847694 -392.299952) (xy 206.858616 -392.298682) (xy 206.88554 -392.296904) (xy 216.974166 -392.296904)
			(xy 216.994168 -392.29737) (xy 217.033412 -392.305124) (xy 217.07039 -392.320381) (xy 217.103685 -392.342554)
			(xy 217.118184 -392.35634) (xy 217.172286 -392.410442) (xy 217.179647 -392.417211) (xy 217.198109 -392.424858)
			(xy 217.218091 -392.424858) (xy 217.236553 -392.417211) (xy 217.243914 -392.410442) (xy 217.320368 -392.333988)
			(xy 217.334849 -392.320176) (xy 217.368138 -392.297978) (xy 217.405124 -392.282713) (xy 217.444379 -392.274969)
			(xy 217.464386 -392.274552) (xy 224.0915 -392.274552) (xy 224.100496 -392.274187) (xy 224.117383 -392.267975)
			(xy 224.13111 -392.256342) (xy 224.140007 -392.240703) (xy 224.141792 -392.23188) (xy 224.160842 -392.114278)
			(xy 224.141538 -392.082528) (xy 224.123758 -392.076432) (xy 224.03786 -392.047266) (xy 223.868442 -391.98236)
			(xy 223.702039 -391.910073) (xy 223.538973 -391.830545) (xy 223.379559 -391.743929) (xy 223.224104 -391.650393)
			(xy 223.072908 -391.550117) (xy 222.926265 -391.443294) (xy 222.784457 -391.330132) (xy 222.647757 -391.210848)
			(xy 222.516431 -391.085674) (xy 222.390731 -390.95485) (xy 222.2709 -390.81863) (xy 222.15717 -390.677277)
			(xy 222.049761 -390.531063) (xy 221.948879 -390.380271) (xy 221.85472 -390.225192) (xy 221.767466 -390.066126)
			(xy 221.687284 -389.90338) (xy 221.614331 -389.737269) (xy 221.548746 -389.568112) (xy 221.519242 -389.48233)
			(xy 221.513908 -389.466836) (xy 221.487492 -389.447786) (xy 221.396306 -389.447786) (xy 221.386236 -389.447364)
			(xy 221.367631 -389.439649) (xy 221.360238 -389.4328) (xy 219.361004 -387.433566) (xy 219.353609 -387.426712)
			(xy 219.33501 -387.418965) (xy 219.324936 -387.41858) (xy 209.869024 -387.41858) (xy 209.85965 -387.418946)
			(xy 209.842121 -387.425586) (xy 209.82816 -387.438093) (xy 209.823558 -387.446266) (xy 209.77606 -387.539484)
			(xy 209.778092 -387.568186) (xy 209.786474 -387.579616) (xy 209.803517 -387.604154) (xy 209.830565 -387.657421)
			(xy 209.848972 -387.714255) (xy 209.858287 -387.773266) (xy 209.858864 -387.803136) (xy 209.858327 -387.832051)
			(xy 209.849595 -387.889218) (xy 209.832336 -387.944413) (xy 209.806945 -387.996372) (xy 209.774005 -388.043903)
			(xy 209.734269 -388.08592) (xy 209.711798 -388.104126) (xy 209.703 -388.111663) (xy 209.692799 -388.132434)
			(xy 209.69224 -388.144004) (xy 209.69224 -388.224268) (xy 209.692864 -388.23582) (xy 209.703061 -388.25656)
			(xy 209.711798 -388.264146) (xy 209.734283 -388.282336) (xy 209.774023 -388.324353) (xy 209.806965 -388.371887)
			(xy 209.832354 -388.423849) (xy 209.849609 -388.479048) (xy 209.858334 -388.536219) (xy 209.858864 -388.565136)
			(xy 209.858378 -388.592387) (xy 209.850622 -388.646335) (xy 209.835267 -388.69863) (xy 209.812625 -388.748207)
			(xy 209.783159 -388.794057) (xy 209.747468 -388.835248) (xy 209.706277 -388.870939) (xy 209.660427 -388.900405)
			(xy 209.61085 -388.923047) (xy 209.558555 -388.938402) (xy 209.504607 -388.946158) (xy 209.450105 -388.946158)
			(xy 209.396157 -388.938402) (xy 209.343862 -388.923047) (xy 209.294285 -388.900405) (xy 209.248435 -388.870939)
			(xy 209.207244 -388.835248) (xy 209.171553 -388.794057) (xy 209.142087 -388.748207) (xy 209.119445 -388.69863)
			(xy 209.10409 -388.646335) (xy 209.096334 -388.592387) (xy 209.095848 -388.565136) (xy 209.096387 -388.536222)
			(xy 209.105123 -388.479057) (xy 209.122385 -388.423866) (xy 209.147779 -388.371911) (xy 209.180722 -388.324383)
			(xy 209.220459 -388.282371) (xy 209.242914 -388.264146) (xy 209.251706 -388.256607) (xy 209.261893 -388.235835)
			(xy 209.262472 -388.224268) (xy 209.262472 -388.144004) (xy 209.261863 -388.132444) (xy 209.251685 -388.111679)
			(xy 209.242914 -388.104126) (xy 209.22043 -388.085936) (xy 209.180692 -388.043918) (xy 209.147753 -387.996384)
			(xy 209.122366 -387.944422) (xy 209.105115 -387.889223) (xy 209.096394 -387.832052) (xy 209.095848 -387.803136)
			(xy 209.096426 -387.773265) (xy 209.105736 -387.714252) (xy 209.124135 -387.657413) (xy 209.151173 -387.604139)
			(xy 209.168238 -387.579616) (xy 209.17662 -387.568186) (xy 209.178652 -387.539484) (xy 209.131154 -387.446266)
			(xy 209.126514 -387.438119) (xy 209.112565 -387.425616) (xy 209.095056 -387.41896) (xy 209.085688 -387.41858)
			(xy 207.83677 -387.41858) (xy 207.82744 -387.418986) (xy 207.810012 -387.425653) (xy 207.796135 -387.438127)
			(xy 207.791558 -387.446266) (xy 207.743806 -387.539484) (xy 207.746092 -387.568186) (xy 207.754474 -387.579616)
			(xy 207.771517 -387.604154) (xy 207.798565 -387.657421) (xy 207.816972 -387.714255) (xy 207.826287 -387.773266)
			(xy 207.826864 -387.803136) (xy 207.826311 -387.833118) (xy 207.816937 -387.892345) (xy 207.798409 -387.949376)
			(xy 207.771185 -388.002804) (xy 207.735934 -388.051313) (xy 207.715104 -388.072884) (xy 207.651604 -388.13613)
			(xy 207.644789 -388.14351) (xy 207.637082 -388.162044) (xy 207.637074 -388.182116) (xy 207.644766 -388.200656)
			(xy 207.651604 -388.208012) (xy 207.715104 -388.271258) (xy 207.735883 -388.292873) (xy 207.771121 -388.341378)
			(xy 207.798342 -388.394797) (xy 207.816874 -388.451815) (xy 207.826263 -388.511029) (xy 207.826864 -388.541006)
			(xy 207.826864 -388.565136) (xy 207.826398 -388.592386) (xy 207.818637 -388.646331) (xy 207.803277 -388.698622)
			(xy 207.780632 -388.748195) (xy 207.751162 -388.79404) (xy 207.715468 -388.835225) (xy 207.674276 -388.87091)
			(xy 207.628424 -388.90037) (xy 207.578847 -388.923005) (xy 207.526552 -388.938354) (xy 207.472606 -388.946104)
			(xy 207.445356 -388.946644) (xy 207.417908 -388.946143) (xy 207.363584 -388.938233) (xy 207.310953 -388.922624)
			(xy 207.261099 -388.89964) (xy 207.215051 -388.869753) (xy 207.173757 -388.833579) (xy 207.155542 -388.81304)
			(xy 207.147969 -388.805017) (xy 207.127953 -388.795792) (xy 207.116934 -388.79526) (xy 205.39202 -388.79526)
			(xy 205.362052 -388.79469) (xy 205.302848 -388.785353) (xy 205.245831 -388.766874) (xy 205.192406 -388.739707)
			(xy 205.143885 -388.704521) (xy 205.122272 -388.683754) (xy 203.872084 -387.433566) (xy 203.864741 -387.426751)
			(xy 203.846278 -387.419014) (xy 203.83627 -387.41858) (xy 201.436732 -387.41858) (xy 201.426858 -387.419048)
			(xy 201.408571 -387.426502) (xy 201.401172 -387.433058) (xy 201.388216 -387.445426) (xy 201.360356 -387.467941)
			(xy 201.345546 -387.478016) (xy 201.341482 -387.48081) (xy 201.328782 -387.49351) (xy 201.321295 -387.501715)
			(xy 201.313653 -387.522541) (xy 201.31405 -387.533642) (xy 201.321924 -387.622542) (xy 201.332846 -387.641846)
			(xy 201.342244 -387.64845) (xy 201.363393 -387.663807) (xy 201.401682 -387.699383) (xy 201.434752 -387.739858)
			(xy 201.46198 -387.784471) (xy 201.482858 -387.832386) (xy 201.496992 -387.882705) (xy 201.504118 -387.934483)
			(xy 201.50455 -387.960616) (xy 201.504063 -387.987868) (xy 201.496305 -388.041816) (xy 201.480949 -388.094111)
			(xy 201.458307 -388.143689) (xy 201.428841 -388.18954) (xy 201.393151 -388.230732) (xy 201.351961 -388.266426)
			(xy 201.306112 -388.295895) (xy 201.256535 -388.31854) (xy 201.204241 -388.333899) (xy 201.150294 -388.341661)
			(xy 201.123042 -388.342124) (xy 201.096911 -388.34169) (xy 201.045139 -388.334547) (xy 200.994827 -388.320402)
			(xy 200.946918 -388.299521) (xy 200.902308 -388.272294) (xy 200.861833 -388.239231) (xy 200.826252 -388.200951)
			(xy 200.810876 -388.179818) (xy 200.804272 -388.17042) (xy 200.784968 -388.159498) (xy 200.696068 -388.151624)
			(xy 200.684982 -388.1513) (xy 200.664184 -388.158941) (xy 200.655936 -388.166356) (xy 199.53732 -389.284972)
			(xy 199.529919 -389.291809) (xy 199.51132 -389.299519) (xy 199.501252 -389.299958) (xy 195.454016 -389.299958)
			(xy 195.444054 -389.300446) (xy 195.425631 -389.308034) (xy 195.418202 -389.31469) (xy 195.388809 -389.343337)
			(xy 195.325598 -389.3957) (xy 195.257832 -389.442017) (xy 195.186089 -389.481896) (xy 195.110977 -389.514996)
			(xy 195.033135 -389.541038) (xy 194.953226 -389.559799) (xy 194.871928 -389.57112) (xy 194.789933 -389.574904)
			(xy 194.707938 -389.57112) (xy 194.62664 -389.559799) (xy 194.546731 -389.541038) (xy 194.468889 -389.514996)
			(xy 194.393777 -389.481896) (xy 194.322034 -389.442017) (xy 194.254268 -389.3957) (xy 194.191057 -389.343337)
			(xy 194.161664 -389.31469) (xy 194.154298 -389.307578) (xy 194.13601 -389.299958) (xy 193.973958 -389.299958)
			(xy 193.963892 -389.299526) (xy 193.945303 -389.291796) (xy 193.93789 -389.284972) (xy 192.691004 -388.038086)
			(xy 192.66662 -388.03072) (xy 192.653666 -388.033514) (xy 192.633844 -388.037535) (xy 192.593626 -388.041859)
			(xy 192.573402 -388.04215) (xy 192.54615 -388.041664) (xy 192.492199 -388.033908) (xy 192.439902 -388.018554)
			(xy 192.390322 -387.995913) (xy 192.344468 -387.966448) (xy 192.303274 -387.930757) (xy 192.267579 -387.889567)
			(xy 192.238108 -387.843717) (xy 192.215462 -387.794139) (xy 192.200101 -387.741844) (xy 192.192339 -387.687894)
			(xy 192.191894 -387.660642) (xy 192.192187 -387.640418) (xy 192.196512 -387.600201) (xy 192.20053 -387.580378)
			(xy 192.203324 -387.567424) (xy 192.195958 -387.54304) (xy 192.086484 -387.433566) (xy 192.079088 -387.426715)
			(xy 192.060489 -387.418976) (xy 192.050416 -387.41858) (xy 187.559188 -387.41858) (xy 187.552379 -387.4188)
			(xy 187.539249 -387.422409) (xy 187.53328 -387.425692) (xy 187.511043 -387.438473) (xy 187.463871 -387.45861)
			(xy 187.414426 -387.472243) (xy 187.363599 -387.479125) (xy 187.337954 -387.47954) (xy 187.324382 -387.479427)
			(xy 187.297306 -387.477518) (xy 187.283852 -387.47573) (xy 187.274708 -387.47446) (xy 187.256928 -387.47827)
			(xy 187.1853 -387.524752) (xy 187.174378 -387.53923) (xy 187.171838 -387.548374) (xy 187.163845 -387.574586)
			(xy 187.141388 -387.624571) (xy 187.112011 -387.670829) (xy 187.076318 -387.712409) (xy 187.035045 -387.748456)
			(xy 186.989039 -387.778227) (xy 186.939247 -387.801111) (xy 186.886694 -387.816637) (xy 186.832461 -387.824484)
			(xy 186.805062 -387.82498) (xy 186.776228 -387.824456) (xy 186.719215 -387.815783) (xy 186.664158 -387.798625)
			(xy 186.612312 -387.773373) (xy 186.564859 -387.740604) (xy 186.52288 -387.701063) (xy 186.487333 -387.655654)
			(xy 186.459028 -387.60541) (xy 186.43861 -387.551477) (xy 186.426545 -387.495084) (xy 186.424316 -387.466332)
			(xy 186.423046 -387.446266) (xy 186.393582 -387.41858) (xy 183.214518 -387.41858) (xy 183.204529 -387.419113)
			(xy 183.18609 -387.42682) (xy 183.178704 -387.433566) (xy 182.148988 -388.463282) (xy 182.14313 -388.469566)
			(xy 182.135643 -388.485017) (xy 182.133711 -388.502077) (xy 182.135272 -388.510526) (xy 182.157116 -388.6073)
			(xy 182.174388 -388.626604) (xy 182.186834 -388.630922) (xy 182.214337 -388.641224) (xy 182.266047 -388.669061)
			(xy 182.31288 -388.704495) (xy 182.353731 -388.746686) (xy 182.387634 -388.794639) (xy 182.413789 -388.84722)
			(xy 182.431577 -388.903189) (xy 182.440578 -388.961222) (xy 182.441088 -388.990586) (xy 182.440607 -389.018016)
			(xy 182.43274 -389.072309) (xy 182.417182 -389.124917) (xy 182.394252 -389.174755) (xy 182.364423 -389.220797)
			(xy 182.32831 -389.262094) (xy 182.286656 -389.297795) (xy 182.24032 -389.327165) (xy 182.190257 -389.349599)
			(xy 182.137498 -389.364634) (xy 182.11038 -389.368792) (xy 182.101236 -389.370062) (xy 182.084726 -389.378698)
			(xy 182.028592 -389.44423) (xy 182.022242 -389.461756) (xy 182.022496 -389.471154) (xy 182.022496 -389.478012)
			(xy 182.021983 -389.506627) (xy 182.01343 -389.563215) (xy 181.996518 -389.61789) (xy 181.971627 -389.669424)
			(xy 181.939316 -389.71666) (xy 181.900309 -389.758539) (xy 181.855483 -389.794119) (xy 181.805844 -389.822602)
			(xy 181.752506 -389.843349) (xy 181.696668 -389.855893) (xy 181.668166 -389.858504) (xy 181.658768 -389.859266)
			(xy 181.642004 -389.86714) (xy 181.629033 -389.880602) (xy 192.195448 -389.880602) (xy 192.199519 -389.82498)
			(xy 192.211645 -389.770543) (xy 192.231568 -389.718452) (xy 192.258864 -389.669817) (xy 192.29295 -389.625674)
			(xy 192.333099 -389.586965) (xy 192.378457 -389.554514) (xy 192.428057 -389.529013) (xy 192.480841 -389.511006)
			(xy 192.535684 -389.500876) (xy 192.591418 -389.498839) (xy 192.646855 -389.504939) (xy 192.700812 -389.519045)
			(xy 192.752141 -389.540857) (xy 192.799747 -389.569911) (xy 192.842615 -389.605586) (xy 192.879832 -389.647123)
			(xy 192.910605 -389.693636) (xy 192.934277 -389.744133) (xy 192.950345 -389.79754) (xy 192.958465 -389.852716)
			(xy 192.958974 -389.880602) (xy 198.820276 -389.880602) (xy 198.824347 -389.82498) (xy 198.836473 -389.770543)
			(xy 198.856396 -389.718452) (xy 198.883692 -389.669817) (xy 198.917778 -389.625674) (xy 198.957927 -389.586965)
			(xy 199.003285 -389.554514) (xy 199.052885 -389.529013) (xy 199.105669 -389.511006) (xy 199.160512 -389.500876)
			(xy 199.216246 -389.498839) (xy 199.271683 -389.504939) (xy 199.32564 -389.519045) (xy 199.376969 -389.540857)
			(xy 199.424575 -389.569911) (xy 199.467443 -389.605586) (xy 199.50466 -389.647123) (xy 199.535433 -389.693636)
			(xy 199.559105 -389.744133) (xy 199.575173 -389.79754) (xy 199.583293 -389.852716) (xy 199.583802 -389.880602)
			(xy 199.583293 -389.908488) (xy 199.575173 -389.963664) (xy 199.559105 -390.017071) (xy 199.535433 -390.067568)
			(xy 199.50466 -390.114081) (xy 199.467443 -390.155618) (xy 199.424575 -390.191293) (xy 199.376969 -390.220347)
			(xy 199.32564 -390.242159) (xy 199.271683 -390.256265) (xy 199.216246 -390.262365) (xy 199.160512 -390.260328)
			(xy 199.105669 -390.250198) (xy 199.052885 -390.232191) (xy 199.003285 -390.20669) (xy 198.957927 -390.174239)
			(xy 198.917778 -390.13553) (xy 198.883692 -390.091387) (xy 198.856396 -390.042752) (xy 198.836473 -389.990661)
			(xy 198.824347 -389.936224) (xy 198.820276 -389.880602) (xy 192.958974 -389.880602) (xy 192.958465 -389.908488)
			(xy 192.950345 -389.963664) (xy 192.934277 -390.017071) (xy 192.910605 -390.067568) (xy 192.879832 -390.114081)
			(xy 192.842615 -390.155618) (xy 192.799747 -390.191293) (xy 192.752141 -390.220347) (xy 192.700812 -390.242159)
			(xy 192.646855 -390.256265) (xy 192.591418 -390.262365) (xy 192.535684 -390.260328) (xy 192.480841 -390.250198)
			(xy 192.428057 -390.232191) (xy 192.378457 -390.20669) (xy 192.333099 -390.174239) (xy 192.29295 -390.13553)
			(xy 192.258864 -390.091387) (xy 192.231568 -390.042752) (xy 192.211645 -389.990661) (xy 192.199519 -389.936224)
			(xy 192.195448 -389.880602) (xy 181.629033 -389.880602) (xy 181.581552 -389.929878) (xy 181.574186 -389.946896)
			(xy 181.573932 -389.956548) (xy 181.572596 -389.98319) (xy 181.563406 -390.035735) (xy 181.546985 -390.086488)
			(xy 181.523656 -390.134459) (xy 181.493872 -390.178713) (xy 181.458215 -390.218386) (xy 181.417379 -390.252707)
			(xy 181.37216 -390.281005) (xy 181.323441 -390.302728) (xy 181.272171 -390.317454) (xy 181.219349 -390.324895)
			(xy 181.192678 -390.325356) (xy 181.168996 -390.324998) (xy 181.121997 -390.319136) (xy 181.098952 -390.313672)
			(xy 181.087268 -390.310624) (xy 181.064662 -390.31545) (xy 180.992018 -390.372092) (xy 180.983188 -390.379681)
			(xy 180.973006 -390.400592) (xy 180.97246 -390.412224) (xy 180.97246 -390.443974) (xy 180.972004 -390.468565)
			(xy 180.96431 -390.517143) (xy 180.949108 -390.563917) (xy 180.926773 -390.607736) (xy 180.897854 -390.647518)
			(xy 180.880766 -390.665208) (xy 180.43652 -391.109454) (xy 180.418818 -391.126528) (xy 180.379042 -391.155452)
			(xy 180.335226 -391.177789) (xy 180.288453 -391.192988) (xy 180.239876 -391.200673) (xy 180.215286 -391.201148)
			(xy 179.957222 -391.201148) (xy 179.947566 -391.201554) (xy 179.929627 -391.208696) (xy 179.915634 -391.222002)
			(xy 179.911248 -391.230612) (xy 179.86629 -391.328148) (xy 179.870354 -391.357358) (xy 179.88026 -391.368788)
			(xy 179.897523 -391.389636) (xy 179.899614 -391.392918) (xy 180.837078 -391.392918) (xy 180.837574 -391.364301)
			(xy 180.846134 -391.307711) (xy 180.863052 -391.253035) (xy 180.887946 -391.201499) (xy 180.920258 -391.154259)
			(xy 180.959264 -391.112376) (xy 181.004089 -391.076788) (xy 181.053726 -391.048295) (xy 181.107062 -391.027536)
			(xy 181.1629 -391.014976) (xy 181.191408 -391.012426) (xy 181.200806 -391.011664) (xy 181.21757 -391.00379)
			(xy 181.278022 -390.941052) (xy 181.285388 -390.924034) (xy 181.285642 -390.914382) (xy 181.287056 -390.886434)
			(xy 181.297072 -390.83138) (xy 181.315023 -390.778379) (xy 181.340525 -390.728569) (xy 181.37303 -390.683019)
			(xy 181.41184 -390.642707) (xy 181.456123 -390.608496) (xy 181.504929 -390.581122) (xy 181.55721 -390.561172)
			(xy 181.611845 -390.549073) (xy 181.639718 -390.54659) (xy 181.649116 -390.545828) (xy 181.66588 -390.537954)
			(xy 181.726332 -390.475216) (xy 181.733698 -390.458198) (xy 181.733952 -390.448546) (xy 181.735278 -390.421902)
			(xy 181.744459 -390.36935) (xy 181.760873 -390.318591) (xy 181.784199 -390.270614) (xy 181.813982 -390.226354)
			(xy 181.849641 -390.186676) (xy 181.890481 -390.152353) (xy 181.935704 -390.124056) (xy 181.984429 -390.102335)
			(xy 182.035705 -390.087615) (xy 182.088532 -390.080183) (xy 182.115206 -390.079738) (xy 182.142461 -390.08015)
			(xy 182.196416 -390.087909) (xy 182.248718 -390.103268) (xy 182.298301 -390.125915) (xy 182.344156 -390.155387)
			(xy 182.38535 -390.191087) (xy 182.421044 -390.232285) (xy 182.45051 -390.278145) (xy 182.47315 -390.327731)
			(xy 182.488502 -390.380035) (xy 182.496254 -390.433991) (xy 182.496714 -390.461246) (xy 182.496193 -390.489862)
			(xy 182.487637 -390.546451) (xy 182.470724 -390.601128) (xy 182.445833 -390.652664) (xy 182.413524 -390.699904)
			(xy 182.37452 -390.741788) (xy 182.329698 -390.777376) (xy 182.280063 -390.80587) (xy 182.226728 -390.826629)
			(xy 182.170891 -390.839189) (xy 182.142384 -390.841738) (xy 182.132986 -390.8425) (xy 182.116222 -390.850374)
			(xy 182.05577 -390.913112) (xy 182.048404 -390.93013) (xy 182.04815 -390.939782) (xy 182.046711 -390.967728)
			(xy 182.0367 -391.022783) (xy 182.018753 -391.075784) (xy 181.993255 -391.125594) (xy 181.960753 -391.171144)
			(xy 181.921945 -391.211457) (xy 181.877664 -391.245668) (xy 181.82886 -391.273043) (xy 181.77658 -391.292993)
			(xy 181.721947 -391.305091) (xy 181.694074 -391.307574) (xy 181.684676 -391.308336) (xy 181.667912 -391.31621)
			(xy 181.60746 -391.378948) (xy 181.600094 -391.395966) (xy 181.59984 -391.405618) (xy 181.59849 -391.432261)
			(xy 181.589313 -391.484812) (xy 181.572903 -391.535572) (xy 181.549581 -391.583549) (xy 181.519801 -391.62781)
			(xy 181.484144 -391.667488) (xy 181.443306 -391.701812) (xy 181.398084 -391.73011) (xy 181.34936 -391.75183)
			(xy 181.298085 -391.76655) (xy 181.245259 -391.773981) (xy 181.218586 -391.774426) (xy 181.191335 -391.773935)
			(xy 181.137389 -391.766177) (xy 181.085095 -391.750821) (xy 181.035519 -391.72818) (xy 180.98967 -391.698714)
			(xy 180.94848 -391.663023) (xy 180.912789 -391.621834) (xy 180.883322 -391.575985) (xy 180.86068 -391.526409)
			(xy 180.845324 -391.474115) (xy 180.837565 -391.420169) (xy 180.837078 -391.392918) (xy 179.899614 -391.392918)
			(xy 179.926606 -391.435286) (xy 179.948945 -391.484588) (xy 179.964092 -391.536553) (xy 179.971742 -391.590136)
			(xy 179.972208 -391.6172) (xy 179.971722 -391.644451) (xy 179.963966 -391.698399) (xy 179.948611 -391.750694)
			(xy 179.925969 -391.800271) (xy 179.896503 -391.846121) (xy 179.860812 -391.887312) (xy 179.819621 -391.923003)
			(xy 179.773771 -391.952469) (xy 179.724194 -391.975111) (xy 179.671899 -391.990466) (xy 179.617951 -391.998222)
			(xy 179.563449 -391.998222) (xy 179.509501 -391.990466) (xy 179.457206 -391.975111) (xy 179.407629 -391.952469)
			(xy 179.361779 -391.923003) (xy 179.320588 -391.887312) (xy 179.284897 -391.846121) (xy 179.255431 -391.800271)
			(xy 179.232789 -391.750694) (xy 179.217434 -391.698399) (xy 179.209678 -391.644451) (xy 179.209192 -391.6172)
			(xy 179.209664 -391.590136) (xy 179.217313 -391.536552) (xy 179.232456 -391.484586) (xy 179.25479 -391.435282)
			(xy 179.283867 -391.389628) (xy 179.30114 -391.368788) (xy 179.311046 -391.357358) (xy 179.31511 -391.328148)
			(xy 179.270152 -391.230612) (xy 179.265705 -391.222051) (xy 179.251704 -391.2088) (xy 179.233814 -391.20162)
			(xy 179.224178 -391.201148) (xy 179.109116 -391.201148) (xy 179.099156 -391.201639) (xy 179.080741 -391.209236)
			(xy 179.073302 -391.21588) (xy 177.833782 -392.4554) (xy 178.253642 -392.4554) (xy 178.257713 -392.399778)
			(xy 178.269839 -392.345341) (xy 178.289762 -392.29325) (xy 178.317058 -392.244615) (xy 178.351144 -392.200472)
			(xy 178.391293 -392.161763) (xy 178.436651 -392.129312) (xy 178.486251 -392.103811) (xy 178.539035 -392.085804)
			(xy 178.593878 -392.075674) (xy 178.649612 -392.073637) (xy 178.705049 -392.079737) (xy 178.759006 -392.093843)
			(xy 178.810335 -392.115655) (xy 178.857941 -392.144709) (xy 178.900809 -392.180384) (xy 178.938026 -392.221921)
			(xy 178.968799 -392.268434) (xy 178.992471 -392.318931) (xy 179.008539 -392.372338) (xy 179.016659 -392.427514)
			(xy 179.017168 -392.4554) (xy 179.016659 -392.483286) (xy 179.008539 -392.538462) (xy 178.992471 -392.591869)
			(xy 178.968799 -392.642366) (xy 178.938026 -392.688879) (xy 178.900809 -392.730416) (xy 178.857941 -392.766091)
			(xy 178.810335 -392.795145) (xy 178.759006 -392.816957) (xy 178.705049 -392.831063) (xy 178.649612 -392.837163)
			(xy 178.593878 -392.835126) (xy 178.539035 -392.824996) (xy 178.486251 -392.806989) (xy 178.436651 -392.781488)
			(xy 178.391293 -392.749037) (xy 178.351144 -392.710328) (xy 178.317058 -392.666185) (xy 178.289762 -392.61755)
			(xy 178.269839 -392.565459) (xy 178.257713 -392.511022) (xy 178.253642 -392.4554) (xy 177.833782 -392.4554)
			(xy 177.08626 -393.202922) (xy 177.079584 -393.210335) (xy 177.072016 -393.22877) (xy 177.071528 -393.238736)
			(xy 177.071528 -393.2936) (xy 179.208682 -393.2936) (xy 179.212753 -393.237978) (xy 179.224879 -393.183541)
			(xy 179.244802 -393.13145) (xy 179.272098 -393.082815) (xy 179.306184 -393.038672) (xy 179.346333 -392.999963)
			(xy 179.391691 -392.967512) (xy 179.441291 -392.942011) (xy 179.494075 -392.924004) (xy 179.548918 -392.913874)
			(xy 179.604652 -392.911837) (xy 179.660089 -392.917937) (xy 179.714046 -392.932043) (xy 179.765375 -392.953855)
			(xy 179.812981 -392.982909) (xy 179.855849 -393.018584) (xy 179.893066 -393.060121) (xy 179.923839 -393.106634)
			(xy 179.947511 -393.157131) (xy 179.963579 -393.210538) (xy 179.971699 -393.265714) (xy 179.972208 -393.2936)
			(xy 179.971699 -393.321486) (xy 179.963579 -393.376662) (xy 179.947511 -393.430069) (xy 179.923839 -393.480566)
			(xy 179.893066 -393.527079) (xy 179.855849 -393.568616) (xy 179.812981 -393.604291) (xy 179.765375 -393.633345)
			(xy 179.714046 -393.655157) (xy 179.660089 -393.669263) (xy 179.604652 -393.675363) (xy 179.548918 -393.673326)
			(xy 179.494075 -393.663196) (xy 179.441291 -393.645189) (xy 179.391691 -393.619688) (xy 179.346333 -393.587237)
			(xy 179.306184 -393.548528) (xy 179.272098 -393.504385) (xy 179.244802 -393.45575) (xy 179.224879 -393.403659)
			(xy 179.212753 -393.349222) (xy 179.208682 -393.2936) (xy 177.071528 -393.2936) (xy 177.071528 -394.159049)
			(xy 178.254678 -394.159049) (xy 178.254678 -394.104551) (xy 178.262433 -394.050606) (xy 178.277786 -393.998315)
			(xy 178.300424 -393.94874) (xy 178.329887 -393.902892) (xy 178.365574 -393.861703) (xy 178.40676 -393.826011)
			(xy 178.452605 -393.796544) (xy 178.502177 -393.7739) (xy 178.554467 -393.758542) (xy 178.608411 -393.750781)
			(xy 178.63566 -393.750292) (xy 178.662971 -393.750762) (xy 178.717034 -393.758553) (xy 178.769432 -393.77398)
			(xy 178.819092 -393.796728) (xy 178.864996 -393.826331) (xy 178.906205 -393.862183) (xy 178.941875 -393.903549)
			(xy 178.95697 -393.926314) (xy 178.963066 -393.935712) (xy 178.981862 -393.94765) (xy 179.08143 -393.960858)
			(xy 179.102512 -393.954254) (xy 179.110894 -393.946634) (xy 179.132057 -393.928015) (xy 179.178884 -393.896638)
			(xy 179.229817 -393.872491) (xy 179.283748 -393.856099) (xy 179.339504 -393.847819) (xy 179.367688 -393.84732)
			(xy 179.394943 -393.847726) (xy 179.4489 -393.855482) (xy 179.501203 -393.870838) (xy 179.550788 -393.893482)
			(xy 179.596646 -393.922952) (xy 179.637843 -393.958648) (xy 179.673541 -393.999844) (xy 179.703012 -394.045701)
			(xy 179.725657 -394.095286) (xy 179.741015 -394.147589) (xy 179.748773 -394.201545) (xy 179.748773 -394.256055)
			(xy 179.741015 -394.310011) (xy 179.725657 -394.362314) (xy 179.703012 -394.411899) (xy 179.673541 -394.457756)
			(xy 179.637843 -394.498952) (xy 179.596646 -394.534648) (xy 179.550788 -394.564118) (xy 179.501203 -394.586762)
			(xy 179.4489 -394.602118) (xy 179.394943 -394.609874) (xy 179.367688 -394.610336) (xy 179.340376 -394.609893)
			(xy 179.286312 -394.602096) (xy 179.233914 -394.586663) (xy 179.184255 -394.56391) (xy 179.138352 -394.534303)
			(xy 179.097143 -394.498449) (xy 179.061473 -394.45708) (xy 179.046378 -394.434314) (xy 179.040282 -394.424916)
			(xy 179.021486 -394.412978) (xy 178.921918 -394.39977) (xy 178.900836 -394.406374) (xy 178.892454 -394.413994)
			(xy 178.871262 -394.432578) (xy 178.824444 -394.463963) (xy 178.773519 -394.488118) (xy 178.719593 -394.504518)
			(xy 178.663842 -394.512805) (xy 178.63566 -394.513308) (xy 178.608411 -394.512819) (xy 178.554467 -394.505058)
			(xy 178.502177 -394.4897) (xy 178.452605 -394.467056) (xy 178.40676 -394.437589) (xy 178.365574 -394.401897)
			(xy 178.329887 -394.360708) (xy 178.300424 -394.31486) (xy 178.277786 -394.265285) (xy 178.262433 -394.212994)
			(xy 178.254678 -394.159049) (xy 177.071528 -394.159049) (xy 177.071528 -395.986) (xy 177.290982 -395.986)
			(xy 177.295053 -395.930378) (xy 177.307179 -395.875941) (xy 177.327102 -395.82385) (xy 177.354398 -395.775215)
			(xy 177.388484 -395.731072) (xy 177.428633 -395.692363) (xy 177.473991 -395.659912) (xy 177.523591 -395.634411)
			(xy 177.576375 -395.616404) (xy 177.631218 -395.606274) (xy 177.686952 -395.604237) (xy 177.742389 -395.610337)
			(xy 177.796346 -395.624443) (xy 177.847675 -395.646255) (xy 177.895281 -395.675309) (xy 177.938149 -395.710984)
			(xy 177.975366 -395.752521) (xy 178.006139 -395.799034) (xy 178.029811 -395.849531) (xy 178.045879 -395.902938)
			(xy 178.053999 -395.958114) (xy 178.054508 -395.986) (xy 178.053999 -396.013886) (xy 178.045879 -396.069062)
			(xy 178.029811 -396.122469) (xy 178.006139 -396.172966) (xy 177.975366 -396.219479) (xy 177.938149 -396.261016)
			(xy 177.895281 -396.296691) (xy 177.847675 -396.325745) (xy 177.796346 -396.347557) (xy 177.742389 -396.361663)
			(xy 177.693886 -396.367) (xy 179.576982 -396.367) (xy 179.581053 -396.311378) (xy 179.593179 -396.256941)
			(xy 179.613102 -396.20485) (xy 179.640398 -396.156215) (xy 179.674484 -396.112072) (xy 179.714633 -396.073363)
			(xy 179.759991 -396.040912) (xy 179.809591 -396.015411) (xy 179.862375 -395.997404) (xy 179.917218 -395.987274)
			(xy 179.972952 -395.985237) (xy 180.028389 -395.991337) (xy 180.082346 -396.005443) (xy 180.133675 -396.027255)
			(xy 180.181281 -396.056309) (xy 180.224149 -396.091984) (xy 180.261366 -396.133521) (xy 180.292139 -396.180034)
			(xy 180.315811 -396.230531) (xy 180.331879 -396.283938) (xy 180.339999 -396.339114) (xy 180.340508 -396.367)
			(xy 180.339999 -396.394886) (xy 180.331879 -396.450062) (xy 180.315811 -396.503469) (xy 180.292139 -396.553966)
			(xy 180.261366 -396.600479) (xy 180.224149 -396.642016) (xy 180.181281 -396.677691) (xy 180.133675 -396.706745)
			(xy 180.082346 -396.728557) (xy 180.028389 -396.742663) (xy 179.972952 -396.748763) (xy 179.917218 -396.746726)
			(xy 179.862375 -396.736596) (xy 179.809591 -396.718589) (xy 179.759991 -396.693088) (xy 179.714633 -396.660637)
			(xy 179.674484 -396.621928) (xy 179.640398 -396.577785) (xy 179.613102 -396.52915) (xy 179.593179 -396.477059)
			(xy 179.581053 -396.422622) (xy 179.576982 -396.367) (xy 177.693886 -396.367) (xy 177.686952 -396.367763)
			(xy 177.631218 -396.365726) (xy 177.576375 -396.355596) (xy 177.523591 -396.337589) (xy 177.473991 -396.312088)
			(xy 177.428633 -396.279637) (xy 177.388484 -396.240928) (xy 177.354398 -396.196785) (xy 177.327102 -396.14815)
			(xy 177.307179 -396.096059) (xy 177.295053 -396.041622) (xy 177.290982 -395.986) (xy 177.071528 -395.986)
			(xy 177.071528 -399.420842) (xy 179.602382 -399.420842) (xy 179.606453 -399.36522) (xy 179.618579 -399.310783)
			(xy 179.638502 -399.258692) (xy 179.665798 -399.210057) (xy 179.699884 -399.165914) (xy 179.740033 -399.127205)
			(xy 179.785391 -399.094754) (xy 179.834991 -399.069253) (xy 179.887775 -399.051246) (xy 179.942618 -399.041116)
			(xy 179.998352 -399.039079) (xy 180.053789 -399.045179) (xy 180.107746 -399.059285) (xy 180.159075 -399.081097)
			(xy 180.206681 -399.110151) (xy 180.249549 -399.145826) (xy 180.286766 -399.187363) (xy 180.317539 -399.233876)
			(xy 180.341211 -399.284373) (xy 180.357279 -399.33778) (xy 180.365399 -399.392956) (xy 180.365908 -399.420842)
			(xy 180.365399 -399.448728) (xy 180.357279 -399.503904) (xy 180.341211 -399.557311) (xy 180.317539 -399.607808)
			(xy 180.286766 -399.654321) (xy 180.249549 -399.695858) (xy 180.206681 -399.731533) (xy 180.159075 -399.760587)
			(xy 180.107746 -399.782399) (xy 180.053789 -399.796505) (xy 179.998352 -399.802605) (xy 179.942618 -399.800568)
			(xy 179.887775 -399.790438) (xy 179.834991 -399.772431) (xy 179.785391 -399.74693) (xy 179.740033 -399.714479)
			(xy 179.699884 -399.67577) (xy 179.665798 -399.631627) (xy 179.638502 -399.582992) (xy 179.618579 -399.530901)
			(xy 179.606453 -399.476464) (xy 179.602382 -399.420842) (xy 177.071528 -399.420842) (xy 177.071528 -400.436842)
			(xy 180.097682 -400.436842) (xy 180.101753 -400.38122) (xy 180.113879 -400.326783) (xy 180.133802 -400.274692)
			(xy 180.161098 -400.226057) (xy 180.195184 -400.181914) (xy 180.235333 -400.143205) (xy 180.280691 -400.110754)
			(xy 180.330291 -400.085253) (xy 180.383075 -400.067246) (xy 180.437918 -400.057116) (xy 180.493652 -400.055079)
			(xy 180.549089 -400.061179) (xy 180.603046 -400.075285) (xy 180.654375 -400.097097) (xy 180.701981 -400.126151)
			(xy 180.744849 -400.161826) (xy 180.782066 -400.203363) (xy 180.812839 -400.249876) (xy 180.836511 -400.300373)
			(xy 180.852579 -400.35378) (xy 180.860699 -400.408956) (xy 180.861208 -400.436842) (xy 180.860699 -400.464728)
			(xy 180.852579 -400.519904) (xy 180.836511 -400.573311) (xy 180.812839 -400.623808) (xy 180.782066 -400.670321)
			(xy 180.744849 -400.711858) (xy 180.701981 -400.747533) (xy 180.654375 -400.776587) (xy 180.603046 -400.798399)
			(xy 180.549089 -400.812505) (xy 180.493652 -400.818605) (xy 180.437918 -400.816568) (xy 180.383075 -400.806438)
			(xy 180.330291 -400.788431) (xy 180.280691 -400.76293) (xy 180.235333 -400.730479) (xy 180.195184 -400.69177)
			(xy 180.161098 -400.647627) (xy 180.133802 -400.598992) (xy 180.113879 -400.546901) (xy 180.101753 -400.492464)
			(xy 180.097682 -400.436842) (xy 177.071528 -400.436842) (xy 177.071528 -401.452842) (xy 177.318922 -401.452842)
			(xy 177.322993 -401.39722) (xy 177.335119 -401.342783) (xy 177.355042 -401.290692) (xy 177.382338 -401.242057)
			(xy 177.416424 -401.197914) (xy 177.456573 -401.159205) (xy 177.501931 -401.126754) (xy 177.551531 -401.101253)
			(xy 177.604315 -401.083246) (xy 177.659158 -401.073116) (xy 177.714892 -401.071079) (xy 177.759051 -401.075938)
			(xy 182.489605 -401.075938) (xy 182.489607 -401.021441) (xy 182.497364 -400.967498) (xy 182.512719 -400.915208)
			(xy 182.535359 -400.865636) (xy 182.564824 -400.81979) (xy 182.600513 -400.778604) (xy 182.6417 -400.742916)
			(xy 182.687547 -400.713453) (xy 182.73712 -400.690815) (xy 182.78941 -400.675461) (xy 182.843353 -400.667706)
			(xy 182.870602 -400.66722) (xy 182.890922 -400.667728) (xy 182.901844 -400.668236) (xy 182.921656 -400.660616)
			(xy 182.99049 -400.591782) (xy 182.99811 -400.57197) (xy 182.997602 -400.561048) (xy 182.997094 -400.540728)
			(xy 182.99758 -400.513477) (xy 183.005336 -400.459529) (xy 183.020691 -400.407234) (xy 183.043333 -400.357657)
			(xy 183.072799 -400.311807) (xy 183.10849 -400.270616) (xy 183.149681 -400.234925) (xy 183.195531 -400.205459)
			(xy 183.245108 -400.182817) (xy 183.297403 -400.167462) (xy 183.351351 -400.159706) (xy 183.405853 -400.159706)
			(xy 183.459801 -400.167462) (xy 183.512096 -400.182817) (xy 183.561673 -400.205459) (xy 183.607523 -400.234925)
			(xy 183.648714 -400.270616) (xy 183.684405 -400.311807) (xy 183.713871 -400.357657) (xy 183.736513 -400.407234)
			(xy 183.751868 -400.459529) (xy 183.759624 -400.513477) (xy 183.76011 -400.540728) (xy 183.759602 -400.561048)
			(xy 183.759094 -400.57197) (xy 183.766714 -400.591782) (xy 183.791606 -400.616674) (xy 184.474102 -400.616674)
			(xy 184.478173 -400.561052) (xy 184.490299 -400.506615) (xy 184.510222 -400.454524) (xy 184.537518 -400.405889)
			(xy 184.571604 -400.361746) (xy 184.611753 -400.323037) (xy 184.657111 -400.290586) (xy 184.706711 -400.265085)
			(xy 184.759495 -400.247078) (xy 184.814338 -400.236948) (xy 184.870072 -400.234911) (xy 184.925509 -400.241011)
			(xy 184.979466 -400.255117) (xy 185.030795 -400.276929) (xy 185.078401 -400.305983) (xy 185.121269 -400.341658)
			(xy 185.158486 -400.383195) (xy 185.189259 -400.429708) (xy 185.212931 -400.480205) (xy 185.228999 -400.533612)
			(xy 185.237119 -400.588788) (xy 185.237628 -400.616674) (xy 185.896502 -400.616674) (xy 185.900573 -400.561052)
			(xy 185.912699 -400.506615) (xy 185.932622 -400.454524) (xy 185.959918 -400.405889) (xy 185.994004 -400.361746)
			(xy 186.034153 -400.323037) (xy 186.079511 -400.290586) (xy 186.129111 -400.265085) (xy 186.181895 -400.247078)
			(xy 186.236738 -400.236948) (xy 186.292472 -400.234911) (xy 186.347909 -400.241011) (xy 186.401866 -400.255117)
			(xy 186.453195 -400.276929) (xy 186.500801 -400.305983) (xy 186.543669 -400.341658) (xy 186.580886 -400.383195)
			(xy 186.611659 -400.429708) (xy 186.635331 -400.480205) (xy 186.651399 -400.533612) (xy 186.659519 -400.588788)
			(xy 186.660028 -400.616674) (xy 187.293502 -400.616674) (xy 187.297573 -400.561052) (xy 187.309699 -400.506615)
			(xy 187.329622 -400.454524) (xy 187.356918 -400.405889) (xy 187.391004 -400.361746) (xy 187.431153 -400.323037)
			(xy 187.476511 -400.290586) (xy 187.526111 -400.265085) (xy 187.578895 -400.247078) (xy 187.633738 -400.236948)
			(xy 187.689472 -400.234911) (xy 187.744909 -400.241011) (xy 187.798866 -400.255117) (xy 187.850195 -400.276929)
			(xy 187.897801 -400.305983) (xy 187.940669 -400.341658) (xy 187.977886 -400.383195) (xy 188.008659 -400.429708)
			(xy 188.032331 -400.480205) (xy 188.048399 -400.533612) (xy 188.056519 -400.588788) (xy 188.057028 -400.616674)
			(xy 188.056519 -400.64456) (xy 188.048399 -400.699736) (xy 188.032331 -400.753143) (xy 188.008659 -400.80364)
			(xy 187.977886 -400.850153) (xy 187.940669 -400.89169) (xy 187.897801 -400.927365) (xy 187.850195 -400.956419)
			(xy 187.798866 -400.978231) (xy 187.744909 -400.992337) (xy 187.689472 -400.998437) (xy 187.633738 -400.9964)
			(xy 187.578895 -400.98627) (xy 187.526111 -400.968263) (xy 187.476511 -400.942762) (xy 187.431153 -400.910311)
			(xy 187.391004 -400.871602) (xy 187.356918 -400.827459) (xy 187.329622 -400.778824) (xy 187.309699 -400.726733)
			(xy 187.297573 -400.672296) (xy 187.293502 -400.616674) (xy 186.660028 -400.616674) (xy 186.659519 -400.64456)
			(xy 186.651399 -400.699736) (xy 186.635331 -400.753143) (xy 186.611659 -400.80364) (xy 186.580886 -400.850153)
			(xy 186.543669 -400.89169) (xy 186.500801 -400.927365) (xy 186.453195 -400.956419) (xy 186.401866 -400.978231)
			(xy 186.347909 -400.992337) (xy 186.292472 -400.998437) (xy 186.236738 -400.9964) (xy 186.181895 -400.98627)
			(xy 186.129111 -400.968263) (xy 186.079511 -400.942762) (xy 186.034153 -400.910311) (xy 185.994004 -400.871602)
			(xy 185.959918 -400.827459) (xy 185.932622 -400.778824) (xy 185.912699 -400.726733) (xy 185.900573 -400.672296)
			(xy 185.896502 -400.616674) (xy 185.237628 -400.616674) (xy 185.237119 -400.64456) (xy 185.228999 -400.699736)
			(xy 185.212931 -400.753143) (xy 185.189259 -400.80364) (xy 185.158486 -400.850153) (xy 185.121269 -400.89169)
			(xy 185.078401 -400.927365) (xy 185.030795 -400.956419) (xy 184.979466 -400.978231) (xy 184.925509 -400.992337)
			(xy 184.870072 -400.998437) (xy 184.814338 -400.9964) (xy 184.759495 -400.98627) (xy 184.706711 -400.968263)
			(xy 184.657111 -400.942762) (xy 184.611753 -400.910311) (xy 184.571604 -400.871602) (xy 184.537518 -400.827459)
			(xy 184.510222 -400.778824) (xy 184.490299 -400.726733) (xy 184.478173 -400.672296) (xy 184.474102 -400.616674)
			(xy 183.791606 -400.616674) (xy 183.835548 -400.660616) (xy 183.85536 -400.668236) (xy 183.866282 -400.667728)
			(xy 183.886602 -400.66722) (xy 183.913853 -400.66768) (xy 183.967799 -400.675436) (xy 184.020093 -400.690791)
			(xy 184.069669 -400.713432) (xy 184.115518 -400.742897) (xy 184.156708 -400.778588) (xy 184.192399 -400.819777)
			(xy 184.221865 -400.865626) (xy 184.244507 -400.915202) (xy 184.259862 -400.967495) (xy 184.26762 -401.021441)
			(xy 184.267621 -401.075943) (xy 184.259866 -401.129889) (xy 184.244512 -401.182183) (xy 184.221873 -401.23176)
			(xy 184.192409 -401.27761) (xy 184.156719 -401.318801) (xy 184.115531 -401.354493) (xy 184.069683 -401.383961)
			(xy 184.020108 -401.406603) (xy 183.967815 -401.42196) (xy 183.913869 -401.429719) (xy 183.859367 -401.429722)
			(xy 183.80542 -401.421968) (xy 183.753126 -401.406616) (xy 183.703549 -401.383978) (xy 183.657698 -401.354515)
			(xy 183.616506 -401.318826) (xy 183.580813 -401.277639) (xy 183.551344 -401.231792) (xy 183.5287 -401.182217)
			(xy 183.513342 -401.129925) (xy 183.505582 -401.075979) (xy 183.505094 -401.048728) (xy 183.505602 -401.028408)
			(xy 183.50611 -401.017486) (xy 183.49849 -400.997674) (xy 183.429656 -400.92884) (xy 183.409844 -400.92122)
			(xy 183.398922 -400.921728) (xy 183.378602 -400.922236) (xy 183.358282 -400.921728) (xy 183.34736 -400.92122)
			(xy 183.327548 -400.92884) (xy 183.258714 -400.997674) (xy 183.251094 -401.017486) (xy 183.251602 -401.028408)
			(xy 183.25211 -401.048728) (xy 183.251592 -401.075977) (xy 183.243832 -401.129919) (xy 183.228475 -401.182208)
			(xy 183.205832 -401.231779) (xy 183.176366 -401.277624) (xy 183.140675 -401.318808) (xy 183.099486 -401.354494)
			(xy 183.053638 -401.383955) (xy 183.004064 -401.406591) (xy 182.951773 -401.421942) (xy 182.89783 -401.429695)
			(xy 182.843332 -401.429692) (xy 182.789389 -401.421934) (xy 182.7371 -401.406578) (xy 182.687528 -401.383936)
			(xy 182.641683 -401.354471) (xy 182.600498 -401.318781) (xy 182.564811 -401.277593) (xy 182.535349 -401.231746)
			(xy 182.512712 -401.182172) (xy 182.49736 -401.129881) (xy 182.489605 -401.075938) (xy 177.759051 -401.075938)
			(xy 177.770329 -401.077179) (xy 177.824286 -401.091285) (xy 177.875615 -401.113097) (xy 177.923221 -401.142151)
			(xy 177.966089 -401.177826) (xy 178.003306 -401.219363) (xy 178.034079 -401.265876) (xy 178.057751 -401.316373)
			(xy 178.073819 -401.36978) (xy 178.081939 -401.424956) (xy 178.082448 -401.452842) (xy 178.081939 -401.480728)
			(xy 178.073819 -401.535904) (xy 178.057751 -401.589311) (xy 178.034079 -401.639808) (xy 178.003306 -401.686321)
			(xy 177.966089 -401.727858) (xy 177.942508 -401.747482) (xy 179.978302 -401.747482) (xy 179.982373 -401.69186)
			(xy 179.994499 -401.637423) (xy 180.014422 -401.585332) (xy 180.041718 -401.536697) (xy 180.075804 -401.492554)
			(xy 180.115953 -401.453845) (xy 180.161311 -401.421394) (xy 180.210911 -401.395893) (xy 180.263695 -401.377886)
			(xy 180.318538 -401.367756) (xy 180.374272 -401.365719) (xy 180.429709 -401.371819) (xy 180.483666 -401.385925)
			(xy 180.534995 -401.407737) (xy 180.582601 -401.436791) (xy 180.625469 -401.472466) (xy 180.662686 -401.514003)
			(xy 180.693459 -401.560516) (xy 180.717131 -401.611013) (xy 180.733199 -401.66442) (xy 180.741319 -401.719596)
			(xy 180.741828 -401.747482) (xy 180.741319 -401.775368) (xy 180.733199 -401.830544) (xy 180.717131 -401.883951)
			(xy 180.700375 -401.919694) (xy 184.474102 -401.919694) (xy 184.478173 -401.864072) (xy 184.490299 -401.809635)
			(xy 184.510222 -401.757544) (xy 184.537518 -401.708909) (xy 184.571604 -401.664766) (xy 184.611753 -401.626057)
			(xy 184.657111 -401.593606) (xy 184.706711 -401.568105) (xy 184.759495 -401.550098) (xy 184.814338 -401.539968)
			(xy 184.870072 -401.537931) (xy 184.925509 -401.544031) (xy 184.979466 -401.558137) (xy 185.030795 -401.579949)
			(xy 185.078401 -401.609003) (xy 185.121269 -401.644678) (xy 185.158486 -401.686215) (xy 185.189259 -401.732728)
			(xy 185.212931 -401.783225) (xy 185.228999 -401.836632) (xy 185.237119 -401.891808) (xy 185.237628 -401.919694)
			(xy 187.293502 -401.919694) (xy 187.297573 -401.864072) (xy 187.309699 -401.809635) (xy 187.329622 -401.757544)
			(xy 187.356918 -401.708909) (xy 187.391004 -401.664766) (xy 187.431153 -401.626057) (xy 187.476511 -401.593606)
			(xy 187.526111 -401.568105) (xy 187.578895 -401.550098) (xy 187.633738 -401.539968) (xy 187.689472 -401.537931)
			(xy 187.744909 -401.544031) (xy 187.798866 -401.558137) (xy 187.850195 -401.579949) (xy 187.897801 -401.609003)
			(xy 187.940669 -401.644678) (xy 187.977886 -401.686215) (xy 188.008659 -401.732728) (xy 188.032331 -401.783225)
			(xy 188.048399 -401.836632) (xy 188.056519 -401.891808) (xy 188.057028 -401.919694) (xy 188.056519 -401.94758)
			(xy 188.048399 -402.002756) (xy 188.032331 -402.056163) (xy 188.008659 -402.10666) (xy 187.977886 -402.153173)
			(xy 187.940669 -402.19471) (xy 187.897801 -402.230385) (xy 187.850195 -402.259439) (xy 187.798866 -402.281251)
			(xy 187.744909 -402.295357) (xy 187.689472 -402.301457) (xy 187.633738 -402.29942) (xy 187.578895 -402.28929)
			(xy 187.526111 -402.271283) (xy 187.476511 -402.245782) (xy 187.431153 -402.213331) (xy 187.391004 -402.174622)
			(xy 187.356918 -402.130479) (xy 187.329622 -402.081844) (xy 187.309699 -402.029753) (xy 187.297573 -401.975316)
			(xy 187.293502 -401.919694) (xy 185.237628 -401.919694) (xy 185.237119 -401.94758) (xy 185.228999 -402.002756)
			(xy 185.212931 -402.056163) (xy 185.189259 -402.10666) (xy 185.158486 -402.153173) (xy 185.121269 -402.19471)
			(xy 185.078401 -402.230385) (xy 185.030795 -402.259439) (xy 184.979466 -402.281251) (xy 184.925509 -402.295357)
			(xy 184.870072 -402.301457) (xy 184.814338 -402.29942) (xy 184.759495 -402.28929) (xy 184.706711 -402.271283)
			(xy 184.657111 -402.245782) (xy 184.611753 -402.213331) (xy 184.571604 -402.174622) (xy 184.537518 -402.130479)
			(xy 184.510222 -402.081844) (xy 184.490299 -402.029753) (xy 184.478173 -401.975316) (xy 184.474102 -401.919694)
			(xy 180.700375 -401.919694) (xy 180.693459 -401.934448) (xy 180.662686 -401.980961) (xy 180.625469 -402.022498)
			(xy 180.582601 -402.058173) (xy 180.534995 -402.087227) (xy 180.483666 -402.109039) (xy 180.429709 -402.123145)
			(xy 180.374272 -402.129245) (xy 180.318538 -402.127208) (xy 180.263695 -402.117078) (xy 180.210911 -402.099071)
			(xy 180.161311 -402.07357) (xy 180.115953 -402.041119) (xy 180.075804 -402.00241) (xy 180.041718 -401.958267)
			(xy 180.014422 -401.909632) (xy 179.994499 -401.857541) (xy 179.982373 -401.803104) (xy 179.978302 -401.747482)
			(xy 177.942508 -401.747482) (xy 177.923221 -401.763533) (xy 177.875615 -401.792587) (xy 177.824286 -401.814399)
			(xy 177.770329 -401.828505) (xy 177.714892 -401.834605) (xy 177.659158 -401.832568) (xy 177.604315 -401.822438)
			(xy 177.551531 -401.804431) (xy 177.501931 -401.77893) (xy 177.456573 -401.746479) (xy 177.416424 -401.70777)
			(xy 177.382338 -401.663627) (xy 177.355042 -401.614992) (xy 177.335119 -401.562901) (xy 177.322993 -401.508464)
			(xy 177.318922 -401.452842) (xy 177.071528 -401.452842) (xy 177.071528 -402.633942) (xy 180.064662 -402.633942)
			(xy 180.068733 -402.57832) (xy 180.080859 -402.523883) (xy 180.100782 -402.471792) (xy 180.128078 -402.423157)
			(xy 180.162164 -402.379014) (xy 180.202313 -402.340305) (xy 180.247671 -402.307854) (xy 180.297271 -402.282353)
			(xy 180.350055 -402.264346) (xy 180.404898 -402.254216) (xy 180.460632 -402.252179) (xy 180.516069 -402.258279)
			(xy 180.570026 -402.272385) (xy 180.621355 -402.294197) (xy 180.668961 -402.323251) (xy 180.711829 -402.358926)
			(xy 180.749046 -402.400463) (xy 180.779819 -402.446976) (xy 180.803491 -402.497473) (xy 180.819559 -402.55088)
			(xy 180.827679 -402.606056) (xy 180.828188 -402.633942) (xy 180.827679 -402.661828) (xy 180.819559 -402.717004)
			(xy 180.803491 -402.770411) (xy 180.779819 -402.820908) (xy 180.749046 -402.867421) (xy 180.711829 -402.908958)
			(xy 180.668961 -402.944633) (xy 180.621355 -402.973687) (xy 180.570026 -402.995499) (xy 180.516069 -403.009605)
			(xy 180.460632 -403.015705) (xy 180.404898 -403.013668) (xy 180.350055 -403.003538) (xy 180.297271 -402.985531)
			(xy 180.247671 -402.96003) (xy 180.202313 -402.927579) (xy 180.162164 -402.88887) (xy 180.128078 -402.844727)
			(xy 180.100782 -402.796092) (xy 180.080859 -402.744001) (xy 180.068733 -402.689564) (xy 180.064662 -402.633942)
			(xy 177.071528 -402.633942) (xy 177.071528 -403.479) (xy 177.291492 -403.479) (xy 177.291978 -403.451749)
			(xy 177.299734 -403.397801) (xy 177.315089 -403.345506) (xy 177.337731 -403.295929) (xy 177.367197 -403.250079)
			(xy 177.402888 -403.208888) (xy 177.444079 -403.173197) (xy 177.489929 -403.143731) (xy 177.539506 -403.121089)
			(xy 177.591801 -403.105734) (xy 177.645749 -403.097978) (xy 177.673 -403.097492) (xy 177.703052 -403.098047)
			(xy 177.762411 -403.107484) (xy 177.819557 -403.126109) (xy 177.873077 -403.153462) (xy 177.921648 -403.188867)
			(xy 177.943256 -403.20976) (xy 177.950672 -403.216433) (xy 177.965948 -403.222714) (xy 184.474102 -403.222714)
			(xy 184.478173 -403.167092) (xy 184.490299 -403.112655) (xy 184.510222 -403.060564) (xy 184.537518 -403.011929)
			(xy 184.571604 -402.967786) (xy 184.611753 -402.929077) (xy 184.657111 -402.896626) (xy 184.706711 -402.871125)
			(xy 184.759495 -402.853118) (xy 184.814338 -402.842988) (xy 184.870072 -402.840951) (xy 184.925509 -402.847051)
			(xy 184.979466 -402.861157) (xy 185.030795 -402.882969) (xy 185.078401 -402.912023) (xy 185.121269 -402.947698)
			(xy 185.158486 -402.989235) (xy 185.189259 -403.035748) (xy 185.212931 -403.086245) (xy 185.228999 -403.139652)
			(xy 185.237119 -403.194828) (xy 185.237628 -403.222714) (xy 185.896502 -403.222714) (xy 185.900573 -403.167092)
			(xy 185.912699 -403.112655) (xy 185.932622 -403.060564) (xy 185.959918 -403.011929) (xy 185.994004 -402.967786)
			(xy 186.034153 -402.929077) (xy 186.079511 -402.896626) (xy 186.129111 -402.871125) (xy 186.181895 -402.853118)
			(xy 186.236738 -402.842988) (xy 186.292472 -402.840951) (xy 186.347909 -402.847051) (xy 186.401866 -402.861157)
			(xy 186.453195 -402.882969) (xy 186.500801 -402.912023) (xy 186.543669 -402.947698) (xy 186.580886 -402.989235)
			(xy 186.611659 -403.035748) (xy 186.635331 -403.086245) (xy 186.651399 -403.139652) (xy 186.659519 -403.194828)
			(xy 186.660028 -403.222714) (xy 187.293502 -403.222714) (xy 187.297573 -403.167092) (xy 187.309699 -403.112655)
			(xy 187.329622 -403.060564) (xy 187.356918 -403.011929) (xy 187.391004 -402.967786) (xy 187.431153 -402.929077)
			(xy 187.476511 -402.896626) (xy 187.526111 -402.871125) (xy 187.578895 -402.853118) (xy 187.633738 -402.842988)
			(xy 187.689472 -402.840951) (xy 187.744909 -402.847051) (xy 187.798866 -402.861157) (xy 187.850195 -402.882969)
			(xy 187.897801 -402.912023) (xy 187.940669 -402.947698) (xy 187.977886 -402.989235) (xy 188.008659 -403.035748)
			(xy 188.032331 -403.086245) (xy 188.048399 -403.139652) (xy 188.056519 -403.194828) (xy 188.057028 -403.222714)
			(xy 188.056519 -403.2506) (xy 188.048399 -403.305776) (xy 188.032331 -403.359183) (xy 188.008659 -403.40968)
			(xy 187.977886 -403.456193) (xy 187.940669 -403.49773) (xy 187.897801 -403.533405) (xy 187.850195 -403.562459)
			(xy 187.798866 -403.584271) (xy 187.744909 -403.598377) (xy 187.689472 -403.604477) (xy 187.633738 -403.60244)
			(xy 187.578895 -403.59231) (xy 187.526111 -403.574303) (xy 187.476511 -403.548802) (xy 187.431153 -403.516351)
			(xy 187.391004 -403.477642) (xy 187.356918 -403.433499) (xy 187.329622 -403.384864) (xy 187.309699 -403.332773)
			(xy 187.297573 -403.278336) (xy 187.293502 -403.222714) (xy 186.660028 -403.222714) (xy 186.659519 -403.2506)
			(xy 186.651399 -403.305776) (xy 186.635331 -403.359183) (xy 186.611659 -403.40968) (xy 186.580886 -403.456193)
			(xy 186.543669 -403.49773) (xy 186.500801 -403.533405) (xy 186.453195 -403.562459) (xy 186.401866 -403.584271)
			(xy 186.347909 -403.598377) (xy 186.292472 -403.604477) (xy 186.236738 -403.60244) (xy 186.181895 -403.59231)
			(xy 186.129111 -403.574303) (xy 186.079511 -403.548802) (xy 186.034153 -403.516351) (xy 185.994004 -403.477642)
			(xy 185.959918 -403.433499) (xy 185.932622 -403.384864) (xy 185.912699 -403.332773) (xy 185.900573 -403.278336)
			(xy 185.896502 -403.222714) (xy 185.237628 -403.222714) (xy 185.237119 -403.2506) (xy 185.228999 -403.305776)
			(xy 185.212931 -403.359183) (xy 185.189259 -403.40968) (xy 185.158486 -403.456193) (xy 185.121269 -403.49773)
			(xy 185.078401 -403.533405) (xy 185.030795 -403.562459) (xy 184.979466 -403.584271) (xy 184.925509 -403.598377)
			(xy 184.870072 -403.604477) (xy 184.814338 -403.60244) (xy 184.759495 -403.59231) (xy 184.706711 -403.574303)
			(xy 184.657111 -403.548802) (xy 184.611753 -403.516351) (xy 184.571604 -403.477642) (xy 184.537518 -403.433499)
			(xy 184.510222 -403.384864) (xy 184.490299 -403.332773) (xy 184.478173 -403.278336) (xy 184.474102 -403.222714)
			(xy 177.965948 -403.222714) (xy 177.969105 -403.224012) (xy 177.97907 -403.224492) (xy 179.07 -403.224492)
			(xy 179.094997 -403.225108) (xy 179.144022 -403.234915) (xy 179.190193 -403.254095) (xy 179.231738 -403.281909)
			(xy 179.249832 -403.299168) (xy 179.997608 -404.046944) (xy 180.005095 -404.053629) (xy 180.02365 -404.061225)
			(xy 180.033676 -404.061676) (xy 180.036978 -404.061676) (xy 180.046272 -404.061273) (xy 180.063642 -404.054651)
			(xy 180.077532 -404.042297) (xy 180.08219 -404.034244) (xy 180.130196 -403.941534) (xy 180.128418 -403.91334)
			(xy 180.120036 -403.901656) (xy 180.103501 -403.877344) (xy 180.077303 -403.824709) (xy 180.059487 -403.76868)
			(xy 180.050473 -403.710581) (xy 180.049932 -403.681184) (xy 180.050418 -403.653933) (xy 180.058174 -403.599985)
			(xy 180.073529 -403.54769) (xy 180.096171 -403.498113) (xy 180.125637 -403.452263) (xy 180.161328 -403.411072)
			(xy 180.202519 -403.375381) (xy 180.248369 -403.345915) (xy 180.297946 -403.323273) (xy 180.350241 -403.307918)
			(xy 180.404189 -403.300162) (xy 180.458691 -403.300162) (xy 180.512639 -403.307918) (xy 180.564934 -403.323273)
			(xy 180.614511 -403.345915) (xy 180.660361 -403.375381) (xy 180.701552 -403.411072) (xy 180.737243 -403.452263)
			(xy 180.766709 -403.498113) (xy 180.789351 -403.54769) (xy 180.804706 -403.599985) (xy 180.812462 -403.653933)
			(xy 180.812948 -403.681184) (xy 180.812378 -403.71058) (xy 180.803369 -403.768676) (xy 180.785561 -403.824706)
			(xy 180.759375 -403.877343) (xy 180.742844 -403.901656) (xy 180.734462 -403.91334) (xy 180.732684 -403.941534)
			(xy 180.78069 -404.034244) (xy 180.785279 -404.042354) (xy 180.799166 -404.054758) (xy 180.816589 -404.061327)
			(xy 180.825902 -404.061676) (xy 180.900324 -404.061676) (xy 180.910369 -404.0613) (xy 180.928965 -404.053716)
			(xy 180.936392 -404.046944) (xy 181.132988 -403.850348) (xy 181.151102 -403.833113) (xy 181.19264 -403.805296)
			(xy 181.238805 -403.786117) (xy 181.287825 -403.776312) (xy 181.31282 -403.775672) (xy 187.909708 -403.775672)
			(xy 187.919752 -403.775288) (xy 187.938348 -403.767709) (xy 187.945776 -403.76094) (xy 189.227968 -402.478748)
			(xy 189.244685 -402.462734) (xy 189.282777 -402.436436) (xy 189.324993 -402.417452) (xy 189.347348 -402.411438)
			(xy 189.358016 -402.408898) (xy 189.375034 -402.39569) (xy 189.420754 -402.309076) (xy 189.422278 -402.28774)
			(xy 189.418468 -402.27758) (xy 189.40735 -402.245499) (xy 189.395334 -402.178682) (xy 189.394592 -402.144738)
			(xy 189.395093 -402.115164) (xy 189.404217 -402.056724) (xy 189.422252 -402.000393) (xy 189.448765 -401.94752)
			(xy 189.483122 -401.899374) (xy 189.524499 -401.857107) (xy 189.571904 -401.821734) (xy 189.597792 -401.807426)
			(xy 189.610746 -401.800568) (xy 189.625224 -401.776438) (xy 189.6237 -401.657058) (xy 189.608714 -401.633182)
			(xy 189.59576 -401.626578) (xy 189.572285 -401.614407) (xy 189.528663 -401.584522) (xy 189.489588 -401.548896)
			(xy 189.455812 -401.508212) (xy 189.427981 -401.463251) (xy 189.406631 -401.414875) (xy 189.39217 -401.364013)
			(xy 189.384876 -401.311641) (xy 189.384432 -401.285202) (xy 189.384918 -401.257951) (xy 189.392674 -401.204003)
			(xy 189.408029 -401.151708) (xy 189.430671 -401.102131) (xy 189.460137 -401.056281) (xy 189.495828 -401.01509)
			(xy 189.537019 -400.979399) (xy 189.582869 -400.949933) (xy 189.632446 -400.927291) (xy 189.684741 -400.911936)
			(xy 189.738689 -400.90418) (xy 189.793191 -400.90418) (xy 189.847139 -400.911936) (xy 189.899434 -400.927291)
			(xy 189.949011 -400.949933) (xy 189.994861 -400.979399) (xy 190.036052 -401.01509) (xy 190.071743 -401.056281)
			(xy 190.101209 -401.102131) (xy 190.123851 -401.151708) (xy 190.139206 -401.204003) (xy 190.146962 -401.257951)
			(xy 190.147448 -401.285202) (xy 190.146877 -401.314773) (xy 190.145151 -401.325842) (xy 192.061082 -401.325842)
			(xy 192.065153 -401.27022) (xy 192.077279 -401.215783) (xy 192.097202 -401.163692) (xy 192.124498 -401.115057)
			(xy 192.158584 -401.070914) (xy 192.198733 -401.032205) (xy 192.244091 -400.999754) (xy 192.293691 -400.974253)
			(xy 192.346475 -400.956246) (xy 192.401318 -400.946116) (xy 192.457052 -400.944079) (xy 192.512489 -400.950179)
			(xy 192.566446 -400.964285) (xy 192.617775 -400.986097) (xy 192.665381 -401.015151) (xy 192.708249 -401.050826)
			(xy 192.745466 -401.092363) (xy 192.776239 -401.138876) (xy 192.799911 -401.189373) (xy 192.815979 -401.24278)
			(xy 192.824099 -401.297956) (xy 192.824608 -401.325842) (xy 192.824099 -401.353728) (xy 192.815979 -401.408904)
			(xy 192.799911 -401.462311) (xy 192.776239 -401.512808) (xy 192.745466 -401.559321) (xy 192.708249 -401.600858)
			(xy 192.665381 -401.636533) (xy 192.617775 -401.665587) (xy 192.566446 -401.687399) (xy 192.512489 -401.701505)
			(xy 192.457052 -401.707605) (xy 192.401318 -401.705568) (xy 192.346475 -401.695438) (xy 192.293691 -401.677431)
			(xy 192.244091 -401.65193) (xy 192.198733 -401.619479) (xy 192.158584 -401.58077) (xy 192.124498 -401.536627)
			(xy 192.097202 -401.487992) (xy 192.077279 -401.435901) (xy 192.065153 -401.381464) (xy 192.061082 -401.325842)
			(xy 190.145151 -401.325842) (xy 190.137763 -401.373209) (xy 190.119739 -401.429537) (xy 190.093237 -401.482409)
			(xy 190.058891 -401.530556) (xy 190.017525 -401.572825) (xy 189.970131 -401.608203) (xy 189.944248 -401.622514)
			(xy 189.931294 -401.629372) (xy 189.916816 -401.653502) (xy 189.91834 -401.772882) (xy 189.933326 -401.796758)
			(xy 189.94628 -401.803362) (xy 189.973286 -401.817478) (xy 190.022802 -401.85299) (xy 190.066042 -401.895922)
			(xy 190.084456 -401.920202) (xy 190.092075 -401.929584) (xy 190.11354 -401.940604) (xy 190.125604 -401.941284)
			(xy 190.534798 -401.941284) (xy 190.554805 -401.941702) (xy 190.594061 -401.949444) (xy 190.631047 -401.964709)
			(xy 190.664336 -401.986908) (xy 190.678816 -402.00072) (xy 191.402462 -402.72462) (xy 191.409934 -402.731326)
			(xy 191.4285 -402.73891) (xy 191.43853 -402.739352) (xy 192.051178 -402.739352) (xy 192.060684 -402.739028)
			(xy 192.078406 -402.732156) (xy 192.092388 -402.719279) (xy 192.096898 -402.710904) (xy 192.14338 -402.615908)
			(xy 192.140332 -402.587206) (xy 192.131442 -402.575522) (xy 192.116355 -402.55538) (xy 192.091006 -402.511905)
			(xy 192.071597 -402.465473) (xy 192.058465 -402.416892) (xy 192.051839 -402.367005) (xy 192.051432 -402.341842)
			(xy 192.051918 -402.314591) (xy 192.059674 -402.260643) (xy 192.075029 -402.208348) (xy 192.097671 -402.158771)
			(xy 192.127137 -402.112921) (xy 192.162828 -402.07173) (xy 192.204019 -402.036039) (xy 192.249869 -402.006573)
			(xy 192.299446 -401.983931) (xy 192.351741 -401.968576) (xy 192.405689 -401.96082) (xy 192.460191 -401.96082)
			(xy 192.514139 -401.968576) (xy 192.566434 -401.983931) (xy 192.616011 -402.006573) (xy 192.661861 -402.036039)
			(xy 192.703052 -402.07173) (xy 192.738743 -402.112921) (xy 192.768209 -402.158771) (xy 192.790851 -402.208348)
			(xy 192.806206 -402.260643) (xy 192.813962 -402.314591) (xy 192.814448 -402.341842) (xy 192.814094 -402.366375)
			(xy 192.807857 -402.415043) (xy 192.802002 -402.43887) (xy 192.799847 -402.449083) (xy 192.803043 -402.469689)
			(xy 192.814187 -402.487313) (xy 192.831432 -402.499035) (xy 192.85192 -402.502911) (xy 192.8622 -402.5011)
			(xy 192.873351 -402.498722) (xy 192.896011 -402.496178) (xy 192.907412 -402.49602) (xy 194.296538 -402.49602)
			(xy 194.316551 -402.496511) (xy 194.355804 -402.504338) (xy 194.392779 -402.519666) (xy 194.426057 -402.541906)
			(xy 194.440556 -402.55571) (xy 195.487544 -403.602952) (xy 195.495018 -403.609654) (xy 195.513583 -403.617239)
			(xy 195.523612 -403.617684) (xy 196.365622 -403.617684) (xy 196.375671 -403.617286) (xy 196.394228 -403.609569)
			(xy 196.408405 -403.595324) (xy 196.412612 -403.586188) (xy 196.454014 -403.484588) (xy 196.447664 -403.454362)
			(xy 196.436488 -403.44344) (xy 196.427214 -403.434255) (xy 196.409798 -403.414808) (xy 196.40169 -403.404578)
			(xy 196.394832 -403.395688) (xy 196.375528 -403.385782) (xy 196.276468 -403.380448) (xy 196.256148 -403.388322)
			(xy 196.248528 -403.39645) (xy 196.230455 -403.414557) (xy 196.190364 -403.446334) (xy 196.146385 -403.472468)
			(xy 196.099308 -403.49249) (xy 196.049978 -403.506041) (xy 195.999279 -403.512878) (xy 195.9737 -403.51329)
			(xy 195.946447 -403.51284) (xy 195.892497 -403.505083) (xy 195.8402 -403.489727) (xy 195.79062 -403.467085)
			(xy 195.744768 -403.437618) (xy 195.703576 -403.401924) (xy 195.667882 -403.360732) (xy 195.638415 -403.31488)
			(xy 195.615773 -403.2653) (xy 195.600417 -403.213003) (xy 195.59266 -403.159053) (xy 195.59266 -403.104547)
			(xy 195.600417 -403.050597) (xy 195.615773 -402.9983) (xy 195.638415 -402.94872) (xy 195.667882 -402.902868)
			(xy 195.703576 -402.861676) (xy 195.744768 -402.825982) (xy 195.79062 -402.796515) (xy 195.8402 -402.773873)
			(xy 195.892497 -402.758517) (xy 195.946447 -402.75076) (xy 195.9737 -402.750274) (xy 196.002618 -402.750764)
			(xy 196.059792 -402.759495) (xy 196.114993 -402.776757) (xy 196.166955 -402.802154) (xy 196.214488 -402.835103)
			(xy 196.256502 -402.874851) (xy 196.27469 -402.89734) (xy 196.281548 -402.90623) (xy 196.300852 -402.916136)
			(xy 196.399912 -402.92147) (xy 196.420232 -402.913596) (xy 196.427852 -402.905468) (xy 196.445872 -402.887307)
			(xy 196.485977 -402.855538) (xy 196.529967 -402.829413) (xy 196.577054 -402.809401) (xy 196.626393 -402.79586)
			(xy 196.677098 -402.789034) (xy 196.70268 -402.788628) (xy 196.729934 -402.789074) (xy 196.783887 -402.796829)
			(xy 196.836188 -402.812185) (xy 196.88577 -402.834827) (xy 196.931625 -402.864297) (xy 196.972819 -402.899992)
			(xy 197.008513 -402.941188) (xy 197.03798 -402.987044) (xy 197.060621 -403.036627) (xy 197.075974 -403.088928)
			(xy 197.083727 -403.142882) (xy 197.084188 -403.170136) (xy 197.08374 -403.195534) (xy 197.077007 -403.245881)
			(xy 197.063652 -403.294889) (xy 197.04391 -403.341691) (xy 197.018132 -403.385459) (xy 196.986773 -403.425418)
			(xy 196.968872 -403.44344) (xy 196.957696 -403.454362) (xy 196.951346 -403.484588) (xy 196.992748 -403.586188)
			(xy 196.996937 -403.595331) (xy 197.011124 -403.609566) (xy 197.029689 -403.617266) (xy 197.039738 -403.617684)
			(xy 197.73011 -403.617684) (xy 197.739528 -403.617261) (xy 197.757083 -403.610431) (xy 197.770993 -403.59773)
			(xy 197.775576 -403.58949) (xy 197.822312 -403.495002) (xy 197.819518 -403.466046) (xy 197.810882 -403.454616)
			(xy 197.796115 -403.434597) (xy 197.771325 -403.391468) (xy 197.752355 -403.345481) (xy 197.739525 -403.297418)
			(xy 197.733054 -403.248095) (xy 197.73265 -403.223222) (xy 197.733136 -403.195971) (xy 197.740892 -403.142023)
			(xy 197.756247 -403.089728) (xy 197.778889 -403.040151) (xy 197.808355 -402.994301) (xy 197.844046 -402.95311)
			(xy 197.885237 -402.917419) (xy 197.931087 -402.887953) (xy 197.980664 -402.865311) (xy 198.032959 -402.849956)
			(xy 198.086907 -402.8422) (xy 198.141409 -402.8422) (xy 198.195357 -402.849956) (xy 198.247652 -402.865311)
			(xy 198.297229 -402.887953) (xy 198.343079 -402.917419) (xy 198.38427 -402.95311) (xy 198.419961 -402.994301)
			(xy 198.449427 -403.040151) (xy 198.472069 -403.089728) (xy 198.487424 -403.142023) (xy 198.49518 -403.195971)
			(xy 198.495666 -403.223222) (xy 198.495254 -403.248095) (xy 198.488792 -403.29742) (xy 198.475968 -403.345485)
			(xy 198.456999 -403.391473) (xy 198.432209 -403.434603) (xy 198.417434 -403.454616) (xy 198.408798 -403.466046)
			(xy 198.406004 -403.495002) (xy 198.45274 -403.58949) (xy 198.457291 -403.597756) (xy 198.471203 -403.610481)
			(xy 198.488779 -403.617306) (xy 198.498206 -403.617684) (xy 199.15251 -403.617684) (xy 199.161928 -403.617261)
			(xy 199.179483 -403.610431) (xy 199.193393 -403.59773) (xy 199.197976 -403.58949) (xy 199.244712 -403.495002)
			(xy 199.241918 -403.466046) (xy 199.233282 -403.454616) (xy 199.218515 -403.434597) (xy 199.193725 -403.391468)
			(xy 199.174755 -403.345481) (xy 199.161925 -403.297418) (xy 199.155454 -403.248095) (xy 199.15505 -403.223222)
			(xy 199.155536 -403.195971) (xy 199.163292 -403.142023) (xy 199.178647 -403.089728) (xy 199.201289 -403.040151)
			(xy 199.230755 -402.994301) (xy 199.266446 -402.95311) (xy 199.307637 -402.917419) (xy 199.353487 -402.887953)
			(xy 199.403064 -402.865311) (xy 199.455359 -402.849956) (xy 199.509307 -402.8422) (xy 199.563809 -402.8422)
			(xy 199.617757 -402.849956) (xy 199.670052 -402.865311) (xy 199.719629 -402.887953) (xy 199.765479 -402.917419)
			(xy 199.80667 -402.95311) (xy 199.842361 -402.994301) (xy 199.871827 -403.040151) (xy 199.894469 -403.089728)
			(xy 199.909824 -403.142023) (xy 199.91758 -403.195971) (xy 199.918066 -403.223222) (xy 199.917654 -403.248095)
			(xy 199.911192 -403.29742) (xy 199.898368 -403.345485) (xy 199.879399 -403.391473) (xy 199.854609 -403.434603)
			(xy 199.839834 -403.454616) (xy 199.831198 -403.466046) (xy 199.828404 -403.495002) (xy 199.87514 -403.58949)
			(xy 199.879691 -403.597756) (xy 199.893603 -403.610481) (xy 199.911179 -403.617306) (xy 199.920606 -403.617684)
			(xy 200.54951 -403.617684) (xy 200.558928 -403.617261) (xy 200.576483 -403.610431) (xy 200.590393 -403.59773)
			(xy 200.594976 -403.58949) (xy 200.641712 -403.495002) (xy 200.638918 -403.466046) (xy 200.630282 -403.454616)
			(xy 200.615515 -403.434597) (xy 200.590725 -403.391468) (xy 200.571755 -403.345481) (xy 200.558925 -403.297418)
			(xy 200.552454 -403.248095) (xy 200.55205 -403.223222) (xy 200.552536 -403.195971) (xy 200.560292 -403.142023)
			(xy 200.575647 -403.089728) (xy 200.598289 -403.040151) (xy 200.627755 -402.994301) (xy 200.663446 -402.95311)
			(xy 200.704637 -402.917419) (xy 200.750487 -402.887953) (xy 200.800064 -402.865311) (xy 200.852359 -402.849956)
			(xy 200.906307 -402.8422) (xy 200.960809 -402.8422) (xy 201.014757 -402.849956) (xy 201.067052 -402.865311)
			(xy 201.116629 -402.887953) (xy 201.162479 -402.917419) (xy 201.20367 -402.95311) (xy 201.239361 -402.994301)
			(xy 201.268827 -403.040151) (xy 201.291469 -403.089728) (xy 201.306824 -403.142023) (xy 201.31458 -403.195971)
			(xy 201.315066 -403.223222) (xy 201.314654 -403.248095) (xy 201.308192 -403.29742) (xy 201.295368 -403.345485)
			(xy 201.276399 -403.391473) (xy 201.251609 -403.434603) (xy 201.236834 -403.454616) (xy 201.228198 -403.466046)
			(xy 201.225404 -403.495002) (xy 201.27214 -403.58949) (xy 201.276691 -403.597756) (xy 201.290603 -403.610481)
			(xy 201.308179 -403.617306) (xy 201.317606 -403.617684) (xy 201.887328 -403.617684) (xy 201.897373 -403.617308)
			(xy 201.915969 -403.609724) (xy 201.923396 -403.602952) (xy 202.13066 -403.395688) (xy 202.137349 -403.388204)
			(xy 202.144942 -403.369647) (xy 202.145392 -403.35962) (xy 202.145392 -402.519642) (xy 202.144726 -402.507614)
			(xy 202.133864 -402.486149) (xy 202.124564 -402.478494) (xy 202.104065 -402.463049) (xy 202.066991 -402.427555)
			(xy 202.035012 -402.38741) (xy 202.008706 -402.34334) (xy 201.988547 -402.296139) (xy 201.9749 -402.246661)
			(xy 201.968012 -402.195801) (xy 201.967592 -402.170138) (xy 201.968091 -402.142886) (xy 201.975842 -402.088936)
			(xy 201.991194 -402.036639) (xy 202.013832 -401.987059) (xy 202.043296 -401.941206) (xy 202.078986 -401.900013)
			(xy 202.120175 -401.864319) (xy 202.166026 -401.83485) (xy 202.215604 -401.812207) (xy 202.267899 -401.796851)
			(xy 202.321848 -401.789093) (xy 202.3491 -401.78863) (xy 202.380009 -401.789214) (xy 202.44102 -401.799171)
			(xy 202.470512 -401.808442) (xy 202.482704 -401.812506) (xy 202.50785 -401.808188) (xy 202.594972 -401.739608)
			(xy 202.605132 -401.71624) (xy 202.604116 -401.703286) (xy 202.602592 -401.670266) (xy 202.603115 -401.643018)
			(xy 202.610875 -401.589077) (xy 202.626233 -401.536789) (xy 202.648875 -401.487219) (xy 202.678342 -401.441376)
			(xy 202.714033 -401.400193) (xy 202.755221 -401.364508) (xy 202.801069 -401.335048) (xy 202.850642 -401.312413)
			(xy 202.902932 -401.297063) (xy 202.956874 -401.289311) (xy 203.011371 -401.289314) (xy 203.065312 -401.297073)
			(xy 203.117601 -401.312429) (xy 203.167171 -401.33507) (xy 203.213015 -401.364535) (xy 203.254199 -401.400225)
			(xy 203.289885 -401.441412) (xy 203.319346 -401.487259) (xy 203.341983 -401.536831) (xy 203.357335 -401.589121)
			(xy 203.365089 -401.643063) (xy 203.365087 -401.69756) (xy 203.35733 -401.751501) (xy 203.341975 -401.80379)
			(xy 203.319335 -401.853361) (xy 203.289872 -401.899206) (xy 203.254183 -401.940391) (xy 203.212997 -401.976078)
			(xy 203.167151 -402.005541) (xy 203.117579 -402.028179) (xy 203.06529 -402.043532) (xy 203.011348 -402.051288)
			(xy 202.9841 -402.051774) (xy 202.953191 -402.051189) (xy 202.89218 -402.041233) (xy 202.862688 -402.031962)
			(xy 202.850496 -402.027898) (xy 202.82535 -402.032216) (xy 202.738228 -402.100796) (xy 202.728068 -402.124164)
			(xy 202.729084 -402.137118) (xy 202.730608 -402.170138) (xy 202.730484 -402.185058) (xy 202.728197 -402.214811)
			(xy 202.726036 -402.229574) (xy 202.724004 -402.241766) (xy 202.73137 -402.264626) (xy 202.765406 -402.298662)
			(xy 202.772814 -402.305492) (xy 202.791407 -402.313219) (xy 202.801474 -402.313648) (xy 204.151484 -402.313648)
			(xy 204.17149 -402.314085) (xy 204.210744 -402.321823) (xy 204.24773 -402.337082) (xy 204.281021 -402.359275)
			(xy 204.295502 -402.373084) (xy 204.659738 -402.73732) (xy 204.673565 -402.751802) (xy 204.695826 -402.785076)
			(xy 204.711159 -402.822057) (xy 204.718972 -402.861321) (xy 204.719428 -402.881338) (xy 204.719428 -403.170136)
			(xy 206.920082 -403.170136) (xy 206.924153 -403.114514) (xy 206.936279 -403.060077) (xy 206.956202 -403.007986)
			(xy 206.983498 -402.959351) (xy 207.017584 -402.915208) (xy 207.057733 -402.876499) (xy 207.103091 -402.844048)
			(xy 207.152691 -402.818547) (xy 207.205475 -402.80054) (xy 207.260318 -402.79041) (xy 207.316052 -402.788373)
			(xy 207.371489 -402.794473) (xy 207.425446 -402.808579) (xy 207.476775 -402.830391) (xy 207.524381 -402.859445)
			(xy 207.567249 -402.89512) (xy 207.604466 -402.936657) (xy 207.635239 -402.98317) (xy 207.658911 -403.033667)
			(xy 207.674979 -403.087074) (xy 207.683099 -403.14225) (xy 207.683608 -403.170136) (xy 207.683099 -403.198022)
			(xy 207.674979 -403.253198) (xy 207.658911 -403.306605) (xy 207.635239 -403.357102) (xy 207.604466 -403.403615)
			(xy 207.567249 -403.445152) (xy 207.524381 -403.480827) (xy 207.476775 -403.509881) (xy 207.425446 -403.531693)
			(xy 207.371489 -403.545799) (xy 207.316052 -403.551899) (xy 207.260318 -403.549862) (xy 207.205475 -403.539732)
			(xy 207.152691 -403.521725) (xy 207.103091 -403.496224) (xy 207.057733 -403.463773) (xy 207.017584 -403.425064)
			(xy 206.983498 -403.380921) (xy 206.956202 -403.332286) (xy 206.936279 -403.280195) (xy 206.924153 -403.225758)
			(xy 206.920082 -403.170136) (xy 204.719428 -403.170136) (xy 204.719428 -403.652736) (xy 204.719797 -403.662781)
			(xy 204.727386 -403.681378) (xy 204.73416 -403.688804) (xy 205.454504 -404.409148) (xy 205.461992 -404.415832)
			(xy 205.480546 -404.423428) (xy 205.490572 -404.42388) (xy 206.137002 -404.42388) (xy 206.146566 -404.423503)
			(xy 206.164391 -404.416576) (xy 206.178447 -404.403609) (xy 206.182976 -404.395178) (xy 206.22895 -404.29942)
			(xy 206.225648 -404.270464) (xy 206.216504 -404.259034) (xy 206.200753 -404.238666) (xy 206.174291 -404.194498)
			(xy 206.154012 -404.147171) (xy 206.140285 -404.097547) (xy 206.13336 -404.046526) (xy 206.132938 -404.020782)
			(xy 206.133424 -403.993531) (xy 206.14118 -403.939583) (xy 206.156535 -403.887288) (xy 206.179177 -403.837711)
			(xy 206.208643 -403.791861) (xy 206.244334 -403.75067) (xy 206.285525 -403.714979) (xy 206.331375 -403.685513)
			(xy 206.380952 -403.662871) (xy 206.433247 -403.647516) (xy 206.487195 -403.63976) (xy 206.541697 -403.63976)
			(xy 206.595645 -403.647516) (xy 206.64794 -403.662871) (xy 206.697517 -403.685513) (xy 206.743367 -403.714979)
			(xy 206.784558 -403.75067) (xy 206.820249 -403.791861) (xy 206.849715 -403.837711) (xy 206.872357 -403.887288)
			(xy 206.887712 -403.939583) (xy 206.895468 -403.993531) (xy 206.895954 -404.020782) (xy 206.895897 -404.031408)
			(xy 206.894754 -404.052629) (xy 206.893668 -404.0632) (xy 206.89189 -404.079456) (xy 206.907384 -404.10765)
			(xy 207.008476 -404.156164) (xy 207.018111 -404.160322) (xy 207.039062 -404.161163) (xy 207.058597 -404.153546)
			(xy 207.066388 -404.146512) (xy 207.534764 -403.677882) (xy 207.549214 -403.66402) (xy 207.582501 -403.641769)
			(xy 207.619491 -403.626447) (xy 207.658762 -403.618643) (xy 207.678782 -403.618192) (xy 208.398364 -403.618192)
			(xy 208.40783 -403.617794) (xy 208.425502 -403.611017) (xy 208.439517 -403.598295) (xy 208.444084 -403.589998)
			(xy 208.49082 -403.495256) (xy 208.488026 -403.466554) (xy 208.479136 -403.455124) (xy 208.464311 -403.435075)
			(xy 208.439446 -403.391855) (xy 208.420417 -403.345765) (xy 208.407547 -403.297592) (xy 208.401055 -403.248153)
			(xy 208.40065 -403.223222) (xy 208.401136 -403.195971) (xy 208.408892 -403.142023) (xy 208.424247 -403.089728)
			(xy 208.446889 -403.040151) (xy 208.476355 -402.994301) (xy 208.512046 -402.95311) (xy 208.553237 -402.917419)
			(xy 208.599087 -402.887953) (xy 208.648664 -402.865311) (xy 208.700959 -402.849956) (xy 208.754907 -402.8422)
			(xy 208.809409 -402.8422) (xy 208.863357 -402.849956) (xy 208.915652 -402.865311) (xy 208.965229 -402.887953)
			(xy 209.011079 -402.917419) (xy 209.05227 -402.95311) (xy 209.087961 -402.994301) (xy 209.117427 -403.040151)
			(xy 209.140069 -403.089728) (xy 209.155424 -403.142023) (xy 209.16318 -403.195971) (xy 209.163666 -403.223222)
			(xy 209.163255 -403.248154) (xy 209.156772 -403.297593) (xy 209.143905 -403.345767) (xy 209.124873 -403.391856)
			(xy 209.100002 -403.435073) (xy 209.08518 -403.455124) (xy 209.07629 -403.466554) (xy 209.073496 -403.495256)
			(xy 209.120232 -403.589998) (xy 209.124811 -403.598297) (xy 209.138806 -403.611055) (xy 209.156481 -403.617852)
			(xy 209.165952 -403.618192) (xy 209.820764 -403.618192) (xy 209.83023 -403.617794) (xy 209.847902 -403.611017)
			(xy 209.861917 -403.598295) (xy 209.866484 -403.589998) (xy 209.91322 -403.495256) (xy 209.910426 -403.466554)
			(xy 209.901536 -403.455124) (xy 209.886711 -403.435075) (xy 209.861846 -403.391855) (xy 209.842817 -403.345765)
			(xy 209.829947 -403.297592) (xy 209.823455 -403.248153) (xy 209.82305 -403.223222) (xy 209.823536 -403.195971)
			(xy 209.831292 -403.142023) (xy 209.846647 -403.089728) (xy 209.869289 -403.040151) (xy 209.898755 -402.994301)
			(xy 209.934446 -402.95311) (xy 209.975637 -402.917419) (xy 210.021487 -402.887953) (xy 210.071064 -402.865311)
			(xy 210.123359 -402.849956) (xy 210.177307 -402.8422) (xy 210.231809 -402.8422) (xy 210.285757 -402.849956)
			(xy 210.338052 -402.865311) (xy 210.387629 -402.887953) (xy 210.433479 -402.917419) (xy 210.47467 -402.95311)
			(xy 210.510361 -402.994301) (xy 210.539827 -403.040151) (xy 210.562469 -403.089728) (xy 210.577824 -403.142023)
			(xy 210.58558 -403.195971) (xy 210.586066 -403.223222) (xy 210.585655 -403.248154) (xy 210.579172 -403.297593)
			(xy 210.566305 -403.345767) (xy 210.547273 -403.391856) (xy 210.522402 -403.435073) (xy 210.50758 -403.455124)
			(xy 210.49869 -403.466554) (xy 210.495896 -403.495256) (xy 210.542632 -403.589998) (xy 210.547211 -403.598297)
			(xy 210.561206 -403.611055) (xy 210.578881 -403.617852) (xy 210.588352 -403.618192) (xy 211.217764 -403.618192)
			(xy 211.22723 -403.617794) (xy 211.244902 -403.611017) (xy 211.258917 -403.598295) (xy 211.263484 -403.589998)
			(xy 211.31022 -403.495256) (xy 211.307426 -403.466554) (xy 211.298536 -403.455124) (xy 211.283711 -403.435075)
			(xy 211.258846 -403.391855) (xy 211.239817 -403.345765) (xy 211.226947 -403.297592) (xy 211.220455 -403.248153)
			(xy 211.22005 -403.223222) (xy 211.220536 -403.195971) (xy 211.228292 -403.142023) (xy 211.243647 -403.089728)
			(xy 211.266289 -403.040151) (xy 211.295755 -402.994301) (xy 211.331446 -402.95311) (xy 211.372637 -402.917419)
			(xy 211.418487 -402.887953) (xy 211.468064 -402.865311) (xy 211.520359 -402.849956) (xy 211.574307 -402.8422)
			(xy 211.628809 -402.8422) (xy 211.682757 -402.849956) (xy 211.735052 -402.865311) (xy 211.784629 -402.887953)
			(xy 211.830479 -402.917419) (xy 211.87167 -402.95311) (xy 211.907361 -402.994301) (xy 211.936827 -403.040151)
			(xy 211.959469 -403.089728) (xy 211.974824 -403.142023) (xy 211.98258 -403.195971) (xy 211.983066 -403.223222)
			(xy 211.982655 -403.248154) (xy 211.976172 -403.297593) (xy 211.963305 -403.345767) (xy 211.944273 -403.391856)
			(xy 211.919402 -403.435073) (xy 211.90458 -403.455124) (xy 211.89569 -403.466554) (xy 211.892896 -403.495256)
			(xy 211.939632 -403.589998) (xy 211.944211 -403.598297) (xy 211.958206 -403.611055) (xy 211.975881 -403.617852)
			(xy 211.985352 -403.618192) (xy 212.318092 -403.618192) (xy 212.32814 -403.617847) (xy 212.346736 -403.610241)
			(xy 212.35416 -403.60346) (xy 212.79866 -403.15896) (xy 212.805362 -403.151485) (xy 212.812947 -403.132921)
			(xy 212.813392 -403.122892) (xy 212.813392 -402.519642) (xy 212.812726 -402.507614) (xy 212.801864 -402.486149)
			(xy 212.792564 -402.478494) (xy 212.772065 -402.463049) (xy 212.734991 -402.427555) (xy 212.703012 -402.38741)
			(xy 212.676706 -402.34334) (xy 212.656547 -402.296139) (xy 212.6429 -402.246661) (xy 212.636012 -402.195801)
			(xy 212.635592 -402.170138) (xy 212.636091 -402.142886) (xy 212.643842 -402.088936) (xy 212.659194 -402.036639)
			(xy 212.681832 -401.987059) (xy 212.711296 -401.941206) (xy 212.746986 -401.900013) (xy 212.788175 -401.864319)
			(xy 212.834026 -401.83485) (xy 212.883604 -401.812207) (xy 212.935899 -401.796851) (xy 212.989848 -401.789093)
			(xy 213.0171 -401.78863) (xy 213.048009 -401.789214) (xy 213.10902 -401.799171) (xy 213.138512 -401.808442)
			(xy 213.150704 -401.812506) (xy 213.17585 -401.808188) (xy 213.262972 -401.739608) (xy 213.273132 -401.71624)
			(xy 213.272116 -401.703286) (xy 213.270592 -401.670266) (xy 213.271115 -401.643018) (xy 213.278875 -401.589077)
			(xy 213.294233 -401.536789) (xy 213.316875 -401.487219) (xy 213.346342 -401.441376) (xy 213.382033 -401.400193)
			(xy 213.423221 -401.364508) (xy 213.469069 -401.335048) (xy 213.518642 -401.312413) (xy 213.570932 -401.297063)
			(xy 213.624874 -401.289311) (xy 213.679371 -401.289314) (xy 213.733312 -401.297073) (xy 213.785601 -401.312429)
			(xy 213.835171 -401.33507) (xy 213.881015 -401.364535) (xy 213.922199 -401.400225) (xy 213.957885 -401.441412)
			(xy 213.987346 -401.487259) (xy 214.009983 -401.536831) (xy 214.025335 -401.589121) (xy 214.033089 -401.643063)
			(xy 214.033087 -401.69756) (xy 214.02533 -401.751501) (xy 214.009975 -401.80379) (xy 213.987335 -401.853361)
			(xy 213.957872 -401.899206) (xy 213.922183 -401.940391) (xy 213.880997 -401.976078) (xy 213.835151 -402.005541)
			(xy 213.785579 -402.028179) (xy 213.73329 -402.043532) (xy 213.679348 -402.051288) (xy 213.6521 -402.051774)
			(xy 213.621191 -402.051189) (xy 213.56018 -402.041233) (xy 213.530688 -402.031962) (xy 213.518496 -402.027898)
			(xy 213.49335 -402.032216) (xy 213.406228 -402.100796) (xy 213.396068 -402.124164) (xy 213.397084 -402.137118)
			(xy 213.398608 -402.170138) (xy 213.398484 -402.185058) (xy 213.396197 -402.214811) (xy 213.394036 -402.229574)
			(xy 213.392004 -402.241766) (xy 213.39937 -402.264626) (xy 213.415118 -402.280374) (xy 213.422521 -402.287211)
			(xy 213.441118 -402.294933) (xy 213.451186 -402.29536) (xy 214.847932 -402.29536) (xy 214.867939 -402.295764)
			(xy 214.907196 -402.303512) (xy 214.944181 -402.318781) (xy 214.97747 -402.340982) (xy 214.99195 -402.354796)
			(xy 215.679782 -403.042628) (xy 215.69362 -403.057099) (xy 215.715877 -403.090378) (xy 215.731206 -403.127362)
			(xy 215.739017 -403.166628) (xy 215.739097 -403.170136) (xy 217.588082 -403.170136) (xy 217.592153 -403.114514)
			(xy 217.604279 -403.060077) (xy 217.624202 -403.007986) (xy 217.651498 -402.959351) (xy 217.685584 -402.915208)
			(xy 217.725733 -402.876499) (xy 217.771091 -402.844048) (xy 217.820691 -402.818547) (xy 217.873475 -402.80054)
			(xy 217.928318 -402.79041) (xy 217.984052 -402.788373) (xy 218.039489 -402.794473) (xy 218.093446 -402.808579)
			(xy 218.144775 -402.830391) (xy 218.192381 -402.859445) (xy 218.235249 -402.89512) (xy 218.272466 -402.936657)
			(xy 218.303239 -402.98317) (xy 218.326911 -403.033667) (xy 218.342979 -403.087074) (xy 218.351099 -403.14225)
			(xy 218.351608 -403.170136) (xy 218.351099 -403.198022) (xy 218.342979 -403.253198) (xy 218.326911 -403.306605)
			(xy 218.303239 -403.357102) (xy 218.272466 -403.403615) (xy 218.235249 -403.445152) (xy 218.192381 -403.480827)
			(xy 218.144775 -403.509881) (xy 218.093446 -403.531693) (xy 218.039489 -403.545799) (xy 217.984052 -403.551899)
			(xy 217.928318 -403.549862) (xy 217.873475 -403.539732) (xy 217.820691 -403.521725) (xy 217.771091 -403.496224)
			(xy 217.725733 -403.463773) (xy 217.685584 -403.425064) (xy 217.651498 -403.380921) (xy 217.624202 -403.332286)
			(xy 217.604279 -403.280195) (xy 217.592153 -403.225758) (xy 217.588082 -403.170136) (xy 215.739097 -403.170136)
			(xy 215.739472 -403.186646) (xy 215.739472 -404.178516) (xy 215.73984 -404.188562) (xy 215.747428 -404.207159)
			(xy 215.754204 -404.214584) (xy 216.061798 -404.522178) (xy 216.069207 -404.529007) (xy 216.087799 -404.536734)
			(xy 216.097866 -404.537164) (xy 217.282522 -404.537164) (xy 217.292594 -404.536759) (xy 217.311192 -404.529025)
			(xy 217.31859 -404.522178) (xy 217.385138 -404.45563) (xy 217.391964 -404.448262) (xy 217.399668 -404.429728)
			(xy 217.399665 -404.409657) (xy 217.391955 -404.391125) (xy 217.385138 -404.383748) (xy 217.374216 -404.372826)
			(xy 217.34399 -404.36673) (xy 217.329512 -404.372826) (xy 217.306135 -404.382169) (xy 217.257527 -404.395281)
			(xy 217.207618 -404.401891) (xy 217.182446 -404.40229) (xy 217.155189 -404.401894) (xy 217.10123 -404.394143)
			(xy 217.048923 -404.378791) (xy 216.999334 -404.356151) (xy 216.953471 -404.326684) (xy 216.912269 -404.29099)
			(xy 216.876566 -404.249795) (xy 216.847089 -404.203939) (xy 216.824438 -404.154354) (xy 216.809075 -404.102051)
			(xy 216.801312 -404.048093) (xy 216.801306 -403.99358) (xy 216.809059 -403.939621) (xy 216.824413 -403.887315)
			(xy 216.847054 -403.837726) (xy 216.876522 -403.791864) (xy 216.912217 -403.750662) (xy 216.953412 -403.71496)
			(xy 216.999269 -403.685485) (xy 217.048855 -403.662835) (xy 217.101158 -403.647473) (xy 217.155116 -403.639711)
			(xy 217.209629 -403.639707) (xy 217.263588 -403.647461) (xy 217.315894 -403.662816) (xy 217.365483 -403.685458)
			(xy 217.411344 -403.714927) (xy 217.452544 -403.750624) (xy 217.488245 -403.79182) (xy 217.51772 -403.837678)
			(xy 217.540368 -403.887263) (xy 217.555729 -403.939567) (xy 217.56349 -403.993525) (xy 217.563954 -404.020782)
			(xy 217.563954 -404.029164) (xy 217.563446 -404.045166) (xy 217.58021 -404.07082) (xy 217.681302 -404.114254)
			(xy 217.690782 -404.117834) (xy 217.711031 -404.117952) (xy 217.729742 -404.110212) (xy 217.737182 -404.103332)
			(xy 218.178634 -403.66188) (xy 218.193116 -403.648075) (xy 218.226418 -403.625908) (xy 218.263402 -403.610657)
			(xy 218.302649 -403.602908) (xy 218.322652 -403.602444) (xy 219.05468 -403.602444) (xy 219.063988 -403.602103)
			(xy 219.081391 -403.595503) (xy 219.095268 -403.583099) (xy 219.099892 -403.575012) (xy 219.147898 -403.482302)
			(xy 219.14612 -403.454108) (xy 219.137992 -403.442424) (xy 219.121639 -403.418215) (xy 219.095713 -403.365864)
			(xy 219.078087 -403.310167) (xy 219.069176 -403.252432) (xy 219.06865 -403.223222) (xy 219.069136 -403.195971)
			(xy 219.076892 -403.142023) (xy 219.092247 -403.089728) (xy 219.114889 -403.040151) (xy 219.144355 -402.994301)
			(xy 219.180046 -402.95311) (xy 219.221237 -402.917419) (xy 219.267087 -402.887953) (xy 219.316664 -402.865311)
			(xy 219.368959 -402.849956) (xy 219.422907 -402.8422) (xy 219.477409 -402.8422) (xy 219.531357 -402.849956)
			(xy 219.583652 -402.865311) (xy 219.633229 -402.887953) (xy 219.679079 -402.917419) (xy 219.72027 -402.95311)
			(xy 219.755961 -402.994301) (xy 219.785427 -403.040151) (xy 219.808069 -403.089728) (xy 219.823424 -403.142023)
			(xy 219.83118 -403.195971) (xy 219.831666 -403.223222) (xy 219.831086 -403.252427) (xy 219.822149 -403.310149)
			(xy 219.804533 -403.365839) (xy 219.778647 -403.4182) (xy 219.762324 -403.442424) (xy 219.754196 -403.454108)
			(xy 219.752418 -403.482302) (xy 219.800424 -403.575012) (xy 219.805062 -403.583077) (xy 219.818965 -403.595419)
			(xy 219.836341 -403.602031) (xy 219.845636 -403.602444) (xy 220.47708 -403.602444) (xy 220.486388 -403.602103)
			(xy 220.503791 -403.595503) (xy 220.517668 -403.583099) (xy 220.522292 -403.575012) (xy 220.570298 -403.482302)
			(xy 220.56852 -403.454108) (xy 220.560392 -403.442424) (xy 220.544039 -403.418215) (xy 220.518113 -403.365864)
			(xy 220.500487 -403.310167) (xy 220.491576 -403.252432) (xy 220.49105 -403.223222) (xy 220.491536 -403.195971)
			(xy 220.499292 -403.142023) (xy 220.514647 -403.089728) (xy 220.537289 -403.040151) (xy 220.566755 -402.994301)
			(xy 220.602446 -402.95311) (xy 220.643637 -402.917419) (xy 220.689487 -402.887953) (xy 220.739064 -402.865311)
			(xy 220.791359 -402.849956) (xy 220.845307 -402.8422) (xy 220.899809 -402.8422) (xy 220.953757 -402.849956)
			(xy 221.006052 -402.865311) (xy 221.055629 -402.887953) (xy 221.101479 -402.917419) (xy 221.14267 -402.95311)
			(xy 221.178361 -402.994301) (xy 221.207827 -403.040151) (xy 221.230469 -403.089728) (xy 221.245824 -403.142023)
			(xy 221.25358 -403.195971) (xy 221.254066 -403.223222) (xy 221.253486 -403.252427) (xy 221.244549 -403.310149)
			(xy 221.226933 -403.365839) (xy 221.201047 -403.4182) (xy 221.184724 -403.442424) (xy 221.176596 -403.454108)
			(xy 221.174818 -403.482302) (xy 221.222824 -403.575012) (xy 221.227462 -403.583077) (xy 221.241365 -403.595419)
			(xy 221.258741 -403.602031) (xy 221.268036 -403.602444) (xy 221.87408 -403.602444) (xy 221.883388 -403.602103)
			(xy 221.900791 -403.595503) (xy 221.914668 -403.583099) (xy 221.919292 -403.575012) (xy 221.967298 -403.482302)
			(xy 221.96552 -403.454108) (xy 221.957392 -403.442424) (xy 221.941039 -403.418215) (xy 221.915113 -403.365864)
			(xy 221.897487 -403.310167) (xy 221.888576 -403.252432) (xy 221.88805 -403.223222) (xy 221.888536 -403.195971)
			(xy 221.896292 -403.142023) (xy 221.911647 -403.089728) (xy 221.934289 -403.040151) (xy 221.963755 -402.994301)
			(xy 221.999446 -402.95311) (xy 222.040637 -402.917419) (xy 222.086487 -402.887953) (xy 222.136064 -402.865311)
			(xy 222.188359 -402.849956) (xy 222.242307 -402.8422) (xy 222.296809 -402.8422) (xy 222.350757 -402.849956)
			(xy 222.403052 -402.865311) (xy 222.452629 -402.887953) (xy 222.498479 -402.917419) (xy 222.53967 -402.95311)
			(xy 222.575361 -402.994301) (xy 222.604827 -403.040151) (xy 222.627469 -403.089728) (xy 222.642824 -403.142023)
			(xy 222.65058 -403.195971) (xy 222.651066 -403.223222) (xy 222.650486 -403.252427) (xy 222.641549 -403.310149)
			(xy 222.623933 -403.365839) (xy 222.598047 -403.4182) (xy 222.581724 -403.442424) (xy 222.573596 -403.454108)
			(xy 222.571818 -403.482302) (xy 222.619824 -403.575012) (xy 222.624462 -403.583077) (xy 222.638365 -403.595419)
			(xy 222.655741 -403.602031) (xy 222.665036 -403.602444) (xy 222.981774 -403.602444) (xy 222.991844 -403.60202)
			(xy 223.010442 -403.5943) (xy 223.017842 -403.587458) (xy 223.46666 -403.13864) (xy 223.47337 -403.131172)
			(xy 223.48095 -403.112603) (xy 223.481392 -403.102572) (xy 223.481392 -402.519642) (xy 223.480726 -402.507614)
			(xy 223.469864 -402.486149) (xy 223.460564 -402.478494) (xy 223.440065 -402.463049) (xy 223.402991 -402.427555)
			(xy 223.371012 -402.38741) (xy 223.344706 -402.34334) (xy 223.324547 -402.296139) (xy 223.3109 -402.246661)
			(xy 223.304012 -402.195801) (xy 223.303592 -402.170138) (xy 223.304091 -402.142886) (xy 223.311842 -402.088936)
			(xy 223.327194 -402.036639) (xy 223.349832 -401.987059) (xy 223.379296 -401.941206) (xy 223.414986 -401.900013)
			(xy 223.456175 -401.864319) (xy 223.502026 -401.83485) (xy 223.551604 -401.812207) (xy 223.603899 -401.796851)
			(xy 223.657848 -401.789093) (xy 223.6851 -401.78863) (xy 223.716009 -401.789214) (xy 223.77702 -401.799171)
			(xy 223.806512 -401.808442) (xy 223.818704 -401.812506) (xy 223.84385 -401.808188) (xy 223.930972 -401.739608)
			(xy 223.941132 -401.71624) (xy 223.940116 -401.703286) (xy 223.938592 -401.670266) (xy 223.939115 -401.643018)
			(xy 223.946875 -401.589077) (xy 223.962233 -401.536789) (xy 223.984875 -401.487219) (xy 224.014342 -401.441376)
			(xy 224.050033 -401.400193) (xy 224.091221 -401.364508) (xy 224.137069 -401.335048) (xy 224.186642 -401.312413)
			(xy 224.238932 -401.297063) (xy 224.292874 -401.289311) (xy 224.347371 -401.289314) (xy 224.401312 -401.297073)
			(xy 224.453601 -401.312429) (xy 224.503171 -401.33507) (xy 224.549015 -401.364535) (xy 224.590199 -401.400225)
			(xy 224.625885 -401.441412) (xy 224.655346 -401.487259) (xy 224.677983 -401.536831) (xy 224.693335 -401.589121)
			(xy 224.701089 -401.643063) (xy 224.701087 -401.69756) (xy 224.69333 -401.751501) (xy 224.677975 -401.80379)
			(xy 224.655335 -401.853361) (xy 224.625872 -401.899206) (xy 224.590183 -401.940391) (xy 224.548997 -401.976078)
			(xy 224.503151 -402.005541) (xy 224.453579 -402.028179) (xy 224.40129 -402.043532) (xy 224.347348 -402.051288)
			(xy 224.3201 -402.051774) (xy 224.289191 -402.051189) (xy 224.22818 -402.041233) (xy 224.198688 -402.031962)
			(xy 224.186496 -402.027898) (xy 224.16135 -402.032216) (xy 224.074228 -402.100796) (xy 224.064068 -402.124164)
			(xy 224.065084 -402.137118) (xy 224.066608 -402.170138) (xy 224.066484 -402.185058) (xy 224.064197 -402.214811)
			(xy 224.062036 -402.229574) (xy 224.060004 -402.241766) (xy 224.06737 -402.264626) (xy 224.092262 -402.289518)
			(xy 224.099679 -402.296336) (xy 224.118265 -402.304068) (xy 224.12833 -402.304504) (xy 225.429064 -402.304504)
			(xy 225.44907 -402.304937) (xy 225.488326 -402.312673) (xy 225.525312 -402.327933) (xy 225.558602 -402.350129)
			(xy 225.573082 -402.36394) (xy 226.165918 -402.956776) (xy 226.179785 -402.971221) (xy 226.202036 -403.004509)
			(xy 226.217356 -403.041502) (xy 226.225158 -403.080774) (xy 226.225608 -403.100794) (xy 226.225608 -403.170136)
			(xy 228.256082 -403.170136) (xy 228.260153 -403.114514) (xy 228.272279 -403.060077) (xy 228.292202 -403.007986)
			(xy 228.319498 -402.959351) (xy 228.353584 -402.915208) (xy 228.393733 -402.876499) (xy 228.439091 -402.844048)
			(xy 228.488691 -402.818547) (xy 228.541475 -402.80054) (xy 228.596318 -402.79041) (xy 228.652052 -402.788373)
			(xy 228.707489 -402.794473) (xy 228.761446 -402.808579) (xy 228.812775 -402.830391) (xy 228.860381 -402.859445)
			(xy 228.903249 -402.89512) (xy 228.940466 -402.936657) (xy 228.971239 -402.98317) (xy 228.994911 -403.033667)
			(xy 229.010979 -403.087074) (xy 229.019099 -403.14225) (xy 229.019608 -403.170136) (xy 229.019099 -403.198022)
			(xy 229.010979 -403.253198) (xy 228.994911 -403.306605) (xy 228.971239 -403.357102) (xy 228.940466 -403.403615)
			(xy 228.903249 -403.445152) (xy 228.860381 -403.480827) (xy 228.812775 -403.509881) (xy 228.761446 -403.531693)
			(xy 228.707489 -403.545799) (xy 228.652052 -403.551899) (xy 228.596318 -403.549862) (xy 228.541475 -403.539732)
			(xy 228.488691 -403.521725) (xy 228.439091 -403.496224) (xy 228.393733 -403.463773) (xy 228.353584 -403.425064)
			(xy 228.319498 -403.380921) (xy 228.292202 -403.332286) (xy 228.272279 -403.280195) (xy 228.260153 -403.225758)
			(xy 228.256082 -403.170136) (xy 226.225608 -403.170136) (xy 226.225608 -403.737572) (xy 226.225963 -403.747619)
			(xy 226.233562 -403.766215) (xy 226.24034 -403.77364) (xy 226.891088 -404.424388) (xy 226.898543 -404.431115)
			(xy 226.917123 -404.438684) (xy 226.927156 -404.43912) (xy 227.485702 -404.43912) (xy 227.495415 -404.438688)
			(xy 227.513449 -404.431467) (xy 227.527506 -404.41806) (xy 227.53193 -404.409402) (xy 227.576634 -404.311612)
			(xy 227.572316 -404.282402) (xy 227.56241 -404.270972) (xy 227.544839 -404.250073) (xy 227.515288 -404.204162)
			(xy 227.49258 -404.154508) (xy 227.477181 -404.102125) (xy 227.469403 -404.048082) (xy 227.468938 -404.020782)
			(xy 227.469424 -403.993531) (xy 227.47718 -403.939583) (xy 227.492535 -403.887288) (xy 227.515177 -403.837711)
			(xy 227.544643 -403.791861) (xy 227.580334 -403.75067) (xy 227.621525 -403.714979) (xy 227.667375 -403.685513)
			(xy 227.716952 -403.662871) (xy 227.769247 -403.647516) (xy 227.823195 -403.63976) (xy 227.877697 -403.63976)
			(xy 227.931645 -403.647516) (xy 227.98394 -403.662871) (xy 228.033517 -403.685513) (xy 228.079367 -403.714979)
			(xy 228.120558 -403.75067) (xy 228.156249 -403.791861) (xy 228.185715 -403.837711) (xy 228.208357 -403.887288)
			(xy 228.223712 -403.939583) (xy 228.231468 -403.993531) (xy 228.231954 -404.020782) (xy 228.231954 -404.03653)
			(xy 228.248972 -404.061676) (xy 228.350064 -404.103586) (xy 228.359487 -404.106972) (xy 228.379493 -404.106976)
			(xy 228.397993 -404.099364) (xy 228.405436 -404.092664) (xy 228.773482 -403.724364) (xy 228.787999 -403.710598)
			(xy 228.821287 -403.68842) (xy 228.85826 -403.673158) (xy 228.8975 -403.665398) (xy 228.9175 -403.664928)
			(xy 229.775004 -403.664928) (xy 229.784993 -403.664413) (xy 229.803418 -403.656675) (xy 229.817495 -403.64249)
			(xy 229.82174 -403.633432) (xy 229.863904 -403.532594) (xy 229.858062 -403.502876) (xy 229.84714 -403.4917)
			(xy 229.82655 -403.470149) (xy 229.791695 -403.421802) (xy 229.764787 -403.368621) (xy 229.746479 -403.3119)
			(xy 229.737219 -403.253023) (xy 229.73665 -403.223222) (xy 229.737136 -403.195971) (xy 229.744892 -403.142023)
			(xy 229.760247 -403.089728) (xy 229.782889 -403.040151) (xy 229.812355 -402.994301) (xy 229.848046 -402.95311)
			(xy 229.889237 -402.917419) (xy 229.935087 -402.887953) (xy 229.984664 -402.865311) (xy 230.036959 -402.849956)
			(xy 230.090907 -402.8422) (xy 230.145409 -402.8422) (xy 230.199357 -402.849956) (xy 230.251652 -402.865311)
			(xy 230.301229 -402.887953) (xy 230.347079 -402.917419) (xy 230.38827 -402.95311) (xy 230.423961 -402.994301)
			(xy 230.453427 -403.040151) (xy 230.476069 -403.089728) (xy 230.491424 -403.142023) (xy 230.49918 -403.195971)
			(xy 230.499666 -403.223222) (xy 230.499101 -403.253021) (xy 230.489819 -403.311891) (xy 230.4715 -403.368603)
			(xy 230.444588 -403.421779) (xy 230.409739 -403.470125) (xy 230.389176 -403.4917) (xy 230.378254 -403.502876)
			(xy 230.372412 -403.532594) (xy 230.414576 -403.633432) (xy 230.418834 -403.642481) (xy 230.432907 -403.656658)
			(xy 230.451327 -403.664388) (xy 230.461312 -403.664928) (xy 231.197404 -403.664928) (xy 231.207393 -403.664413)
			(xy 231.225818 -403.656675) (xy 231.239895 -403.64249) (xy 231.24414 -403.633432) (xy 231.286304 -403.532594)
			(xy 231.280462 -403.502876) (xy 231.26954 -403.4917) (xy 231.24895 -403.470149) (xy 231.214095 -403.421802)
			(xy 231.187187 -403.368621) (xy 231.168879 -403.3119) (xy 231.159619 -403.253023) (xy 231.15905 -403.223222)
			(xy 231.159536 -403.195971) (xy 231.167292 -403.142023) (xy 231.182647 -403.089728) (xy 231.205289 -403.040151)
			(xy 231.234755 -402.994301) (xy 231.270446 -402.95311) (xy 231.311637 -402.917419) (xy 231.357487 -402.887953)
			(xy 231.407064 -402.865311) (xy 231.459359 -402.849956) (xy 231.513307 -402.8422) (xy 231.567809 -402.8422)
			(xy 231.621757 -402.849956) (xy 231.674052 -402.865311) (xy 231.723629 -402.887953) (xy 231.769479 -402.917419)
			(xy 231.81067 -402.95311) (xy 231.846361 -402.994301) (xy 231.875827 -403.040151) (xy 231.898469 -403.089728)
			(xy 231.913824 -403.142023) (xy 231.92158 -403.195971) (xy 231.922066 -403.223222) (xy 231.921501 -403.253021)
			(xy 231.912219 -403.311891) (xy 231.8939 -403.368603) (xy 231.866988 -403.421779) (xy 231.832139 -403.470125)
			(xy 231.811576 -403.4917) (xy 231.800654 -403.502876) (xy 231.794812 -403.532594) (xy 231.836976 -403.633432)
			(xy 231.841234 -403.642481) (xy 231.855307 -403.656658) (xy 231.873727 -403.664388) (xy 231.883712 -403.664928)
			(xy 232.594404 -403.664928) (xy 232.604393 -403.664413) (xy 232.622818 -403.656675) (xy 232.636895 -403.64249)
			(xy 232.64114 -403.633432) (xy 232.683304 -403.532594) (xy 232.677462 -403.502876) (xy 232.66654 -403.4917)
			(xy 232.64595 -403.470149) (xy 232.611095 -403.421802) (xy 232.584187 -403.368621) (xy 232.565879 -403.3119)
			(xy 232.556619 -403.253023) (xy 232.55605 -403.223222) (xy 232.556599 -403.195973) (xy 232.564351 -403.14203)
			(xy 232.579701 -403.089739) (xy 232.602337 -403.040165) (xy 232.631797 -402.994316) (xy 232.667482 -402.953127)
			(xy 232.708665 -402.917435) (xy 232.754509 -402.887967) (xy 232.804079 -402.865324) (xy 232.856367 -402.849965)
			(xy 232.910309 -402.842203) (xy 232.937558 -402.841714) (xy 232.964834 -402.84219) (xy 233.01883 -402.849954)
			(xy 233.071169 -402.865331) (xy 233.120785 -402.888007) (xy 233.166664 -402.91752) (xy 233.207871 -402.953266)
			(xy 233.243566 -402.994518) (xy 233.273021 -403.040435) (xy 233.295635 -403.090078) (xy 233.310947 -403.142437)
			(xy 233.315256 -403.169374) (xy 233.317288 -403.183852) (xy 233.335576 -403.20595) (xy 233.435652 -403.239224)
			(xy 233.444704 -403.241829) (xy 233.463508 -403.240936) (xy 233.48074 -403.233359) (xy 233.487722 -403.227032)
			(xy 234.13466 -402.580094) (xy 234.141347 -402.572608) (xy 234.14894 -402.554052) (xy 234.149392 -402.544026)
			(xy 234.149392 -402.507196) (xy 234.138724 -402.48586) (xy 234.128564 -402.478494) (xy 234.108065 -402.463049)
			(xy 234.070991 -402.427555) (xy 234.039012 -402.38741) (xy 234.012706 -402.34334) (xy 233.992547 -402.296139)
			(xy 233.9789 -402.246661) (xy 233.972012 -402.195801) (xy 233.971592 -402.170138) (xy 233.972078 -402.142887)
			(xy 233.979834 -402.088939) (xy 233.995189 -402.036644) (xy 234.017831 -401.987067) (xy 234.047297 -401.941217)
			(xy 234.082988 -401.900026) (xy 234.124179 -401.864335) (xy 234.170029 -401.834869) (xy 234.219606 -401.812227)
			(xy 234.271901 -401.796872) (xy 234.325849 -401.789116) (xy 234.380351 -401.789116) (xy 234.434299 -401.796872)
			(xy 234.486594 -401.812227) (xy 234.536171 -401.834869) (xy 234.582021 -401.864335) (xy 234.623212 -401.900026)
			(xy 234.658903 -401.941217) (xy 234.688369 -401.987067) (xy 234.711011 -402.036644) (xy 234.726366 -402.088939)
			(xy 234.734122 -402.142887) (xy 234.734608 -402.170138) (xy 234.73417 -402.195802) (xy 234.727302 -402.246667)
			(xy 234.713669 -402.296151) (xy 234.693517 -402.343356) (xy 234.667211 -402.38743) (xy 234.635227 -402.427573)
			(xy 234.598145 -402.463061) (xy 234.577636 -402.478494) (xy 234.568284 -402.48611) (xy 234.55741 -402.507597)
			(xy 234.556808 -402.519642) (xy 234.556808 -402.649436) (xy 234.556308 -402.669448) (xy 234.548482 -402.7087)
			(xy 234.533157 -402.745675) (xy 234.51092 -402.778955) (xy 234.497118 -402.793454) (xy 233.278172 -404.0124)
			(xy 233.263684 -404.026198) (xy 233.230385 -404.048368) (xy 233.193403 -404.06362) (xy 233.154157 -404.071371)
			(xy 233.134154 -404.071836) (xy 229.02291 -404.071836) (xy 229.01284 -404.072257) (xy 228.994242 -404.07998)
			(xy 228.986842 -404.086822) (xy 228.287072 -404.786846) (xy 228.272595 -404.800678) (xy 228.239319 -404.822938)
			(xy 228.202337 -404.838269) (xy 228.163071 -404.84608) (xy 228.143054 -404.846536) (xy 226.821746 -404.846536)
			(xy 226.801734 -404.846039) (xy 226.762482 -404.838211) (xy 226.725507 -404.822884) (xy 226.692228 -404.800648)
			(xy 226.677728 -404.786846) (xy 225.877882 -403.987) (xy 225.864051 -403.972523) (xy 225.841794 -403.939246)
			(xy 225.826463 -403.902263) (xy 225.81865 -403.862999) (xy 225.818192 -403.842982) (xy 225.818192 -403.206204)
			(xy 225.817797 -403.196161) (xy 225.810225 -403.177565) (xy 225.80346 -403.170136) (xy 225.772218 -403.138894)
			(xy 225.765294 -403.132483) (xy 225.74804 -403.124869) (xy 225.7292 -403.124034) (xy 225.720148 -403.126702)
			(xy 225.619818 -403.16023) (xy 225.601784 -403.182328) (xy 225.599752 -403.196806) (xy 225.595551 -403.22384)
			(xy 225.580376 -403.276401) (xy 225.557849 -403.326257) (xy 225.528433 -403.372385) (xy 225.492731 -403.413839)
			(xy 225.451475 -403.449769) (xy 225.40551 -403.479439) (xy 225.35578 -403.502241) (xy 225.303302 -403.517707)
			(xy 225.249154 -403.52552) (xy 225.2218 -403.52599) (xy 225.191749 -403.525411) (xy 225.132392 -403.515976)
			(xy 225.075247 -403.497355) (xy 225.021727 -403.470008) (xy 224.973155 -403.434611) (xy 224.951544 -403.413722)
			(xy 224.944135 -403.407005) (xy 224.925714 -403.39928) (xy 224.91573 -403.398736) (xy 224.598484 -403.398736)
			(xy 224.588413 -403.399144) (xy 224.569814 -403.406876) (xy 224.562416 -403.413722) (xy 223.519492 -404.456646)
			(xy 223.501398 -404.473885) (xy 223.459833 -404.501624) (xy 223.413658 -404.520727) (xy 223.364645 -404.530461)
			(xy 223.33966 -404.531068) (xy 222.689674 -404.531068) (xy 222.679186 -404.531638) (xy 222.660006 -404.540144)
			(xy 222.645821 -404.555605) (xy 222.641922 -404.565358) (xy 222.604838 -404.671276) (xy 222.613982 -404.702264)
			(xy 222.626682 -404.712424) (xy 222.648791 -404.730644) (xy 222.687867 -404.772535) (xy 222.720238 -404.819799)
			(xy 222.745177 -404.871373) (xy 222.762122 -404.926096) (xy 222.770692 -404.982739) (xy 222.771208 -405.011382)
			(xy 222.770712 -405.0403) (xy 222.761983 -405.097474) (xy 222.744723 -405.152675) (xy 222.719327 -405.204637)
			(xy 222.686378 -405.25217) (xy 222.646631 -405.294184) (xy 222.624142 -405.312372) (xy 222.615387 -405.31994)
			(xy 222.605202 -405.340695) (xy 222.604584 -405.35225) (xy 222.604584 -405.432514) (xy 222.605152 -405.444082)
			(xy 222.615349 -405.464852) (xy 222.624142 -405.472392) (xy 222.644907 -405.489167) (xy 222.682037 -405.527517)
			(xy 222.713459 -405.570669) (xy 222.738558 -405.61778) (xy 222.756845 -405.66793) (xy 222.767963 -405.72014)
			(xy 222.771694 -405.773389) (xy 222.767966 -405.826639) (xy 222.756851 -405.878849) (xy 222.738567 -405.928999)
			(xy 222.71347 -405.976112) (xy 222.682052 -406.019266) (xy 222.644924 -406.057619) (xy 222.624142 -406.074372)
			(xy 222.615387 -406.08194) (xy 222.605202 -406.102695) (xy 222.604584 -406.11425) (xy 222.604584 -406.194514)
			(xy 222.605152 -406.206082) (xy 222.615349 -406.226852) (xy 222.624142 -406.234392) (xy 222.644907 -406.251167)
			(xy 222.682037 -406.289517) (xy 222.713459 -406.332669) (xy 222.738558 -406.37978) (xy 222.756845 -406.42993)
			(xy 222.767963 -406.48214) (xy 222.771694 -406.535389) (xy 222.767966 -406.588639) (xy 222.756851 -406.640849)
			(xy 222.738567 -406.690999) (xy 222.71347 -406.738112) (xy 222.682052 -406.781266) (xy 222.644924 -406.819619)
			(xy 222.624142 -406.836372) (xy 222.615387 -406.84394) (xy 222.605202 -406.864695) (xy 222.604584 -406.87625)
			(xy 222.604584 -406.956514) (xy 222.605152 -406.968082) (xy 222.615349 -406.988852) (xy 222.624142 -406.996392)
			(xy 222.64254 -407.011172) (xy 222.675911 -407.044541) (xy 222.69069 -407.06294) (xy 222.698254 -407.0717)
			(xy 222.719011 -407.081883) (xy 222.730568 -407.082498) (xy 222.810832 -407.082498) (xy 222.822395 -407.081889)
			(xy 222.843166 -407.071722) (xy 222.85071 -407.06294) (xy 222.868905 -407.04046) (xy 222.910923 -407.000723)
			(xy 222.958457 -406.967782) (xy 223.010417 -406.942393) (xy 223.065615 -406.925136) (xy 223.122784 -406.916408)
			(xy 223.1517 -406.915874) (xy 223.17895 -406.916378) (xy 223.232897 -406.924134) (xy 223.28519 -406.939488)
			(xy 223.334766 -406.962128) (xy 223.380615 -406.991592) (xy 223.421805 -407.027282) (xy 223.457497 -407.06847)
			(xy 223.486964 -407.114318) (xy 223.509606 -407.163893) (xy 223.524962 -407.216186) (xy 223.532721 -407.270132)
			(xy 223.533208 -407.297382) (xy 223.532712 -407.3263) (xy 223.523983 -407.383474) (xy 223.506723 -407.438675)
			(xy 223.481327 -407.490637) (xy 223.448378 -407.53817) (xy 223.408631 -407.580184) (xy 223.386142 -407.598372)
			(xy 223.377387 -407.60594) (xy 223.367202 -407.626695) (xy 223.366584 -407.63825) (xy 223.366584 -407.718514)
			(xy 223.367152 -407.730082) (xy 223.377349 -407.750852) (xy 223.386142 -407.758392) (xy 223.40863 -407.776577)
			(xy 223.448363 -407.818599) (xy 223.481301 -407.866136) (xy 223.506688 -407.918098) (xy 223.523943 -407.973296)
			(xy 223.532673 -408.030466) (xy 223.533208 -408.059382) (xy 223.532728 -408.086634) (xy 223.524973 -408.140585)
			(xy 223.50962 -408.192882) (xy 223.486979 -408.242462) (xy 223.457513 -408.288316) (xy 223.421821 -408.329508)
			(xy 223.38063 -408.365202) (xy 223.334778 -408.394671) (xy 223.285199 -408.417313) (xy 223.232902 -408.43267)
			(xy 223.178952 -408.440427) (xy 223.1517 -408.44089) (xy 223.122783 -408.440375) (xy 223.065611 -408.431646)
			(xy 223.010412 -408.414388) (xy 222.958451 -408.388995) (xy 222.910917 -408.356051) (xy 222.8689 -408.31631)
			(xy 222.85071 -408.293824) (xy 222.843152 -408.285058) (xy 222.82239 -408.27488) (xy 222.810832 -408.274266)
			(xy 222.730568 -408.274266) (xy 222.719002 -408.274852) (xy 222.698229 -408.285033) (xy 222.69069 -408.293824)
			(xy 222.673937 -408.314607) (xy 222.635583 -408.351737) (xy 222.592429 -408.383159) (xy 222.545315 -408.408258)
			(xy 222.495163 -408.426544) (xy 222.442952 -408.437661) (xy 222.3897 -408.441391) (xy 222.336448 -408.437661)
			(xy 222.284237 -408.426544) (xy 222.234085 -408.408258) (xy 222.186971 -408.383159) (xy 222.143817 -408.351737)
			(xy 222.105463 -408.314607) (xy 222.08871 -408.293824) (xy 222.081152 -408.285058) (xy 222.06039 -408.27488)
			(xy 222.048832 -408.274266) (xy 221.968568 -408.274266) (xy 221.957002 -408.274852) (xy 221.936229 -408.285033)
			(xy 221.92869 -408.293824) (xy 221.911937 -408.314607) (xy 221.873583 -408.351737) (xy 221.830429 -408.383159)
			(xy 221.783315 -408.408258) (xy 221.733163 -408.426544) (xy 221.680952 -408.437661) (xy 221.6277 -408.441391)
			(xy 221.574448 -408.437661) (xy 221.522237 -408.426544) (xy 221.472085 -408.408258) (xy 221.424971 -408.383159)
			(xy 221.381817 -408.351737) (xy 221.343463 -408.314607) (xy 221.32671 -408.293824) (xy 221.319152 -408.285058)
			(xy 221.29839 -408.27488) (xy 221.286832 -408.274266) (xy 221.206568 -408.274266) (xy 221.195002 -408.274852)
			(xy 221.174229 -408.285033) (xy 221.16669 -408.293824) (xy 221.149937 -408.314607) (xy 221.111583 -408.351737)
			(xy 221.068429 -408.383159) (xy 221.021315 -408.408258) (xy 220.971163 -408.426544) (xy 220.918952 -408.437661)
			(xy 220.8657 -408.441391) (xy 220.812448 -408.437661) (xy 220.760237 -408.426544) (xy 220.710085 -408.408258)
			(xy 220.662971 -408.383159) (xy 220.619817 -408.351737) (xy 220.581463 -408.314607) (xy 220.56471 -408.293824)
			(xy 220.557152 -408.285058) (xy 220.53639 -408.27488) (xy 220.524832 -408.274266) (xy 220.444568 -408.274266)
			(xy 220.433002 -408.274852) (xy 220.412229 -408.285033) (xy 220.40469 -408.293824) (xy 220.387937 -408.314607)
			(xy 220.349583 -408.351737) (xy 220.306429 -408.383159) (xy 220.259315 -408.408258) (xy 220.209163 -408.426544)
			(xy 220.156952 -408.437661) (xy 220.1037 -408.441391) (xy 220.050448 -408.437661) (xy 219.998237 -408.426544)
			(xy 219.948085 -408.408258) (xy 219.900971 -408.383159) (xy 219.857817 -408.351737) (xy 219.819463 -408.314607)
			(xy 219.80271 -408.293824) (xy 219.795152 -408.285058) (xy 219.77439 -408.27488) (xy 219.762832 -408.274266)
			(xy 219.682568 -408.274266) (xy 219.671002 -408.274852) (xy 219.650229 -408.285033) (xy 219.64269 -408.293824)
			(xy 219.625937 -408.314607) (xy 219.587583 -408.351737) (xy 219.544429 -408.383159) (xy 219.497315 -408.408258)
			(xy 219.447163 -408.426544) (xy 219.394952 -408.437661) (xy 219.3417 -408.441391) (xy 219.288448 -408.437661)
			(xy 219.236237 -408.426544) (xy 219.186085 -408.408258) (xy 219.138971 -408.383159) (xy 219.095817 -408.351737)
			(xy 219.057463 -408.314607) (xy 219.04071 -408.293824) (xy 219.033152 -408.285058) (xy 219.01239 -408.27488)
			(xy 219.000832 -408.274266) (xy 218.920568 -408.274266) (xy 218.909002 -408.274852) (xy 218.888229 -408.285033)
			(xy 218.88069 -408.293824) (xy 218.863937 -408.314607) (xy 218.825583 -408.351737) (xy 218.782429 -408.383159)
			(xy 218.735315 -408.408258) (xy 218.685163 -408.426544) (xy 218.632952 -408.437661) (xy 218.5797 -408.441391)
			(xy 218.526448 -408.437661) (xy 218.474237 -408.426544) (xy 218.424085 -408.408258) (xy 218.376971 -408.383159)
			(xy 218.333817 -408.351737) (xy 218.295463 -408.314607) (xy 218.27871 -408.293824) (xy 218.271152 -408.285058)
			(xy 218.25039 -408.27488) (xy 218.238832 -408.274266) (xy 218.158568 -408.274266) (xy 218.147002 -408.274852)
			(xy 218.126229 -408.285033) (xy 218.11869 -408.293824) (xy 218.100511 -408.316317) (xy 218.058488 -408.356051)
			(xy 218.01095 -408.388988) (xy 217.958987 -408.414374) (xy 217.903787 -408.431629) (xy 217.846617 -408.440356)
			(xy 217.8177 -408.44089) (xy 217.790447 -408.44044) (xy 217.736497 -408.432683) (xy 217.6842 -408.417327)
			(xy 217.63462 -408.394685) (xy 217.588768 -408.365218) (xy 217.547576 -408.329524) (xy 217.511882 -408.288332)
			(xy 217.482415 -408.24248) (xy 217.459773 -408.1929) (xy 217.444417 -408.140603) (xy 217.43666 -408.086653)
			(xy 217.43666 -408.032147) (xy 217.444417 -407.978197) (xy 217.459773 -407.9259) (xy 217.482415 -407.87632)
			(xy 217.511882 -407.830468) (xy 217.547576 -407.789276) (xy 217.588768 -407.753582) (xy 217.63462 -407.724115)
			(xy 217.6842 -407.701473) (xy 217.736497 -407.686117) (xy 217.790447 -407.67836) (xy 217.8177 -407.677874)
			(xy 217.846618 -407.678364) (xy 217.903792 -407.687095) (xy 217.958993 -407.704357) (xy 218.010955 -407.729754)
			(xy 218.058488 -407.762703) (xy 218.100502 -407.802451) (xy 218.11869 -407.82494) (xy 218.126254 -407.8337)
			(xy 218.147011 -407.843883) (xy 218.158568 -407.844498) (xy 218.238832 -407.844498) (xy 218.250395 -407.843889)
			(xy 218.271166 -407.833722) (xy 218.27871 -407.82494) (xy 218.293486 -407.806539) (xy 218.326858 -407.77317)
			(xy 218.345258 -407.758392) (xy 218.354029 -407.750839) (xy 218.364205 -407.730073) (xy 218.364816 -407.718514)
			(xy 218.364816 -407.63825) (xy 218.364211 -407.626687) (xy 218.35404 -407.605916) (xy 218.345258 -407.598372)
			(xy 218.322752 -407.580207) (xy 218.28302 -407.538181) (xy 218.250085 -407.49064) (xy 218.224701 -407.438674)
			(xy 218.207449 -407.383472) (xy 218.198725 -407.326299) (xy 218.198192 -407.297382) (xy 218.198661 -407.27013)
			(xy 218.20642 -407.216182) (xy 218.221777 -407.163887) (xy 218.244421 -407.11431) (xy 218.273889 -407.068459)
			(xy 218.309582 -407.027269) (xy 218.350774 -406.991578) (xy 218.396625 -406.962112) (xy 218.446204 -406.939471)
			(xy 218.4985 -406.924116) (xy 218.552448 -406.91636) (xy 218.5797 -406.915874) (xy 218.608618 -406.916364)
			(xy 218.665792 -406.925095) (xy 218.720993 -406.942357) (xy 218.772955 -406.967754) (xy 218.820488 -407.000703)
			(xy 218.862502 -407.040451) (xy 218.88069 -407.06294) (xy 218.888254 -407.0717) (xy 218.909011 -407.081883)
			(xy 218.920568 -407.082498) (xy 219.000832 -407.082498) (xy 219.012395 -407.081889) (xy 219.033166 -407.071722)
			(xy 219.04071 -407.06294) (xy 219.055486 -407.044539) (xy 219.088858 -407.01117) (xy 219.107258 -406.996392)
			(xy 219.116029 -406.988839) (xy 219.126205 -406.968073) (xy 219.126816 -406.956514) (xy 219.126816 -406.87625)
			(xy 219.126211 -406.864687) (xy 219.11604 -406.843916) (xy 219.107258 -406.836372) (xy 219.086457 -406.81964)
			(xy 219.049327 -406.781284) (xy 219.017905 -406.738127) (xy 218.992807 -406.691011) (xy 218.974521 -406.640856)
			(xy 218.963406 -406.588642) (xy 218.959678 -406.535389) (xy 218.963409 -406.482136) (xy 218.974528 -406.429922)
			(xy 218.992816 -406.379769) (xy 219.017917 -406.332654) (xy 219.049341 -406.289499) (xy 219.086474 -406.251145)
			(xy 219.107258 -406.234392) (xy 219.116029 -406.226839) (xy 219.126205 -406.206073) (xy 219.126816 -406.194514)
			(xy 219.126816 -406.11425) (xy 219.126211 -406.102687) (xy 219.11604 -406.081916) (xy 219.107258 -406.074372)
			(xy 219.086457 -406.05764) (xy 219.049327 -406.019284) (xy 219.017905 -405.976127) (xy 218.992807 -405.929011)
			(xy 218.974521 -405.878856) (xy 218.963406 -405.826642) (xy 218.959678 -405.773389) (xy 218.963409 -405.720136)
			(xy 218.974528 -405.667922) (xy 218.992816 -405.617769) (xy 219.017917 -405.570654) (xy 219.049341 -405.527499)
			(xy 219.086474 -405.489145) (xy 219.107258 -405.472392) (xy 219.116029 -405.464839) (xy 219.126205 -405.444073)
			(xy 219.126816 -405.432514) (xy 219.126816 -405.35225) (xy 219.126211 -405.340687) (xy 219.11604 -405.319916)
			(xy 219.107258 -405.312372) (xy 219.084752 -405.294207) (xy 219.04502 -405.252181) (xy 219.012085 -405.20464)
			(xy 218.986701 -405.152674) (xy 218.969449 -405.097472) (xy 218.960725 -405.040299) (xy 218.960192 -405.011382)
			(xy 218.960746 -404.98274) (xy 218.969312 -404.926099) (xy 218.986249 -404.871375) (xy 219.011177 -404.819797)
			(xy 219.043534 -404.772526) (xy 219.082594 -404.730623) (xy 219.104718 -404.712424) (xy 219.117418 -404.702264)
			(xy 219.126562 -404.671276) (xy 219.089478 -404.565358) (xy 219.0856 -404.555593) (xy 219.071413 -404.540125)
			(xy 219.052218 -404.531633) (xy 219.041726 -404.531068) (xy 218.70416 -404.531068) (xy 218.694086 -404.531455)
			(xy 218.675487 -404.5392) (xy 218.668092 -404.546054) (xy 217.794078 -405.420068) (xy 217.77598 -405.437322)
			(xy 217.734437 -405.465134) (xy 217.688266 -405.484308) (xy 217.639242 -405.494107) (xy 217.614246 -405.494744)
			(xy 215.709754 -405.494744) (xy 215.684759 -405.494085) (xy 215.635737 -405.484289) (xy 215.589566 -405.465123)
			(xy 215.548019 -405.437321) (xy 215.529922 -405.420068) (xy 214.818468 -404.708614) (xy 214.801237 -404.690496)
			(xy 214.773419 -404.64896) (xy 214.754238 -404.602796) (xy 214.744432 -404.553777) (xy 214.743792 -404.528782)
			(xy 214.743792 -403.715474) (xy 214.743412 -403.70543) (xy 214.73583 -403.686834) (xy 214.72906 -403.679406)
			(xy 214.583264 -403.53361) (xy 214.564722 -403.52599) (xy 214.554308 -403.52599) (xy 214.553292 -403.52599)
			(xy 214.542878 -403.52599) (xy 214.524336 -403.53361) (xy 213.569296 -404.48865) (xy 213.5512 -404.505888)
			(xy 213.509636 -404.533626) (xy 213.463462 -404.55273) (xy 213.414449 -404.562464) (xy 213.389464 -404.563072)
			(xy 212.05825 -404.563072) (xy 212.048184 -404.56355) (xy 212.02962 -404.571349) (xy 212.015455 -404.58566)
			(xy 212.01126 -404.594822) (xy 211.969858 -404.696676) (xy 211.976208 -404.726648) (xy 211.987384 -404.73757)
			(xy 212.005359 -404.755604) (xy 212.036855 -404.79561) (xy 212.062751 -404.83945) (xy 212.082587 -404.886344)
			(xy 212.096011 -404.935459) (xy 212.102785 -404.985924) (xy 212.103208 -405.011382) (xy 212.102712 -405.0403)
			(xy 212.093983 -405.097474) (xy 212.076723 -405.152675) (xy 212.051327 -405.204637) (xy 212.018378 -405.25217)
			(xy 211.978631 -405.294184) (xy 211.956142 -405.312372) (xy 211.947387 -405.31994) (xy 211.937202 -405.340695)
			(xy 211.936584 -405.35225) (xy 211.936584 -405.432514) (xy 211.937152 -405.444082) (xy 211.947349 -405.464852)
			(xy 211.956142 -405.472392) (xy 211.976907 -405.489167) (xy 212.014037 -405.527517) (xy 212.045459 -405.570669)
			(xy 212.070558 -405.61778) (xy 212.088845 -405.66793) (xy 212.099963 -405.72014) (xy 212.103694 -405.773389)
			(xy 212.099966 -405.826639) (xy 212.088851 -405.878849) (xy 212.070567 -405.928999) (xy 212.04547 -405.976112)
			(xy 212.014052 -406.019266) (xy 211.976924 -406.057619) (xy 211.956142 -406.074372) (xy 211.947387 -406.08194)
			(xy 211.937202 -406.102695) (xy 211.936584 -406.11425) (xy 211.936584 -406.194514) (xy 211.937152 -406.206082)
			(xy 211.947349 -406.226852) (xy 211.956142 -406.234392) (xy 211.976907 -406.251167) (xy 212.014037 -406.289517)
			(xy 212.045459 -406.332669) (xy 212.070558 -406.37978) (xy 212.088845 -406.42993) (xy 212.099963 -406.48214)
			(xy 212.103694 -406.535389) (xy 212.099966 -406.588639) (xy 212.088851 -406.640849) (xy 212.070567 -406.690999)
			(xy 212.04547 -406.738112) (xy 212.014052 -406.781266) (xy 211.976924 -406.819619) (xy 211.956142 -406.836372)
			(xy 211.947387 -406.84394) (xy 211.937202 -406.864695) (xy 211.936584 -406.87625) (xy 211.936584 -406.956514)
			(xy 211.937152 -406.968082) (xy 211.947349 -406.988852) (xy 211.956142 -406.996392) (xy 211.97454 -407.011172)
			(xy 212.007911 -407.044541) (xy 212.02269 -407.06294) (xy 212.030254 -407.0717) (xy 212.051011 -407.081883)
			(xy 212.062568 -407.082498) (xy 212.142832 -407.082498) (xy 212.154395 -407.081889) (xy 212.175166 -407.071722)
			(xy 212.18271 -407.06294) (xy 212.200905 -407.04046) (xy 212.242923 -407.000723) (xy 212.290457 -406.967782)
			(xy 212.342417 -406.942393) (xy 212.397615 -406.925136) (xy 212.454784 -406.916408) (xy 212.4837 -406.915874)
			(xy 212.51095 -406.916378) (xy 212.564897 -406.924134) (xy 212.61719 -406.939488) (xy 212.666766 -406.962128)
			(xy 212.712615 -406.991592) (xy 212.753805 -407.027282) (xy 212.789497 -407.06847) (xy 212.818964 -407.114318)
			(xy 212.841606 -407.163893) (xy 212.856962 -407.216186) (xy 212.864721 -407.270132) (xy 212.865208 -407.297382)
			(xy 212.864712 -407.3263) (xy 212.855983 -407.383474) (xy 212.838723 -407.438675) (xy 212.813327 -407.490637)
			(xy 212.780378 -407.53817) (xy 212.740631 -407.580184) (xy 212.718142 -407.598372) (xy 212.709387 -407.60594)
			(xy 212.699202 -407.626695) (xy 212.698584 -407.63825) (xy 212.698584 -407.718514) (xy 212.699152 -407.730082)
			(xy 212.709349 -407.750852) (xy 212.718142 -407.758392) (xy 212.74063 -407.776577) (xy 212.780363 -407.818599)
			(xy 212.813301 -407.866136) (xy 212.838688 -407.918098) (xy 212.855943 -407.973296) (xy 212.864673 -408.030466)
			(xy 212.865208 -408.059382) (xy 212.864728 -408.086634) (xy 212.856973 -408.140585) (xy 212.84162 -408.192882)
			(xy 212.818979 -408.242462) (xy 212.789513 -408.288316) (xy 212.753821 -408.329508) (xy 212.71263 -408.365202)
			(xy 212.666778 -408.394671) (xy 212.617199 -408.417313) (xy 212.564902 -408.43267) (xy 212.510952 -408.440427)
			(xy 212.4837 -408.44089) (xy 212.454783 -408.440375) (xy 212.397611 -408.431646) (xy 212.342412 -408.414388)
			(xy 212.290451 -408.388995) (xy 212.242917 -408.356051) (xy 212.2009 -408.31631) (xy 212.18271 -408.293824)
			(xy 212.175152 -408.285058) (xy 212.15439 -408.27488) (xy 212.142832 -408.274266) (xy 212.062568 -408.274266)
			(xy 212.051002 -408.274852) (xy 212.030229 -408.285033) (xy 212.02269 -408.293824) (xy 212.005937 -408.314607)
			(xy 211.967583 -408.351737) (xy 211.924429 -408.383159) (xy 211.877315 -408.408258) (xy 211.827163 -408.426544)
			(xy 211.774952 -408.437661) (xy 211.7217 -408.441391) (xy 211.668448 -408.437661) (xy 211.616237 -408.426544)
			(xy 211.566085 -408.408258) (xy 211.518971 -408.383159) (xy 211.475817 -408.351737) (xy 211.437463 -408.314607)
			(xy 211.42071 -408.293824) (xy 211.413152 -408.285058) (xy 211.39239 -408.27488) (xy 211.380832 -408.274266)
			(xy 211.300568 -408.274266) (xy 211.289002 -408.274852) (xy 211.268229 -408.285033) (xy 211.26069 -408.293824)
			(xy 211.243937 -408.314607) (xy 211.205583 -408.351737) (xy 211.162429 -408.383159) (xy 211.115315 -408.408258)
			(xy 211.065163 -408.426544) (xy 211.012952 -408.437661) (xy 210.9597 -408.441391) (xy 210.906448 -408.437661)
			(xy 210.854237 -408.426544) (xy 210.804085 -408.408258) (xy 210.756971 -408.383159) (xy 210.713817 -408.351737)
			(xy 210.675463 -408.314607) (xy 210.65871 -408.293824) (xy 210.651152 -408.285058) (xy 210.63039 -408.27488)
			(xy 210.618832 -408.274266) (xy 210.538568 -408.274266) (xy 210.527002 -408.274852) (xy 210.506229 -408.285033)
			(xy 210.49869 -408.293824) (xy 210.481937 -408.314607) (xy 210.443583 -408.351737) (xy 210.400429 -408.383159)
			(xy 210.353315 -408.408258) (xy 210.303163 -408.426544) (xy 210.250952 -408.437661) (xy 210.1977 -408.441391)
			(xy 210.144448 -408.437661) (xy 210.092237 -408.426544) (xy 210.042085 -408.408258) (xy 209.994971 -408.383159)
			(xy 209.951817 -408.351737) (xy 209.913463 -408.314607) (xy 209.89671 -408.293824) (xy 209.889152 -408.285058)
			(xy 209.86839 -408.27488) (xy 209.856832 -408.274266) (xy 209.776568 -408.274266) (xy 209.765002 -408.274852)
			(xy 209.744229 -408.285033) (xy 209.73669 -408.293824) (xy 209.719937 -408.314607) (xy 209.681583 -408.351737)
			(xy 209.638429 -408.383159) (xy 209.591315 -408.408258) (xy 209.541163 -408.426544) (xy 209.488952 -408.437661)
			(xy 209.4357 -408.441391) (xy 209.382448 -408.437661) (xy 209.330237 -408.426544) (xy 209.280085 -408.408258)
			(xy 209.232971 -408.383159) (xy 209.189817 -408.351737) (xy 209.151463 -408.314607) (xy 209.13471 -408.293824)
			(xy 209.127152 -408.285058) (xy 209.10639 -408.27488) (xy 209.094832 -408.274266) (xy 209.014568 -408.274266)
			(xy 209.003002 -408.274852) (xy 208.982229 -408.285033) (xy 208.97469 -408.293824) (xy 208.957937 -408.314607)
			(xy 208.919583 -408.351737) (xy 208.876429 -408.383159) (xy 208.829315 -408.408258) (xy 208.779163 -408.426544)
			(xy 208.726952 -408.437661) (xy 208.6737 -408.441391) (xy 208.620448 -408.437661) (xy 208.568237 -408.426544)
			(xy 208.518085 -408.408258) (xy 208.470971 -408.383159) (xy 208.427817 -408.351737) (xy 208.389463 -408.314607)
			(xy 208.37271 -408.293824) (xy 208.365152 -408.285058) (xy 208.34439 -408.27488) (xy 208.332832 -408.274266)
			(xy 208.252568 -408.274266) (xy 208.241002 -408.274852) (xy 208.220229 -408.285033) (xy 208.21269 -408.293824)
			(xy 208.195937 -408.314607) (xy 208.157583 -408.351737) (xy 208.114429 -408.383159) (xy 208.067315 -408.408258)
			(xy 208.017163 -408.426544) (xy 207.964952 -408.437661) (xy 207.9117 -408.441391) (xy 207.858448 -408.437661)
			(xy 207.806237 -408.426544) (xy 207.756085 -408.408258) (xy 207.708971 -408.383159) (xy 207.665817 -408.351737)
			(xy 207.627463 -408.314607) (xy 207.61071 -408.293824) (xy 207.603152 -408.285058) (xy 207.58239 -408.27488)
			(xy 207.570832 -408.274266) (xy 207.490568 -408.274266) (xy 207.479002 -408.274852) (xy 207.458229 -408.285033)
			(xy 207.45069 -408.293824) (xy 207.432511 -408.316317) (xy 207.390488 -408.356051) (xy 207.34295 -408.388988)
			(xy 207.290987 -408.414374) (xy 207.235787 -408.431629) (xy 207.178617 -408.440356) (xy 207.1497 -408.44089)
			(xy 207.122447 -408.44044) (xy 207.068497 -408.432683) (xy 207.0162 -408.417327) (xy 206.96662 -408.394685)
			(xy 206.920768 -408.365218) (xy 206.879576 -408.329524) (xy 206.843882 -408.288332) (xy 206.814415 -408.24248)
			(xy 206.791773 -408.1929) (xy 206.776417 -408.140603) (xy 206.76866 -408.086653) (xy 206.76866 -408.032147)
			(xy 206.776417 -407.978197) (xy 206.791773 -407.9259) (xy 206.814415 -407.87632) (xy 206.843882 -407.830468)
			(xy 206.879576 -407.789276) (xy 206.920768 -407.753582) (xy 206.96662 -407.724115) (xy 207.0162 -407.701473)
			(xy 207.068497 -407.686117) (xy 207.122447 -407.67836) (xy 207.1497 -407.677874) (xy 207.178618 -407.678364)
			(xy 207.235792 -407.687095) (xy 207.290993 -407.704357) (xy 207.342955 -407.729754) (xy 207.390488 -407.762703)
			(xy 207.432502 -407.802451) (xy 207.45069 -407.82494) (xy 207.458254 -407.8337) (xy 207.479011 -407.843883)
			(xy 207.490568 -407.844498) (xy 207.570832 -407.844498) (xy 207.582395 -407.843889) (xy 207.603166 -407.833722)
			(xy 207.61071 -407.82494) (xy 207.625486 -407.806539) (xy 207.658858 -407.77317) (xy 207.677258 -407.758392)
			(xy 207.686029 -407.750839) (xy 207.696205 -407.730073) (xy 207.696816 -407.718514) (xy 207.696816 -407.63825)
			(xy 207.696211 -407.626687) (xy 207.68604 -407.605916) (xy 207.677258 -407.598372) (xy 207.654752 -407.580207)
			(xy 207.61502 -407.538181) (xy 207.582085 -407.49064) (xy 207.556701 -407.438674) (xy 207.539449 -407.383472)
			(xy 207.530725 -407.326299) (xy 207.530192 -407.297382) (xy 207.530661 -407.27013) (xy 207.53842 -407.216182)
			(xy 207.553777 -407.163887) (xy 207.576421 -407.11431) (xy 207.605889 -407.068459) (xy 207.641582 -407.027269)
			(xy 207.682774 -406.991578) (xy 207.728625 -406.962112) (xy 207.778204 -406.939471) (xy 207.8305 -406.924116)
			(xy 207.884448 -406.91636) (xy 207.9117 -406.915874) (xy 207.940618 -406.916364) (xy 207.997792 -406.925095)
			(xy 208.052993 -406.942357) (xy 208.104955 -406.967754) (xy 208.152488 -407.000703) (xy 208.194502 -407.040451)
			(xy 208.21269 -407.06294) (xy 208.220254 -407.0717) (xy 208.241011 -407.081883) (xy 208.252568 -407.082498)
			(xy 208.332832 -407.082498) (xy 208.344395 -407.081889) (xy 208.365166 -407.071722) (xy 208.37271 -407.06294)
			(xy 208.387486 -407.044539) (xy 208.420858 -407.01117) (xy 208.439258 -406.996392) (xy 208.448029 -406.988839)
			(xy 208.458205 -406.968073) (xy 208.458816 -406.956514) (xy 208.458816 -406.87625) (xy 208.458211 -406.864687)
			(xy 208.44804 -406.843916) (xy 208.439258 -406.836372) (xy 208.418457 -406.81964) (xy 208.381327 -406.781284)
			(xy 208.349905 -406.738127) (xy 208.324807 -406.691011) (xy 208.306521 -406.640856) (xy 208.295406 -406.588642)
			(xy 208.291678 -406.535389) (xy 208.295409 -406.482136) (xy 208.306528 -406.429922) (xy 208.324816 -406.379769)
			(xy 208.349917 -406.332654) (xy 208.381341 -406.289499) (xy 208.418474 -406.251145) (xy 208.439258 -406.234392)
			(xy 208.448029 -406.226839) (xy 208.458205 -406.206073) (xy 208.458816 -406.194514) (xy 208.458816 -406.11425)
			(xy 208.458211 -406.102687) (xy 208.44804 -406.081916) (xy 208.439258 -406.074372) (xy 208.418457 -406.05764)
			(xy 208.381327 -406.019284) (xy 208.349905 -405.976127) (xy 208.324807 -405.929011) (xy 208.306521 -405.878856)
			(xy 208.295406 -405.826642) (xy 208.291678 -405.773389) (xy 208.295409 -405.720136) (xy 208.306528 -405.667922)
			(xy 208.324816 -405.617769) (xy 208.349917 -405.570654) (xy 208.381341 -405.527499) (xy 208.418474 -405.489145)
			(xy 208.439258 -405.472392) (xy 208.448029 -405.464839) (xy 208.458205 -405.444073) (xy 208.458816 -405.432514)
			(xy 208.458816 -405.35225) (xy 208.458211 -405.340687) (xy 208.44804 -405.319916) (xy 208.439258 -405.312372)
			(xy 208.416752 -405.294207) (xy 208.37702 -405.252181) (xy 208.344085 -405.20464) (xy 208.318701 -405.152674)
			(xy 208.301449 -405.097472) (xy 208.292725 -405.040299) (xy 208.292192 -405.011382) (xy 208.292621 -404.985923)
			(xy 208.299385 -404.935457) (xy 208.312804 -404.886339) (xy 208.332639 -404.839444) (xy 208.358537 -404.795605)
			(xy 208.390038 -404.755602) (xy 208.408016 -404.73757) (xy 208.419192 -404.726648) (xy 208.425542 -404.696676)
			(xy 208.38414 -404.594822) (xy 208.379963 -404.585639) (xy 208.365822 -404.571277) (xy 208.347228 -404.563501)
			(xy 208.33715 -404.563072) (xy 208.123028 -404.563072) (xy 208.112958 -404.563493) (xy 208.094359 -404.571215)
			(xy 208.08696 -404.578058) (xy 207.374998 -405.29002) (xy 207.3569 -405.307273) (xy 207.315356 -405.335083)
			(xy 207.269185 -405.354257) (xy 207.220162 -405.364058) (xy 207.195166 -405.364696) (xy 205.013306 -405.364696)
			(xy 204.988311 -405.364051) (xy 204.939289 -405.354248) (xy 204.893118 -405.335077) (xy 204.851571 -405.307273)
			(xy 204.833474 -405.29002) (xy 203.705968 -404.162514) (xy 203.688737 -404.144396) (xy 203.660919 -404.10286)
			(xy 203.641738 -404.056696) (xy 203.631932 -404.007677) (xy 203.631292 -403.982682) (xy 203.631292 -403.865588)
			(xy 203.614528 -403.840188) (xy 203.60005 -403.834346) (xy 203.590625 -403.830964) (xy 203.57062 -403.830955)
			(xy 203.552119 -403.838567) (xy 203.544678 -403.845268) (xy 202.86599 -404.523956) (xy 202.847886 -404.541202)
			(xy 202.806345 -404.569016) (xy 202.760176 -404.588193) (xy 202.711154 -404.597994) (xy 202.686158 -404.598632)
			(xy 201.42327 -404.598632) (xy 201.413615 -404.599063) (xy 201.395638 -404.606103) (xy 201.381536 -404.619289)
			(xy 201.377042 -404.627842) (xy 201.332084 -404.72487) (xy 201.335894 -404.75408) (xy 201.345546 -404.76551)
			(xy 201.362443 -404.786224) (xy 201.390836 -404.831516) (xy 201.412619 -404.880333) (xy 201.427365 -404.931715)
			(xy 201.434784 -404.984654) (xy 201.435208 -405.011382) (xy 201.434712 -405.0403) (xy 201.425983 -405.097474)
			(xy 201.408723 -405.152675) (xy 201.383327 -405.204637) (xy 201.350378 -405.25217) (xy 201.310631 -405.294184)
			(xy 201.288142 -405.312372) (xy 201.279387 -405.31994) (xy 201.269202 -405.340695) (xy 201.268584 -405.35225)
			(xy 201.268584 -405.432514) (xy 201.269152 -405.444082) (xy 201.279349 -405.464852) (xy 201.288142 -405.472392)
			(xy 201.308907 -405.489167) (xy 201.346037 -405.527517) (xy 201.377459 -405.570669) (xy 201.402558 -405.61778)
			(xy 201.420845 -405.66793) (xy 201.431963 -405.72014) (xy 201.435694 -405.773389) (xy 201.431966 -405.826639)
			(xy 201.420851 -405.878849) (xy 201.402567 -405.928999) (xy 201.37747 -405.976112) (xy 201.346052 -406.019266)
			(xy 201.308924 -406.057619) (xy 201.288142 -406.074372) (xy 201.279387 -406.08194) (xy 201.269202 -406.102695)
			(xy 201.268584 -406.11425) (xy 201.268584 -406.194514) (xy 201.269152 -406.206082) (xy 201.279349 -406.226852)
			(xy 201.288142 -406.234392) (xy 201.308907 -406.251167) (xy 201.346037 -406.289517) (xy 201.377459 -406.332669)
			(xy 201.402558 -406.37978) (xy 201.420845 -406.42993) (xy 201.431963 -406.48214) (xy 201.435694 -406.535389)
			(xy 201.431966 -406.588639) (xy 201.420851 -406.640849) (xy 201.402567 -406.690999) (xy 201.37747 -406.738112)
			(xy 201.346052 -406.781266) (xy 201.308924 -406.819619) (xy 201.288142 -406.836372) (xy 201.279387 -406.84394)
			(xy 201.269202 -406.864695) (xy 201.268584 -406.87625) (xy 201.268584 -406.956514) (xy 201.269152 -406.968082)
			(xy 201.279349 -406.988852) (xy 201.288142 -406.996392) (xy 201.308907 -407.013167) (xy 201.346037 -407.051517)
			(xy 201.377459 -407.094669) (xy 201.402558 -407.14178) (xy 201.420845 -407.19193) (xy 201.431963 -407.24414)
			(xy 201.435694 -407.297389) (xy 201.431966 -407.350639) (xy 201.420851 -407.402849) (xy 201.402567 -407.452999)
			(xy 201.37747 -407.500112) (xy 201.346052 -407.543266) (xy 201.308924 -407.581619) (xy 201.288142 -407.598372)
			(xy 201.279387 -407.60594) (xy 201.269202 -407.626695) (xy 201.268584 -407.63825) (xy 201.268584 -407.718514)
			(xy 201.269152 -407.730082) (xy 201.279349 -407.750852) (xy 201.288142 -407.758392) (xy 201.31063 -407.776577)
			(xy 201.350363 -407.818599) (xy 201.383301 -407.866136) (xy 201.408688 -407.918098) (xy 201.425943 -407.973296)
			(xy 201.434673 -408.030466) (xy 201.435208 -408.059382) (xy 201.434728 -408.086634) (xy 201.426973 -408.140585)
			(xy 201.41162 -408.192882) (xy 201.388979 -408.242462) (xy 201.359513 -408.288316) (xy 201.323821 -408.329508)
			(xy 201.28263 -408.365202) (xy 201.236778 -408.394671) (xy 201.187199 -408.417313) (xy 201.134902 -408.43267)
			(xy 201.080952 -408.440427) (xy 201.0537 -408.44089) (xy 201.024783 -408.440375) (xy 200.967611 -408.431646)
			(xy 200.912412 -408.414388) (xy 200.860451 -408.388995) (xy 200.812917 -408.356051) (xy 200.7709 -408.31631)
			(xy 200.75271 -408.293824) (xy 200.745152 -408.285058) (xy 200.72439 -408.27488) (xy 200.712832 -408.274266)
			(xy 200.632568 -408.274266) (xy 200.621002 -408.274852) (xy 200.600229 -408.285033) (xy 200.59269 -408.293824)
			(xy 200.575937 -408.314607) (xy 200.537583 -408.351737) (xy 200.494429 -408.383159) (xy 200.447315 -408.408258)
			(xy 200.397163 -408.426544) (xy 200.344952 -408.437661) (xy 200.2917 -408.441391) (xy 200.238448 -408.437661)
			(xy 200.186237 -408.426544) (xy 200.136085 -408.408258) (xy 200.088971 -408.383159) (xy 200.045817 -408.351737)
			(xy 200.007463 -408.314607) (xy 199.99071 -408.293824) (xy 199.983152 -408.285058) (xy 199.96239 -408.27488)
			(xy 199.950832 -408.274266) (xy 199.870568 -408.274266) (xy 199.859002 -408.274852) (xy 199.838229 -408.285033)
			(xy 199.83069 -408.293824) (xy 199.813937 -408.314607) (xy 199.775583 -408.351737) (xy 199.732429 -408.383159)
			(xy 199.685315 -408.408258) (xy 199.635163 -408.426544) (xy 199.582952 -408.437661) (xy 199.5297 -408.441391)
			(xy 199.476448 -408.437661) (xy 199.424237 -408.426544) (xy 199.374085 -408.408258) (xy 199.326971 -408.383159)
			(xy 199.283817 -408.351737) (xy 199.245463 -408.314607) (xy 199.22871 -408.293824) (xy 199.221152 -408.285058)
			(xy 199.20039 -408.27488) (xy 199.188832 -408.274266) (xy 199.108568 -408.274266) (xy 199.097002 -408.274852)
			(xy 199.076229 -408.285033) (xy 199.06869 -408.293824) (xy 199.051937 -408.314607) (xy 199.013583 -408.351737)
			(xy 198.970429 -408.383159) (xy 198.923315 -408.408258) (xy 198.873163 -408.426544) (xy 198.820952 -408.437661)
			(xy 198.7677 -408.441391) (xy 198.714448 -408.437661) (xy 198.662237 -408.426544) (xy 198.612085 -408.408258)
			(xy 198.564971 -408.383159) (xy 198.521817 -408.351737) (xy 198.483463 -408.314607) (xy 198.46671 -408.293824)
			(xy 198.459152 -408.285058) (xy 198.43839 -408.27488) (xy 198.426832 -408.274266) (xy 198.346568 -408.274266)
			(xy 198.335002 -408.274852) (xy 198.314229 -408.285033) (xy 198.30669 -408.293824) (xy 198.289937 -408.314607)
			(xy 198.251583 -408.351737) (xy 198.208429 -408.383159) (xy 198.161315 -408.408258) (xy 198.111163 -408.426544)
			(xy 198.058952 -408.437661) (xy 198.0057 -408.441391) (xy 197.952448 -408.437661) (xy 197.900237 -408.426544)
			(xy 197.850085 -408.408258) (xy 197.802971 -408.383159) (xy 197.759817 -408.351737) (xy 197.721463 -408.314607)
			(xy 197.70471 -408.293824) (xy 197.697152 -408.285058) (xy 197.67639 -408.27488) (xy 197.664832 -408.274266)
			(xy 197.584568 -408.274266) (xy 197.573002 -408.274852) (xy 197.552229 -408.285033) (xy 197.54469 -408.293824)
			(xy 197.526511 -408.316317) (xy 197.484488 -408.356051) (xy 197.43695 -408.388988) (xy 197.384987 -408.414374)
			(xy 197.329787 -408.431629) (xy 197.272617 -408.440356) (xy 197.2437 -408.44089) (xy 197.216446 -408.440445)
			(xy 197.162494 -408.432687) (xy 197.110195 -408.41733) (xy 197.060613 -408.394686) (xy 197.014759 -408.365217)
			(xy 196.973566 -408.329521) (xy 196.937872 -408.288326) (xy 196.908405 -408.242471) (xy 196.885763 -408.192889)
			(xy 196.870409 -408.140589) (xy 196.862654 -408.086636) (xy 196.862192 -408.059382) (xy 196.862734 -408.030466)
			(xy 196.871454 -407.973294) (xy 196.888704 -407.918094) (xy 196.914091 -407.866131) (xy 196.947033 -407.818597)
			(xy 196.986773 -407.776581) (xy 197.009258 -407.758392) (xy 197.018029 -407.750839) (xy 197.028205 -407.730073)
			(xy 197.028816 -407.718514) (xy 197.028816 -407.63825) (xy 197.028211 -407.626687) (xy 197.01804 -407.605916)
			(xy 197.009258 -407.598372) (xy 196.988457 -407.58164) (xy 196.951327 -407.543284) (xy 196.919905 -407.500127)
			(xy 196.894807 -407.453011) (xy 196.876521 -407.402856) (xy 196.865406 -407.350642) (xy 196.861678 -407.297389)
			(xy 196.865409 -407.244136) (xy 196.876528 -407.191922) (xy 196.894816 -407.141769) (xy 196.919917 -407.094654)
			(xy 196.951341 -407.051499) (xy 196.988474 -407.013145) (xy 197.009258 -406.996392) (xy 197.018029 -406.988839)
			(xy 197.028205 -406.968073) (xy 197.028816 -406.956514) (xy 197.028816 -406.87625) (xy 197.028211 -406.864687)
			(xy 197.01804 -406.843916) (xy 197.009258 -406.836372) (xy 196.988457 -406.81964) (xy 196.951327 -406.781284)
			(xy 196.919905 -406.738127) (xy 196.894807 -406.691011) (xy 196.876521 -406.640856) (xy 196.865406 -406.588642)
			(xy 196.861678 -406.535389) (xy 196.865409 -406.482136) (xy 196.876528 -406.429922) (xy 196.894816 -406.379769)
			(xy 196.919917 -406.332654) (xy 196.951341 -406.289499) (xy 196.988474 -406.251145) (xy 197.009258 -406.234392)
			(xy 197.018029 -406.226839) (xy 197.028205 -406.206073) (xy 197.028816 -406.194514) (xy 197.028816 -406.11425)
			(xy 197.028211 -406.102687) (xy 197.01804 -406.081916) (xy 197.009258 -406.074372) (xy 196.988457 -406.05764)
			(xy 196.951327 -406.019284) (xy 196.919905 -405.976127) (xy 196.894807 -405.929011) (xy 196.876521 -405.878856)
			(xy 196.865406 -405.826642) (xy 196.861678 -405.773389) (xy 196.865409 -405.720136) (xy 196.876528 -405.667922)
			(xy 196.894816 -405.617769) (xy 196.919917 -405.570654) (xy 196.951341 -405.527499) (xy 196.988474 -405.489145)
			(xy 197.009258 -405.472392) (xy 197.018029 -405.464839) (xy 197.028205 -405.444073) (xy 197.028816 -405.432514)
			(xy 197.028816 -405.35225) (xy 197.028211 -405.340687) (xy 197.01804 -405.319916) (xy 197.009258 -405.312372)
			(xy 196.986752 -405.294207) (xy 196.94702 -405.252181) (xy 196.914085 -405.20464) (xy 196.888701 -405.152674)
			(xy 196.871449 -405.097472) (xy 196.862725 -405.040299) (xy 196.862192 -405.011382) (xy 196.862619 -404.984657)
			(xy 196.870074 -404.931729) (xy 196.884836 -404.880357) (xy 196.906617 -404.831546) (xy 196.93499 -404.786248)
			(xy 196.951854 -404.76551) (xy 196.961506 -404.75408) (xy 196.965316 -404.72487) (xy 196.920358 -404.627842)
			(xy 196.915879 -404.619272) (xy 196.901781 -404.606058) (xy 196.883793 -404.599002) (xy 196.87413 -404.598632)
			(xy 195.154042 -404.598632) (xy 195.129046 -404.597983) (xy 195.080024 -404.588185) (xy 195.033853 -404.569015)
			(xy 194.992306 -404.54121) (xy 194.97421 -404.523956) (xy 194.671188 -404.220934) (xy 194.663782 -404.214101)
			(xy 194.645188 -404.206376) (xy 194.63512 -404.205948) (xy 193.008758 -404.205948) (xy 192.998685 -404.206339)
			(xy 192.980086 -404.214082) (xy 192.97269 -404.220934) (xy 192.821052 -404.372826) (xy 192.814305 -404.380195)
			(xy 192.80668 -404.398646) (xy 192.806691 -404.41861) (xy 192.814337 -404.437052) (xy 192.821052 -404.444454)
			(xy 192.831212 -404.454868) (xy 192.859406 -404.461472) (xy 192.873376 -404.456646) (xy 192.889279 -404.451558)
			(xy 192.922214 -404.446076) (xy 192.938908 -404.445724) (xy 193.811906 -404.445724) (xy 193.831918 -404.446234)
			(xy 193.87117 -404.454055) (xy 193.908145 -404.469377) (xy 193.941424 -404.491612) (xy 193.955924 -404.505414)
			(xy 194.234308 -404.783798) (xy 194.248093 -404.798297) (xy 194.270265 -404.831593) (xy 194.285521 -404.868571)
			(xy 194.293276 -404.907814) (xy 194.293744 -404.927816) (xy 194.293744 -409.895802) (xy 194.294157 -409.905873)
			(xy 194.301885 -409.924471) (xy 194.30873 -409.93187) (xy 195.253102 -410.876242) (xy 195.260502 -410.883081)
			(xy 195.279102 -410.8908) (xy 195.28917 -410.891228) (xy 201.91095 -410.891228) (xy 201.921019 -410.890795)
			(xy 201.939618 -410.883082) (xy 201.947018 -410.876242) (xy 202.79614 -410.02712) (xy 202.802857 -410.019657)
			(xy 202.810434 -410.001084) (xy 202.810872 -409.991052) (xy 202.810872 -407.604722) (xy 202.811352 -407.584709)
			(xy 202.819185 -407.545456) (xy 202.834517 -407.508482) (xy 202.856758 -407.475203) (xy 202.870562 -407.460704)
			(xy 204.422502 -405.908764) (xy 204.437011 -405.894989) (xy 204.470302 -405.872813) (xy 204.507277 -405.857553)
			(xy 204.546519 -405.849796) (xy 204.56652 -405.849328) (xy 205.428596 -405.849328) (xy 205.440658 -405.848622)
			(xy 205.462133 -405.837628) (xy 205.469744 -405.828246) (xy 205.485161 -405.807725) (xy 205.52066 -405.770653)
			(xy 205.56081 -405.738676) (xy 205.604886 -405.712373) (xy 205.652091 -405.692218) (xy 205.701572 -405.678575)
			(xy 205.752436 -405.671692) (xy 205.7781 -405.671274) (xy 205.80535 -405.671796) (xy 205.859295 -405.679552)
			(xy 205.911587 -405.694907) (xy 205.961162 -405.717547) (xy 206.00701 -405.747012) (xy 206.048199 -405.782701)
			(xy 206.083888 -405.82389) (xy 206.113353 -405.869738) (xy 206.135993 -405.919313) (xy 206.151348 -405.971605)
			(xy 206.159104 -406.02555) (xy 206.159104 -406.08005) (xy 206.151348 -406.133995) (xy 206.135993 -406.186287)
			(xy 206.113353 -406.235862) (xy 206.083888 -406.28171) (xy 206.048199 -406.322899) (xy 206.00701 -406.358588)
			(xy 205.961162 -406.388053) (xy 205.911587 -406.410693) (xy 205.859295 -406.426048) (xy 205.80535 -406.433804)
			(xy 205.7781 -406.43429) (xy 205.76318 -406.434173) (xy 205.733427 -406.431881) (xy 205.718664 -406.429718)
			(xy 205.706472 -406.427686) (xy 205.683612 -406.435052) (xy 205.45298 -406.665684) (xy 205.446265 -406.673148)
			(xy 205.438686 -406.69172) (xy 205.438248 -406.701752) (xy 205.438248 -409.373832) (xy 205.438614 -409.383878)
			(xy 205.446205 -409.402474) (xy 205.45298 -409.4099) (xy 207.000602 -410.957522) (xy 207.008005 -410.964359)
			(xy 207.026602 -410.97208) (xy 207.03667 -410.972508) (xy 213.19109 -410.972508) (xy 213.201162 -410.972102)
			(xy 213.219761 -410.96437) (xy 213.227158 -410.957522) (xy 213.415118 -410.769562) (xy 213.42197 -410.762171)
			(xy 213.429682 -410.743565) (xy 213.430104 -410.733494) (xy 213.430104 -407.793444) (xy 213.430542 -407.773438)
			(xy 213.438277 -407.734183) (xy 213.453535 -407.697197) (xy 213.475729 -407.663906) (xy 213.48954 -407.649426)
			(xy 215.230202 -405.908764) (xy 215.244711 -405.894989) (xy 215.278002 -405.872813) (xy 215.314977 -405.857553)
			(xy 215.354219 -405.849796) (xy 215.37422 -405.849328) (xy 216.096596 -405.849328) (xy 216.108658 -405.848622)
			(xy 216.130133 -405.837628) (xy 216.137744 -405.828246) (xy 216.153161 -405.807725) (xy 216.18866 -405.770653)
			(xy 216.22881 -405.738676) (xy 216.272886 -405.712373) (xy 216.320091 -405.692218) (xy 216.369572 -405.678575)
			(xy 216.420436 -405.671692) (xy 216.4461 -405.671274) (xy 216.47335 -405.671796) (xy 216.527295 -405.679552)
			(xy 216.579587 -405.694907) (xy 216.629162 -405.717547) (xy 216.67501 -405.747012) (xy 216.716199 -405.782701)
			(xy 216.751888 -405.82389) (xy 216.781353 -405.869738) (xy 216.803993 -405.919313) (xy 216.819348 -405.971605)
			(xy 216.827104 -406.02555) (xy 216.827104 -406.08005) (xy 216.819348 -406.133995) (xy 216.803993 -406.186287)
			(xy 216.781353 -406.235862) (xy 216.751888 -406.28171) (xy 216.716199 -406.322899) (xy 216.67501 -406.358588)
			(xy 216.629162 -406.388053) (xy 216.579587 -406.410693) (xy 216.527295 -406.426048) (xy 216.47335 -406.433804)
			(xy 216.4461 -406.43429) (xy 216.43118 -406.434173) (xy 216.401427 -406.431881) (xy 216.386664 -406.429718)
			(xy 216.374472 -406.427686) (xy 216.351612 -406.435052) (xy 216.00668 -406.779984) (xy 215.999965 -406.787448)
			(xy 215.992386 -406.80602) (xy 215.991948 -406.816052) (xy 215.991948 -409.287472) (xy 215.992293 -409.29752)
			(xy 215.999898 -409.316117) (xy 216.00668 -409.32354) (xy 217.48877 -410.80563) (xy 217.496183 -410.812454)
			(xy 217.514772 -410.820182) (xy 217.524838 -410.820616) (xy 224.054924 -410.820616) (xy 224.060512 -410.815028)
			(xy 224.067221 -410.807559) (xy 224.074803 -410.788991) (xy 224.075244 -410.77896) (xy 224.075244 -407.78557)
			(xy 224.075733 -407.765557) (xy 224.08356 -407.726304) (xy 224.098888 -407.689328) (xy 224.121129 -407.65605)
			(xy 224.134934 -407.641552) (xy 225.867722 -405.908764) (xy 225.882222 -405.894979) (xy 225.915516 -405.872805)
			(xy 225.952495 -405.857548) (xy 225.991738 -405.849794) (xy 226.01174 -405.849328) (xy 226.764596 -405.849328)
			(xy 226.776658 -405.848622) (xy 226.798133 -405.837628) (xy 226.805744 -405.828246) (xy 226.821161 -405.807725)
			(xy 226.85666 -405.770653) (xy 226.89681 -405.738676) (xy 226.940886 -405.712373) (xy 226.988091 -405.692218)
			(xy 227.037572 -405.678575) (xy 227.088436 -405.671692) (xy 227.1141 -405.671274) (xy 227.14135 -405.671796)
			(xy 227.195295 -405.679552) (xy 227.247587 -405.694907) (xy 227.297162 -405.717547) (xy 227.34301 -405.747012)
			(xy 227.384199 -405.782701) (xy 227.419888 -405.82389) (xy 227.449353 -405.869738) (xy 227.471993 -405.919313)
			(xy 227.487348 -405.971605) (xy 227.495104 -406.02555) (xy 227.495104 -406.08005) (xy 227.487348 -406.133995)
			(xy 227.471993 -406.186287) (xy 227.449353 -406.235862) (xy 227.419888 -406.28171) (xy 227.384199 -406.322899)
			(xy 227.34301 -406.358588) (xy 227.297162 -406.388053) (xy 227.247587 -406.410693) (xy 227.195295 -406.426048)
			(xy 227.14135 -406.433804) (xy 227.1141 -406.43429) (xy 227.09918 -406.434173) (xy 227.069427 -406.431881)
			(xy 227.054664 -406.429718) (xy 227.042472 -406.427686) (xy 227.019612 -406.435052) (xy 226.67468 -406.779984)
			(xy 226.667965 -406.787448) (xy 226.660386 -406.80602) (xy 226.659948 -406.816052) (xy 226.659948 -408.086653)
			(xy 228.10466 -408.086653) (xy 228.10466 -408.032147) (xy 228.112417 -407.978197) (xy 228.127773 -407.9259)
			(xy 228.150415 -407.87632) (xy 228.179882 -407.830468) (xy 228.215576 -407.789276) (xy 228.256768 -407.753582)
			(xy 228.30262 -407.724115) (xy 228.3522 -407.701473) (xy 228.404497 -407.686117) (xy 228.458447 -407.67836)
			(xy 228.4857 -407.677874) (xy 228.514618 -407.678364) (xy 228.571792 -407.687095) (xy 228.626993 -407.704357)
			(xy 228.678955 -407.729754) (xy 228.726488 -407.762703) (xy 228.768502 -407.802451) (xy 228.78669 -407.82494)
			(xy 228.794254 -407.8337) (xy 228.815011 -407.843883) (xy 228.826568 -407.844498) (xy 228.906832 -407.844498)
			(xy 228.918395 -407.843889) (xy 228.939166 -407.833722) (xy 228.94671 -407.82494) (xy 228.961486 -407.806539)
			(xy 228.994858 -407.77317) (xy 229.013258 -407.758392) (xy 229.022029 -407.750839) (xy 229.032205 -407.730073)
			(xy 229.032816 -407.718514) (xy 229.032816 -407.63825) (xy 229.032211 -407.626687) (xy 229.02204 -407.605916)
			(xy 229.013258 -407.598372) (xy 228.990752 -407.580207) (xy 228.95102 -407.538181) (xy 228.918085 -407.49064)
			(xy 228.892701 -407.438674) (xy 228.875449 -407.383472) (xy 228.866725 -407.326299) (xy 228.866192 -407.297382)
			(xy 228.866661 -407.27013) (xy 228.87442 -407.216182) (xy 228.889777 -407.163887) (xy 228.912421 -407.11431)
			(xy 228.941889 -407.068459) (xy 228.977582 -407.027269) (xy 229.018774 -406.991578) (xy 229.064625 -406.962112)
			(xy 229.114204 -406.939471) (xy 229.1665 -406.924116) (xy 229.220448 -406.91636) (xy 229.2477 -406.915874)
			(xy 229.276618 -406.916364) (xy 229.333792 -406.925095) (xy 229.388993 -406.942357) (xy 229.440955 -406.967754)
			(xy 229.488488 -407.000703) (xy 229.530502 -407.040451) (xy 229.54869 -407.06294) (xy 229.556254 -407.0717)
			(xy 229.577011 -407.081883) (xy 229.588568 -407.082498) (xy 229.668832 -407.082498) (xy 229.680395 -407.081889)
			(xy 229.701166 -407.071722) (xy 229.70871 -407.06294) (xy 229.723486 -407.044539) (xy 229.756858 -407.01117)
			(xy 229.775258 -406.996392) (xy 229.784029 -406.988839) (xy 229.794205 -406.968073) (xy 229.794816 -406.956514)
			(xy 229.794816 -406.87625) (xy 229.794211 -406.864687) (xy 229.78404 -406.843916) (xy 229.775258 -406.836372)
			(xy 229.754457 -406.81964) (xy 229.717327 -406.781284) (xy 229.685905 -406.738127) (xy 229.660807 -406.691011)
			(xy 229.642521 -406.640856) (xy 229.631406 -406.588642) (xy 229.627678 -406.535389) (xy 229.631409 -406.482136)
			(xy 229.642528 -406.429922) (xy 229.660816 -406.379769) (xy 229.685917 -406.332654) (xy 229.717341 -406.289499)
			(xy 229.754474 -406.251145) (xy 229.775258 -406.234392) (xy 229.784029 -406.226839) (xy 229.794205 -406.206073)
			(xy 229.794816 -406.194514) (xy 229.794816 -406.11425) (xy 229.794211 -406.102687) (xy 229.78404 -406.081916)
			(xy 229.775258 -406.074372) (xy 229.754457 -406.05764) (xy 229.717327 -406.019284) (xy 229.685905 -405.976127)
			(xy 229.660807 -405.929011) (xy 229.642521 -405.878856) (xy 229.631406 -405.826642) (xy 229.627678 -405.773389)
			(xy 229.631409 -405.720136) (xy 229.642528 -405.667922) (xy 229.660816 -405.617769) (xy 229.685917 -405.570654)
			(xy 229.717341 -405.527499) (xy 229.754474 -405.489145) (xy 229.775258 -405.472392) (xy 229.784029 -405.464839)
			(xy 229.794205 -405.444073) (xy 229.794816 -405.432514) (xy 229.794816 -405.35225) (xy 229.794211 -405.340687)
			(xy 229.78404 -405.319916) (xy 229.775258 -405.312372) (xy 229.752752 -405.294207) (xy 229.71302 -405.252181)
			(xy 229.680085 -405.20464) (xy 229.654701 -405.152674) (xy 229.637449 -405.097472) (xy 229.628725 -405.040299)
			(xy 229.628192 -405.011382) (xy 229.628661 -404.98413) (xy 229.63642 -404.930182) (xy 229.651777 -404.877887)
			(xy 229.674421 -404.82831) (xy 229.703889 -404.782459) (xy 229.739582 -404.741269) (xy 229.780774 -404.705578)
			(xy 229.826625 -404.676112) (xy 229.876204 -404.653471) (xy 229.9285 -404.638116) (xy 229.982448 -404.63036)
			(xy 230.0097 -404.629874) (xy 230.038618 -404.630364) (xy 230.095792 -404.639095) (xy 230.150993 -404.656357)
			(xy 230.202955 -404.681754) (xy 230.250488 -404.714703) (xy 230.292502 -404.754451) (xy 230.31069 -404.77694)
			(xy 230.318254 -404.7857) (xy 230.339011 -404.795883) (xy 230.350568 -404.796498) (xy 230.430832 -404.796498)
			(xy 230.442395 -404.795889) (xy 230.463166 -404.785722) (xy 230.47071 -404.77694) (xy 230.487463 -404.756157)
			(xy 230.525817 -404.719027) (xy 230.568971 -404.687605) (xy 230.616085 -404.662506) (xy 230.666237 -404.64422)
			(xy 230.718448 -404.633103) (xy 230.7717 -404.629373) (xy 230.824952 -404.633103) (xy 230.877163 -404.64422)
			(xy 230.927315 -404.662506) (xy 230.974429 -404.687605) (xy 231.017583 -404.719027) (xy 231.055937 -404.756157)
			(xy 231.07269 -404.77694) (xy 231.080254 -404.7857) (xy 231.101011 -404.795883) (xy 231.112568 -404.796498)
			(xy 231.192832 -404.796498) (xy 231.204395 -404.795889) (xy 231.225166 -404.785722) (xy 231.23271 -404.77694)
			(xy 231.249463 -404.756157) (xy 231.287817 -404.719027) (xy 231.330971 -404.687605) (xy 231.378085 -404.662506)
			(xy 231.428237 -404.64422) (xy 231.480448 -404.633103) (xy 231.5337 -404.629373) (xy 231.586952 -404.633103)
			(xy 231.639163 -404.64422) (xy 231.689315 -404.662506) (xy 231.736429 -404.687605) (xy 231.779583 -404.719027)
			(xy 231.817937 -404.756157) (xy 231.83469 -404.77694) (xy 231.842254 -404.7857) (xy 231.863011 -404.795883)
			(xy 231.874568 -404.796498) (xy 231.954832 -404.796498) (xy 231.966395 -404.795889) (xy 231.987166 -404.785722)
			(xy 231.99471 -404.77694) (xy 232.011463 -404.756157) (xy 232.049817 -404.719027) (xy 232.092971 -404.687605)
			(xy 232.140085 -404.662506) (xy 232.190237 -404.64422) (xy 232.242448 -404.633103) (xy 232.2957 -404.629373)
			(xy 232.348952 -404.633103) (xy 232.401163 -404.64422) (xy 232.451315 -404.662506) (xy 232.498429 -404.687605)
			(xy 232.541583 -404.719027) (xy 232.579937 -404.756157) (xy 232.59669 -404.77694) (xy 232.604254 -404.7857)
			(xy 232.625011 -404.795883) (xy 232.636568 -404.796498) (xy 232.716832 -404.796498) (xy 232.728395 -404.795889)
			(xy 232.749166 -404.785722) (xy 232.75671 -404.77694) (xy 232.774905 -404.75446) (xy 232.816923 -404.714723)
			(xy 232.864457 -404.681782) (xy 232.916417 -404.656393) (xy 232.971615 -404.639136) (xy 233.028784 -404.630408)
			(xy 233.0577 -404.629874) (xy 233.08495 -404.630378) (xy 233.138897 -404.638134) (xy 233.19119 -404.653488)
			(xy 233.240766 -404.676128) (xy 233.286615 -404.705592) (xy 233.327805 -404.741282) (xy 233.363497 -404.78247)
			(xy 233.392964 -404.828318) (xy 233.415606 -404.877893) (xy 233.430962 -404.930186) (xy 233.438721 -404.984132)
			(xy 233.439208 -405.011382) (xy 233.438712 -405.0403) (xy 233.429983 -405.097474) (xy 233.412723 -405.152675)
			(xy 233.387327 -405.204637) (xy 233.354378 -405.25217) (xy 233.314631 -405.294184) (xy 233.292142 -405.312372)
			(xy 233.283387 -405.31994) (xy 233.273202 -405.340695) (xy 233.272584 -405.35225) (xy 233.272584 -405.432514)
			(xy 233.273152 -405.444082) (xy 233.283349 -405.464852) (xy 233.292142 -405.472392) (xy 233.312907 -405.489167)
			(xy 233.350037 -405.527517) (xy 233.381459 -405.570669) (xy 233.406558 -405.61778) (xy 233.424845 -405.66793)
			(xy 233.435963 -405.72014) (xy 233.439694 -405.773389) (xy 233.435966 -405.826639) (xy 233.424851 -405.878849)
			(xy 233.406567 -405.928999) (xy 233.38147 -405.976112) (xy 233.350052 -406.019266) (xy 233.312924 -406.057619)
			(xy 233.292142 -406.074372) (xy 233.283387 -406.08194) (xy 233.273202 -406.102695) (xy 233.272584 -406.11425)
			(xy 233.272584 -406.194514) (xy 233.273152 -406.206082) (xy 233.283349 -406.226852) (xy 233.292142 -406.234392)
			(xy 233.312907 -406.251167) (xy 233.350037 -406.289517) (xy 233.381459 -406.332669) (xy 233.406558 -406.37978)
			(xy 233.424845 -406.42993) (xy 233.435963 -406.48214) (xy 233.439694 -406.535389) (xy 233.435966 -406.588639)
			(xy 233.424851 -406.640849) (xy 233.406567 -406.690999) (xy 233.38147 -406.738112) (xy 233.350052 -406.781266)
			(xy 233.312924 -406.819619) (xy 233.292142 -406.836372) (xy 233.283387 -406.84394) (xy 233.273202 -406.864695)
			(xy 233.272584 -406.87625) (xy 233.272584 -406.956514) (xy 233.273152 -406.968082) (xy 233.283349 -406.988852)
			(xy 233.292142 -406.996392) (xy 233.31054 -407.011172) (xy 233.343911 -407.044541) (xy 233.35869 -407.06294)
			(xy 233.366254 -407.0717) (xy 233.387011 -407.081883) (xy 233.398568 -407.082498) (xy 233.478832 -407.082498)
			(xy 233.490395 -407.081889) (xy 233.511166 -407.071722) (xy 233.51871 -407.06294) (xy 233.536905 -407.04046)
			(xy 233.578923 -407.000723) (xy 233.626457 -406.967782) (xy 233.678417 -406.942393) (xy 233.733615 -406.925136)
			(xy 233.790784 -406.916408) (xy 233.8197 -406.915874) (xy 233.84695 -406.916378) (xy 233.900897 -406.924134)
			(xy 233.95319 -406.939488) (xy 234.002766 -406.962128) (xy 234.048615 -406.991592) (xy 234.089805 -407.027282)
			(xy 234.125497 -407.06847) (xy 234.154964 -407.114318) (xy 234.177606 -407.163893) (xy 234.192962 -407.216186)
			(xy 234.200721 -407.270132) (xy 234.201208 -407.297382) (xy 234.200712 -407.3263) (xy 234.191983 -407.383474)
			(xy 234.174723 -407.438675) (xy 234.149327 -407.490637) (xy 234.116378 -407.53817) (xy 234.076631 -407.580184)
			(xy 234.054142 -407.598372) (xy 234.045387 -407.60594) (xy 234.035202 -407.626695) (xy 234.034584 -407.63825)
			(xy 234.034584 -407.718514) (xy 234.035152 -407.730082) (xy 234.045349 -407.750852) (xy 234.054142 -407.758392)
			(xy 234.07663 -407.776577) (xy 234.116363 -407.818599) (xy 234.149301 -407.866136) (xy 234.174688 -407.918098)
			(xy 234.191943 -407.973296) (xy 234.200673 -408.030466) (xy 234.201208 -408.059382) (xy 234.200728 -408.086634)
			(xy 234.192973 -408.140585) (xy 234.17762 -408.192882) (xy 234.154979 -408.242462) (xy 234.125513 -408.288316)
			(xy 234.089821 -408.329508) (xy 234.04863 -408.365202) (xy 234.002778 -408.394671) (xy 233.953199 -408.417313)
			(xy 233.900902 -408.43267) (xy 233.846952 -408.440427) (xy 233.8197 -408.44089) (xy 233.790783 -408.440375)
			(xy 233.733611 -408.431646) (xy 233.678412 -408.414388) (xy 233.626451 -408.388995) (xy 233.578917 -408.356051)
			(xy 233.5369 -408.31631) (xy 233.51871 -408.293824) (xy 233.511152 -408.285058) (xy 233.49039 -408.27488)
			(xy 233.478832 -408.274266) (xy 233.398568 -408.274266) (xy 233.387002 -408.274852) (xy 233.366229 -408.285033)
			(xy 233.35869 -408.293824) (xy 233.341937 -408.314607) (xy 233.303583 -408.351737) (xy 233.260429 -408.383159)
			(xy 233.213315 -408.408258) (xy 233.163163 -408.426544) (xy 233.110952 -408.437661) (xy 233.0577 -408.441391)
			(xy 233.004448 -408.437661) (xy 232.952237 -408.426544) (xy 232.902085 -408.408258) (xy 232.854971 -408.383159)
			(xy 232.811817 -408.351737) (xy 232.773463 -408.314607) (xy 232.75671 -408.293824) (xy 232.749152 -408.285058)
			(xy 232.72839 -408.27488) (xy 232.716832 -408.274266) (xy 232.636568 -408.274266) (xy 232.625002 -408.274852)
			(xy 232.604229 -408.285033) (xy 232.59669 -408.293824) (xy 232.579937 -408.314607) (xy 232.541583 -408.351737)
			(xy 232.498429 -408.383159) (xy 232.451315 -408.408258) (xy 232.401163 -408.426544) (xy 232.348952 -408.437661)
			(xy 232.2957 -408.441391) (xy 232.242448 -408.437661) (xy 232.190237 -408.426544) (xy 232.140085 -408.408258)
			(xy 232.092971 -408.383159) (xy 232.049817 -408.351737) (xy 232.011463 -408.314607) (xy 231.99471 -408.293824)
			(xy 231.987152 -408.285058) (xy 231.96639 -408.27488) (xy 231.954832 -408.274266) (xy 231.874568 -408.274266)
			(xy 231.863002 -408.274852) (xy 231.842229 -408.285033) (xy 231.83469 -408.293824) (xy 231.817937 -408.314607)
			(xy 231.779583 -408.351737) (xy 231.736429 -408.383159) (xy 231.689315 -408.408258) (xy 231.639163 -408.426544)
			(xy 231.586952 -408.437661) (xy 231.5337 -408.441391) (xy 231.480448 -408.437661) (xy 231.428237 -408.426544)
			(xy 231.378085 -408.408258) (xy 231.330971 -408.383159) (xy 231.287817 -408.351737) (xy 231.249463 -408.314607)
			(xy 231.23271 -408.293824) (xy 231.225152 -408.285058) (xy 231.20439 -408.27488) (xy 231.192832 -408.274266)
			(xy 231.112568 -408.274266) (xy 231.101002 -408.274852) (xy 231.080229 -408.285033) (xy 231.07269 -408.293824)
			(xy 231.055937 -408.314607) (xy 231.017583 -408.351737) (xy 230.974429 -408.383159) (xy 230.927315 -408.408258)
			(xy 230.877163 -408.426544) (xy 230.824952 -408.437661) (xy 230.7717 -408.441391) (xy 230.718448 -408.437661)
			(xy 230.666237 -408.426544) (xy 230.616085 -408.408258) (xy 230.568971 -408.383159) (xy 230.525817 -408.351737)
			(xy 230.487463 -408.314607) (xy 230.47071 -408.293824) (xy 230.463152 -408.285058) (xy 230.44239 -408.27488)
			(xy 230.430832 -408.274266) (xy 230.350568 -408.274266) (xy 230.339002 -408.274852) (xy 230.318229 -408.285033)
			(xy 230.31069 -408.293824) (xy 230.293937 -408.314607) (xy 230.255583 -408.351737) (xy 230.212429 -408.383159)
			(xy 230.165315 -408.408258) (xy 230.115163 -408.426544) (xy 230.062952 -408.437661) (xy 230.0097 -408.441391)
			(xy 229.956448 -408.437661) (xy 229.904237 -408.426544) (xy 229.854085 -408.408258) (xy 229.806971 -408.383159)
			(xy 229.763817 -408.351737) (xy 229.725463 -408.314607) (xy 229.70871 -408.293824) (xy 229.701152 -408.285058)
			(xy 229.68039 -408.27488) (xy 229.668832 -408.274266) (xy 229.588568 -408.274266) (xy 229.577002 -408.274852)
			(xy 229.556229 -408.285033) (xy 229.54869 -408.293824) (xy 229.531937 -408.314607) (xy 229.493583 -408.351737)
			(xy 229.450429 -408.383159) (xy 229.403315 -408.408258) (xy 229.353163 -408.426544) (xy 229.300952 -408.437661)
			(xy 229.2477 -408.441391) (xy 229.194448 -408.437661) (xy 229.142237 -408.426544) (xy 229.092085 -408.408258)
			(xy 229.044971 -408.383159) (xy 229.001817 -408.351737) (xy 228.963463 -408.314607) (xy 228.94671 -408.293824)
			(xy 228.939152 -408.285058) (xy 228.91839 -408.27488) (xy 228.906832 -408.274266) (xy 228.826568 -408.274266)
			(xy 228.815002 -408.274852) (xy 228.794229 -408.285033) (xy 228.78669 -408.293824) (xy 228.768511 -408.316317)
			(xy 228.726488 -408.356051) (xy 228.67895 -408.388988) (xy 228.626987 -408.414374) (xy 228.571787 -408.431629)
			(xy 228.514617 -408.440356) (xy 228.4857 -408.44089) (xy 228.458447 -408.44044) (xy 228.404497 -408.432683)
			(xy 228.3522 -408.417327) (xy 228.30262 -408.394685) (xy 228.256768 -408.365218) (xy 228.215576 -408.329524)
			(xy 228.179882 -408.288332) (xy 228.150415 -408.24248) (xy 228.127773 -408.1929) (xy 228.112417 -408.140603)
			(xy 228.10466 -408.086653) (xy 226.659948 -408.086653) (xy 226.659948 -408.19197) (xy 226.660294 -408.202018)
			(xy 226.667898 -408.220614) (xy 226.67468 -408.228038) (xy 227.252784 -408.806142) (xy 227.260191 -408.812973)
			(xy 227.278785 -408.820697) (xy 227.288852 -408.821128) (xy 234.206288 -408.821128) (xy 234.216359 -408.820715)
			(xy 234.234958 -408.812988) (xy 234.242356 -408.806142) (xy 236.312202 -406.736296) (xy 236.319037 -406.728892)
			(xy 236.326759 -406.710296) (xy 236.327188 -406.700228) (xy 236.327188 -404.15464) (xy 236.327628 -404.134634)
			(xy 236.335363 -404.095379) (xy 236.350621 -404.058393) (xy 236.372814 -404.025103) (xy 236.386624 -404.010622)
			(xy 237.39983 -402.99767) (xy 237.407196 -402.97481) (xy 237.405164 -402.962618) (xy 237.403001 -402.947855)
			(xy 237.400715 -402.918102) (xy 237.400592 -402.903182) (xy 237.401098 -402.875932) (xy 237.408856 -402.821988)
			(xy 237.424213 -402.769697) (xy 237.446855 -402.720124) (xy 237.476321 -402.674277) (xy 237.512012 -402.633091)
			(xy 237.553201 -402.597403) (xy 237.59905 -402.56794) (xy 237.648625 -402.545302) (xy 237.700917 -402.52995)
			(xy 237.754862 -402.522195) (xy 237.809362 -402.522197) (xy 237.863306 -402.529955) (xy 237.915597 -402.54531)
			(xy 237.965171 -402.567952) (xy 238.011018 -402.597417) (xy 238.052205 -402.633108) (xy 238.087893 -402.674296)
			(xy 238.117357 -402.720145) (xy 238.139996 -402.76972) (xy 238.155349 -402.822012) (xy 238.163104 -402.875956)
			(xy 238.163103 -402.930456) (xy 238.155347 -402.9844) (xy 238.139992 -403.036692) (xy 238.117351 -403.086266)
			(xy 238.087886 -403.132113) (xy 238.052196 -403.173301) (xy 238.011008 -403.20899) (xy 237.96516 -403.238454)
			(xy 237.915586 -403.261094) (xy 237.863294 -403.276448) (xy 237.80935 -403.284204) (xy 237.7821 -403.28469)
			(xy 237.76718 -403.284573) (xy 237.737427 -403.282281) (xy 237.722664 -403.280118) (xy 237.710472 -403.278086)
			(xy 237.687612 -403.285452) (xy 236.749082 -404.223982) (xy 236.742255 -404.231392) (xy 236.734528 -404.249984)
			(xy 236.734096 -404.26005) (xy 236.734096 -406.805638) (xy 236.733708 -406.825646) (xy 236.725958 -406.864904)
			(xy 236.710684 -406.90189) (xy 236.688477 -406.935178) (xy 236.67466 -406.949656) (xy 234.455716 -409.1686)
			(xy 234.44121 -409.182378) (xy 234.407917 -409.204551) (xy 234.37094 -409.219809) (xy 234.331699 -409.227567)
			(xy 234.311698 -409.228036) (xy 227.183442 -409.228036) (xy 227.163437 -409.227588) (xy 227.124182 -409.219854)
			(xy 227.087197 -409.204598) (xy 227.053906 -409.182408) (xy 227.039424 -409.1686) (xy 226.312222 -408.441398)
			(xy 226.298397 -408.426915) (xy 226.276137 -408.393641) (xy 226.260805 -408.35666) (xy 226.25299 -408.317397)
			(xy 226.252532 -408.29738) (xy 226.252532 -406.710642) (xy 226.253007 -406.690628) (xy 226.260839 -406.651374)
			(xy 226.276171 -406.614399) (xy 226.298416 -406.581122) (xy 226.312222 -406.566624) (xy 226.546918 -406.331928)
			(xy 226.553014 -406.30221) (xy 226.546918 -406.287732) (xy 226.542672 -406.27862) (xy 226.52851 -406.264382)
			(xy 226.509969 -406.256666) (xy 226.499928 -406.256236) (xy 226.11715 -406.256236) (xy 226.107082 -406.256678)
			(xy 226.088484 -406.264386) (xy 226.081082 -406.271222) (xy 224.497392 -407.854912) (xy 224.49071 -407.862402)
			(xy 224.483112 -407.880954) (xy 224.48266 -407.89098) (xy 224.48266 -410.88437) (xy 224.482194 -410.904384)
			(xy 224.47436 -410.943639) (xy 224.459025 -410.980614) (xy 224.436778 -411.013891) (xy 224.42297 -411.028388)
			(xy 224.28327 -411.168088) (xy 224.268781 -411.181885) (xy 224.235483 -411.204055) (xy 224.198501 -411.219309)
			(xy 224.159255 -411.227059) (xy 224.139252 -411.227524) (xy 217.419428 -411.227524) (xy 217.399422 -411.227088)
			(xy 217.360167 -411.219351) (xy 217.323181 -411.204092) (xy 217.289891 -411.181898) (xy 217.27541 -411.168088)
			(xy 215.644222 -409.5369) (xy 215.630398 -409.522416) (xy 215.608138 -409.489142) (xy 215.592805 -409.452162)
			(xy 215.58499 -409.412899) (xy 215.584532 -409.392882) (xy 215.584532 -406.710642) (xy 215.585007 -406.690628)
			(xy 215.592839 -406.651374) (xy 215.608171 -406.614399) (xy 215.630416 -406.581122) (xy 215.644222 -406.566624)
			(xy 215.878918 -406.331928) (xy 215.885014 -406.30221) (xy 215.878918 -406.287732) (xy 215.874672 -406.27862)
			(xy 215.86051 -406.264382) (xy 215.841969 -406.256666) (xy 215.831928 -406.256236) (xy 215.47963 -406.256236)
			(xy 215.469561 -406.256668) (xy 215.450963 -406.264383) (xy 215.443562 -406.271222) (xy 213.851998 -407.862786)
			(xy 213.845171 -407.870197) (xy 213.837444 -407.888788) (xy 213.837012 -407.898854) (xy 213.837012 -410.838904)
			(xy 213.836599 -410.858911) (xy 213.828856 -410.898167) (xy 213.813589 -410.935153) (xy 213.791389 -410.968442)
			(xy 213.777576 -410.982922) (xy 213.440518 -411.31998) (xy 213.426008 -411.333753) (xy 213.392717 -411.355928)
			(xy 213.355741 -411.371188) (xy 213.316501 -411.378947) (xy 213.2965 -411.379416) (xy 206.93126 -411.379416)
			(xy 206.911252 -411.379024) (xy 206.871995 -411.371274) (xy 206.835009 -411.356001) (xy 206.801721 -411.333796)
			(xy 206.787242 -411.31998) (xy 205.090522 -409.62326) (xy 205.076679 -409.608793) (xy 205.054422 -409.575513)
			(xy 205.039095 -409.538527) (xy 205.031286 -409.49926) (xy 205.030832 -409.479242) (xy 205.030832 -406.596342)
			(xy 205.031307 -406.576328) (xy 205.039139 -406.537074) (xy 205.054471 -406.500099) (xy 205.076716 -406.466822)
			(xy 205.090522 -406.452324) (xy 205.210918 -406.331928) (xy 205.217014 -406.30221) (xy 205.210918 -406.287732)
			(xy 205.206672 -406.27862) (xy 205.19251 -406.264382) (xy 205.173969 -406.256666) (xy 205.163928 -406.256236)
			(xy 204.67193 -406.256236) (xy 204.661861 -406.256668) (xy 204.643263 -406.264383) (xy 204.635862 -406.271222)
			(xy 203.23302 -407.674064) (xy 203.226305 -407.681528) (xy 203.218729 -407.700101) (xy 203.218288 -407.710132)
			(xy 203.218288 -410.096462) (xy 203.217809 -410.116475) (xy 203.209978 -410.155729) (xy 203.194646 -410.192704)
			(xy 203.172403 -410.225982) (xy 203.158598 -410.24048) (xy 202.160378 -411.2387) (xy 202.145888 -411.252496)
			(xy 202.112589 -411.274665) (xy 202.075608 -411.289919) (xy 202.036362 -411.297671) (xy 202.01636 -411.298136)
			(xy 195.18376 -411.298136) (xy 195.163752 -411.297738) (xy 195.124496 -411.289989) (xy 195.08751 -411.274718)
			(xy 195.054222 -411.252514) (xy 195.039742 -411.2387) (xy 193.946272 -410.14523) (xy 193.932513 -410.130706)
			(xy 193.910334 -410.097421) (xy 193.89507 -410.06045) (xy 193.887307 -410.021212) (xy 193.886836 -410.001212)
			(xy 193.886836 -405.033226) (xy 193.886414 -405.023156) (xy 193.878693 -405.004557) (xy 193.87185 -404.997158)
			(xy 193.742564 -404.867872) (xy 193.735084 -404.861177) (xy 193.716524 -404.853587) (xy 193.706496 -404.85314)
			(xy 193.549016 -404.85314) (xy 193.539493 -404.853526) (xy 193.521766 -404.860493) (xy 193.507796 -404.87344)
			(xy 193.503296 -404.881842) (xy 193.457322 -404.9776) (xy 193.460624 -405.00681) (xy 193.469768 -405.01824)
			(xy 193.485611 -405.038622) (xy 193.5122 -405.082872) (xy 193.532588 -405.130299) (xy 193.546404 -405.18004)
			(xy 193.553396 -405.231188) (xy 193.553842 -405.257) (xy 193.553436 -405.282665) (xy 193.546561 -405.333531)
			(xy 193.532921 -405.383015) (xy 193.512764 -405.43022) (xy 193.486453 -405.474293) (xy 193.454466 -405.514436)
			(xy 193.41738 -405.549923) (xy 193.39687 -405.565356) (xy 193.387483 -405.572969) (xy 193.376467 -405.594439)
			(xy 193.375788 -405.606504) (xy 193.375788 -410.108146) (xy 193.376218 -410.118215) (xy 193.383933 -410.136814)
			(xy 193.390774 -410.144214) (xy 194.760342 -411.513782) (xy 194.767736 -411.520631) (xy 194.78634 -411.528346)
			(xy 194.79641 -411.528768) (xy 202.63485 -411.528768) (xy 202.644917 -411.528325) (xy 202.663516 -411.520617)
			(xy 202.670918 -411.513782) (xy 203.52766 -410.65704) (xy 203.53437 -410.649572) (xy 203.54195 -410.631003)
			(xy 203.542392 -410.620972) (xy 203.542392 -408.434286) (xy 203.5417 -408.422262) (xy 203.530857 -408.400796)
			(xy 203.521564 -408.393138) (xy 203.497724 -408.375012) (xy 203.455405 -408.332645) (xy 203.420227 -408.284184)
			(xy 203.393054 -408.230822) (xy 203.374555 -408.173868) (xy 203.365184 -408.114723) (xy 203.364592 -408.084782)
			(xy 203.365078 -408.057531) (xy 203.372834 -408.003583) (xy 203.388189 -407.951288) (xy 203.410831 -407.901711)
			(xy 203.440297 -407.855861) (xy 203.475988 -407.81467) (xy 203.517179 -407.778979) (xy 203.563029 -407.749513)
			(xy 203.612606 -407.726871) (xy 203.664901 -407.711516) (xy 203.718849 -407.70376) (xy 203.773351 -407.70376)
			(xy 203.827299 -407.711516) (xy 203.879594 -407.726871) (xy 203.929171 -407.749513) (xy 203.975021 -407.778979)
			(xy 204.016212 -407.81467) (xy 204.051903 -407.855861) (xy 204.081369 -407.901711) (xy 204.104011 -407.951288)
			(xy 204.119366 -408.003583) (xy 204.127122 -408.057531) (xy 204.127608 -408.084782) (xy 204.127203 -408.110447)
			(xy 204.120329 -408.161314) (xy 204.10669 -408.210798) (xy 204.086533 -408.258004) (xy 204.060222 -408.302077)
			(xy 204.028234 -408.34222) (xy 203.991147 -408.377706) (xy 203.970636 -408.393138) (xy 203.961264 -408.400733)
			(xy 203.9504 -408.422236) (xy 203.949808 -408.434286) (xy 203.949808 -410.620972) (xy 203.950163 -410.631019)
			(xy 203.957762 -410.649615) (xy 203.96454 -410.65704) (xy 204.795882 -411.488382) (xy 204.803296 -411.495204)
			(xy 204.821885 -411.502935) (xy 204.83195 -411.503368) (xy 213.55431 -411.503368) (xy 213.564381 -411.502956)
			(xy 213.582979 -411.495227) (xy 213.590378 -411.488382) (xy 214.19566 -410.8831) (xy 214.202344 -410.875612)
			(xy 214.209939 -410.857058) (xy 214.210392 -410.847032) (xy 214.210392 -408.434286) (xy 214.2097 -408.422262)
			(xy 214.198857 -408.400796) (xy 214.189564 -408.393138) (xy 214.165724 -408.375012) (xy 214.123405 -408.332645)
			(xy 214.088227 -408.284184) (xy 214.061054 -408.230822) (xy 214.042555 -408.173868) (xy 214.033184 -408.114723)
			(xy 214.032592 -408.084782) (xy 214.033078 -408.057531) (xy 214.040834 -408.003583) (xy 214.056189 -407.951288)
			(xy 214.078831 -407.901711) (xy 214.108297 -407.855861) (xy 214.143988 -407.81467) (xy 214.185179 -407.778979)
			(xy 214.231029 -407.749513) (xy 214.280606 -407.726871) (xy 214.332901 -407.711516) (xy 214.386849 -407.70376)
			(xy 214.441351 -407.70376) (xy 214.495299 -407.711516) (xy 214.547594 -407.726871) (xy 214.597171 -407.749513)
			(xy 214.643021 -407.778979) (xy 214.684212 -407.81467) (xy 214.719903 -407.855861) (xy 214.749369 -407.901711)
			(xy 214.772011 -407.951288) (xy 214.787366 -408.003583) (xy 214.795122 -408.057531) (xy 214.795608 -408.084782)
			(xy 214.795203 -408.110447) (xy 214.788329 -408.161314) (xy 214.77469 -408.210798) (xy 214.754533 -408.258004)
			(xy 214.728222 -408.302077) (xy 214.696234 -408.34222) (xy 214.659147 -408.377706) (xy 214.638636 -408.393138)
			(xy 214.629264 -408.400733) (xy 214.6184 -408.422236) (xy 214.617808 -408.434286) (xy 214.617808 -410.847032)
			(xy 214.618184 -410.857077) (xy 214.625769 -410.875673) (xy 214.63254 -410.8831) (xy 215.260682 -411.511242)
			(xy 215.268089 -411.518073) (xy 215.286683 -411.525797) (xy 215.29675 -411.526228) (xy 224.16135 -411.526228)
			(xy 224.171419 -411.525795) (xy 224.190018 -411.518082) (xy 224.197418 -411.511242) (xy 224.86366 -410.845)
			(xy 224.870344 -410.837512) (xy 224.877939 -410.818958) (xy 224.878392 -410.808932) (xy 224.878392 -408.434286)
			(xy 224.8777 -408.422262) (xy 224.866857 -408.400796) (xy 224.857564 -408.393138) (xy 224.833724 -408.375012)
			(xy 224.791405 -408.332645) (xy 224.756227 -408.284184) (xy 224.729054 -408.230822) (xy 224.710555 -408.173868)
			(xy 224.701184 -408.114723) (xy 224.700592 -408.084782) (xy 224.701078 -408.057531) (xy 224.708834 -408.003583)
			(xy 224.724189 -407.951288) (xy 224.746831 -407.901711) (xy 224.776297 -407.855861) (xy 224.811988 -407.81467)
			(xy 224.853179 -407.778979) (xy 224.899029 -407.749513) (xy 224.948606 -407.726871) (xy 225.000901 -407.711516)
			(xy 225.054849 -407.70376) (xy 225.109351 -407.70376) (xy 225.163299 -407.711516) (xy 225.215594 -407.726871)
			(xy 225.265171 -407.749513) (xy 225.311021 -407.778979) (xy 225.352212 -407.81467) (xy 225.387903 -407.855861)
			(xy 225.417369 -407.901711) (xy 225.440011 -407.951288) (xy 225.455366 -408.003583) (xy 225.463122 -408.057531)
			(xy 225.463608 -408.084782) (xy 225.463203 -408.110447) (xy 225.456329 -408.161314) (xy 225.44269 -408.210798)
			(xy 225.422533 -408.258004) (xy 225.396222 -408.302077) (xy 225.364234 -408.34222) (xy 225.327147 -408.377706)
			(xy 225.306636 -408.393138) (xy 225.297264 -408.400733) (xy 225.2864 -408.422236) (xy 225.285808 -408.434286)
			(xy 225.285808 -410.914342) (xy 225.285312 -410.934354) (xy 225.277484 -410.973607) (xy 225.262158 -411.010581)
			(xy 225.239921 -411.043861) (xy 225.226118 -411.05836) (xy 224.410778 -411.8737) (xy 224.396288 -411.887496)
			(xy 224.362989 -411.909665) (xy 224.326008 -411.924919) (xy 224.286762 -411.932671) (xy 224.26676 -411.933136)
			(xy 215.19134 -411.933136) (xy 215.171335 -411.932689) (xy 215.13208 -411.924955) (xy 215.095095 -411.909699)
			(xy 215.061804 -411.887508) (xy 215.047322 -411.8737) (xy 214.449914 -411.276292) (xy 214.442553 -411.269523)
			(xy 214.424091 -411.261876) (xy 214.404109 -411.261876) (xy 214.385647 -411.269523) (xy 214.378286 -411.276292)
			(xy 213.803738 -411.85084) (xy 213.789213 -411.864597) (xy 213.755928 -411.886777) (xy 213.718957 -411.902041)
			(xy 213.679719 -411.909805) (xy 213.65972 -411.910276) (xy 204.72654 -411.910276) (xy 204.706535 -411.909818)
			(xy 204.667282 -411.902085) (xy 204.630297 -411.886832) (xy 204.597005 -411.864646) (xy 204.582522 -411.85084)
			(xy 203.781914 -411.050232) (xy 203.774553 -411.043463) (xy 203.756091 -411.035816) (xy 203.736109 -411.035816)
			(xy 203.717647 -411.043463) (xy 203.710286 -411.050232) (xy 202.884278 -411.87624) (xy 202.869779 -411.890026)
			(xy 202.836484 -411.9122) (xy 202.799506 -411.927457) (xy 202.760262 -411.935211) (xy 202.74026 -411.935676)
			(xy 194.691 -411.935676) (xy 194.670994 -411.935242) (xy 194.63174 -411.927502) (xy 194.594755 -411.912242)
			(xy 194.561464 -411.890049) (xy 194.546982 -411.87624) (xy 193.028316 -410.357574) (xy 193.014521 -410.343083)
			(xy 192.992351 -410.309785) (xy 192.977097 -410.272804) (xy 192.969345 -410.233558) (xy 192.96888 -410.213556)
			(xy 192.96888 -405.606504) (xy 192.968154 -405.594446) (xy 192.957173 -405.572971) (xy 192.947798 -405.565356)
			(xy 192.927506 -405.550082) (xy 192.89077 -405.515008) (xy 192.859009 -405.475374) (xy 192.832783 -405.431878)
			(xy 192.812556 -405.385289) (xy 192.798684 -405.33643) (xy 192.794636 -405.311356) (xy 192.792604 -405.296878)
			(xy 192.774316 -405.275034) (xy 192.67424 -405.24176) (xy 192.665222 -405.239199) (xy 192.646511 -405.240101)
			(xy 192.629368 -405.247652) (xy 192.622424 -405.253952) (xy 192.531238 -405.345138) (xy 192.516774 -405.358985)
			(xy 192.483494 -405.381242) (xy 192.446507 -405.39657) (xy 192.407239 -405.404376) (xy 192.38722 -405.404828)
			(xy 191.12738 -405.404828) (xy 191.107369 -405.404312) (xy 191.068118 -405.39649) (xy 191.031143 -405.38117)
			(xy 190.997862 -405.358938) (xy 190.983362 -405.345138) (xy 190.790322 -405.152098) (xy 190.776497 -405.137615)
			(xy 190.754237 -405.104341) (xy 190.738905 -405.06736) (xy 190.73109 -405.028097) (xy 190.730632 -405.00808)
			(xy 190.730632 -404.70201) (xy 190.730092 -404.692057) (xy 190.722437 -404.673676) (xy 190.708384 -404.65957)
			(xy 190.69939 -404.655274) (xy 190.598298 -404.61311) (xy 190.56858 -404.618952) (xy 190.557404 -404.630128)
			(xy 190.535837 -404.650805) (xy 190.487427 -404.685818) (xy 190.434149 -404.712852) (xy 190.377306 -404.731247)
			(xy 190.318291 -404.740552) (xy 190.288418 -404.741126) (xy 190.261168 -404.740605) (xy 190.207223 -404.732851)
			(xy 190.15493 -404.7175) (xy 190.105354 -404.694862) (xy 190.059504 -404.665399) (xy 190.018314 -404.629711)
			(xy 189.982622 -404.588525) (xy 189.953155 -404.542678) (xy 189.930513 -404.493104) (xy 189.915156 -404.440813)
			(xy 189.907398 -404.386868) (xy 189.90691 -404.359618) (xy 189.907356 -404.332561) (xy 189.915001 -404.278989)
			(xy 189.930138 -404.227034) (xy 189.952465 -404.17774) (xy 189.981533 -404.132096) (xy 190.01676 -404.091017)
			(xy 190.057437 -404.055328) (xy 190.10275 -404.025745) (xy 190.151788 -404.002861) (xy 190.203568 -403.987137)
			(xy 190.25705 -403.978887) (xy 190.2841 -403.97811) (xy 190.29934 -403.977856) (xy 190.32474 -403.960838)
			(xy 190.365888 -403.859746) (xy 190.369282 -403.850345) (xy 190.369226 -403.830374) (xy 190.361511 -403.811953)
			(xy 190.354712 -403.804628) (xy 190.102236 -403.552152) (xy 190.060834 -403.552152) (xy 190.045594 -403.566884)
			(xy 190.02409 -403.587211) (xy 189.975932 -403.621591) (xy 189.923042 -403.648123) (xy 189.866689 -403.666169)
			(xy 189.808226 -403.675297) (xy 189.77864 -403.67585) (xy 189.751392 -403.675285) (xy 189.697449 -403.667535)
			(xy 189.645158 -403.652187) (xy 189.595584 -403.629553) (xy 189.549736 -403.600095) (xy 189.508546 -403.564412)
			(xy 189.472854 -403.52323) (xy 189.443386 -403.477388) (xy 189.420742 -403.427819) (xy 189.405383 -403.375531)
			(xy 189.397621 -403.32159) (xy 189.397132 -403.294342) (xy 189.397386 -403.278086) (xy 189.398148 -403.262338)
			(xy 189.381638 -403.235922) (xy 189.280546 -403.191472) (xy 189.27104 -403.187749) (xy 189.250643 -403.187409)
			(xy 189.231717 -403.195022) (xy 189.224158 -403.201886) (xy 188.216032 -404.210012) (xy 188.197961 -404.227295)
			(xy 188.156407 -404.2551) (xy 188.110229 -404.274265) (xy 188.061198 -404.284056) (xy 188.0362 -404.284688)
			(xy 181.439312 -404.284688) (xy 181.429262 -404.285014) (xy 181.410665 -404.292631) (xy 181.403244 -404.29942)
			(xy 181.206648 -404.496016) (xy 181.188571 -404.513292) (xy 181.147019 -404.541098) (xy 181.100842 -404.560265)
			(xy 181.051814 -404.570059) (xy 181.026816 -404.570692) (xy 179.907184 -404.570692) (xy 179.882188 -404.570061)
			(xy 179.833165 -404.560255) (xy 179.786995 -404.541079) (xy 179.745449 -404.513271) (xy 179.727352 -404.496016)
			(xy 178.979576 -403.74824) (xy 178.972096 -403.741545) (xy 178.953536 -403.733956) (xy 178.943508 -403.733508)
			(xy 177.97907 -403.733508) (xy 177.969098 -403.73394) (xy 177.950661 -403.741545) (xy 177.943256 -403.74824)
			(xy 177.94224 -403.749256) (xy 177.935567 -403.756672) (xy 177.927988 -403.775105) (xy 177.927508 -403.78507)
			(xy 177.927508 -404.089616) (xy 177.927893 -404.09966) (xy 177.935471 -404.118256) (xy 177.94224 -404.125684)
			(xy 178.562 -404.745444) (xy 178.57927 -404.763527) (xy 178.607077 -404.805076) (xy 178.626247 -404.851251)
			(xy 178.636042 -404.900279) (xy 178.636676 -404.925276) (xy 178.636676 -405.059134) (xy 179.916326 -405.059134)
			(xy 179.920397 -405.003512) (xy 179.932523 -404.949075) (xy 179.952446 -404.896984) (xy 179.979742 -404.848349)
			(xy 180.013828 -404.804206) (xy 180.053977 -404.765497) (xy 180.099335 -404.733046) (xy 180.148935 -404.707545)
			(xy 180.201719 -404.689538) (xy 180.256562 -404.679408) (xy 180.312296 -404.677371) (xy 180.367733 -404.683471)
			(xy 180.42169 -404.697577) (xy 180.473019 -404.719389) (xy 180.520625 -404.748443) (xy 180.563493 -404.784118)
			(xy 180.60071 -404.825655) (xy 180.631483 -404.872168) (xy 180.655155 -404.922665) (xy 180.671223 -404.976072)
			(xy 180.679343 -405.031248) (xy 180.679657 -405.048466) (xy 181.06847 -405.048466) (xy 181.072541 -404.992844)
			(xy 181.084667 -404.938407) (xy 181.10459 -404.886316) (xy 181.131886 -404.837681) (xy 181.165972 -404.793538)
			(xy 181.206121 -404.754829) (xy 181.251479 -404.722378) (xy 181.301079 -404.696877) (xy 181.353863 -404.67887)
			(xy 181.408706 -404.66874) (xy 181.46444 -404.666703) (xy 181.519877 -404.672803) (xy 181.573834 -404.686909)
			(xy 181.625163 -404.708721) (xy 181.672769 -404.737775) (xy 181.715637 -404.77345) (xy 181.752854 -404.814987)
			(xy 181.783627 -404.8615) (xy 181.807299 -404.911997) (xy 181.823367 -404.965404) (xy 181.831487 -405.02058)
			(xy 181.831996 -405.048466) (xy 181.831487 -405.076352) (xy 181.823367 -405.131528) (xy 181.807299 -405.184935)
			(xy 181.794592 -405.212042) (xy 183.409842 -405.212042) (xy 183.413913 -405.15642) (xy 183.426039 -405.101983)
			(xy 183.445962 -405.049892) (xy 183.473258 -405.001257) (xy 183.507344 -404.957114) (xy 183.547493 -404.918405)
			(xy 183.592851 -404.885954) (xy 183.642451 -404.860453) (xy 183.695235 -404.842446) (xy 183.750078 -404.832316)
			(xy 183.805812 -404.830279) (xy 183.861249 -404.836379) (xy 183.915206 -404.850485) (xy 183.966535 -404.872297)
			(xy 184.014141 -404.901351) (xy 184.057009 -404.937026) (xy 184.094226 -404.978563) (xy 184.124999 -405.025076)
			(xy 184.148671 -405.075573) (xy 184.164739 -405.12898) (xy 184.172859 -405.184156) (xy 184.173368 -405.212042)
			(xy 184.172859 -405.239928) (xy 184.164739 -405.295104) (xy 184.148671 -405.348511) (xy 184.124999 -405.399008)
			(xy 184.094226 -405.445521) (xy 184.057009 -405.487058) (xy 184.014141 -405.522733) (xy 183.966535 -405.551787)
			(xy 183.915206 -405.573599) (xy 183.861249 -405.587705) (xy 183.805812 -405.593805) (xy 183.750078 -405.591768)
			(xy 183.695235 -405.581638) (xy 183.642451 -405.563631) (xy 183.592851 -405.53813) (xy 183.547493 -405.505679)
			(xy 183.507344 -405.46697) (xy 183.473258 -405.422827) (xy 183.445962 -405.374192) (xy 183.426039 -405.322101)
			(xy 183.413913 -405.267664) (xy 183.409842 -405.212042) (xy 181.794592 -405.212042) (xy 181.783627 -405.235432)
			(xy 181.752854 -405.281945) (xy 181.715637 -405.323482) (xy 181.672769 -405.359157) (xy 181.625163 -405.388211)
			(xy 181.573834 -405.410023) (xy 181.519877 -405.424129) (xy 181.46444 -405.430229) (xy 181.408706 -405.428192)
			(xy 181.353863 -405.418062) (xy 181.301079 -405.400055) (xy 181.251479 -405.374554) (xy 181.206121 -405.342103)
			(xy 181.165972 -405.303394) (xy 181.131886 -405.259251) (xy 181.10459 -405.210616) (xy 181.084667 -405.158525)
			(xy 181.072541 -405.104088) (xy 181.06847 -405.048466) (xy 180.679657 -405.048466) (xy 180.679852 -405.059134)
			(xy 180.679343 -405.08702) (xy 180.671223 -405.142196) (xy 180.655155 -405.195603) (xy 180.631483 -405.2461)
			(xy 180.60071 -405.292613) (xy 180.563493 -405.33415) (xy 180.520625 -405.369825) (xy 180.473019 -405.398879)
			(xy 180.42169 -405.420691) (xy 180.367733 -405.434797) (xy 180.312296 -405.440897) (xy 180.256562 -405.43886)
			(xy 180.201719 -405.42873) (xy 180.148935 -405.410723) (xy 180.099335 -405.385222) (xy 180.053977 -405.352771)
			(xy 180.013828 -405.314062) (xy 179.979742 -405.269919) (xy 179.952446 -405.221284) (xy 179.932523 -405.169193)
			(xy 179.920397 -405.114756) (xy 179.916326 -405.059134) (xy 178.636676 -405.059134) (xy 178.636676 -405.676608)
			(xy 182.21655 -405.676608) (xy 182.220621 -405.620986) (xy 182.232747 -405.566549) (xy 182.25267 -405.514458)
			(xy 182.279966 -405.465823) (xy 182.314052 -405.42168) (xy 182.354201 -405.382971) (xy 182.399559 -405.35052)
			(xy 182.449159 -405.325019) (xy 182.501943 -405.307012) (xy 182.556786 -405.296882) (xy 182.61252 -405.294845)
			(xy 182.667957 -405.300945) (xy 182.721914 -405.315051) (xy 182.773243 -405.336863) (xy 182.820849 -405.365917)
			(xy 182.863717 -405.401592) (xy 182.900934 -405.443129) (xy 182.931707 -405.489642) (xy 182.955379 -405.540139)
			(xy 182.971447 -405.593546) (xy 182.979567 -405.648722) (xy 182.980076 -405.676608) (xy 182.979567 -405.704494)
			(xy 182.972046 -405.755601) (xy 185.291488 -405.755601) (xy 185.295218 -405.70235) (xy 185.306334 -405.650139)
			(xy 185.32462 -405.599987) (xy 185.349718 -405.552874) (xy 185.381138 -405.509719) (xy 185.418268 -405.471366)
			(xy 185.43905 -405.454612) (xy 185.447811 -405.447049) (xy 185.457993 -405.426291) (xy 185.458608 -405.414734)
			(xy 185.458608 -405.33447) (xy 185.457994 -405.322908) (xy 185.44783 -405.302137) (xy 185.43905 -405.294592)
			(xy 185.416552 -405.276418) (xy 185.37682 -405.234393) (xy 185.343884 -405.186854) (xy 185.318499 -405.13489)
			(xy 185.301245 -405.07969) (xy 185.292518 -405.022519) (xy 185.291984 -404.993602) (xy 185.29248 -404.966351)
			(xy 185.300236 -404.912404) (xy 185.31559 -404.86011) (xy 185.33823 -404.810533) (xy 185.367696 -404.764683)
			(xy 185.403386 -404.723493) (xy 185.444575 -404.687802) (xy 185.490425 -404.658335) (xy 185.540001 -404.635694)
			(xy 185.592294 -404.620338) (xy 185.646241 -404.61258) (xy 185.673492 -404.612094) (xy 185.70241 -404.612582)
			(xy 185.759585 -404.621313) (xy 185.814786 -404.638574) (xy 185.866748 -404.663971) (xy 185.914281 -404.696922)
			(xy 185.956294 -404.736671) (xy 185.974482 -404.75916) (xy 185.982046 -404.767919) (xy 186.002803 -404.778102)
			(xy 186.01436 -404.778718) (xy 186.094624 -404.778718) (xy 186.106185 -404.778098) (xy 186.126956 -404.767938)
			(xy 186.134502 -404.75916) (xy 186.151255 -404.738377) (xy 186.189609 -404.701247) (xy 186.232763 -404.669825)
			(xy 186.279877 -404.644726) (xy 186.330029 -404.62644) (xy 186.38224 -404.615323) (xy 186.435492 -404.611593)
			(xy 186.488744 -404.615323) (xy 186.540955 -404.62644) (xy 186.591107 -404.644726) (xy 186.638221 -404.669825)
			(xy 186.681375 -404.701247) (xy 186.719729 -404.738377) (xy 186.736482 -404.75916) (xy 186.744046 -404.767919)
			(xy 186.764803 -404.778102) (xy 186.77636 -404.778718) (xy 186.856624 -404.778718) (xy 186.868185 -404.778098)
			(xy 186.888956 -404.767938) (xy 186.896502 -404.75916) (xy 186.913255 -404.738377) (xy 186.951609 -404.701247)
			(xy 186.994763 -404.669825) (xy 187.041877 -404.644726) (xy 187.092029 -404.62644) (xy 187.14424 -404.615323)
			(xy 187.197492 -404.611593) (xy 187.250744 -404.615323) (xy 187.302955 -404.62644) (xy 187.353107 -404.644726)
			(xy 187.400221 -404.669825) (xy 187.443375 -404.701247) (xy 187.481729 -404.738377) (xy 187.498482 -404.75916)
			(xy 187.506046 -404.767919) (xy 187.526803 -404.778102) (xy 187.53836 -404.778718) (xy 187.618624 -404.778718)
			(xy 187.630185 -404.778098) (xy 187.650956 -404.767938) (xy 187.658502 -404.75916) (xy 187.675255 -404.738377)
			(xy 187.713609 -404.701247) (xy 187.756763 -404.669825) (xy 187.803877 -404.644726) (xy 187.854029 -404.62644)
			(xy 187.90624 -404.615323) (xy 187.959492 -404.611593) (xy 188.012744 -404.615323) (xy 188.064955 -404.62644)
			(xy 188.115107 -404.644726) (xy 188.162221 -404.669825) (xy 188.205375 -404.701247) (xy 188.243729 -404.738377)
			(xy 188.260482 -404.75916) (xy 188.268046 -404.767919) (xy 188.288803 -404.778102) (xy 188.30036 -404.778718)
			(xy 188.380624 -404.778718) (xy 188.392185 -404.778098) (xy 188.412956 -404.767938) (xy 188.420502 -404.75916)
			(xy 188.437255 -404.738377) (xy 188.475609 -404.701247) (xy 188.518763 -404.669825) (xy 188.565877 -404.644726)
			(xy 188.616029 -404.62644) (xy 188.66824 -404.615323) (xy 188.721492 -404.611593) (xy 188.774744 -404.615323)
			(xy 188.826955 -404.62644) (xy 188.877107 -404.644726) (xy 188.924221 -404.669825) (xy 188.967375 -404.701247)
			(xy 189.005729 -404.738377) (xy 189.022482 -404.75916) (xy 189.030046 -404.767919) (xy 189.050803 -404.778102)
			(xy 189.06236 -404.778718) (xy 189.142624 -404.778718) (xy 189.154185 -404.778098) (xy 189.174956 -404.767938)
			(xy 189.182502 -404.75916) (xy 189.200682 -404.736667) (xy 189.242705 -404.696934) (xy 189.290243 -404.663998)
			(xy 189.342206 -404.638611) (xy 189.397405 -404.621357) (xy 189.454576 -404.612629) (xy 189.483492 -404.612094)
			(xy 189.510745 -404.612563) (xy 189.564696 -404.620319) (xy 189.616993 -404.635674) (xy 189.666574 -404.658316)
			(xy 189.712427 -404.687783) (xy 189.75362 -404.723476) (xy 189.789314 -404.764668) (xy 189.818782 -404.810521)
			(xy 189.841424 -404.860101) (xy 189.85678 -404.912399) (xy 189.864537 -404.966349) (xy 189.865 -404.993602)
			(xy 189.864483 -405.022519) (xy 189.855754 -405.07969) (xy 189.838495 -405.134889) (xy 189.813103 -405.186851)
			(xy 189.78016 -405.234385) (xy 189.740419 -405.276402) (xy 189.717934 -405.294592) (xy 189.709169 -405.30215)
			(xy 189.69899 -405.322912) (xy 189.698376 -405.33447) (xy 189.698376 -405.414734) (xy 189.698958 -405.426301)
			(xy 189.709142 -405.447074) (xy 189.717934 -405.454612) (xy 189.738719 -405.471363) (xy 189.77585 -405.509716)
			(xy 189.807272 -405.552871) (xy 189.832372 -405.599985) (xy 189.850658 -405.650137) (xy 189.861775 -405.702349)
			(xy 189.865505 -405.755601) (xy 189.861775 -405.808853) (xy 189.850658 -405.861065) (xy 189.832371 -405.911218)
			(xy 189.807271 -405.958331) (xy 189.775849 -406.001486) (xy 189.738717 -406.039839) (xy 189.717934 -406.056592)
			(xy 189.709169 -406.06415) (xy 189.69899 -406.084912) (xy 189.698376 -406.09647) (xy 189.698376 -406.176734)
			(xy 189.698958 -406.188301) (xy 189.709142 -406.209074) (xy 189.717934 -406.216612) (xy 189.74043 -406.234788)
			(xy 189.780163 -406.276812) (xy 189.8131 -406.32435) (xy 189.838486 -406.376314) (xy 189.855739 -406.431514)
			(xy 189.864466 -406.488685) (xy 189.865 -406.517602) (xy 189.864546 -406.544861) (xy 189.856778 -406.598822)
			(xy 189.841413 -406.65113) (xy 189.818765 -406.700721) (xy 189.789293 -406.746587) (xy 189.753598 -406.787794)
			(xy 189.712404 -406.823505) (xy 189.68974 -406.838658) (xy 189.682774 -406.843511) (xy 189.672253 -406.85682)
			(xy 189.666689 -406.872847) (xy 189.666372 -406.88133) (xy 189.666372 -406.966674) (xy 189.666741 -406.975149)
			(xy 189.672311 -406.99116) (xy 189.682787 -407.004488) (xy 189.68974 -407.009346) (xy 189.712384 -407.024528)
			(xy 189.753582 -407.060229) (xy 189.789281 -407.101429) (xy 189.818753 -407.14729) (xy 189.841398 -407.196878)
			(xy 189.856756 -407.249185) (xy 189.864514 -407.303145) (xy 189.865 -407.330402) (xy 189.864483 -407.359319)
			(xy 189.855754 -407.41649) (xy 189.838495 -407.471689) (xy 189.813103 -407.523651) (xy 189.78016 -407.571185)
			(xy 189.740419 -407.613202) (xy 189.717934 -407.631392) (xy 189.709169 -407.63895) (xy 189.69899 -407.659712)
			(xy 189.698376 -407.67127) (xy 189.698376 -407.751534) (xy 189.698958 -407.763101) (xy 189.709142 -407.783874)
			(xy 189.717934 -407.791412) (xy 189.74043 -407.809588) (xy 189.780163 -407.851612) (xy 189.8131 -407.89915)
			(xy 189.838486 -407.951114) (xy 189.855739 -408.006314) (xy 189.864466 -408.063485) (xy 189.865 -408.092402)
			(xy 189.864546 -408.119655) (xy 189.856789 -408.173607) (xy 189.841432 -408.225905) (xy 189.818789 -408.275486)
			(xy 189.78932 -408.32134) (xy 189.753625 -408.362532) (xy 189.712432 -408.398226) (xy 189.666577 -408.427694)
			(xy 189.616996 -408.450336) (xy 189.564697 -408.465691) (xy 189.510745 -408.473447) (xy 189.483492 -408.47391)
			(xy 189.454576 -408.47336) (xy 189.397405 -408.464642) (xy 189.342205 -408.447393) (xy 189.290242 -408.422007)
			(xy 189.242708 -408.389067) (xy 189.200692 -408.349329) (xy 189.182502 -408.326844) (xy 189.174945 -408.318078)
			(xy 189.154182 -408.307899) (xy 189.142624 -408.307286) (xy 189.06236 -408.307286) (xy 189.050797 -408.307896)
			(xy 189.030026 -408.318063) (xy 189.022482 -408.326844) (xy 189.005729 -408.347627) (xy 188.967375 -408.384757)
			(xy 188.924221 -408.416179) (xy 188.877107 -408.441278) (xy 188.826955 -408.459564) (xy 188.774744 -408.470681)
			(xy 188.721492 -408.474411) (xy 188.66824 -408.470681) (xy 188.616029 -408.459564) (xy 188.565877 -408.441278)
			(xy 188.518763 -408.416179) (xy 188.475609 -408.384757) (xy 188.437255 -408.347627) (xy 188.420502 -408.326844)
			(xy 188.412945 -408.318078) (xy 188.392182 -408.307899) (xy 188.380624 -408.307286) (xy 188.30036 -408.307286)
			(xy 188.288797 -408.307896) (xy 188.268026 -408.318063) (xy 188.260482 -408.326844) (xy 188.243729 -408.347627)
			(xy 188.205375 -408.384757) (xy 188.162221 -408.416179) (xy 188.115107 -408.441278) (xy 188.064955 -408.459564)
			(xy 188.012744 -408.470681) (xy 187.959492 -408.474411) (xy 187.90624 -408.470681) (xy 187.854029 -408.459564)
			(xy 187.803877 -408.441278) (xy 187.756763 -408.416179) (xy 187.713609 -408.384757) (xy 187.675255 -408.347627)
			(xy 187.658502 -408.326844) (xy 187.650945 -408.318078) (xy 187.630182 -408.307899) (xy 187.618624 -408.307286)
			(xy 187.53836 -408.307286) (xy 187.526797 -408.307896) (xy 187.506026 -408.318063) (xy 187.498482 -408.326844)
			(xy 187.481729 -408.347627) (xy 187.443375 -408.384757) (xy 187.400221 -408.416179) (xy 187.353107 -408.441278)
			(xy 187.302955 -408.459564) (xy 187.250744 -408.470681) (xy 187.197492 -408.474411) (xy 187.14424 -408.470681)
			(xy 187.092029 -408.459564) (xy 187.041877 -408.441278) (xy 186.994763 -408.416179) (xy 186.951609 -408.384757)
			(xy 186.913255 -408.347627) (xy 186.896502 -408.326844) (xy 186.888945 -408.318078) (xy 186.868182 -408.307899)
			(xy 186.856624 -408.307286) (xy 186.77636 -408.307286) (xy 186.764797 -408.307896) (xy 186.744026 -408.318063)
			(xy 186.736482 -408.326844) (xy 186.719729 -408.347627) (xy 186.681375 -408.384757) (xy 186.638221 -408.416179)
			(xy 186.591107 -408.441278) (xy 186.540955 -408.459564) (xy 186.488744 -408.470681) (xy 186.435492 -408.474411)
			(xy 186.38224 -408.470681) (xy 186.330029 -408.459564) (xy 186.279877 -408.441278) (xy 186.232763 -408.416179)
			(xy 186.189609 -408.384757) (xy 186.151255 -408.347627) (xy 186.134502 -408.326844) (xy 186.126945 -408.318078)
			(xy 186.106182 -408.307899) (xy 186.094624 -408.307286) (xy 186.01436 -408.307286) (xy 186.002797 -408.307896)
			(xy 185.982026 -408.318063) (xy 185.974482 -408.326844) (xy 185.956312 -408.349345) (xy 185.914287 -408.389077)
			(xy 185.866747 -408.422013) (xy 185.814782 -408.447398) (xy 185.759581 -408.464651) (xy 185.702409 -408.473377)
			(xy 185.673492 -408.47391) (xy 185.646241 -408.47343) (xy 185.592293 -408.465672) (xy 185.539998 -408.450316)
			(xy 185.490421 -408.427674) (xy 185.444571 -408.398207) (xy 185.403381 -408.362515) (xy 185.367689 -408.321324)
			(xy 185.338223 -408.275474) (xy 185.315582 -408.225896) (xy 185.300227 -408.173601) (xy 185.29247 -408.119653)
			(xy 185.291984 -408.092402) (xy 185.292472 -408.063484) (xy 185.301203 -408.00631) (xy 185.318465 -407.951109)
			(xy 185.343862 -407.899146) (xy 185.376812 -407.851614) (xy 185.416561 -407.8096) (xy 185.43905 -407.791412)
			(xy 185.447811 -407.783849) (xy 185.457993 -407.763091) (xy 185.458608 -407.751534) (xy 185.458608 -407.67127)
			(xy 185.457994 -407.659708) (xy 185.44783 -407.638937) (xy 185.43905 -407.631392) (xy 185.416552 -407.613218)
			(xy 185.37682 -407.571193) (xy 185.343884 -407.523654) (xy 185.318499 -407.47169) (xy 185.301245 -407.41649)
			(xy 185.292518 -407.359319) (xy 185.291984 -407.330402) (xy 185.292448 -407.303144) (xy 185.300216 -407.249183)
			(xy 185.315579 -407.196875) (xy 185.338226 -407.147285) (xy 185.367696 -407.101419) (xy 185.403389 -407.060212)
			(xy 185.444581 -407.0245) (xy 185.467244 -407.009346) (xy 185.474205 -407.004486) (xy 185.484728 -406.991181)
			(xy 185.490294 -406.975156) (xy 185.490612 -406.966674) (xy 185.490612 -406.88133) (xy 185.490247 -406.872854)
			(xy 185.484677 -406.856842) (xy 185.474198 -406.843515) (xy 185.467244 -406.838658) (xy 185.444599 -406.823478)
			(xy 185.403401 -406.787777) (xy 185.367703 -406.746576) (xy 185.338231 -406.700715) (xy 185.315586 -406.651126)
			(xy 185.300228 -406.598819) (xy 185.29247 -406.544859) (xy 185.291984 -406.517602) (xy 185.292472 -406.488684)
			(xy 185.301203 -406.43151) (xy 185.318465 -406.376309) (xy 185.343862 -406.324346) (xy 185.376812 -406.276814)
			(xy 185.416561 -406.2348) (xy 185.43905 -406.216612) (xy 185.447811 -406.209049) (xy 185.457993 -406.188291)
			(xy 185.458608 -406.176734) (xy 185.458608 -406.09647) (xy 185.457994 -406.084908) (xy 185.44783 -406.064137)
			(xy 185.43905 -406.056592) (xy 185.418269 -406.039836) (xy 185.38114 -406.001483) (xy 185.349719 -405.958328)
			(xy 185.324621 -405.911215) (xy 185.306335 -405.861063) (xy 185.295218 -405.808852) (xy 185.291488 -405.755601)
			(xy 182.972046 -405.755601) (xy 182.971447 -405.75967) (xy 182.955379 -405.813077) (xy 182.931707 -405.863574)
			(xy 182.900934 -405.910087) (xy 182.863717 -405.951624) (xy 182.820849 -405.987299) (xy 182.773243 -406.016353)
			(xy 182.721914 -406.038165) (xy 182.667957 -406.052271) (xy 182.61252 -406.058371) (xy 182.556786 -406.056334)
			(xy 182.501943 -406.046204) (xy 182.449159 -406.028197) (xy 182.399559 -406.002696) (xy 182.354201 -405.970245)
			(xy 182.314052 -405.931536) (xy 182.279966 -405.887393) (xy 182.25267 -405.838758) (xy 182.232747 -405.786667)
			(xy 182.220621 -405.73223) (xy 182.21655 -405.676608) (xy 178.636676 -405.676608) (xy 178.636676 -406.042368)
			(xy 178.636021 -406.067363) (xy 178.626222 -406.116385) (xy 178.607054 -406.162555) (xy 178.579253 -406.204103)
			(xy 178.562 -406.2222) (xy 178.547268 -406.236932) (xy 184.161682 -406.236932) (xy 184.165753 -406.18131)
			(xy 184.177879 -406.126873) (xy 184.197802 -406.074782) (xy 184.225098 -406.026147) (xy 184.259184 -405.982004)
			(xy 184.299333 -405.943295) (xy 184.344691 -405.910844) (xy 184.394291 -405.885343) (xy 184.447075 -405.867336)
			(xy 184.501918 -405.857206) (xy 184.557652 -405.855169) (xy 184.613089 -405.861269) (xy 184.667046 -405.875375)
			(xy 184.718375 -405.897187) (xy 184.765981 -405.926241) (xy 184.808849 -405.961916) (xy 184.846066 -406.003453)
			(xy 184.876839 -406.049966) (xy 184.900511 -406.100463) (xy 184.916579 -406.15387) (xy 184.924699 -406.209046)
			(xy 184.925208 -406.236932) (xy 184.924699 -406.264818) (xy 184.916579 -406.319994) (xy 184.900511 -406.373401)
			(xy 184.876839 -406.423898) (xy 184.846066 -406.470411) (xy 184.808849 -406.511948) (xy 184.765981 -406.547623)
			(xy 184.718375 -406.576677) (xy 184.667046 -406.598489) (xy 184.613089 -406.612595) (xy 184.557652 -406.618695)
			(xy 184.501918 -406.616658) (xy 184.447075 -406.606528) (xy 184.394291 -406.588521) (xy 184.344691 -406.56302)
			(xy 184.299333 -406.530569) (xy 184.259184 -406.49186) (xy 184.225098 -406.447717) (xy 184.197802 -406.399082)
			(xy 184.177879 -406.346991) (xy 184.165753 -406.292554) (xy 184.161682 -406.236932) (xy 178.547268 -406.236932)
			(xy 178.331368 -406.452832) (xy 178.313295 -406.470116) (xy 178.271746 -406.497934) (xy 178.225568 -406.517112)
			(xy 178.176536 -406.526913) (xy 178.151536 -406.527508) (xy 177.97907 -406.527508) (xy 177.969098 -406.52794)
			(xy 177.950661 -406.535545) (xy 177.943256 -406.54224) (xy 177.921631 -406.563116) (xy 177.873071 -406.598532)
			(xy 177.819555 -406.62589) (xy 177.762411 -406.644515) (xy 177.703052 -406.653944) (xy 177.673 -406.654508)
			(xy 177.645749 -406.654022) (xy 177.591801 -406.646266) (xy 177.539506 -406.630911) (xy 177.489929 -406.608269)
			(xy 177.444079 -406.578803) (xy 177.402888 -406.543112) (xy 177.367197 -406.501921) (xy 177.337731 -406.456071)
			(xy 177.315089 -406.406494) (xy 177.299734 -406.354199) (xy 177.291978 -406.300251) (xy 177.291978 -406.245749)
			(xy 177.299734 -406.191801) (xy 177.315089 -406.139506) (xy 177.337731 -406.089929) (xy 177.367197 -406.044079)
			(xy 177.402888 -406.002888) (xy 177.444079 -405.967197) (xy 177.489929 -405.937731) (xy 177.539506 -405.915089)
			(xy 177.591801 -405.899734) (xy 177.645749 -405.891978) (xy 177.673 -405.891492) (xy 177.703052 -405.892047)
			(xy 177.762411 -405.901484) (xy 177.819557 -405.920109) (xy 177.873077 -405.947462) (xy 177.921648 -405.982867)
			(xy 177.943256 -406.00376) (xy 177.950368 -406.010872) (xy 177.96891 -406.018492) (xy 178.025044 -406.018492)
			(xy 178.035089 -406.018122) (xy 178.053685 -406.010533) (xy 178.061112 -406.00376) (xy 178.112928 -405.951944)
			(xy 178.119632 -405.944471) (xy 178.127217 -405.925906) (xy 178.12766 -405.915876) (xy 178.12766 -405.051768)
			(xy 178.127292 -405.041722) (xy 178.119703 -405.023126) (xy 178.112928 -405.0157) (xy 177.493168 -404.39594)
			(xy 177.475871 -404.377879) (xy 177.448055 -404.336326) (xy 177.428881 -404.290144) (xy 177.419085 -404.241109)
			(xy 177.418492 -404.216108) (xy 177.418492 -403.78507) (xy 177.41806 -403.775098) (xy 177.410455 -403.756661)
			(xy 177.40376 -403.749256) (xy 177.382884 -403.727631) (xy 177.347468 -403.679071) (xy 177.32011 -403.625555)
			(xy 177.301485 -403.568411) (xy 177.292056 -403.509052) (xy 177.291492 -403.479) (xy 177.071528 -403.479)
			(xy 177.071528 -406.70734) (xy 179.80101 -406.70734) (xy 179.805081 -406.651718) (xy 179.817207 -406.597281)
			(xy 179.83713 -406.54519) (xy 179.864426 -406.496555) (xy 179.898512 -406.452412) (xy 179.938661 -406.413703)
			(xy 179.984019 -406.381252) (xy 180.033619 -406.355751) (xy 180.086403 -406.337744) (xy 180.141246 -406.327614)
			(xy 180.19698 -406.325577) (xy 180.252417 -406.331677) (xy 180.306374 -406.345783) (xy 180.357703 -406.367595)
			(xy 180.405309 -406.396649) (xy 180.448177 -406.432324) (xy 180.485394 -406.473861) (xy 180.516167 -406.520374)
			(xy 180.539839 -406.570871) (xy 180.555907 -406.624278) (xy 180.564027 -406.679454) (xy 180.564536 -406.70734)
			(xy 180.564027 -406.735226) (xy 180.555907 -406.790402) (xy 180.539839 -406.843809) (xy 180.516167 -406.894306)
			(xy 180.485394 -406.940819) (xy 180.448177 -406.982356) (xy 180.405309 -407.018031) (xy 180.357703 -407.047085)
			(xy 180.306374 -407.068897) (xy 180.252417 -407.083003) (xy 180.19698 -407.089103) (xy 180.141246 -407.087066)
			(xy 180.086403 -407.076936) (xy 180.033619 -407.058929) (xy 179.984019 -407.033428) (xy 179.938661 -407.000977)
			(xy 179.898512 -406.962268) (xy 179.864426 -406.918125) (xy 179.83713 -406.86949) (xy 179.817207 -406.817399)
			(xy 179.805081 -406.762962) (xy 179.80101 -406.70734) (xy 177.071528 -406.70734) (xy 177.071528 -407.491946)
			(xy 177.070914 -407.519621) (xy 177.061136 -407.574101) (xy 177.041927 -407.626011) (xy 177.013888 -407.673734)
			(xy 176.996344 -407.695146) (xy 176.98339 -407.710386) (xy 176.984914 -407.75001) (xy 177.455068 -408.220164)
			(xy 177.487326 -408.225498) (xy 177.502058 -408.217878) (xy 177.52873 -408.20513) (xy 177.585033 -408.18712)
			(xy 177.643443 -408.178029) (xy 177.673 -408.177492) (xy 177.700251 -408.177978) (xy 177.754199 -408.185734)
			(xy 177.806494 -408.201089) (xy 177.856071 -408.223731) (xy 177.901921 -408.253197) (xy 177.943112 -408.288888)
			(xy 177.944377 -408.290348) (xy 181.939686 -408.290348) (xy 181.939686 -408.235848) (xy 181.947442 -408.181902)
			(xy 181.962797 -408.129608) (xy 181.985438 -408.080033) (xy 182.014903 -408.034184) (xy 182.050593 -407.992995)
			(xy 182.091782 -407.957304) (xy 182.137631 -407.927839) (xy 182.187207 -407.905198) (xy 182.2395 -407.889843)
			(xy 182.293446 -407.882086) (xy 182.347946 -407.882085) (xy 182.401893 -407.889841) (xy 182.454186 -407.905195)
			(xy 182.503762 -407.927835) (xy 182.549611 -407.957299) (xy 182.590801 -407.992989) (xy 182.626492 -408.034177)
			(xy 182.655959 -408.080026) (xy 182.6786 -408.129601) (xy 182.693956 -408.181894) (xy 182.701714 -408.23584)
			(xy 182.7022 -408.26309) (xy 182.701974 -408.281109) (xy 182.698543 -408.316984) (xy 182.695342 -408.334718)
			(xy 182.693056 -408.347418) (xy 182.700676 -408.371802) (xy 182.781448 -408.448764) (xy 182.805832 -408.455622)
			(xy 182.818786 -408.452574) (xy 182.840498 -408.447729) (xy 182.88468 -408.442514) (xy 182.906924 -408.44216)
			(xy 182.934174 -408.442655) (xy 182.98812 -408.450414) (xy 183.040413 -408.465771) (xy 183.089988 -408.488412)
			(xy 183.135837 -408.517878) (xy 183.177026 -408.553569) (xy 183.212717 -408.594757) (xy 183.242184 -408.640605)
			(xy 183.264826 -408.69018) (xy 183.280184 -408.742472) (xy 183.287944 -408.796418) (xy 183.288432 -408.823668)
			(xy 183.28767 -408.845766) (xy 183.286908 -408.859482) (xy 183.299354 -408.883866) (xy 183.396382 -408.946858)
			(xy 183.42356 -408.948382) (xy 183.435752 -408.942032) (xy 183.462926 -408.928675) (xy 183.520445 -408.909769)
			(xy 183.580231 -408.900196) (xy 183.610504 -408.899614) (xy 183.637755 -408.900082) (xy 183.691701 -408.907839)
			(xy 183.743994 -408.923194) (xy 183.79357 -408.945835) (xy 183.839419 -408.9753) (xy 183.880609 -409.010991)
			(xy 183.916299 -409.05218) (xy 183.945765 -409.098029) (xy 183.968406 -409.147605) (xy 183.983761 -409.199898)
			(xy 183.991518 -409.253845) (xy 183.991519 -409.308346) (xy 183.983763 -409.362292) (xy 183.968409 -409.414586)
			(xy 183.945769 -409.464163) (xy 183.916305 -409.510012) (xy 183.880615 -409.551202) (xy 183.839427 -409.586894)
			(xy 183.793578 -409.616361) (xy 183.744003 -409.639003) (xy 183.69171 -409.654359) (xy 183.637764 -409.662117)
			(xy 183.583263 -409.662119) (xy 183.529316 -409.654365) (xy 183.477022 -409.639012) (xy 183.427445 -409.616374)
			(xy 183.381595 -409.58691) (xy 183.340404 -409.551221) (xy 183.304711 -409.510034) (xy 183.275243 -409.464186)
			(xy 183.2526 -409.414611) (xy 183.237243 -409.362319) (xy 183.229483 -409.308373) (xy 183.228996 -409.281122)
			(xy 183.229758 -409.259024) (xy 183.23052 -409.245308) (xy 183.218074 -409.220924) (xy 183.121046 -409.157932)
			(xy 183.093868 -409.156408) (xy 183.081676 -409.162758) (xy 183.054497 -409.176104) (xy 182.99698 -409.195014)
			(xy 182.937197 -409.204592) (xy 182.906924 -409.205176) (xy 182.87967 -409.204722) (xy 182.825717 -409.196968)
			(xy 182.773417 -409.181613) (xy 182.723835 -409.158971) (xy 182.67798 -409.129503) (xy 182.636787 -409.093808)
			(xy 182.601093 -409.052613) (xy 182.571625 -409.006758) (xy 182.548984 -408.957175) (xy 182.533631 -408.904875)
			(xy 182.525877 -408.850922) (xy 182.525416 -408.823668) (xy 182.525638 -408.805649) (xy 182.529072 -408.769774)
			(xy 182.532274 -408.75204) (xy 182.53456 -408.73934) (xy 182.52694 -408.714956) (xy 182.446168 -408.637994)
			(xy 182.421784 -408.631136) (xy 182.40883 -408.634184) (xy 182.387117 -408.639026) (xy 182.342936 -408.644243)
			(xy 182.320692 -408.644598) (xy 182.293442 -408.644114) (xy 182.239496 -408.636356) (xy 182.187203 -408.621001)
			(xy 182.137628 -408.598359) (xy 182.091779 -408.568893) (xy 182.050591 -408.533202) (xy 182.014901 -408.492013)
			(xy 181.985436 -408.446164) (xy 181.962796 -408.396588) (xy 181.947442 -408.344295) (xy 181.939686 -408.290348)
			(xy 177.944377 -408.290348) (xy 177.978803 -408.330079) (xy 178.008269 -408.375929) (xy 178.030911 -408.425506)
			(xy 178.046266 -408.477801) (xy 178.054022 -408.531749) (xy 178.054508 -408.559) (xy 178.053949 -408.588554)
			(xy 178.044839 -408.646957) (xy 178.02685 -408.703263) (xy 178.022847 -408.711654) (xy 179.709062 -408.711654)
			(xy 179.713133 -408.656032) (xy 179.725259 -408.601595) (xy 179.745182 -408.549504) (xy 179.772478 -408.500869)
			(xy 179.806564 -408.456726) (xy 179.846713 -408.418017) (xy 179.892071 -408.385566) (xy 179.941671 -408.360065)
			(xy 179.994455 -408.342058) (xy 180.049298 -408.331928) (xy 180.105032 -408.329891) (xy 180.160469 -408.335991)
			(xy 180.214426 -408.350097) (xy 180.265755 -408.371909) (xy 180.313361 -408.400963) (xy 180.356229 -408.436638)
			(xy 180.393446 -408.478175) (xy 180.424219 -408.524688) (xy 180.447891 -408.575185) (xy 180.463959 -408.628592)
			(xy 180.472079 -408.683768) (xy 180.472588 -408.711654) (xy 180.472079 -408.73954) (xy 180.463959 -408.794716)
			(xy 180.447891 -408.848123) (xy 180.424219 -408.89862) (xy 180.393446 -408.945133) (xy 180.356229 -408.98667)
			(xy 180.340584 -408.99969) (xy 180.902354 -408.99969) (xy 180.906425 -408.944068) (xy 180.918551 -408.889631)
			(xy 180.938474 -408.83754) (xy 180.96577 -408.788905) (xy 180.999856 -408.744762) (xy 181.040005 -408.706053)
			(xy 181.085363 -408.673602) (xy 181.134963 -408.648101) (xy 181.187747 -408.630094) (xy 181.24259 -408.619964)
			(xy 181.298324 -408.617927) (xy 181.353761 -408.624027) (xy 181.407718 -408.638133) (xy 181.459047 -408.659945)
			(xy 181.506653 -408.688999) (xy 181.549521 -408.724674) (xy 181.586738 -408.766211) (xy 181.617511 -408.812724)
			(xy 181.641183 -408.863221) (xy 181.657251 -408.916628) (xy 181.665371 -408.971804) (xy 181.66588 -408.99969)
			(xy 181.665371 -409.027576) (xy 181.657251 -409.082752) (xy 181.641183 -409.136159) (xy 181.617511 -409.186656)
			(xy 181.586738 -409.233169) (xy 181.549521 -409.274706) (xy 181.506653 -409.310381) (xy 181.459047 -409.339435)
			(xy 181.407718 -409.361247) (xy 181.353761 -409.375353) (xy 181.298324 -409.381453) (xy 181.24259 -409.379416)
			(xy 181.187747 -409.369286) (xy 181.134963 -409.351279) (xy 181.085363 -409.325778) (xy 181.040005 -409.293327)
			(xy 180.999856 -409.254618) (xy 180.96577 -409.210475) (xy 180.938474 -409.16184) (xy 180.918551 -409.109749)
			(xy 180.906425 -409.055312) (xy 180.902354 -408.99969) (xy 180.340584 -408.99969) (xy 180.313361 -409.022345)
			(xy 180.265755 -409.051399) (xy 180.214426 -409.073211) (xy 180.160469 -409.087317) (xy 180.105032 -409.093417)
			(xy 180.049298 -409.09138) (xy 179.994455 -409.08125) (xy 179.941671 -409.063243) (xy 179.892071 -409.037742)
			(xy 179.846713 -409.005291) (xy 179.806564 -408.966582) (xy 179.772478 -408.922439) (xy 179.745182 -408.873804)
			(xy 179.725259 -408.821713) (xy 179.713133 -408.767276) (xy 179.709062 -408.711654) (xy 178.022847 -408.711654)
			(xy 178.014122 -408.729942) (xy 178.006502 -408.744674) (xy 178.011836 -408.776932) (xy 178.569874 -409.33497)
			(xy 178.577222 -409.341772) (xy 178.595685 -409.349483) (xy 178.605688 -409.349956) (xy 179.670456 -409.349956)
			(xy 179.695035 -409.350419) (xy 179.743593 -409.358069) (xy 179.790357 -409.37322) (xy 179.834176 -409.395499)
			(xy 179.873971 -409.424357) (xy 179.89169 -409.441396) (xy 179.993798 -409.543504) (xy 181.794148 -409.543504)
			(xy 181.798219 -409.487882) (xy 181.810345 -409.433445) (xy 181.830268 -409.381354) (xy 181.857564 -409.332719)
			(xy 181.89165 -409.288576) (xy 181.931799 -409.249867) (xy 181.977157 -409.217416) (xy 182.026757 -409.191915)
			(xy 182.079541 -409.173908) (xy 182.134384 -409.163778) (xy 182.190118 -409.161741) (xy 182.245555 -409.167841)
			(xy 182.299512 -409.181947) (xy 182.350841 -409.203759) (xy 182.398447 -409.232813) (xy 182.441315 -409.268488)
			(xy 182.478532 -409.310025) (xy 182.509305 -409.356538) (xy 182.532977 -409.407035) (xy 182.549045 -409.460442)
			(xy 182.557165 -409.515618) (xy 182.557674 -409.543504) (xy 182.557165 -409.57139) (xy 182.549045 -409.626566)
			(xy 182.532977 -409.679973) (xy 182.509305 -409.73047) (xy 182.478532 -409.776983) (xy 182.441315 -409.81852)
			(xy 182.398447 -409.854195) (xy 182.350841 -409.883249) (xy 182.299512 -409.905061) (xy 182.245555 -409.919167)
			(xy 182.190118 -409.925267) (xy 182.134384 -409.92323) (xy 182.079541 -409.9131) (xy 182.026757 -409.895093)
			(xy 181.977157 -409.869592) (xy 181.931799 -409.837141) (xy 181.89165 -409.798432) (xy 181.857564 -409.754289)
			(xy 181.830268 -409.705654) (xy 181.810345 -409.653563) (xy 181.798219 -409.599126) (xy 181.794148 -409.543504)
			(xy 179.993798 -409.543504) (xy 182.02021 -411.569916) (xy 182.037285 -411.587618) (xy 182.066212 -411.627394)
			(xy 182.088554 -411.671209) (xy 182.103759 -411.717982) (xy 182.111453 -411.766559) (xy 182.111904 -411.79115)
			(xy 182.111904 -411.967934) (xy 182.112076 -411.975246) (xy 182.116088 -411.989304) (xy 182.119778 -411.99562)
			(xy 182.132846 -412.016693) (xy 182.154027 -412.061529) (xy 182.169235 -412.108726) (xy 182.174134 -412.133034)
			(xy 182.176166 -412.143702) (xy 182.188104 -412.161228) (xy 182.270146 -412.212282) (xy 182.291228 -412.21533)
			(xy 182.301642 -412.212536) (xy 182.326908 -412.20591) (xy 182.37865 -412.198774) (xy 182.404766 -412.198312)
			(xy 182.435273 -412.198886) (xy 182.495515 -412.208552) (xy 182.553449 -412.22769) (xy 182.580788 -412.241238)
			(xy 182.586376 -412.244286) (xy 182.597806 -412.24708)
		)
		(stroke
			(width 0)
			(type solid)
		)
		(fill yes)
		(layer "In4.Cu")
		(net "AGND_HSC")
	)
	(gr_poly
		(pts
			(xy 40.826182 -373.099838) (xy 40.836244 -373.099398) (xy 40.854821 -373.091656) (xy 40.86225 -373.084852)
			(xy 41.933114 -372.013988) (xy 41.939968 -372.006593) (xy 41.947712 -371.987994) (xy 41.9481 -371.97792)
			(xy 41.9481 -371.086634) (xy 41.948535 -371.076569) (xy 41.956267 -371.057982) (xy 41.963086 -371.050566)
			(xy 43.569128 -369.444524) (xy 43.57597 -369.437125) (xy 43.583688 -369.418526) (xy 43.584114 -369.408456)
			(xy 43.584114 -368.449606) (xy 43.584536 -368.439536) (xy 43.592251 -368.420931) (xy 43.5991 -368.413538)
			(xy 44.412662 -367.599976) (xy 44.42006 -367.593131) (xy 44.438659 -367.585407) (xy 44.44873 -367.58499)
			(xy 72.30745 -367.58499) (xy 72.317516 -367.584557) (xy 72.336106 -367.576829) (xy 72.343518 -367.570004)
			(xy 79.98333 -359.930446) (xy 79.990728 -359.923599) (xy 80.009327 -359.915869) (xy 80.019398 -359.91546)
			(xy 81.418938 -359.91546) (xy 81.423958 -359.915369) (xy 81.433811 -359.913454) (xy 81.438496 -359.91165)
			(xy 81.559908 -359.861104) (xy 81.564472 -359.859098) (xy 81.572788 -359.8536) (xy 81.576418 -359.850182)
			(xy 84.26323 -357.16337) (xy 84.270627 -357.156521) (xy 84.289226 -357.148786) (xy 84.299298 -357.148384)
			(xy 88.099646 -357.148384) (xy 88.104665 -357.148292) (xy 88.114517 -357.146372) (xy 88.119204 -357.144574)
			(xy 93.363034 -354.97262) (xy 93.371691 -354.96862) (xy 93.385457 -354.955439) (xy 93.393499 -354.938161)
			(xy 93.39453 -354.928678) (xy 93.399864 -354.837492) (xy 93.400108 -354.828026) (xy 93.394394 -354.809988)
			(xy 93.382484 -354.795285) (xy 93.374464 -354.790248) (xy 93.37421 -354.790248) (xy 93.355812 -354.779533)
			(xy 93.32131 -354.754585) (xy 93.305376 -354.740464) (xy 93.298518 -354.734114) (xy 93.280738 -354.727256)
			(xy 93.193108 -354.727256) (xy 93.175328 -354.734114) (xy 93.16847 -354.740464) (xy 93.147265 -354.75914)
			(xy 93.100379 -354.790677) (xy 93.049355 -354.814952) (xy 92.995308 -354.831435) (xy 92.93942 -354.839765)
			(xy 92.911168 -354.840286) (xy 92.883667 -354.839804) (xy 92.829236 -354.831907) (xy 92.776501 -354.816281)
			(xy 92.726555 -354.793249) (xy 92.68043 -354.763288) (xy 92.639082 -354.727019) (xy 92.620846 -354.706428)
			(xy 92.613657 -354.698714) (xy 92.594766 -354.689398) (xy 92.58427 -354.688394) (xy 92.510102 -354.6856)
			(xy 92.499536 -354.68565) (xy 92.479851 -354.693259) (xy 92.472002 -354.700332) (xy 92.450412 -354.720983)
			(xy 92.402003 -354.755992) (xy 92.34873 -354.78303) (xy 92.291895 -354.801437) (xy 92.232887 -354.810763)
			(xy 92.203016 -354.81133) (xy 92.202762 -354.81133) (xy 92.174709 -354.810839) (xy 92.119208 -354.802633)
			(xy 92.065505 -354.78639) (xy 92.01476 -354.762459) (xy 91.968065 -354.731357) (xy 91.926428 -354.693752)
			(xy 91.890744 -354.650457) (xy 91.875864 -354.626672) (xy 91.875864 -354.626164) (xy 91.86926 -354.615496)
			(xy 91.847924 -354.602796) (xy 91.73845 -354.5967) (xy 91.71559 -354.607368) (xy 91.70797 -354.617528)
			(xy 91.689803 -354.640512) (xy 91.647614 -354.681161) (xy 91.599713 -354.714889) (xy 91.547222 -354.740907)
			(xy 91.491374 -354.758603) (xy 91.433478 -354.767563) (xy 91.404186 -354.76815) (xy 91.374745 -354.767603)
			(xy 91.316562 -354.758555) (xy 91.260461 -354.740676) (xy 91.207771 -354.714391) (xy 91.159746 -354.680323)
			(xy 91.138248 -354.6602) (xy 91.130882 -354.653088) (xy 91.113102 -354.645976) (xy 91.021916 -354.645976)
			(xy 91.004136 -354.653088) (xy 90.99677 -354.6602) (xy 90.975279 -354.680329) (xy 90.927252 -354.714396)
			(xy 90.874561 -354.740678) (xy 90.818457 -354.758551) (xy 90.760273 -354.767589) (xy 90.730832 -354.76815)
			(xy 90.702651 -354.767646) (xy 90.646901 -354.759354) (xy 90.592979 -354.742948) (xy 90.54206 -354.718783)
			(xy 90.495251 -354.687387) (xy 90.453574 -354.649443) (xy 90.417935 -354.605778) (xy 90.389112 -354.557343)
			(xy 90.367732 -354.505194) (xy 90.35426 -354.450465) (xy 90.351102 -354.422456) (xy 90.351102 -354.422202)
			(xy 90.349773 -354.412897) (xy 90.341355 -354.39611) (xy 90.327458 -354.383479) (xy 90.309945 -354.376698)
			(xy 90.300556 -354.376228) (xy 89.917778 -354.376228) (xy 89.908385 -354.376661) (xy 89.890865 -354.383444)
			(xy 89.87697 -354.396089) (xy 89.86857 -354.412893) (xy 89.867232 -354.422202) (xy 89.867232 -354.422456)
			(xy 89.864083 -354.450461) (xy 89.850594 -354.505176) (xy 89.829201 -354.557311) (xy 89.800369 -354.605731)
			(xy 89.764727 -354.649382) (xy 89.72305 -354.687313) (xy 89.676246 -354.718699) (xy 89.625333 -354.742856)
			(xy 89.571419 -354.75926) (xy 89.515679 -354.767551) (xy 89.459325 -354.767551) (xy 89.403585 -354.75926)
			(xy 89.349671 -354.742856) (xy 89.298758 -354.718699) (xy 89.251954 -354.687313) (xy 89.210277 -354.649382)
			(xy 89.174635 -354.605731) (xy 89.145803 -354.557311) (xy 89.12441 -354.505176) (xy 89.110921 -354.450461)
			(xy 89.107772 -354.422456) (xy 89.107772 -354.422202) (xy 89.106442 -354.412899) (xy 89.098023 -354.396118)
			(xy 89.084125 -354.383494) (xy 89.066613 -354.376723) (xy 89.057226 -354.376228) (xy 89.03462 -354.376228)
			(xy 89.024598 -354.376645) (xy 89.006079 -354.384312) (xy 88.991908 -354.398486) (xy 88.984243 -354.417006)
			(xy 88.98382 -354.427028) (xy 88.98382 -354.429568) (xy 88.983359 -354.456823) (xy 88.975606 -354.510778)
			(xy 88.960253 -354.56308) (xy 88.937612 -354.612665) (xy 88.908145 -354.658523) (xy 88.872452 -354.699721)
			(xy 88.831259 -354.735419) (xy 88.785404 -354.764891) (xy 88.735821 -354.787538) (xy 88.683521 -354.802897)
			(xy 88.629567 -354.810656) (xy 88.602312 -354.811076) (xy 88.572259 -354.810513) (xy 88.512898 -354.801087)
			(xy 88.45575 -354.782467) (xy 88.40223 -354.755113) (xy 88.353664 -354.719702) (xy 88.332056 -354.698808)
			(xy 88.325452 -354.692204) (xy 88.308434 -354.684584) (xy 88.231472 -354.680012) (xy 88.222302 -354.679939)
			(xy 88.204858 -354.685547) (xy 88.197436 -354.690934) (xy 88.197182 -354.690934) (xy 88.17689 -354.7064)
			(xy 88.13298 -354.732382) (xy 88.086 -354.752282) (xy 88.036787 -354.765745) (xy 87.986219 -354.772531)
			(xy 87.960708 -354.772976) (xy 87.931826 -354.772444) (xy 87.874723 -354.763734) (xy 87.819586 -354.746512)
			(xy 87.767677 -354.721173) (xy 87.720183 -354.688294) (xy 87.698834 -354.668836) (xy 87.691976 -354.662486)
			(xy 87.674958 -354.655374) (xy 87.597742 -354.653088) (xy 87.588665 -354.653239) (xy 87.571495 -354.659095)
			(xy 87.564214 -354.664518) (xy 87.56396 -354.664772) (xy 87.54329 -354.681475) (xy 87.4982 -354.709599)
			(xy 87.44964 -354.731189) (xy 87.398553 -354.745826) (xy 87.345929 -354.753228) (xy 87.319358 -354.753672)
			(xy 87.29211 -354.753183) (xy 87.238168 -354.745421) (xy 87.185881 -354.730062) (xy 87.136311 -354.707418)
			(xy 87.090469 -354.67795) (xy 87.049287 -354.642258) (xy 87.013603 -354.601069) (xy 86.984144 -354.55522)
			(xy 86.961511 -354.505646) (xy 86.946162 -354.453355) (xy 86.938412 -354.399412) (xy 86.93785 -354.372164)
			(xy 86.938281 -354.346241) (xy 86.945299 -354.294872) (xy 86.959213 -354.244928) (xy 86.979767 -354.197331)
			(xy 87.006581 -354.152958) (xy 87.039161 -354.112628) (xy 87.057738 -354.094542) (xy 87.064596 -354.087938)
			(xy 87.072724 -354.07092) (xy 87.078312 -353.992688) (xy 87.078637 -353.983278) (xy 87.073143 -353.965281)
			(xy 87.067644 -353.957636) (xy 87.052109 -353.937349) (xy 87.026031 -353.893407) (xy 87.006056 -353.846376)
			(xy 86.992541 -353.797098) (xy 86.985728 -353.746457) (xy 86.985348 -353.720908) (xy 86.985819 -353.693538)
			(xy 86.993643 -353.63936) (xy 87.009131 -353.586857) (xy 87.031964 -353.537106) (xy 87.061675 -353.491131)
			(xy 87.079328 -353.47021) (xy 87.079328 -353.469956) (xy 87.079582 -353.469956) (xy 87.085177 -353.462872)
			(xy 87.09144 -353.445955) (xy 87.091774 -353.436936) (xy 87.091774 -353.36988) (xy 87.09141 -353.360865)
			(xy 87.085156 -353.343956) (xy 87.079582 -353.33686) (xy 87.079328 -353.336606) (xy 87.061687 -353.315673)
			(xy 87.031961 -353.269705) (xy 87.009114 -353.219959) (xy 86.993617 -353.167456) (xy 86.985787 -353.113277)
			(xy 86.985786 -353.058535) (xy 86.993614 -353.004356) (xy 87.00911 -352.951853) (xy 87.031955 -352.902105)
			(xy 87.061679 -352.856136) (xy 87.079328 -352.83521) (xy 87.079328 -352.834956) (xy 87.079582 -352.834956)
			(xy 87.085177 -352.827872) (xy 87.09144 -352.810955) (xy 87.091774 -352.801936) (xy 87.091774 -352.73488)
			(xy 87.09141 -352.725865) (xy 87.085156 -352.708956) (xy 87.079582 -352.70186) (xy 87.079328 -352.701606)
			(xy 87.061687 -352.680673) (xy 87.031961 -352.634705) (xy 87.009114 -352.584959) (xy 86.993617 -352.532456)
			(xy 86.985787 -352.478277) (xy 86.985786 -352.423535) (xy 86.993614 -352.369356) (xy 87.00911 -352.316853)
			(xy 87.031955 -352.267105) (xy 87.061679 -352.221136) (xy 87.079328 -352.20021) (xy 87.079328 -352.199956)
			(xy 87.079582 -352.199956) (xy 87.085177 -352.192872) (xy 87.09144 -352.175955) (xy 87.091774 -352.166936)
			(xy 87.091774 -352.09988) (xy 87.09141 -352.090865) (xy 87.085156 -352.073956) (xy 87.079582 -352.06686)
			(xy 87.079328 -352.066606) (xy 87.061687 -352.045673) (xy 87.031961 -351.999705) (xy 87.009114 -351.949959)
			(xy 86.993617 -351.897456) (xy 86.985787 -351.843277) (xy 86.985786 -351.788535) (xy 86.993614 -351.734356)
			(xy 87.00911 -351.681853) (xy 87.031955 -351.632105) (xy 87.061679 -351.586136) (xy 87.079328 -351.56521)
			(xy 87.079328 -351.564956) (xy 87.079582 -351.564956) (xy 87.085177 -351.557872) (xy 87.09144 -351.540955)
			(xy 87.091774 -351.531936) (xy 87.091774 -351.46488) (xy 87.09141 -351.455865) (xy 87.085156 -351.438956)
			(xy 87.079582 -351.43186) (xy 87.079328 -351.431606) (xy 87.061687 -351.410673) (xy 87.031961 -351.364705)
			(xy 87.009114 -351.314959) (xy 86.993617 -351.262456) (xy 86.985787 -351.208277) (xy 86.985786 -351.153535)
			(xy 86.993614 -351.099356) (xy 87.00911 -351.046853) (xy 87.031955 -350.997105) (xy 87.061679 -350.951136)
			(xy 87.079328 -350.93021) (xy 87.079328 -350.929956) (xy 87.079582 -350.929956) (xy 87.085177 -350.922872)
			(xy 87.09144 -350.905955) (xy 87.091774 -350.896936) (xy 87.091774 -350.82988) (xy 87.09141 -350.820865)
			(xy 87.085156 -350.803956) (xy 87.079582 -350.79686) (xy 87.079328 -350.796606) (xy 87.061685 -350.775675)
			(xy 87.031956 -350.72971) (xy 87.00911 -350.679963) (xy 86.993618 -350.627459) (xy 86.985798 -350.573279)
			(xy 86.985348 -350.545908) (xy 86.985833 -350.518655) (xy 86.993589 -350.464704) (xy 87.008943 -350.412406)
			(xy 87.031583 -350.362825) (xy 87.061048 -350.31697) (xy 87.096739 -350.275776) (xy 87.137929 -350.240079)
			(xy 87.183779 -350.210608) (xy 87.233357 -350.187961) (xy 87.285653 -350.1726) (xy 87.339603 -350.164837)
			(xy 87.366856 -350.1644) (xy 87.394225 -350.164876) (xy 87.448399 -350.172707) (xy 87.500898 -350.1882)
			(xy 87.550644 -350.211037) (xy 87.596615 -350.24075) (xy 87.617554 -350.25838) (xy 87.617808 -350.25838)
			(xy 87.617808 -350.258634) (xy 87.624896 -350.264215) (xy 87.641813 -350.27045) (xy 87.650828 -350.270826)
			(xy 87.717884 -350.270826) (xy 87.726902 -350.270469) (xy 87.743823 -350.264229) (xy 87.750904 -350.258634)
			(xy 87.751158 -350.25838) (xy 87.772091 -350.240739) (xy 87.818059 -350.211015) (xy 87.867805 -350.188169)
			(xy 87.920307 -350.172673) (xy 87.974485 -350.164844) (xy 88.029227 -350.164844) (xy 88.083405 -350.172673)
			(xy 88.135907 -350.188169) (xy 88.185653 -350.211015) (xy 88.231621 -350.240739) (xy 88.252554 -350.25838)
			(xy 88.252808 -350.25838) (xy 88.252808 -350.258634) (xy 88.259896 -350.264215) (xy 88.276813 -350.27045)
			(xy 88.285828 -350.270826) (xy 88.352884 -350.270826) (xy 88.361902 -350.270469) (xy 88.378823 -350.264229)
			(xy 88.385904 -350.258634) (xy 88.386158 -350.25838) (xy 88.407091 -350.240739) (xy 88.453059 -350.211015)
			(xy 88.502805 -350.188169) (xy 88.555307 -350.172673) (xy 88.609485 -350.164844) (xy 88.664227 -350.164844)
			(xy 88.718405 -350.172673) (xy 88.770907 -350.188169) (xy 88.820653 -350.211015) (xy 88.866621 -350.240739)
			(xy 88.887554 -350.25838) (xy 88.887808 -350.25838) (xy 88.887808 -350.258634) (xy 88.894896 -350.264215)
			(xy 88.911813 -350.27045) (xy 88.920828 -350.270826) (xy 88.987884 -350.270826) (xy 88.996902 -350.270469)
			(xy 89.013823 -350.264229) (xy 89.020904 -350.258634) (xy 89.021158 -350.25838) (xy 89.042091 -350.240739)
			(xy 89.088059 -350.211015) (xy 89.137805 -350.188169) (xy 89.190307 -350.172673) (xy 89.244485 -350.164844)
			(xy 89.299227 -350.164844) (xy 89.353405 -350.172673) (xy 89.405907 -350.188169) (xy 89.455653 -350.211015)
			(xy 89.501621 -350.240739) (xy 89.522554 -350.25838) (xy 89.522808 -350.25838) (xy 89.522808 -350.258634)
			(xy 89.529896 -350.264215) (xy 89.546813 -350.27045) (xy 89.555828 -350.270826) (xy 89.622884 -350.270826)
			(xy 89.631902 -350.270469) (xy 89.648823 -350.264229) (xy 89.655904 -350.258634) (xy 89.656158 -350.25838)
			(xy 89.677091 -350.240739) (xy 89.723059 -350.211015) (xy 89.772805 -350.188169) (xy 89.825307 -350.172673)
			(xy 89.879485 -350.164844) (xy 89.934227 -350.164844) (xy 89.988405 -350.172673) (xy 90.040907 -350.188169)
			(xy 90.090653 -350.211015) (xy 90.136621 -350.240739) (xy 90.157554 -350.25838) (xy 90.157808 -350.25838)
			(xy 90.157808 -350.258634) (xy 90.164896 -350.264215) (xy 90.181813 -350.27045) (xy 90.190828 -350.270826)
			(xy 90.257884 -350.270826) (xy 90.266902 -350.270469) (xy 90.283823 -350.264229) (xy 90.290904 -350.258634)
			(xy 90.291158 -350.25838) (xy 90.312091 -350.240739) (xy 90.358059 -350.211015) (xy 90.407805 -350.188169)
			(xy 90.460307 -350.172673) (xy 90.514485 -350.164844) (xy 90.569227 -350.164844) (xy 90.623405 -350.172673)
			(xy 90.675907 -350.188169) (xy 90.725653 -350.211015) (xy 90.771621 -350.240739) (xy 90.792554 -350.25838)
			(xy 90.792808 -350.25838) (xy 90.792808 -350.258634) (xy 90.799896 -350.264215) (xy 90.816813 -350.27045)
			(xy 90.825828 -350.270826) (xy 90.892884 -350.270826) (xy 90.901902 -350.270469) (xy 90.918823 -350.264229)
			(xy 90.925904 -350.258634) (xy 90.926158 -350.25838) (xy 90.947091 -350.240739) (xy 90.993059 -350.211015)
			(xy 91.042805 -350.188169) (xy 91.095307 -350.172673) (xy 91.149485 -350.164844) (xy 91.204227 -350.164844)
			(xy 91.258405 -350.172673) (xy 91.310907 -350.188169) (xy 91.360653 -350.211015) (xy 91.406621 -350.240739)
			(xy 91.427554 -350.25838) (xy 91.427808 -350.25838) (xy 91.427808 -350.258634) (xy 91.434896 -350.264215)
			(xy 91.451813 -350.27045) (xy 91.460828 -350.270826) (xy 91.527884 -350.270826) (xy 91.536902 -350.270469)
			(xy 91.553823 -350.264229) (xy 91.560904 -350.258634) (xy 91.561158 -350.25838) (xy 91.582091 -350.240739)
			(xy 91.628059 -350.211015) (xy 91.677805 -350.188169) (xy 91.730307 -350.172673) (xy 91.784485 -350.164844)
			(xy 91.839227 -350.164844) (xy 91.893405 -350.172673) (xy 91.945907 -350.188169) (xy 91.995653 -350.211015)
			(xy 92.041621 -350.240739) (xy 92.062554 -350.25838) (xy 92.062808 -350.25838) (xy 92.062808 -350.258634)
			(xy 92.069896 -350.264215) (xy 92.086813 -350.27045) (xy 92.095828 -350.270826) (xy 92.162884 -350.270826)
			(xy 92.171902 -350.270469) (xy 92.188823 -350.264229) (xy 92.195904 -350.258634) (xy 92.196158 -350.25838)
			(xy 92.217091 -350.240739) (xy 92.263059 -350.211015) (xy 92.312805 -350.188169) (xy 92.365307 -350.172673)
			(xy 92.419485 -350.164844) (xy 92.474227 -350.164844) (xy 92.528405 -350.172673) (xy 92.580907 -350.188169)
			(xy 92.630653 -350.211015) (xy 92.676621 -350.240739) (xy 92.697554 -350.25838) (xy 92.697808 -350.25838)
			(xy 92.697808 -350.258634) (xy 92.704896 -350.264215) (xy 92.721813 -350.27045) (xy 92.730828 -350.270826)
			(xy 92.797884 -350.270826) (xy 92.806902 -350.270469) (xy 92.823823 -350.264229) (xy 92.830904 -350.258634)
			(xy 92.831158 -350.25838) (xy 92.852091 -350.240739) (xy 92.898059 -350.211015) (xy 92.947805 -350.188169)
			(xy 93.000307 -350.172673) (xy 93.054485 -350.164844) (xy 93.109227 -350.164844) (xy 93.163405 -350.172673)
			(xy 93.215907 -350.188169) (xy 93.265653 -350.211015) (xy 93.311621 -350.240739) (xy 93.332554 -350.25838)
			(xy 93.332808 -350.25838) (xy 93.332808 -350.258634) (xy 93.339896 -350.264215) (xy 93.356813 -350.27045)
			(xy 93.365828 -350.270826) (xy 93.432884 -350.270826) (xy 93.441902 -350.270469) (xy 93.458823 -350.264229)
			(xy 93.465904 -350.258634) (xy 93.466158 -350.25838) (xy 93.487091 -350.240742) (xy 93.533059 -350.211025)
			(xy 93.582807 -350.18819) (xy 93.635309 -350.172709) (xy 93.689487 -350.164899) (xy 93.716856 -350.1644)
			(xy 93.744111 -350.16486) (xy 93.798066 -350.172612) (xy 93.850369 -350.187965) (xy 93.899954 -350.210605)
			(xy 93.945812 -350.240072) (xy 93.987009 -350.275765) (xy 94.022707 -350.316959) (xy 94.052178 -350.362815)
			(xy 94.074823 -350.412398) (xy 94.09018 -350.464699) (xy 94.097937 -350.518653) (xy 94.098364 -350.545908)
			(xy 94.097892 -350.573278) (xy 94.090066 -350.627455) (xy 94.074577 -350.679957) (xy 94.051742 -350.729706)
			(xy 94.022031 -350.77568) (xy 94.004384 -350.796606) (xy 94.004384 -350.79686) (xy 94.00413 -350.79686)
			(xy 93.998536 -350.803944) (xy 93.992277 -350.820861) (xy 93.991938 -350.82988) (xy 93.991938 -350.896936)
			(xy 93.992302 -350.905951) (xy 93.998553 -350.922864) (xy 94.00413 -350.929956) (xy 94.004384 -350.93021)
			(xy 94.022024 -350.951143) (xy 94.051746 -350.997111) (xy 94.07459 -351.046857) (xy 94.090085 -351.099358)
			(xy 94.097912 -351.153536) (xy 94.097911 -351.208276) (xy 94.090082 -351.262454) (xy 94.074586 -351.314955)
			(xy 94.051741 -351.3647) (xy 94.022016 -351.410667) (xy 94.004384 -351.431606) (xy 94.004384 -351.43186)
			(xy 94.00413 -351.43186) (xy 93.998536 -351.438944) (xy 93.992277 -351.455861) (xy 93.991938 -351.46488)
			(xy 93.991938 -351.531936) (xy 93.992302 -351.540951) (xy 93.998553 -351.557864) (xy 94.00413 -351.564956)
			(xy 94.004384 -351.56521) (xy 94.022026 -351.586141) (xy 94.051752 -351.632108) (xy 94.074595 -351.681854)
			(xy 94.090085 -351.734358) (xy 94.097902 -351.788538) (xy 94.098364 -351.815908) (xy 94.097833 -351.844763)
			(xy 94.089137 -351.901813) (xy 94.071944 -351.956902) (xy 94.046647 -352.008772) (xy 94.013824 -352.056238)
			(xy 93.974224 -352.098216) (xy 93.951806 -352.11639) (xy 93.944186 -352.122232) (xy 93.934534 -352.138488)
			(xy 93.92031 -352.22561) (xy 93.92412 -352.244152) (xy 93.9292 -352.252026) (xy 93.943858 -352.275368)
			(xy 93.967025 -352.325379) (xy 93.982743 -352.378207) (xy 93.990684 -352.432748) (xy 93.991176 -352.460306)
			(xy 93.990744 -352.486168) (xy 93.983753 -352.537418) (xy 93.969898 -352.587252) (xy 93.949436 -352.634757)
			(xy 93.92274 -352.67906) (xy 93.890302 -352.719349) (xy 93.871796 -352.73742) (xy 93.871542 -352.737674)
			(xy 93.864394 -352.745154) (xy 93.856287 -352.764167) (xy 93.855794 -352.774504) (xy 93.855794 -352.858832)
			(xy 93.864176 -352.878136) (xy 93.871796 -352.885248) (xy 93.890334 -352.903329) (xy 93.922849 -352.943635)
			(xy 93.949606 -352.987971) (xy 93.970113 -353.035523) (xy 93.983993 -353.085413) (xy 93.990989 -353.136723)
			(xy 93.99143 -353.162616) (xy 93.990957 -353.189985) (xy 93.98313 -353.244161) (xy 93.967639 -353.296662)
			(xy 93.944802 -353.346409) (xy 93.915088 -353.392381) (xy 93.89745 -353.413314) (xy 93.89745 -353.413568)
			(xy 93.897196 -353.413568) (xy 93.891606 -353.420654) (xy 93.885354 -353.43757) (xy 93.885004 -353.446588)
			(xy 93.885004 -353.513644) (xy 93.885371 -353.522657) (xy 93.89163 -353.539564) (xy 93.897196 -353.546664)
			(xy 93.89745 -353.546918) (xy 93.915093 -353.567849) (xy 93.944821 -353.613815) (xy 93.967665 -353.663561)
			(xy 93.983155 -353.716065) (xy 93.990972 -353.770245) (xy 93.99143 -353.797616) (xy 93.990987 -353.823944)
			(xy 93.983743 -353.8761) (xy 93.969396 -353.926764) (xy 93.948218 -353.974974) (xy 93.920612 -354.019814)
			(xy 93.887102 -354.060431) (xy 93.867986 -354.07854) (xy 93.86062 -354.085398) (xy 93.852492 -354.102416)
			(xy 93.846904 -354.181664) (xy 93.846593 -354.191222) (xy 93.852203 -354.20949) (xy 93.857826 -354.217224)
			(xy 93.85808 -354.217478) (xy 93.874188 -354.23798) (xy 93.90128 -354.282526) (xy 93.922055 -354.330346)
			(xy 93.936125 -354.380549) (xy 93.943228 -354.432201) (xy 93.943678 -354.45827) (xy 93.943217 -354.48406)
			(xy 93.936209 -354.535163) (xy 93.929708 -354.560124) (xy 93.929708 -354.560378) (xy 93.927572 -354.569577)
			(xy 93.929516 -354.588348) (xy 93.938152 -354.605127) (xy 93.944948 -354.611686) (xy 94.013274 -354.672392)
			(xy 94.020671 -354.678428) (xy 94.03858 -354.685004) (xy 94.057654 -354.684581) (xy 94.066614 -354.681282)
			(xy 102.168198 -351.325688) (xy 102.16896 -351.325434) (xy 102.179374 -351.319846) (xy 102.179882 -351.319338)
			(xy 102.190296 -351.312734) (xy 102.190804 -351.312226) (xy 113.47577 -343.77249) (xy 113.485826 -343.764971)
			(xy 113.497672 -343.742863) (xy 113.498376 -343.730326) (xy 113.498376 -343.55151) (xy 113.498797 -343.541438)
			(xy 113.506506 -343.522829) (xy 113.513362 -343.515442) (xy 113.536476 -343.492328) (xy 115.271296 -341.757762)
			(xy 115.278137 -341.750362) (xy 115.285858 -341.731763) (xy 115.286282 -341.721694) (xy 115.286282 -337.287108)
			(xy 115.285828 -337.277324) (xy 115.278506 -337.259176) (xy 115.272058 -337.251802) (xy 115.253945 -337.232317)
			(xy 115.222735 -337.189236) (xy 115.19781 -337.142238) (xy 115.179652 -337.092234) (xy 115.168613 -337.040194)
			(xy 115.164907 -336.987125) (xy 115.168606 -336.934055) (xy 115.179639 -336.882013) (xy 115.19779 -336.832007)
			(xy 115.222709 -336.785006) (xy 115.253914 -336.74192) (xy 115.272058 -336.722466) (xy 115.27917 -336.7151)
			(xy 115.286282 -336.69732) (xy 115.286282 -336.66811) (xy 115.286004 -336.659583) (xy 115.280469 -336.643455)
			(xy 115.269915 -336.630062) (xy 115.262914 -336.625184) (xy 115.239401 -336.60948) (xy 115.196853 -336.572246)
			(xy 115.160269 -336.529137) (xy 115.130452 -336.481099) (xy 115.108056 -336.429184) (xy 115.093571 -336.374531)
			(xy 115.087314 -336.318339) (xy 115.089424 -336.261838) (xy 115.099854 -336.206269) (xy 115.118376 -336.152849)
			(xy 115.144582 -336.102749) (xy 115.160806 -336.079592) (xy 115.166052 -336.071778) (xy 115.170911 -336.053608)
			(xy 115.168876 -336.03491) (xy 115.160221 -336.018211) (xy 115.146117 -336.005768) (xy 115.137438 -336.002122)
			(xy 115.110517 -335.991487) (xy 115.059984 -335.963263) (xy 115.014294 -335.927729) (xy 114.974497 -335.8857)
			(xy 114.941507 -335.838141) (xy 114.91608 -335.786144) (xy 114.8988 -335.730903) (xy 114.890064 -335.673685)
			(xy 114.889534 -335.644744) (xy 114.890123 -335.613889) (xy 114.900042 -335.55298) (xy 114.919628 -335.49446)
			(xy 114.948372 -335.439852) (xy 114.966496 -335.414874) (xy 114.972039 -335.40673) (xy 114.977052 -335.387698)
			(xy 114.974524 -335.36818) (xy 114.964828 -335.351053) (xy 114.949393 -335.338842) (xy 114.94008 -335.335626)
			(xy 114.913921 -335.327581) (xy 114.864049 -335.305041) (xy 114.817908 -335.27561) (xy 114.776443 -335.239891)
			(xy 114.740505 -335.198616) (xy 114.710829 -335.152632) (xy 114.688025 -335.102881) (xy 114.67256 -335.050383)
			(xy 114.664751 -334.996214) (xy 114.664236 -334.96885) (xy 114.66467 -334.942979) (xy 114.671667 -334.891712)
			(xy 114.685526 -334.841861) (xy 114.705993 -334.794339) (xy 114.732693 -334.750018) (xy 114.748564 -334.729582)
			(xy 114.754368 -334.721763) (xy 114.760132 -334.703179) (xy 114.758536 -334.683787) (xy 114.749813 -334.666395)
			(xy 114.735224 -334.653521) (xy 114.726212 -334.649826) (xy 114.723418 -334.64881) (xy 114.697376 -334.640719)
			(xy 114.647743 -334.618125) (xy 114.601837 -334.58869) (xy 114.560593 -334.553013) (xy 114.524855 -334.511824)
			(xy 114.49535 -334.465962) (xy 114.472682 -334.416363) (xy 114.457313 -334.364041) (xy 114.449557 -334.310063)
			(xy 114.449098 -334.282796) (xy 114.449523 -334.257302) (xy 114.456311 -334.206769) (xy 114.469767 -334.15759)
			(xy 114.479324 -334.133952) (xy 114.48542 -334.119474) (xy 114.479324 -334.089248) (xy 111.249206 -330.85913)
			(xy 111.241809 -330.85228) (xy 111.223211 -330.844538) (xy 111.213138 -330.844144) (xy 73.039732 -330.844144)
			(xy 73.029668 -330.844581) (xy 73.011086 -330.852318) (xy 73.003664 -330.85913) (xy 72.032368 -331.830426)
			(xy 72.024971 -331.837275) (xy 72.006372 -331.84501) (xy 71.9963 -331.845412) (xy 69.011038 -331.845412)
			(xy 69.000973 -331.845847) (xy 68.982386 -331.853578) (xy 68.97497 -331.860398) (xy 65.37198 -335.463388)
			(xy 65.364581 -335.470233) (xy 65.345983 -335.477962) (xy 65.335912 -335.478374) (xy 29.212286 -335.478374)
			(xy 29.202216 -335.478799) (xy 29.183613 -335.486514) (xy 29.176218 -335.49336) (xy 28.014676 -336.654902)
			(xy 66.344546 -336.654902) (xy 66.345051 -336.626992) (xy 66.353184 -336.571767) (xy 66.369277 -336.518317)
			(xy 66.392987 -336.467782) (xy 66.423807 -336.421241) (xy 66.442082 -336.40014) (xy 66.448002 -336.392979)
			(xy 66.45464 -336.375642) (xy 66.455036 -336.366358) (xy 66.455036 -336.288634) (xy 66.448432 -336.271362)
			(xy 66.442082 -336.26425) (xy 66.423803 -336.243151) (xy 66.392977 -336.196612) (xy 66.369262 -336.146077)
			(xy 66.353165 -336.092626) (xy 66.345031 -336.037399) (xy 66.344546 -336.009488) (xy 66.345032 -335.982237)
			(xy 66.352788 -335.928289) (xy 66.368143 -335.875994) (xy 66.390785 -335.826417) (xy 66.420251 -335.780567)
			(xy 66.455942 -335.739376) (xy 66.497133 -335.703685) (xy 66.542983 -335.674219) (xy 66.59256 -335.651577)
			(xy 66.644855 -335.636222) (xy 66.698803 -335.628466) (xy 66.753305 -335.628466) (xy 66.807253 -335.636222)
			(xy 66.859548 -335.651577) (xy 66.909125 -335.674219) (xy 66.954975 -335.703685) (xy 66.996166 -335.739376)
			(xy 67.031857 -335.780567) (xy 67.061323 -335.826417) (xy 67.083965 -335.875994) (xy 67.09932 -335.928289)
			(xy 67.107076 -335.982237) (xy 67.107562 -336.009488) (xy 67.107049 -336.037398) (xy 67.098918 -336.092622)
			(xy 67.082826 -336.146072) (xy 67.059118 -336.196607) (xy 67.0283 -336.243149) (xy 67.010026 -336.26425)
			(xy 67.004111 -336.271415) (xy 66.99747 -336.288749) (xy 66.997072 -336.298032) (xy 66.997072 -336.375756)
			(xy 67.003676 -336.393028) (xy 67.010026 -336.40014) (xy 67.028301 -336.421242) (xy 67.059128 -336.46778)
			(xy 67.082844 -336.518314) (xy 67.098941 -336.571765) (xy 67.107076 -336.626991) (xy 67.107562 -336.654902)
			(xy 67.107076 -336.682153) (xy 67.09932 -336.736101) (xy 67.083965 -336.788396) (xy 67.061323 -336.837973)
			(xy 67.031857 -336.883823) (xy 66.996166 -336.925014) (xy 66.954975 -336.960705) (xy 66.911881 -336.9884)
			(xy 70.726737 -336.9884) (xy 70.730906 -336.93278) (xy 70.743318 -336.878402) (xy 70.763696 -336.826482)
			(xy 70.791586 -336.778179) (xy 70.826364 -336.734573) (xy 70.867252 -336.696638) (xy 70.913338 -336.66522)
			(xy 70.963593 -336.641023) (xy 71.016892 -336.624587) (xy 71.072046 -336.616279) (xy 71.099934 -336.615786)
			(xy 71.126356 -336.616227) (xy 71.178672 -336.623682) (xy 71.229411 -336.638451) (xy 71.277555 -336.660238)
			(xy 71.322139 -336.688607) (xy 71.342504 -336.705448) (xy 71.349362 -336.71129) (xy 71.36638 -336.71764)
			(xy 71.450708 -336.71764) (xy 71.467726 -336.71129) (xy 71.474584 -336.705448) (xy 71.49495 -336.688609)
			(xy 71.539536 -336.660244) (xy 71.58768 -336.638457) (xy 71.638417 -336.623686) (xy 71.690732 -336.616226)
			(xy 71.743576 -336.616226) (xy 71.795891 -336.623686) (xy 71.846628 -336.638457) (xy 71.894772 -336.660244)
			(xy 71.939358 -336.688609) (xy 71.959724 -336.705448) (xy 71.966582 -336.71129) (xy 71.9836 -336.71764)
			(xy 72.067928 -336.71764) (xy 72.084946 -336.71129) (xy 72.091804 -336.705448) (xy 72.114863 -336.686472)
			(xy 72.165817 -336.655339) (xy 72.221092 -336.632749) (xy 72.250046 -336.625438) (xy 72.262238 -336.622644)
			(xy 72.281288 -336.606134) (xy 72.320658 -336.503772) (xy 72.31761 -336.47888) (xy 72.310244 -336.468466)
			(xy 72.294537 -336.444928) (xy 72.269667 -336.3941) (xy 72.252765 -336.340098) (xy 72.244219 -336.284161)
			(xy 72.243696 -336.255868) (xy 72.244204 -336.228226) (xy 72.252358 -336.173546) (xy 72.268498 -336.120671)
			(xy 72.292271 -336.070759) (xy 72.323153 -336.024905) (xy 72.360469 -335.984114) (xy 72.381618 -335.966308)
			(xy 72.390048 -335.958715) (xy 72.399807 -335.938267) (xy 72.400414 -335.926938) (xy 72.400414 -335.848198)
			(xy 72.399784 -335.836877) (xy 72.390021 -335.816442) (xy 72.381618 -335.808828) (xy 72.360486 -335.791003)
			(xy 72.323176 -335.750211) (xy 72.292295 -335.70436) (xy 72.26852 -335.654452) (xy 72.252371 -335.601583)
			(xy 72.244202 -335.546908) (xy 72.243696 -335.519268) (xy 72.244217 -335.491383) (xy 72.252529 -335.436236)
			(xy 72.268967 -335.382944) (xy 72.293165 -335.332698) (xy 72.324581 -335.286619) (xy 72.362514 -335.245737)
			(xy 72.406116 -335.210965) (xy 72.454414 -335.18308) (xy 72.506329 -335.162705) (xy 72.5607 -335.150295)
			(xy 72.616314 -335.146128) (xy 72.671928 -335.150295) (xy 72.726299 -335.162705) (xy 72.778214 -335.18308)
			(xy 72.826512 -335.210965) (xy 72.870114 -335.245737) (xy 72.908047 -335.286619) (xy 72.939463 -335.332698)
			(xy 72.963661 -335.382944) (xy 72.980099 -335.436236) (xy 72.988411 -335.491383) (xy 72.988932 -335.519268)
			(xy 72.98844 -335.546911) (xy 72.98028 -335.60159) (xy 72.964136 -335.654466) (xy 72.940361 -335.704377)
			(xy 72.909477 -335.750231) (xy 72.872159 -335.791022) (xy 72.85101 -335.808828) (xy 72.842568 -335.81641)
			(xy 72.832814 -335.836866) (xy 72.832214 -335.848198) (xy 72.832214 -335.926938) (xy 72.832848 -335.938258)
			(xy 72.842611 -335.958691) (xy 72.85101 -335.966308) (xy 72.872144 -335.98413) (xy 72.909457 -336.024921)
			(xy 72.94034 -336.070772) (xy 72.964115 -336.12068) (xy 72.980263 -336.173551) (xy 72.988428 -336.228227)
			(xy 72.988932 -336.255868) (xy 72.988393 -336.283672) (xy 72.980133 -336.338664) (xy 72.963792 -336.391817)
			(xy 72.939733 -336.441952) (xy 72.90849 -336.487954) (xy 72.870758 -336.528802) (xy 72.827373 -336.563589)
			(xy 72.779301 -336.591541) (xy 72.727608 -336.612039) (xy 72.700642 -336.618834) (xy 72.68845 -336.621628)
			(xy 72.6694 -336.638138) (xy 72.665688 -336.64779) (xy 74.70013 -336.64779) (xy 74.700632 -336.61988)
			(xy 74.708766 -336.564655) (xy 74.724861 -336.511205) (xy 74.748571 -336.46067) (xy 74.779391 -336.414129)
			(xy 74.797666 -336.393028) (xy 74.803559 -336.385848) (xy 74.810211 -336.368525) (xy 74.81062 -336.359246)
			(xy 74.81062 -336.281522) (xy 74.804016 -336.26425) (xy 74.797666 -336.257138) (xy 74.779379 -336.236046)
			(xy 74.748554 -336.189505) (xy 74.724841 -336.138968) (xy 74.708747 -336.085516) (xy 74.700614 -336.030288)
			(xy 74.70013 -336.002376) (xy 74.700616 -335.975125) (xy 74.708372 -335.921177) (xy 74.723727 -335.868882)
			(xy 74.746369 -335.819305) (xy 74.775835 -335.773455) (xy 74.811526 -335.732264) (xy 74.852717 -335.696573)
			(xy 74.898567 -335.667107) (xy 74.948144 -335.644465) (xy 75.000439 -335.62911) (xy 75.054387 -335.621354)
			(xy 75.108889 -335.621354) (xy 75.162837 -335.62911) (xy 75.215132 -335.644465) (xy 75.264709 -335.667107)
			(xy 75.310559 -335.696573) (xy 75.35175 -335.732264) (xy 75.387441 -335.773455) (xy 75.416907 -335.819305)
			(xy 75.439549 -335.868882) (xy 75.454904 -335.921177) (xy 75.46266 -335.975125) (xy 75.463146 -336.002376)
			(xy 75.46263 -336.030286) (xy 75.4545 -336.08551) (xy 75.438409 -336.13896) (xy 75.414702 -336.189496)
			(xy 75.383884 -336.236037) (xy 75.36561 -336.257138) (xy 75.359698 -336.264305) (xy 75.353056 -336.281638)
			(xy 75.352656 -336.29092) (xy 75.352656 -336.368644) (xy 75.35926 -336.385916) (xy 75.36561 -336.393028)
			(xy 75.383877 -336.414137) (xy 75.414706 -336.460673) (xy 75.438423 -336.511205) (xy 75.454522 -336.564654)
			(xy 75.462659 -336.619879) (xy 75.463146 -336.64779) (xy 75.46266 -336.675041) (xy 75.454904 -336.728989)
			(xy 75.439549 -336.781284) (xy 75.416907 -336.830861) (xy 75.387441 -336.876711) (xy 75.35175 -336.917902)
			(xy 75.310559 -336.953593) (xy 75.267446 -336.9813) (xy 79.082325 -336.9813) (xy 79.086494 -336.92568)
			(xy 79.098906 -336.871302) (xy 79.119284 -336.819381) (xy 79.147173 -336.771078) (xy 79.18195 -336.727471)
			(xy 79.222838 -336.689534) (xy 79.268923 -336.658115) (xy 79.319177 -336.633917) (xy 79.372476 -336.617478)
			(xy 79.42763 -336.609168) (xy 79.455518 -336.608674) (xy 79.48194 -336.609127) (xy 79.534255 -336.616579)
			(xy 79.584994 -336.631346) (xy 79.633138 -336.65313) (xy 79.677723 -336.681496) (xy 79.698088 -336.698336)
			(xy 79.704946 -336.704178) (xy 79.721964 -336.710528) (xy 79.806292 -336.710528) (xy 79.82331 -336.704178)
			(xy 79.830168 -336.698336) (xy 79.850534 -336.681497) (xy 79.89512 -336.653132) (xy 79.943264 -336.631345)
			(xy 79.994001 -336.616574) (xy 80.046316 -336.609114) (xy 80.09916 -336.609114) (xy 80.151475 -336.616574)
			(xy 80.202212 -336.631345) (xy 80.250356 -336.653132) (xy 80.294942 -336.681497) (xy 80.315308 -336.698336)
			(xy 80.322166 -336.704178) (xy 80.339184 -336.710528) (xy 80.423512 -336.710528) (xy 80.44053 -336.704178)
			(xy 80.447388 -336.698336) (xy 80.471196 -336.678767) (xy 80.523961 -336.646931) (xy 80.581236 -336.624189)
			(xy 80.611218 -336.617056) (xy 80.62341 -336.614516) (xy 80.642968 -336.598006) (xy 80.683354 -336.495136)
			(xy 80.680306 -336.470244) (xy 80.67294 -336.459576) (xy 80.657025 -336.435937) (xy 80.631775 -336.384853)
			(xy 80.614606 -336.330517) (xy 80.60592 -336.2742) (xy 80.605376 -336.245708) (xy 80.605919 -336.218067)
			(xy 80.614067 -336.16339) (xy 80.630201 -336.110515) (xy 80.653967 -336.060603) (xy 80.684843 -336.014748)
			(xy 80.722152 -335.973956) (xy 80.743298 -335.956148) (xy 80.751752 -335.948578) (xy 80.761499 -335.928113)
			(xy 80.762094 -335.916778) (xy 80.762094 -335.838038) (xy 80.761415 -335.826724) (xy 80.751684 -335.80629)
			(xy 80.743298 -335.798668) (xy 80.722154 -335.780857) (xy 80.684841 -335.740064) (xy 80.65396 -335.694211)
			(xy 80.630186 -335.6443) (xy 80.614041 -335.591427) (xy 80.605878 -335.53675) (xy 80.605376 -335.509108)
			(xy 80.605897 -335.481223) (xy 80.614209 -335.426076) (xy 80.630647 -335.372784) (xy 80.654845 -335.322538)
			(xy 80.686261 -335.276459) (xy 80.724194 -335.235577) (xy 80.767796 -335.200805) (xy 80.816094 -335.17292)
			(xy 80.868009 -335.152545) (xy 80.92238 -335.140135) (xy 80.977994 -335.135968) (xy 81.033608 -335.140135)
			(xy 81.087979 -335.152545) (xy 81.139894 -335.17292) (xy 81.188192 -335.200805) (xy 81.231794 -335.235577)
			(xy 81.269727 -335.276459) (xy 81.301143 -335.322538) (xy 81.325341 -335.372784) (xy 81.341779 -335.426076)
			(xy 81.350091 -335.481223) (xy 81.350612 -335.509108) (xy 81.350085 -335.536749) (xy 81.341934 -335.591428)
			(xy 81.325797 -335.644303) (xy 81.302029 -335.694215) (xy 81.27115 -335.74007) (xy 81.233837 -335.780861)
			(xy 81.21269 -335.798668) (xy 81.204272 -335.806272) (xy 81.194506 -335.826711) (xy 81.193894 -335.838038)
			(xy 81.193894 -335.916778) (xy 81.194568 -335.928093) (xy 81.204304 -335.948526) (xy 81.21269 -335.956148)
			(xy 81.23386 -335.973929) (xy 81.271167 -336.014731) (xy 81.302043 -336.060591) (xy 81.325812 -336.110507)
			(xy 81.341952 -336.163384) (xy 81.350111 -336.218065) (xy 81.350612 -336.245708) (xy 81.350052 -336.273832)
			(xy 81.34161 -336.329444) (xy 81.324904 -336.383154) (xy 81.300313 -336.433743) (xy 81.268398 -336.48006)
			(xy 81.229882 -336.521053) (xy 81.185641 -336.55579) (xy 81.136681 -336.583482) (xy 81.084115 -336.603499)
			(xy 81.056734 -336.609944) (xy 81.044542 -336.612484) (xy 81.024984 -336.628994) (xy 81.023289 -336.633312)
			(xy 83.057746 -336.633312) (xy 83.058257 -336.605402) (xy 83.066389 -336.550177) (xy 83.08248 -336.496727)
			(xy 83.106189 -336.446192) (xy 83.137008 -336.399651) (xy 83.155282 -336.37855) (xy 83.161198 -336.371386)
			(xy 83.167838 -336.354051) (xy 83.168236 -336.344768) (xy 83.168236 -336.267044) (xy 83.161632 -336.249772)
			(xy 83.155282 -336.24266) (xy 83.137008 -336.221557) (xy 83.106181 -336.175019) (xy 83.082465 -336.124486)
			(xy 83.066367 -336.071035) (xy 83.058232 -336.015809) (xy 83.057746 -335.987898) (xy 83.058232 -335.960647)
			(xy 83.065988 -335.906699) (xy 83.081343 -335.854404) (xy 83.103985 -335.804827) (xy 83.133451 -335.758977)
			(xy 83.169142 -335.717786) (xy 83.210333 -335.682095) (xy 83.256183 -335.652629) (xy 83.30576 -335.629987)
			(xy 83.358055 -335.614632) (xy 83.412003 -335.606876) (xy 83.466505 -335.606876) (xy 83.520453 -335.614632)
			(xy 83.572748 -335.629987) (xy 83.622325 -335.652629) (xy 83.668175 -335.682095) (xy 83.709366 -335.717786)
			(xy 83.745057 -335.758977) (xy 83.774523 -335.804827) (xy 83.797165 -335.854404) (xy 83.81252 -335.906699)
			(xy 83.820276 -335.960647) (xy 83.820762 -335.987898) (xy 83.820255 -336.015808) (xy 83.812122 -336.071033)
			(xy 83.796029 -336.124483) (xy 83.77232 -336.175018) (xy 83.7415 -336.221559) (xy 83.723226 -336.24266)
			(xy 83.717307 -336.249822) (xy 83.710668 -336.267159) (xy 83.710272 -336.276442) (xy 83.710272 -336.354166)
			(xy 83.716876 -336.371438) (xy 83.723226 -336.37855) (xy 83.741506 -336.399648) (xy 83.772332 -336.446187)
			(xy 83.796047 -336.496722) (xy 83.812143 -336.550174) (xy 83.820277 -336.605401) (xy 83.820762 -336.633312)
			(xy 83.820276 -336.660563) (xy 83.81252 -336.714511) (xy 83.797165 -336.766806) (xy 83.774523 -336.816383)
			(xy 83.745057 -336.862233) (xy 83.709366 -336.903424) (xy 83.668175 -336.939115) (xy 83.625096 -336.9668)
			(xy 87.439947 -336.9668) (xy 87.444116 -336.911181) (xy 87.456528 -336.856805) (xy 87.476905 -336.804886)
			(xy 87.504794 -336.756585) (xy 87.539571 -336.71298) (xy 87.580458 -336.675045) (xy 87.626543 -336.643629)
			(xy 87.676796 -336.619433) (xy 87.730094 -336.602997) (xy 87.785247 -336.594688) (xy 87.813134 -336.594196)
			(xy 87.839556 -336.594635) (xy 87.891873 -336.60209) (xy 87.942611 -336.616859) (xy 87.990755 -336.638647)
			(xy 88.035339 -336.667017) (xy 88.055704 -336.683858) (xy 88.062562 -336.6897) (xy 88.07958 -336.69605)
			(xy 88.163908 -336.69605) (xy 88.180926 -336.6897) (xy 88.187784 -336.683858) (xy 88.20815 -336.667019)
			(xy 88.252736 -336.638654) (xy 88.30088 -336.616867) (xy 88.351617 -336.602096) (xy 88.403932 -336.594636)
			(xy 88.456776 -336.594636) (xy 88.509091 -336.602096) (xy 88.559828 -336.616867) (xy 88.607972 -336.638654)
			(xy 88.652558 -336.667019) (xy 88.672924 -336.683858) (xy 88.679782 -336.6897) (xy 88.6968 -336.69605)
			(xy 88.781128 -336.69605) (xy 88.798146 -336.6897) (xy 88.805004 -336.683858) (xy 88.825835 -336.666667)
			(xy 88.871508 -336.637844) (xy 88.920863 -336.615915) (xy 88.946736 -336.608166) (xy 88.95842 -336.604864)
			(xy 88.9762 -336.588608) (xy 89.009474 -336.501232) (xy 89.01313 -336.489877) (xy 89.010739 -336.46617)
			(xy 89.004902 -336.455766) (xy 88.99112 -336.43326) (xy 88.969376 -336.385174) (xy 88.954635 -336.334501)
			(xy 88.947192 -336.282255) (xy 88.946736 -336.255868) (xy 88.947229 -336.228225) (xy 88.955384 -336.173544)
			(xy 88.971527 -336.120668) (xy 88.995301 -336.070755) (xy 89.026187 -336.024902) (xy 89.063507 -335.984113)
			(xy 89.084658 -335.966308) (xy 89.093079 -335.958705) (xy 89.102846 -335.938266) (xy 89.103454 -335.926938)
			(xy 89.103454 -335.848198) (xy 89.102811 -335.836879) (xy 89.093055 -335.816445) (xy 89.084658 -335.808828)
			(xy 89.063534 -335.790994) (xy 89.026222 -335.750205) (xy 88.995339 -335.704356) (xy 88.971562 -335.65445)
			(xy 88.955412 -335.601581) (xy 88.947242 -335.546908) (xy 88.946736 -335.519268) (xy 88.947257 -335.491383)
			(xy 88.955569 -335.436236) (xy 88.972007 -335.382944) (xy 88.996205 -335.332698) (xy 89.027621 -335.286619)
			(xy 89.065554 -335.245737) (xy 89.109156 -335.210965) (xy 89.157454 -335.18308) (xy 89.209369 -335.162705)
			(xy 89.26374 -335.150295) (xy 89.319354 -335.146128) (xy 89.374968 -335.150295) (xy 89.429339 -335.162705)
			(xy 89.481254 -335.18308) (xy 89.529552 -335.210965) (xy 89.573154 -335.245737) (xy 89.611087 -335.286619)
			(xy 89.642503 -335.332698) (xy 89.666701 -335.382944) (xy 89.683139 -335.436236) (xy 89.691451 -335.491383)
			(xy 89.691972 -335.519268) (xy 89.691502 -335.546912) (xy 89.683341 -335.601593) (xy 89.667194 -335.65447)
			(xy 89.643415 -335.704382) (xy 89.612525 -335.750235) (xy 89.575202 -335.791023) (xy 89.55405 -335.808828)
			(xy 89.545615 -335.816417) (xy 89.535855 -335.836867) (xy 89.535254 -335.848198) (xy 89.535254 -335.926938)
			(xy 89.535874 -335.93826) (xy 89.545645 -335.958694) (xy 89.55405 -335.966308) (xy 89.575192 -335.984121)
			(xy 89.612503 -336.024914) (xy 89.643384 -336.070768) (xy 89.667157 -336.120678) (xy 89.683303 -336.17355)
			(xy 89.691468 -336.228227) (xy 89.691972 -336.255868) (xy 89.69155 -336.282722) (xy 89.683817 -336.335871)
			(xy 89.668536 -336.38736) (xy 89.646023 -336.436122) (xy 89.616744 -336.481149) (xy 89.581306 -336.521506)
			(xy 89.540442 -336.55636) (xy 89.494998 -336.584987) (xy 89.445917 -336.606796) (xy 89.420192 -336.614516)
			(xy 89.408508 -336.617818) (xy 89.390728 -336.634074) (xy 89.357454 -336.72145) (xy 89.353819 -336.732809)
			(xy 89.356199 -336.75651) (xy 89.362026 -336.766916) (xy 89.375793 -336.789431) (xy 89.397542 -336.837513)
			(xy 89.412288 -336.888183) (xy 89.419734 -336.940428) (xy 89.420192 -336.966814) (xy 89.419779 -336.993433)
			(xy 89.4122 -337.04613) (xy 89.397199 -337.097211) (xy 89.37508 -337.145638) (xy 89.346295 -337.190424)
			(xy 89.311429 -337.230657) (xy 89.271192 -337.265519) (xy 89.226403 -337.294299) (xy 89.177974 -337.316413)
			(xy 89.126891 -337.331408) (xy 89.074193 -337.338982) (xy 89.047574 -337.339432) (xy 89.021152 -337.338982)
			(xy 88.968837 -337.331529) (xy 88.918098 -337.316762) (xy 88.869954 -337.294976) (xy 88.825369 -337.26661)
			(xy 88.805004 -337.24977) (xy 88.798146 -337.243928) (xy 88.781128 -337.237578) (xy 88.6968 -337.237578)
			(xy 88.679782 -337.243928) (xy 88.672924 -337.24977) (xy 88.652558 -337.266609) (xy 88.607972 -337.294974)
			(xy 88.559828 -337.316761) (xy 88.509091 -337.331532) (xy 88.456776 -337.338992) (xy 88.403932 -337.338992)
			(xy 88.351617 -337.331532) (xy 88.30088 -337.316761) (xy 88.252736 -337.294974) (xy 88.20815 -337.266609)
			(xy 88.187784 -337.24977) (xy 88.180926 -337.243928) (xy 88.163908 -337.237578) (xy 88.07958 -337.237578)
			(xy 88.062562 -337.243928) (xy 88.055704 -337.24977) (xy 88.035333 -337.266602) (xy 87.990745 -337.294959)
			(xy 87.942602 -337.31674) (xy 87.891866 -337.331509) (xy 87.839555 -337.33897) (xy 87.813134 -337.339432)
			(xy 87.785247 -337.338912) (xy 87.730094 -337.330603) (xy 87.676796 -337.314167) (xy 87.626543 -337.289971)
			(xy 87.580458 -337.258555) (xy 87.539571 -337.22062) (xy 87.504794 -337.177015) (xy 87.476905 -337.128714)
			(xy 87.456528 -337.076795) (xy 87.444116 -337.022419) (xy 87.439947 -336.9668) (xy 83.625096 -336.9668)
			(xy 83.622325 -336.968581) (xy 83.572748 -336.991223) (xy 83.520453 -337.006578) (xy 83.466505 -337.014334)
			(xy 83.412003 -337.014334) (xy 83.358055 -337.006578) (xy 83.30576 -336.991223) (xy 83.256183 -336.968581)
			(xy 83.210333 -336.939115) (xy 83.169142 -336.903424) (xy 83.133451 -336.862233) (xy 83.103985 -336.816383)
			(xy 83.081343 -336.766806) (xy 83.065988 -336.714511) (xy 83.058232 -336.660563) (xy 83.057746 -336.633312)
			(xy 81.023289 -336.633312) (xy 80.984598 -336.731864) (xy 80.987646 -336.756756) (xy 80.995012 -336.767424)
			(xy 81.010922 -336.791067) (xy 81.036174 -336.842149) (xy 81.053345 -336.896483) (xy 81.062032 -336.9528)
			(xy 81.062576 -336.981292) (xy 81.062158 -337.007912) (xy 81.054582 -337.060609) (xy 81.039583 -337.111691)
			(xy 81.017466 -337.160119) (xy 80.988681 -337.204906) (xy 80.953816 -337.24514) (xy 80.913578 -337.280002)
			(xy 80.868789 -337.308782) (xy 80.820359 -337.330895) (xy 80.769275 -337.345889) (xy 80.716578 -337.353461)
			(xy 80.689958 -337.35391) (xy 80.663535 -337.353474) (xy 80.611219 -337.346019) (xy 80.56048 -337.331248)
			(xy 80.512336 -337.30946) (xy 80.467753 -337.28109) (xy 80.447388 -337.264248) (xy 80.44053 -337.258406)
			(xy 80.423512 -337.252056) (xy 80.339184 -337.252056) (xy 80.322166 -337.258406) (xy 80.315308 -337.264248)
			(xy 80.294942 -337.281087) (xy 80.250356 -337.309452) (xy 80.202212 -337.331239) (xy 80.151475 -337.34601)
			(xy 80.09916 -337.35347) (xy 80.046316 -337.35347) (xy 79.994001 -337.34601) (xy 79.943264 -337.331239)
			(xy 79.89512 -337.309452) (xy 79.850534 -337.281087) (xy 79.830168 -337.264248) (xy 79.82331 -337.258406)
			(xy 79.806292 -337.252056) (xy 79.721964 -337.252056) (xy 79.704946 -337.258406) (xy 79.698088 -337.264248)
			(xy 79.67772 -337.281084) (xy 79.633132 -337.309441) (xy 79.584988 -337.331221) (xy 79.534252 -337.34599)
			(xy 79.481939 -337.35345) (xy 79.455518 -337.35391) (xy 79.42763 -337.353432) (xy 79.372476 -337.345122)
			(xy 79.319177 -337.328683) (xy 79.268923 -337.304485) (xy 79.222838 -337.273066) (xy 79.18195 -337.235129)
			(xy 79.147173 -337.191522) (xy 79.119284 -337.143219) (xy 79.098906 -337.091298) (xy 79.086494 -337.03692)
			(xy 79.082325 -336.9813) (xy 75.267446 -336.9813) (xy 75.264709 -336.983059) (xy 75.215132 -337.005701)
			(xy 75.162837 -337.021056) (xy 75.108889 -337.028812) (xy 75.054387 -337.028812) (xy 75.000439 -337.021056)
			(xy 74.948144 -337.005701) (xy 74.898567 -336.983059) (xy 74.852717 -336.953593) (xy 74.811526 -336.917902)
			(xy 74.775835 -336.876711) (xy 74.746369 -336.830861) (xy 74.723727 -336.781284) (xy 74.708372 -336.728989)
			(xy 74.700616 -336.675041) (xy 74.70013 -336.64779) (xy 72.665688 -336.64779) (xy 72.63003 -336.7405)
			(xy 72.633078 -336.765392) (xy 72.640444 -336.775806) (xy 72.65615 -336.799345) (xy 72.681017 -336.850173)
			(xy 72.697919 -336.904175) (xy 72.706468 -336.960111) (xy 72.706992 -336.988404) (xy 72.706569 -337.015023)
			(xy 72.698992 -337.067719) (xy 72.683992 -337.118801) (xy 72.661875 -337.167227) (xy 72.633091 -337.212013)
			(xy 72.598225 -337.252247) (xy 72.557989 -337.287109) (xy 72.513201 -337.315889) (xy 72.464773 -337.338002)
			(xy 72.41369 -337.352998) (xy 72.360993 -337.360572) (xy 72.334374 -337.361022) (xy 72.307952 -337.360574)
			(xy 72.255636 -337.353121) (xy 72.204898 -337.338353) (xy 72.156754 -337.316568) (xy 72.112169 -337.2882)
			(xy 72.091804 -337.27136) (xy 72.084946 -337.265518) (xy 72.067928 -337.259168) (xy 71.9836 -337.259168)
			(xy 71.966582 -337.265518) (xy 71.959724 -337.27136) (xy 71.939358 -337.288199) (xy 71.894772 -337.316564)
			(xy 71.846628 -337.338351) (xy 71.795891 -337.353122) (xy 71.743576 -337.360582) (xy 71.690732 -337.360582)
			(xy 71.638417 -337.353122) (xy 71.58768 -337.338351) (xy 71.539536 -337.316564) (xy 71.49495 -337.288199)
			(xy 71.474584 -337.27136) (xy 71.467726 -337.265518) (xy 71.450708 -337.259168) (xy 71.36638 -337.259168)
			(xy 71.349362 -337.265518) (xy 71.342504 -337.27136) (xy 71.322132 -337.28819) (xy 71.277545 -337.316548)
			(xy 71.229401 -337.338329) (xy 71.178666 -337.353099) (xy 71.126355 -337.36056) (xy 71.099934 -337.361022)
			(xy 71.072046 -337.360521) (xy 71.016892 -337.352213) (xy 70.963593 -337.335777) (xy 70.913338 -337.31158)
			(xy 70.867252 -337.280162) (xy 70.826364 -337.242227) (xy 70.791586 -337.198621) (xy 70.763696 -337.150318)
			(xy 70.743318 -337.098398) (xy 70.730906 -337.04402) (xy 70.726737 -336.9884) (xy 66.911881 -336.9884)
			(xy 66.909125 -336.990171) (xy 66.859548 -337.012813) (xy 66.807253 -337.028168) (xy 66.753305 -337.035924)
			(xy 66.698803 -337.035924) (xy 66.644855 -337.028168) (xy 66.59256 -337.012813) (xy 66.542983 -336.990171)
			(xy 66.497133 -336.960705) (xy 66.455942 -336.925014) (xy 66.420251 -336.883823) (xy 66.390785 -336.837973)
			(xy 66.368143 -336.788396) (xy 66.352788 -336.736101) (xy 66.345032 -336.682153) (xy 66.344546 -336.654902)
			(xy 28.014676 -336.654902) (xy 26.78303 -337.886548) (xy 67.302378 -337.886548) (xy 67.306449 -337.830926)
			(xy 67.318575 -337.776489) (xy 67.338498 -337.724398) (xy 67.365794 -337.675763) (xy 67.39988 -337.63162)
			(xy 67.440029 -337.592911) (xy 67.485387 -337.56046) (xy 67.534987 -337.534959) (xy 67.587771 -337.516952)
			(xy 67.642614 -337.506822) (xy 67.698348 -337.504785) (xy 67.753785 -337.510885) (xy 67.807742 -337.524991)
			(xy 67.859071 -337.546803) (xy 67.906677 -337.575857) (xy 67.949545 -337.611532) (xy 67.986762 -337.653069)
			(xy 68.017535 -337.699582) (xy 68.041207 -337.750079) (xy 68.057275 -337.803486) (xy 68.065395 -337.858662)
			(xy 68.065904 -337.886548) (xy 68.065395 -337.914434) (xy 68.057275 -337.96961) (xy 68.041207 -338.023017)
			(xy 68.017535 -338.073514) (xy 67.986762 -338.120027) (xy 67.949545 -338.161564) (xy 67.906677 -338.197239)
			(xy 67.859071 -338.226293) (xy 67.807742 -338.248105) (xy 67.753785 -338.262211) (xy 67.698348 -338.268311)
			(xy 67.642614 -338.266274) (xy 67.587771 -338.256144) (xy 67.534987 -338.238137) (xy 67.485387 -338.212636)
			(xy 67.440029 -338.180185) (xy 67.39988 -338.141476) (xy 67.365794 -338.097333) (xy 67.338498 -338.048698)
			(xy 67.318575 -337.996607) (xy 67.306449 -337.94217) (xy 67.302378 -337.886548) (xy 26.78303 -337.886548)
			(xy 25.969214 -338.700364) (xy 25.962376 -338.707765) (xy 25.954663 -338.726364) (xy 25.954228 -338.736432)
			(xy 25.954228 -338.781898) (xy 66.723258 -338.781898) (xy 66.727329 -338.726276) (xy 66.739455 -338.671839)
			(xy 66.759378 -338.619748) (xy 66.786674 -338.571113) (xy 66.82076 -338.52697) (xy 66.860909 -338.488261)
			(xy 66.906267 -338.45581) (xy 66.955867 -338.430309) (xy 67.008651 -338.412302) (xy 67.063494 -338.402172)
			(xy 67.119228 -338.400135) (xy 67.174665 -338.406235) (xy 67.228622 -338.420341) (xy 67.279951 -338.442153)
			(xy 67.327557 -338.471207) (xy 67.370425 -338.506882) (xy 67.407642 -338.548419) (xy 67.438415 -338.594932)
			(xy 67.462087 -338.645429) (xy 67.478155 -338.698836) (xy 67.486275 -338.754012) (xy 67.486784 -338.781898)
			(xy 67.486275 -338.809784) (xy 67.478155 -338.86496) (xy 67.462087 -338.918367) (xy 67.438415 -338.968864)
			(xy 67.407642 -339.015377) (xy 67.370425 -339.056914) (xy 67.327557 -339.092589) (xy 67.279951 -339.121643)
			(xy 67.228622 -339.143455) (xy 67.174665 -339.157561) (xy 67.119228 -339.163661) (xy 67.063494 -339.161624)
			(xy 67.008651 -339.151494) (xy 66.955867 -339.133487) (xy 66.906267 -339.107986) (xy 66.860909 -339.075535)
			(xy 66.82076 -339.036826) (xy 66.786674 -338.992683) (xy 66.759378 -338.944048) (xy 66.739455 -338.891957)
			(xy 66.727329 -338.83752) (xy 66.723258 -338.781898) (xy 25.954228 -338.781898) (xy 25.954228 -339.457538)
			(xy 68.062094 -339.457538) (xy 68.062604 -339.430064) (xy 68.070491 -339.375686) (xy 68.086105 -339.323004)
			(xy 68.109124 -339.273111) (xy 68.139071 -339.227041) (xy 68.156836 -339.206078) (xy 68.15709 -339.205824)
			(xy 68.162672 -339.198734) (xy 68.168922 -339.18182) (xy 68.169282 -339.172804) (xy 68.169282 -339.10524)
			(xy 68.16891 -339.096225) (xy 68.162673 -339.079307) (xy 68.15709 -339.07222) (xy 68.156582 -339.071712)
			(xy 68.138855 -339.05076) (xy 68.108972 -339.004729) (xy 68.086005 -338.954885) (xy 68.070429 -338.902261)
			(xy 68.062566 -338.847946) (xy 68.062094 -338.820506) (xy 68.06258 -338.793255) (xy 68.070336 -338.739307)
			(xy 68.085691 -338.687012) (xy 68.108333 -338.637435) (xy 68.137799 -338.591585) (xy 68.17349 -338.550394)
			(xy 68.214681 -338.514703) (xy 68.260531 -338.485237) (xy 68.310108 -338.462595) (xy 68.362403 -338.44724)
			(xy 68.416351 -338.439484) (xy 68.470853 -338.439484) (xy 68.524801 -338.44724) (xy 68.577096 -338.462595)
			(xy 68.626673 -338.485237) (xy 68.672523 -338.514703) (xy 68.713714 -338.550394) (xy 68.749405 -338.591585)
			(xy 68.778871 -338.637435) (xy 68.801513 -338.687012) (xy 68.816868 -338.739307) (xy 68.824624 -338.793255)
			(xy 68.82511 -338.820506) (xy 68.824625 -338.847981) (xy 68.816732 -338.90236) (xy 68.801112 -338.955042)
			(xy 68.778087 -339.004935) (xy 68.748135 -339.051004) (xy 68.730368 -339.071966) (xy 68.730114 -339.07222)
			(xy 68.724514 -339.079298) (xy 68.718275 -339.096221) (xy 68.717922 -339.10524) (xy 68.717922 -339.172804)
			(xy 68.718272 -339.181822) (xy 68.724524 -339.198739) (xy 68.730114 -339.205824) (xy 68.730622 -339.206332)
			(xy 68.74837 -339.227266) (xy 68.77825 -339.273303) (xy 68.801213 -339.323151) (xy 68.816784 -339.375779)
			(xy 68.824641 -339.430096) (xy 68.82511 -339.457538) (xy 68.824624 -339.484789) (xy 68.816868 -339.538737)
			(xy 68.801513 -339.591032) (xy 68.778871 -339.640609) (xy 68.749405 -339.686459) (xy 68.713714 -339.72765)
			(xy 68.672523 -339.763341) (xy 68.626673 -339.792807) (xy 68.577096 -339.815449) (xy 68.524801 -339.830804)
			(xy 68.470853 -339.83856) (xy 68.416351 -339.83856) (xy 68.362403 -339.830804) (xy 68.310108 -339.815449)
			(xy 68.260531 -339.792807) (xy 68.214681 -339.763341) (xy 68.17349 -339.72765) (xy 68.137799 -339.686459)
			(xy 68.108333 -339.640609) (xy 68.085691 -339.591032) (xy 68.070336 -339.538737) (xy 68.06258 -339.484789)
			(xy 68.062094 -339.457538) (xy 25.954228 -339.457538) (xy 25.954228 -348.7095) (xy 28.918321 -348.7095)
			(xy 28.92249 -348.653877) (xy 28.934903 -348.599498) (xy 28.955282 -348.547575) (xy 28.983173 -348.49927)
			(xy 29.017952 -348.455662) (xy 29.058842 -348.417725) (xy 29.10493 -348.386307) (xy 29.155187 -348.362108)
			(xy 29.208488 -348.345671) (xy 29.263645 -348.337363) (xy 29.291534 -348.33687) (xy 29.317956 -348.337315)
			(xy 29.370272 -348.344769) (xy 29.42101 -348.359538) (xy 29.469154 -348.381324) (xy 29.513739 -348.409692)
			(xy 29.534104 -348.426532) (xy 29.540962 -348.432374) (xy 29.55798 -348.438724) (xy 29.642308 -348.438724)
			(xy 29.659326 -348.432374) (xy 29.666184 -348.426532) (xy 29.68655 -348.409693) (xy 29.731136 -348.381328)
			(xy 29.77928 -348.359541) (xy 29.830017 -348.34477) (xy 29.882332 -348.33731) (xy 29.935176 -348.33731)
			(xy 29.987491 -348.34477) (xy 30.038228 -348.359541) (xy 30.086372 -348.381328) (xy 30.130958 -348.409693)
			(xy 30.151324 -348.426532) (xy 30.158182 -348.432374) (xy 30.1752 -348.438724) (xy 30.259528 -348.438724)
			(xy 30.276546 -348.432374) (xy 30.283404 -348.426532) (xy 30.304989 -348.408734) (xy 30.35245 -348.379119)
			(xy 30.403805 -348.356931) (xy 30.430724 -348.349316) (xy 30.44317 -348.346014) (xy 30.461204 -348.32925)
			(xy 30.49778 -348.22638) (xy 30.494224 -348.201488) (xy 30.486858 -348.191328) (xy 30.469611 -348.166737)
			(xy 30.442275 -348.113255) (xy 30.423672 -348.056145) (xy 30.414262 -347.996824) (xy 30.413706 -347.966792)
			(xy 30.413706 -347.966538) (xy 30.414196 -347.938964) (xy 30.422143 -347.884392) (xy 30.437863 -347.831533)
			(xy 30.461029 -347.781487) (xy 30.491157 -347.735297) (xy 30.527621 -347.693924) (xy 30.548326 -347.675708)
			(xy 30.556402 -347.668154) (xy 30.565755 -347.648142) (xy 30.56636 -347.6371) (xy 30.56636 -347.559376)
			(xy 30.565762 -347.54833) (xy 30.556419 -347.528308) (xy 30.548326 -347.520768) (xy 30.527601 -347.502571)
			(xy 30.491131 -347.4612) (xy 30.461 -347.415008) (xy 30.437836 -347.364957) (xy 30.422123 -347.312091)
			(xy 30.414188 -347.257514) (xy 30.413706 -347.229938) (xy 30.414192 -347.202687) (xy 30.421948 -347.148739)
			(xy 30.437303 -347.096444) (xy 30.459945 -347.046867) (xy 30.489411 -347.001017) (xy 30.525102 -346.959826)
			(xy 30.566293 -346.924135) (xy 30.612143 -346.894669) (xy 30.66172 -346.872027) (xy 30.714015 -346.856672)
			(xy 30.767963 -346.848916) (xy 30.822465 -346.848916) (xy 30.876413 -346.856672) (xy 30.928708 -346.872027)
			(xy 30.978285 -346.894669) (xy 31.024135 -346.924135) (xy 31.065326 -346.959826) (xy 31.101017 -347.001017)
			(xy 31.130483 -347.046867) (xy 31.153125 -347.096444) (xy 31.16848 -347.148739) (xy 31.176236 -347.202687)
			(xy 31.176722 -347.229938) (xy 31.176206 -347.257511) (xy 31.168263 -347.312081) (xy 31.152547 -347.36494)
			(xy 31.129386 -347.414986) (xy 31.099263 -347.461176) (xy 31.062805 -347.50255) (xy 31.042102 -347.520768)
			(xy 31.034041 -347.528336) (xy 31.024679 -347.548338) (xy 31.024068 -347.559376) (xy 31.024068 -347.6371)
			(xy 31.02467 -347.648146) (xy 31.034009 -347.668168) (xy 31.042102 -347.675708) (xy 31.062821 -347.693911)
			(xy 31.09929 -347.735282) (xy 31.129421 -347.781473) (xy 31.152586 -347.831523) (xy 31.168301 -347.884387)
			(xy 31.176238 -347.938963) (xy 31.176722 -347.966538) (xy 31.176251 -347.994643) (xy 31.167999 -348.050245)
			(xy 31.151678 -348.104034) (xy 31.127642 -348.154846) (xy 31.096411 -348.201583) (xy 31.058662 -348.243231)
			(xy 31.01521 -348.27889) (xy 30.966997 -348.307789) (xy 30.915065 -348.329301) (xy 30.887924 -348.336616)
			(xy 30.876191 -348.340398) (xy 30.857883 -348.356849) (xy 30.852872 -348.368112) (xy 30.84993 -348.375986)
			(xy 32.816546 -348.375986) (xy 32.817041 -348.348075) (xy 32.825177 -348.29285) (xy 32.841272 -348.2394)
			(xy 32.864984 -348.188865) (xy 32.895806 -348.142325) (xy 32.914082 -348.121224) (xy 32.919966 -348.114037)
			(xy 32.926625 -348.096719) (xy 32.927036 -348.087442) (xy 32.927036 -348.009718) (xy 32.920432 -347.992446)
			(xy 32.914082 -347.985334) (xy 32.895796 -347.964241) (xy 32.86497 -347.917701) (xy 32.841257 -347.867164)
			(xy 32.825162 -347.813712) (xy 32.81703 -347.758484) (xy 32.816546 -347.730572) (xy 32.817032 -347.703321)
			(xy 32.824788 -347.649373) (xy 32.840143 -347.597078) (xy 32.862785 -347.547501) (xy 32.892251 -347.501651)
			(xy 32.927942 -347.46046) (xy 32.969133 -347.424769) (xy 33.014983 -347.395303) (xy 33.06456 -347.372661)
			(xy 33.116855 -347.357306) (xy 33.170803 -347.34955) (xy 33.225305 -347.34955) (xy 33.279253 -347.357306)
			(xy 33.331548 -347.372661) (xy 33.381125 -347.395303) (xy 33.426975 -347.424769) (xy 33.468166 -347.46046)
			(xy 33.503857 -347.501651) (xy 33.533323 -347.547501) (xy 33.555965 -347.597078) (xy 33.57132 -347.649373)
			(xy 33.579076 -347.703321) (xy 33.579562 -347.730572) (xy 33.579099 -347.758484) (xy 33.570955 -347.81371)
			(xy 33.554852 -347.867161) (xy 33.531133 -347.917695) (xy 33.500305 -347.964234) (xy 33.482026 -347.985334)
			(xy 33.476118 -347.992504) (xy 33.469473 -348.009834) (xy 33.469072 -348.019116) (xy 33.469072 -348.09684)
			(xy 33.475676 -348.114112) (xy 33.482026 -348.121224) (xy 33.500294 -348.142332) (xy 33.531122 -348.188868)
			(xy 33.554839 -348.239401) (xy 33.570938 -348.29285) (xy 33.579075 -348.348075) (xy 33.579562 -348.375986)
			(xy 33.579076 -348.403237) (xy 33.57132 -348.457185) (xy 33.555965 -348.50948) (xy 33.533323 -348.559057)
			(xy 33.503857 -348.604907) (xy 33.468166 -348.646098) (xy 33.426975 -348.681789) (xy 33.383856 -348.7095)
			(xy 37.198721 -348.7095) (xy 37.20289 -348.653877) (xy 37.215303 -348.599498) (xy 37.235682 -348.547575)
			(xy 37.263573 -348.49927) (xy 37.298352 -348.455662) (xy 37.339242 -348.417725) (xy 37.38533 -348.386307)
			(xy 37.435587 -348.362108) (xy 37.488888 -348.345671) (xy 37.544045 -348.337363) (xy 37.571934 -348.33687)
			(xy 37.598356 -348.337315) (xy 37.650672 -348.344769) (xy 37.70141 -348.359538) (xy 37.749554 -348.381324)
			(xy 37.794139 -348.409692) (xy 37.814504 -348.426532) (xy 37.821362 -348.432374) (xy 37.83838 -348.438724)
			(xy 37.922708 -348.438724) (xy 37.939726 -348.432374) (xy 37.946584 -348.426532) (xy 37.96695 -348.409693)
			(xy 38.011536 -348.381328) (xy 38.05968 -348.359541) (xy 38.110417 -348.34477) (xy 38.162732 -348.33731)
			(xy 38.215576 -348.33731) (xy 38.267891 -348.34477) (xy 38.318628 -348.359541) (xy 38.366772 -348.381328)
			(xy 38.411358 -348.409693) (xy 38.431724 -348.426532) (xy 38.438582 -348.432374) (xy 38.4556 -348.438724)
			(xy 38.539928 -348.438724) (xy 38.556946 -348.432374) (xy 38.563804 -348.426532) (xy 38.582653 -348.410899)
			(xy 38.623697 -348.384187) (xy 38.667889 -348.363089) (xy 38.691058 -348.355158) (xy 38.691312 -348.355158)
			(xy 38.702426 -348.350745) (xy 38.719249 -348.333795) (xy 38.72357 -348.322646) (xy 38.749224 -348.244414)
			(xy 38.752273 -348.232768) (xy 38.748427 -348.209037) (xy 38.741858 -348.198948) (xy 38.741858 -348.198694)
			(xy 38.724615 -348.1741) (xy 38.697284 -348.120617) (xy 38.678681 -348.063509) (xy 38.669266 -348.004189)
			(xy 38.668706 -347.974158) (xy 38.66921 -347.946585) (xy 38.677154 -347.892014) (xy 38.692871 -347.839154)
			(xy 38.716034 -347.789108) (xy 38.74616 -347.742918) (xy 38.782622 -347.701545) (xy 38.803326 -347.683328)
			(xy 38.811393 -347.675766) (xy 38.820751 -347.65576) (xy 38.82136 -347.64472) (xy 38.82136 -347.566996)
			(xy 38.820751 -347.555951) (xy 38.811416 -347.535929) (xy 38.803326 -347.528388) (xy 38.782611 -347.510181)
			(xy 38.74614 -347.468812) (xy 38.716008 -347.422621) (xy 38.692842 -347.372573) (xy 38.677127 -347.319709)
			(xy 38.66919 -347.265133) (xy 38.668706 -347.237558) (xy 38.669192 -347.210307) (xy 38.676948 -347.156359)
			(xy 38.692303 -347.104064) (xy 38.714945 -347.054487) (xy 38.744411 -347.008637) (xy 38.780102 -346.967446)
			(xy 38.821293 -346.931755) (xy 38.867143 -346.902289) (xy 38.91672 -346.879647) (xy 38.969015 -346.864292)
			(xy 39.022963 -346.856536) (xy 39.077465 -346.856536) (xy 39.131413 -346.864292) (xy 39.183708 -346.879647)
			(xy 39.233285 -346.902289) (xy 39.279135 -346.931755) (xy 39.320326 -346.967446) (xy 39.356017 -347.008637)
			(xy 39.385483 -347.054487) (xy 39.408125 -347.104064) (xy 39.42348 -347.156359) (xy 39.431236 -347.210307)
			(xy 39.431722 -347.237558) (xy 39.43122 -347.265131) (xy 39.423274 -347.319702) (xy 39.407555 -347.372561)
			(xy 39.384392 -347.422607) (xy 39.354266 -347.468797) (xy 39.317806 -347.510171) (xy 39.297102 -347.528388)
			(xy 39.289032 -347.535948) (xy 39.279675 -347.555956) (xy 39.279068 -347.566996) (xy 39.279068 -347.64472)
			(xy 39.279659 -347.655767) (xy 39.289006 -347.67579) (xy 39.297102 -347.683328) (xy 39.31783 -347.70152)
			(xy 39.354299 -347.742893) (xy 39.384429 -347.789087) (xy 39.407592 -347.839139) (xy 39.423305 -347.892005)
			(xy 39.431239 -347.946582) (xy 39.431722 -347.974158) (xy 39.431285 -348.001084) (xy 39.423713 -348.0544)
			(xy 39.408714 -348.10612) (xy 39.386586 -348.155215) (xy 39.357769 -348.200708) (xy 39.322837 -348.241693)
			(xy 39.282486 -348.277354) (xy 39.237518 -348.306983) (xy 39.188828 -348.329988) (xy 39.163244 -348.338394)
			(xy 39.16299 -348.338394) (xy 39.151826 -348.342701) (xy 39.134852 -348.359516) (xy 39.130478 -348.370652)
			(xy 39.12866 -348.375986) (xy 41.122346 -348.375986) (xy 41.122841 -348.348075) (xy 41.130977 -348.29285)
			(xy 41.147072 -348.2394) (xy 41.170784 -348.188865) (xy 41.201606 -348.142325) (xy 41.219882 -348.121224)
			(xy 41.225766 -348.114037) (xy 41.232425 -348.096719) (xy 41.232836 -348.087442) (xy 41.232836 -348.009718)
			(xy 41.226232 -347.992446) (xy 41.219882 -347.985334) (xy 41.201596 -347.964241) (xy 41.17077 -347.917701)
			(xy 41.147057 -347.867164) (xy 41.130962 -347.813712) (xy 41.12283 -347.758484) (xy 41.122346 -347.730572)
			(xy 41.122832 -347.703321) (xy 41.130588 -347.649373) (xy 41.145943 -347.597078) (xy 41.168585 -347.547501)
			(xy 41.198051 -347.501651) (xy 41.233742 -347.46046) (xy 41.274933 -347.424769) (xy 41.320783 -347.395303)
			(xy 41.37036 -347.372661) (xy 41.422655 -347.357306) (xy 41.476603 -347.34955) (xy 41.531105 -347.34955)
			(xy 41.585053 -347.357306) (xy 41.637348 -347.372661) (xy 41.686925 -347.395303) (xy 41.732775 -347.424769)
			(xy 41.773966 -347.46046) (xy 41.809657 -347.501651) (xy 41.839123 -347.547501) (xy 41.861765 -347.597078)
			(xy 41.87712 -347.649373) (xy 41.884876 -347.703321) (xy 41.885362 -347.730572) (xy 41.884899 -347.758484)
			(xy 41.876755 -347.81371) (xy 41.860652 -347.867161) (xy 41.836933 -347.917695) (xy 41.806105 -347.964234)
			(xy 41.787826 -347.985334) (xy 41.781918 -347.992504) (xy 41.775273 -348.009834) (xy 41.774872 -348.019116)
			(xy 41.774872 -348.09684) (xy 41.781476 -348.114112) (xy 41.787826 -348.121224) (xy 41.806094 -348.142332)
			(xy 41.836922 -348.188868) (xy 41.860639 -348.239401) (xy 41.876738 -348.29285) (xy 41.884875 -348.348075)
			(xy 41.885362 -348.375986) (xy 41.884876 -348.403237) (xy 41.87712 -348.457185) (xy 41.861765 -348.50948)
			(xy 41.839123 -348.559057) (xy 41.809657 -348.604907) (xy 41.773966 -348.646098) (xy 41.732775 -348.681789)
			(xy 41.689656 -348.7095) (xy 45.504521 -348.7095) (xy 45.50869 -348.653877) (xy 45.521103 -348.599498)
			(xy 45.541482 -348.547575) (xy 45.569373 -348.49927) (xy 45.604152 -348.455662) (xy 45.645042 -348.417725)
			(xy 45.69113 -348.386307) (xy 45.741387 -348.362108) (xy 45.794688 -348.345671) (xy 45.849845 -348.337363)
			(xy 45.877734 -348.33687) (xy 45.904156 -348.337315) (xy 45.956472 -348.344769) (xy 46.00721 -348.359538)
			(xy 46.055354 -348.381324) (xy 46.099939 -348.409692) (xy 46.120304 -348.426532) (xy 46.127162 -348.432374)
			(xy 46.14418 -348.438724) (xy 46.228508 -348.438724) (xy 46.245526 -348.432374) (xy 46.252384 -348.426532)
			(xy 46.27275 -348.409693) (xy 46.317336 -348.381328) (xy 46.36548 -348.359541) (xy 46.416217 -348.34477)
			(xy 46.468532 -348.33731) (xy 46.521376 -348.33731) (xy 46.573691 -348.34477) (xy 46.624428 -348.359541)
			(xy 46.672572 -348.381328) (xy 46.717158 -348.409693) (xy 46.737524 -348.426532) (xy 46.744382 -348.432374)
			(xy 46.7614 -348.438724) (xy 46.845728 -348.438724) (xy 46.862746 -348.432374) (xy 46.869604 -348.426532)
			(xy 46.895641 -348.405213) (xy 46.953781 -348.371343) (xy 46.985174 -348.359222) (xy 46.995597 -348.354864)
			(xy 47.011554 -348.338913) (xy 47.015908 -348.328488) (xy 47.04207 -348.254828) (xy 47.045301 -348.244099)
			(xy 47.043211 -348.221822) (xy 47.038006 -348.211902) (xy 47.02535 -348.189724) (xy 47.005398 -348.14272)
			(xy 46.991893 -348.093476) (xy 46.985077 -348.042869) (xy 46.984666 -348.017338) (xy 46.985135 -347.989763)
			(xy 46.993083 -347.93519) (xy 47.008806 -347.882329) (xy 47.031976 -347.832282) (xy 47.062109 -347.786093)
			(xy 47.098578 -347.744723) (xy 47.119286 -347.726508) (xy 47.127356 -347.718948) (xy 47.136714 -347.69894)
			(xy 47.13732 -347.6879) (xy 47.13732 -347.610176) (xy 47.136735 -347.599128) (xy 47.127384 -347.579105)
			(xy 47.119286 -347.571568) (xy 47.098553 -347.55338) (xy 47.062085 -347.512006) (xy 47.031956 -347.465811)
			(xy 47.008794 -347.415759) (xy 46.993082 -347.362892) (xy 46.985148 -347.308314) (xy 46.984666 -347.280738)
			(xy 46.985152 -347.253487) (xy 46.992908 -347.199539) (xy 47.008263 -347.147244) (xy 47.030905 -347.097667)
			(xy 47.060371 -347.051817) (xy 47.096062 -347.010626) (xy 47.137253 -346.974935) (xy 47.183103 -346.945469)
			(xy 47.23268 -346.922827) (xy 47.284975 -346.907472) (xy 47.338923 -346.899716) (xy 47.393425 -346.899716)
			(xy 47.447373 -346.907472) (xy 47.499668 -346.922827) (xy 47.549245 -346.945469) (xy 47.595095 -346.974935)
			(xy 47.636286 -347.010626) (xy 47.671977 -347.051817) (xy 47.701443 -347.097667) (xy 47.724085 -347.147244)
			(xy 47.73944 -347.199539) (xy 47.747196 -347.253487) (xy 47.747682 -347.280738) (xy 47.74718 -347.308311)
			(xy 47.739236 -347.362883) (xy 47.723518 -347.415742) (xy 47.700355 -347.465789) (xy 47.670229 -347.511979)
			(xy 47.633767 -347.553351) (xy 47.613062 -347.571568) (xy 47.604995 -347.57913) (xy 47.595638 -347.599136)
			(xy 47.595028 -347.610176) (xy 47.595028 -347.6879) (xy 47.595643 -347.698944) (xy 47.604974 -347.718966)
			(xy 47.613062 -347.726508) (xy 47.633773 -347.74472) (xy 47.670245 -347.786088) (xy 47.700378 -347.832277)
			(xy 47.723544 -347.882325) (xy 47.73926 -347.935188) (xy 47.747198 -347.989763) (xy 47.747682 -348.017338)
			(xy 47.747249 -348.043602) (xy 47.740051 -348.095633) (xy 47.725782 -348.146185) (xy 47.704713 -348.194302)
			(xy 47.677241 -348.239072) (xy 47.643886 -348.27965) (xy 47.60528 -348.315268) (xy 47.562152 -348.345253)
			(xy 47.515318 -348.369037) (xy 47.496219 -348.375986) (xy 49.478946 -348.375986) (xy 49.479441 -348.348075)
			(xy 49.487577 -348.29285) (xy 49.503672 -348.2394) (xy 49.527384 -348.188865) (xy 49.558206 -348.142325)
			(xy 49.576482 -348.121224) (xy 49.582366 -348.114037) (xy 49.589025 -348.096719) (xy 49.589436 -348.087442)
			(xy 49.589436 -348.009718) (xy 49.582832 -347.992446) (xy 49.576482 -347.985334) (xy 49.558196 -347.964241)
			(xy 49.52737 -347.917701) (xy 49.503657 -347.867164) (xy 49.487562 -347.813712) (xy 49.47943 -347.758484)
			(xy 49.478946 -347.730572) (xy 49.479432 -347.703321) (xy 49.487188 -347.649373) (xy 49.502543 -347.597078)
			(xy 49.525185 -347.547501) (xy 49.554651 -347.501651) (xy 49.590342 -347.46046) (xy 49.631533 -347.424769)
			(xy 49.677383 -347.395303) (xy 49.72696 -347.372661) (xy 49.779255 -347.357306) (xy 49.833203 -347.34955)
			(xy 49.887705 -347.34955) (xy 49.941653 -347.357306) (xy 49.993948 -347.372661) (xy 50.043525 -347.395303)
			(xy 50.089375 -347.424769) (xy 50.130566 -347.46046) (xy 50.166257 -347.501651) (xy 50.195723 -347.547501)
			(xy 50.218365 -347.597078) (xy 50.23372 -347.649373) (xy 50.241476 -347.703321) (xy 50.241962 -347.730572)
			(xy 50.241499 -347.758484) (xy 50.233355 -347.81371) (xy 50.217252 -347.867161) (xy 50.193533 -347.917695)
			(xy 50.162705 -347.964234) (xy 50.144426 -347.985334) (xy 50.138518 -347.992504) (xy 50.131873 -348.009834)
			(xy 50.131472 -348.019116) (xy 50.131472 -348.09684) (xy 50.138076 -348.114112) (xy 50.144426 -348.121224)
			(xy 50.162694 -348.142332) (xy 50.193522 -348.188868) (xy 50.217239 -348.239401) (xy 50.233338 -348.29285)
			(xy 50.241475 -348.348075) (xy 50.241962 -348.375986) (xy 50.241476 -348.403237) (xy 50.23372 -348.457185)
			(xy 50.218365 -348.50948) (xy 50.195723 -348.559057) (xy 50.166257 -348.604907) (xy 50.130566 -348.646098)
			(xy 50.089375 -348.681789) (xy 50.046256 -348.7095) (xy 53.861121 -348.7095) (xy 53.86529 -348.653877)
			(xy 53.877703 -348.599498) (xy 53.898082 -348.547575) (xy 53.925973 -348.49927) (xy 53.960752 -348.455662)
			(xy 54.001642 -348.417725) (xy 54.04773 -348.386307) (xy 54.097987 -348.362108) (xy 54.151288 -348.345671)
			(xy 54.206445 -348.337363) (xy 54.234334 -348.33687) (xy 54.260756 -348.337315) (xy 54.313072 -348.344769)
			(xy 54.36381 -348.359538) (xy 54.411954 -348.381324) (xy 54.456539 -348.409692) (xy 54.476904 -348.426532)
			(xy 54.483762 -348.432374) (xy 54.50078 -348.438724) (xy 54.585108 -348.438724) (xy 54.602126 -348.432374)
			(xy 54.608984 -348.426532) (xy 54.62935 -348.409693) (xy 54.673936 -348.381328) (xy 54.72208 -348.359541)
			(xy 54.772817 -348.34477) (xy 54.825132 -348.33731) (xy 54.877976 -348.33731) (xy 54.930291 -348.34477)
			(xy 54.981028 -348.359541) (xy 55.029172 -348.381328) (xy 55.073758 -348.409693) (xy 55.094124 -348.426532)
			(xy 55.100982 -348.432374) (xy 55.118 -348.438724) (xy 55.202328 -348.438724) (xy 55.219346 -348.432374)
			(xy 55.226204 -348.426532) (xy 55.245009 -348.410904) (xy 55.285974 -348.384209) (xy 55.33008 -348.363102)
			(xy 55.353204 -348.355158) (xy 55.36438 -348.351602) (xy 55.381398 -348.335092) (xy 55.412386 -348.248224)
			(xy 55.415708 -348.236964) (xy 55.412936 -348.213678) (xy 55.407052 -348.20352) (xy 55.392675 -348.180322)
			(xy 55.369981 -348.130687) (xy 55.354589 -348.078326) (xy 55.346812 -348.024306) (xy 55.346346 -347.997018)
			(xy 55.346808 -347.969443) (xy 55.354759 -347.914869) (xy 55.370484 -347.862009) (xy 55.393654 -347.811962)
			(xy 55.423788 -347.765773) (xy 55.460258 -347.724403) (xy 55.480966 -347.706188) (xy 55.489058 -347.698648)
			(xy 55.4984 -347.678625) (xy 55.499 -347.66758) (xy 55.499 -347.589856) (xy 55.4984 -347.578811)
			(xy 55.489057 -347.558789) (xy 55.480966 -347.551248) (xy 55.460268 -347.533023) (xy 55.423798 -347.491656)
			(xy 55.393665 -347.445469) (xy 55.370498 -347.395424) (xy 55.354778 -347.342564) (xy 55.346834 -347.287992)
			(xy 55.346346 -347.260418) (xy 55.346832 -347.233167) (xy 55.354588 -347.179219) (xy 55.369943 -347.126924)
			(xy 55.392585 -347.077347) (xy 55.422051 -347.031497) (xy 55.457742 -346.990306) (xy 55.498933 -346.954615)
			(xy 55.544783 -346.925149) (xy 55.59436 -346.902507) (xy 55.646655 -346.887152) (xy 55.700603 -346.879396)
			(xy 55.755105 -346.879396) (xy 55.809053 -346.887152) (xy 55.861348 -346.902507) (xy 55.910925 -346.925149)
			(xy 55.956775 -346.954615) (xy 55.997966 -346.990306) (xy 56.033657 -347.031497) (xy 56.063123 -347.077347)
			(xy 56.085765 -347.126924) (xy 56.10112 -347.179219) (xy 56.108876 -347.233167) (xy 56.109362 -347.260418)
			(xy 56.108853 -347.287991) (xy 56.100911 -347.342563) (xy 56.085196 -347.395422) (xy 56.062034 -347.445469)
			(xy 56.031908 -347.491659) (xy 55.995447 -347.533032) (xy 55.974742 -347.551248) (xy 55.966636 -347.558775)
			(xy 55.957301 -347.578808) (xy 55.956708 -347.589856) (xy 55.956708 -347.66758) (xy 55.957285 -347.678628)
			(xy 55.966644 -347.698649) (xy 55.974742 -347.706188) (xy 55.995459 -347.724393) (xy 56.031927 -347.765764)
			(xy 56.062057 -347.811955) (xy 56.085222 -347.862005) (xy 56.100937 -347.914868) (xy 56.108877 -347.969443)
			(xy 56.109362 -347.997018) (xy 56.108932 -348.023945) (xy 56.101364 -348.077263) (xy 56.086367 -348.128986)
			(xy 56.06424 -348.178083) (xy 56.035422 -348.223577) (xy 56.000489 -348.264562) (xy 55.960135 -348.300223)
			(xy 55.915163 -348.329849) (xy 55.86647 -348.352851) (xy 55.840884 -348.361254) (xy 55.84063 -348.361254)
			(xy 55.829745 -348.365308) (xy 55.818532 -348.375986) (xy 57.810146 -348.375986) (xy 57.810641 -348.348075)
			(xy 57.818777 -348.29285) (xy 57.834872 -348.2394) (xy 57.858584 -348.188865) (xy 57.889406 -348.142325)
			(xy 57.907682 -348.121224) (xy 57.913566 -348.114037) (xy 57.920225 -348.096719) (xy 57.920636 -348.087442)
			(xy 57.920636 -348.009718) (xy 57.914032 -347.992446) (xy 57.907682 -347.985334) (xy 57.889396 -347.964241)
			(xy 57.85857 -347.917701) (xy 57.834857 -347.867164) (xy 57.818762 -347.813712) (xy 57.81063 -347.758484)
			(xy 57.810146 -347.730572) (xy 57.810632 -347.703321) (xy 57.818388 -347.649373) (xy 57.833743 -347.597078)
			(xy 57.856385 -347.547501) (xy 57.885851 -347.501651) (xy 57.921542 -347.46046) (xy 57.962733 -347.424769)
			(xy 58.008583 -347.395303) (xy 58.05816 -347.372661) (xy 58.110455 -347.357306) (xy 58.164403 -347.34955)
			(xy 58.218905 -347.34955) (xy 58.272853 -347.357306) (xy 58.325148 -347.372661) (xy 58.374725 -347.395303)
			(xy 58.420575 -347.424769) (xy 58.461766 -347.46046) (xy 58.497457 -347.501651) (xy 58.526923 -347.547501)
			(xy 58.549565 -347.597078) (xy 58.56492 -347.649373) (xy 58.572676 -347.703321) (xy 58.573162 -347.730572)
			(xy 58.572699 -347.758484) (xy 58.564555 -347.81371) (xy 58.548452 -347.867161) (xy 58.524733 -347.917695)
			(xy 58.493905 -347.964234) (xy 58.475626 -347.985334) (xy 58.469718 -347.992504) (xy 58.463073 -348.009834)
			(xy 58.462672 -348.019116) (xy 58.462672 -348.09684) (xy 58.469276 -348.114112) (xy 58.475626 -348.121224)
			(xy 58.493894 -348.142332) (xy 58.524722 -348.188868) (xy 58.548439 -348.239401) (xy 58.564538 -348.29285)
			(xy 58.572675 -348.348075) (xy 58.573162 -348.375986) (xy 58.572676 -348.403237) (xy 58.56492 -348.457185)
			(xy 58.549565 -348.50948) (xy 58.526923 -348.559057) (xy 58.497457 -348.604907) (xy 58.461766 -348.646098)
			(xy 58.420575 -348.681789) (xy 58.377456 -348.7095) (xy 62.192321 -348.7095) (xy 62.19649 -348.653877)
			(xy 62.208903 -348.599498) (xy 62.229282 -348.547575) (xy 62.257173 -348.49927) (xy 62.291952 -348.455662)
			(xy 62.332842 -348.417725) (xy 62.37893 -348.386307) (xy 62.429187 -348.362108) (xy 62.482488 -348.345671)
			(xy 62.537645 -348.337363) (xy 62.565534 -348.33687) (xy 62.591956 -348.337315) (xy 62.644272 -348.344769)
			(xy 62.69501 -348.359538) (xy 62.743154 -348.381324) (xy 62.787739 -348.409692) (xy 62.808104 -348.426532)
			(xy 62.814962 -348.432374) (xy 62.83198 -348.438724) (xy 62.916308 -348.438724) (xy 62.933326 -348.432374)
			(xy 62.940184 -348.426532) (xy 62.96055 -348.409693) (xy 63.005136 -348.381328) (xy 63.05328 -348.359541)
			(xy 63.104017 -348.34477) (xy 63.156332 -348.33731) (xy 63.209176 -348.33731) (xy 63.261491 -348.34477)
			(xy 63.312228 -348.359541) (xy 63.360372 -348.381328) (xy 63.404958 -348.409693) (xy 63.425324 -348.426532)
			(xy 63.432182 -348.432374) (xy 63.4492 -348.438724) (xy 63.533528 -348.438724) (xy 63.550546 -348.432374)
			(xy 63.557404 -348.426532) (xy 63.575177 -348.411793) (xy 63.613713 -348.386357) (xy 63.655099 -348.365882)
			(xy 63.676784 -348.357952) (xy 63.677038 -348.357952) (xy 63.687058 -348.353786) (xy 63.702581 -348.338649)
			(xy 63.70701 -348.328742) (xy 63.739268 -348.246192) (xy 63.737998 -348.224094) (xy 63.732664 -348.214188)
			(xy 63.718927 -348.187081) (xy 63.699447 -348.129523) (xy 63.689577 -348.069565) (xy 63.688976 -348.039182)
			(xy 63.688976 -348.038928) (xy 63.689463 -348.011285) (xy 63.697623 -347.956605) (xy 63.713768 -347.903729)
			(xy 63.737544 -347.853818) (xy 63.76843 -347.807964) (xy 63.805748 -347.767174) (xy 63.826898 -347.749368)
			(xy 63.835343 -347.741789) (xy 63.845095 -347.721331) (xy 63.845694 -347.709998) (xy 63.845694 -347.631258)
			(xy 63.84506 -347.619938) (xy 63.835297 -347.599505) (xy 63.826898 -347.591888) (xy 63.805763 -347.574066)
			(xy 63.76845 -347.533276) (xy 63.737567 -347.487424) (xy 63.713792 -347.437516) (xy 63.697645 -347.384645)
			(xy 63.689479 -347.329969) (xy 63.688976 -347.302328) (xy 63.689497 -347.274443) (xy 63.697809 -347.219296)
			(xy 63.714247 -347.166004) (xy 63.738445 -347.115758) (xy 63.769861 -347.069679) (xy 63.807794 -347.028797)
			(xy 63.851396 -346.994025) (xy 63.899694 -346.96614) (xy 63.951609 -346.945765) (xy 64.00598 -346.933355)
			(xy 64.061594 -346.929188) (xy 64.117208 -346.933355) (xy 64.171579 -346.945765) (xy 64.223494 -346.96614)
			(xy 64.271792 -346.994025) (xy 64.315394 -347.028797) (xy 64.353327 -347.069679) (xy 64.384743 -347.115758)
			(xy 64.408941 -347.166004) (xy 64.425379 -347.219296) (xy 64.433691 -347.274443) (xy 64.434212 -347.302328)
			(xy 64.433699 -347.32997) (xy 64.425545 -347.384649) (xy 64.409406 -347.437524) (xy 64.385634 -347.487436)
			(xy 64.354753 -347.533291) (xy 64.317438 -347.574082) (xy 64.29629 -347.591888) (xy 64.287863 -347.599484)
			(xy 64.278102 -347.619929) (xy 64.277494 -347.631258) (xy 64.277494 -347.709998) (xy 64.278157 -347.721314)
			(xy 64.2879 -347.741747) (xy 64.29629 -347.749368) (xy 64.31747 -347.767139) (xy 64.354776 -347.807942)
			(xy 64.385651 -347.853805) (xy 64.409418 -347.903723) (xy 64.425556 -347.956602) (xy 64.433713 -348.011284)
			(xy 64.434212 -348.038928) (xy 64.433698 -348.067675) (xy 64.424872 -348.124486) (xy 64.407417 -348.179265)
			(xy 64.381749 -348.23071) (xy 64.348478 -348.277598) (xy 64.308395 -348.318815) (xy 64.262453 -348.35338)
			(xy 64.211743 -348.380472) (xy 64.184784 -348.390464) (xy 64.18453 -348.390464) (xy 64.174519 -348.394649)
			(xy 64.15899 -348.409771) (xy 64.154558 -348.419674) (xy 64.1223 -348.502224) (xy 64.12357 -348.524322)
			(xy 64.128904 -348.534228) (xy 64.142644 -348.561333) (xy 64.162124 -348.618892) (xy 64.171992 -348.678851)
			(xy 64.172592 -348.709234) (xy 64.172592 -348.709488) (xy 64.172155 -348.736107) (xy 64.164579 -348.788802)
			(xy 64.149581 -348.839884) (xy 64.127466 -348.88831) (xy 64.098683 -348.933096) (xy 64.06382 -348.97333)
			(xy 64.023585 -349.008192) (xy 63.978798 -349.036973) (xy 63.93037 -349.059086) (xy 63.879289 -349.074082)
			(xy 63.826593 -349.081656) (xy 63.799974 -349.082106) (xy 63.773552 -349.081662) (xy 63.721236 -349.074208)
			(xy 63.670497 -349.05944) (xy 63.622353 -349.037653) (xy 63.577769 -349.009285) (xy 63.557404 -348.992444)
			(xy 63.550546 -348.986602) (xy 63.533528 -348.980252) (xy 63.4492 -348.980252) (xy 63.432182 -348.986602)
			(xy 63.425324 -348.992444) (xy 63.404958 -349.009283) (xy 63.360372 -349.037648) (xy 63.312228 -349.059435)
			(xy 63.261491 -349.074206) (xy 63.209176 -349.081666) (xy 63.156332 -349.081666) (xy 63.104017 -349.074206)
			(xy 63.05328 -349.059435) (xy 63.005136 -349.037648) (xy 62.96055 -349.009283) (xy 62.940184 -348.992444)
			(xy 62.933326 -348.986602) (xy 62.916308 -348.980252) (xy 62.83198 -348.980252) (xy 62.814962 -348.986602)
			(xy 62.808104 -348.992444) (xy 62.78773 -349.009272) (xy 62.743143 -349.03763) (xy 62.695001 -349.059412)
			(xy 62.644266 -349.074182) (xy 62.591954 -349.081644) (xy 62.565534 -349.082106) (xy 62.537645 -349.081637)
			(xy 62.482488 -349.073329) (xy 62.429187 -349.056892) (xy 62.37893 -349.032693) (xy 62.332842 -349.001275)
			(xy 62.291952 -348.963338) (xy 62.257173 -348.91973) (xy 62.229282 -348.871425) (xy 62.208903 -348.819502)
			(xy 62.19649 -348.765123) (xy 62.192321 -348.7095) (xy 58.377456 -348.7095) (xy 58.374725 -348.711255)
			(xy 58.325148 -348.733897) (xy 58.272853 -348.749252) (xy 58.218905 -348.757008) (xy 58.164403 -348.757008)
			(xy 58.110455 -348.749252) (xy 58.05816 -348.733897) (xy 58.008583 -348.711255) (xy 57.962733 -348.681789)
			(xy 57.921542 -348.646098) (xy 57.885851 -348.604907) (xy 57.856385 -348.559057) (xy 57.833743 -348.50948)
			(xy 57.818388 -348.457185) (xy 57.810632 -348.403237) (xy 57.810146 -348.375986) (xy 55.818532 -348.375986)
			(xy 55.812942 -348.38131) (xy 55.808372 -348.391988) (xy 55.776114 -348.478856) (xy 55.7784 -348.50197)
			(xy 55.78475 -348.51213) (xy 55.798167 -348.534423) (xy 55.81936 -348.581941) (xy 55.833718 -348.63195)
			(xy 55.840962 -348.683473) (xy 55.841392 -348.709488) (xy 55.840955 -348.736107) (xy 55.833379 -348.788802)
			(xy 55.818381 -348.839884) (xy 55.796266 -348.88831) (xy 55.767483 -348.933096) (xy 55.73262 -348.97333)
			(xy 55.692385 -349.008192) (xy 55.647598 -349.036973) (xy 55.59917 -349.059086) (xy 55.548089 -349.074082)
			(xy 55.495393 -349.081656) (xy 55.468774 -349.082106) (xy 55.442352 -349.081662) (xy 55.390036 -349.074208)
			(xy 55.339297 -349.05944) (xy 55.291153 -349.037653) (xy 55.246569 -349.009285) (xy 55.226204 -348.992444)
			(xy 55.219346 -348.986602) (xy 55.202328 -348.980252) (xy 55.118 -348.980252) (xy 55.100982 -348.986602)
			(xy 55.094124 -348.992444) (xy 55.073758 -349.009283) (xy 55.029172 -349.037648) (xy 54.981028 -349.059435)
			(xy 54.930291 -349.074206) (xy 54.877976 -349.081666) (xy 54.825132 -349.081666) (xy 54.772817 -349.074206)
			(xy 54.72208 -349.059435) (xy 54.673936 -349.037648) (xy 54.62935 -349.009283) (xy 54.608984 -348.992444)
			(xy 54.602126 -348.986602) (xy 54.585108 -348.980252) (xy 54.50078 -348.980252) (xy 54.483762 -348.986602)
			(xy 54.476904 -348.992444) (xy 54.45653 -349.009272) (xy 54.411943 -349.03763) (xy 54.363801 -349.059412)
			(xy 54.313066 -349.074182) (xy 54.260754 -349.081644) (xy 54.234334 -349.082106) (xy 54.206445 -349.081637)
			(xy 54.151288 -349.073329) (xy 54.097987 -349.056892) (xy 54.04773 -349.032693) (xy 54.001642 -349.001275)
			(xy 53.960752 -348.963338) (xy 53.925973 -348.91973) (xy 53.898082 -348.871425) (xy 53.877703 -348.819502)
			(xy 53.86529 -348.765123) (xy 53.861121 -348.7095) (xy 50.046256 -348.7095) (xy 50.043525 -348.711255)
			(xy 49.993948 -348.733897) (xy 49.941653 -348.749252) (xy 49.887705 -348.757008) (xy 49.833203 -348.757008)
			(xy 49.779255 -348.749252) (xy 49.72696 -348.733897) (xy 49.677383 -348.711255) (xy 49.631533 -348.681789)
			(xy 49.590342 -348.646098) (xy 49.554651 -348.604907) (xy 49.525185 -348.559057) (xy 49.502543 -348.50948)
			(xy 49.487188 -348.457185) (xy 49.479432 -348.403237) (xy 49.478946 -348.375986) (xy 47.496219 -348.375986)
			(xy 47.490634 -348.378018) (xy 47.479712 -348.381574) (xy 47.46371 -348.397322) (xy 47.432214 -348.48165)
			(xy 47.42878 -348.492215) (xy 47.430365 -348.51435) (xy 47.435262 -348.524322) (xy 47.435516 -348.524322)
			(xy 47.435516 -348.52483) (xy 47.44719 -348.545996) (xy 47.465591 -348.590694) (xy 47.478056 -348.637397)
			(xy 47.484374 -348.68532) (xy 47.484792 -348.709488) (xy 47.484355 -348.736107) (xy 47.476779 -348.788802)
			(xy 47.461781 -348.839884) (xy 47.439666 -348.88831) (xy 47.410883 -348.933096) (xy 47.37602 -348.97333)
			(xy 47.335785 -349.008192) (xy 47.290998 -349.036973) (xy 47.24257 -349.059086) (xy 47.191489 -349.074082)
			(xy 47.138793 -349.081656) (xy 47.112174 -349.082106) (xy 47.085752 -349.081662) (xy 47.033436 -349.074208)
			(xy 46.982697 -349.05944) (xy 46.934553 -349.037653) (xy 46.889969 -349.009285) (xy 46.869604 -348.992444)
			(xy 46.862746 -348.986602) (xy 46.845728 -348.980252) (xy 46.7614 -348.980252) (xy 46.744382 -348.986602)
			(xy 46.737524 -348.992444) (xy 46.717158 -349.009283) (xy 46.672572 -349.037648) (xy 46.624428 -349.059435)
			(xy 46.573691 -349.074206) (xy 46.521376 -349.081666) (xy 46.468532 -349.081666) (xy 46.416217 -349.074206)
			(xy 46.36548 -349.059435) (xy 46.317336 -349.037648) (xy 46.27275 -349.009283) (xy 46.252384 -348.992444)
			(xy 46.245526 -348.986602) (xy 46.228508 -348.980252) (xy 46.14418 -348.980252) (xy 46.127162 -348.986602)
			(xy 46.120304 -348.992444) (xy 46.09993 -349.009272) (xy 46.055343 -349.03763) (xy 46.007201 -349.059412)
			(xy 45.956466 -349.074182) (xy 45.904154 -349.081644) (xy 45.877734 -349.082106) (xy 45.849845 -349.081637)
			(xy 45.794688 -349.073329) (xy 45.741387 -349.056892) (xy 45.69113 -349.032693) (xy 45.645042 -349.001275)
			(xy 45.604152 -348.963338) (xy 45.569373 -348.91973) (xy 45.541482 -348.871425) (xy 45.521103 -348.819502)
			(xy 45.50869 -348.765123) (xy 45.504521 -348.7095) (xy 41.689656 -348.7095) (xy 41.686925 -348.711255)
			(xy 41.637348 -348.733897) (xy 41.585053 -348.749252) (xy 41.531105 -348.757008) (xy 41.476603 -348.757008)
			(xy 41.422655 -348.749252) (xy 41.37036 -348.733897) (xy 41.320783 -348.711255) (xy 41.274933 -348.681789)
			(xy 41.233742 -348.646098) (xy 41.198051 -348.604907) (xy 41.168585 -348.559057) (xy 41.145943 -348.50948)
			(xy 41.130588 -348.457185) (xy 41.122832 -348.403237) (xy 41.122346 -348.375986) (xy 39.12866 -348.375986)
			(xy 39.103808 -348.448884) (xy 39.100616 -348.460369) (xy 39.103913 -348.483944) (xy 39.110158 -348.494096)
			(xy 39.110666 -348.494604) (xy 39.126771 -348.518304) (xy 39.152276 -348.569614) (xy 39.169637 -348.62422)
			(xy 39.178445 -348.680839) (xy 39.178992 -348.709488) (xy 39.178555 -348.736107) (xy 39.170979 -348.788802)
			(xy 39.155981 -348.839884) (xy 39.133866 -348.88831) (xy 39.105083 -348.933096) (xy 39.07022 -348.97333)
			(xy 39.029985 -349.008192) (xy 38.985198 -349.036973) (xy 38.93677 -349.059086) (xy 38.885689 -349.074082)
			(xy 38.832993 -349.081656) (xy 38.806374 -349.082106) (xy 38.779952 -349.081662) (xy 38.727636 -349.074208)
			(xy 38.676897 -349.05944) (xy 38.628753 -349.037653) (xy 38.584169 -349.009285) (xy 38.563804 -348.992444)
			(xy 38.556946 -348.986602) (xy 38.539928 -348.980252) (xy 38.4556 -348.980252) (xy 38.438582 -348.986602)
			(xy 38.431724 -348.992444) (xy 38.411358 -349.009283) (xy 38.366772 -349.037648) (xy 38.318628 -349.059435)
			(xy 38.267891 -349.074206) (xy 38.215576 -349.081666) (xy 38.162732 -349.081666) (xy 38.110417 -349.074206)
			(xy 38.05968 -349.059435) (xy 38.011536 -349.037648) (xy 37.96695 -349.009283) (xy 37.946584 -348.992444)
			(xy 37.939726 -348.986602) (xy 37.922708 -348.980252) (xy 37.83838 -348.980252) (xy 37.821362 -348.986602)
			(xy 37.814504 -348.992444) (xy 37.79413 -349.009272) (xy 37.749543 -349.03763) (xy 37.701401 -349.059412)
			(xy 37.650666 -349.074182) (xy 37.598354 -349.081644) (xy 37.571934 -349.082106) (xy 37.544045 -349.081637)
			(xy 37.488888 -349.073329) (xy 37.435587 -349.056892) (xy 37.38533 -349.032693) (xy 37.339242 -349.001275)
			(xy 37.298352 -348.963338) (xy 37.263573 -348.91973) (xy 37.235682 -348.871425) (xy 37.215303 -348.819502)
			(xy 37.20289 -348.765123) (xy 37.198721 -348.7095) (xy 33.383856 -348.7095) (xy 33.381125 -348.711255)
			(xy 33.331548 -348.733897) (xy 33.279253 -348.749252) (xy 33.225305 -348.757008) (xy 33.170803 -348.757008)
			(xy 33.116855 -348.749252) (xy 33.06456 -348.733897) (xy 33.014983 -348.711255) (xy 32.969133 -348.681789)
			(xy 32.927942 -348.646098) (xy 32.892251 -348.604907) (xy 32.862785 -348.559057) (xy 32.840143 -348.50948)
			(xy 32.824788 -348.457185) (xy 32.817032 -348.403237) (xy 32.816546 -348.375986) (xy 30.84993 -348.375986)
			(xy 30.81909 -348.458536) (xy 30.822646 -348.483428) (xy 30.830012 -348.493842) (xy 30.84618 -348.517552)
			(xy 30.871785 -348.568909) (xy 30.889211 -348.623585) (xy 30.898046 -348.680287) (xy 30.898592 -348.70898)
			(xy 30.898592 -348.709488) (xy 30.898155 -348.736107) (xy 30.890579 -348.788802) (xy 30.875581 -348.839884)
			(xy 30.853466 -348.88831) (xy 30.824683 -348.933096) (xy 30.78982 -348.97333) (xy 30.749585 -349.008192)
			(xy 30.704798 -349.036973) (xy 30.65637 -349.059086) (xy 30.605289 -349.074082) (xy 30.552593 -349.081656)
			(xy 30.525974 -349.082106) (xy 30.499552 -349.081662) (xy 30.447236 -349.074208) (xy 30.396497 -349.05944)
			(xy 30.348353 -349.037653) (xy 30.303769 -349.009285) (xy 30.283404 -348.992444) (xy 30.276546 -348.986602)
			(xy 30.259528 -348.980252) (xy 30.1752 -348.980252) (xy 30.158182 -348.986602) (xy 30.151324 -348.992444)
			(xy 30.130958 -349.009283) (xy 30.086372 -349.037648) (xy 30.038228 -349.059435) (xy 29.987491 -349.074206)
			(xy 29.935176 -349.081666) (xy 29.882332 -349.081666) (xy 29.830017 -349.074206) (xy 29.77928 -349.059435)
			(xy 29.731136 -349.037648) (xy 29.68655 -349.009283) (xy 29.666184 -348.992444) (xy 29.659326 -348.986602)
			(xy 29.642308 -348.980252) (xy 29.55798 -348.980252) (xy 29.540962 -348.986602) (xy 29.534104 -348.992444)
			(xy 29.51373 -349.009272) (xy 29.469143 -349.03763) (xy 29.421001 -349.059412) (xy 29.370266 -349.074182)
			(xy 29.317954 -349.081644) (xy 29.291534 -349.082106) (xy 29.263645 -349.081637) (xy 29.208488 -349.073329)
			(xy 29.155187 -349.056892) (xy 29.10493 -349.032693) (xy 29.058842 -349.001275) (xy 29.017952 -348.963338)
			(xy 28.983173 -348.91973) (xy 28.955282 -348.871425) (xy 28.934903 -348.819502) (xy 28.92249 -348.765123)
			(xy 28.918321 -348.7095) (xy 25.954228 -348.7095) (xy 25.954228 -349.2119) (xy 25.973786 -349.23857)
			(xy 25.989788 -349.243396) (xy 26.015306 -349.251873) (xy 26.063854 -349.27499) (xy 26.108679 -349.304689)
			(xy 26.148894 -349.340383) (xy 26.183705 -349.381364) (xy 26.212423 -349.426824) (xy 26.234479 -349.475863)
			(xy 26.249439 -349.527511) (xy 26.257005 -349.580747) (xy 26.257504 -349.607632) (xy 26.257016 -349.634882)
			(xy 26.249256 -349.688826) (xy 26.233898 -349.741116) (xy 26.211255 -349.790689) (xy 26.181788 -349.836535)
			(xy 26.146096 -349.877722) (xy 26.104907 -349.913409) (xy 26.059058 -349.942872) (xy 26.009483 -349.96551)
			(xy 25.95719 -349.980863) (xy 25.903246 -349.988619) (xy 25.875996 -349.98914) (xy 25.84796 -349.988643)
			(xy 25.792493 -349.98043) (xy 25.738827 -349.96418) (xy 25.68812 -349.940245) (xy 25.641466 -349.90914)
			(xy 25.599871 -349.871538) (xy 25.564233 -349.828248) (xy 25.549352 -349.804482) (xy 25.54605 -349.799148)
			(xy 25.541478 -349.79483) (xy 25.534066 -349.788146) (xy 25.515633 -349.780549) (xy 25.495695 -349.780549)
			(xy 25.477262 -349.788146) (xy 25.46985 -349.79483) (xy 25.465786 -349.798894) (xy 25.458929 -349.806288)
			(xy 25.451179 -349.824887) (xy 25.4508 -349.834962) (xy 25.4508 -350.122236) (xy 25.451187 -350.131371)
			(xy 25.45761 -350.148476) (xy 25.469626 -350.16224) (xy 25.47747 -350.16694) (xy 25.501402 -350.180339)
			(xy 25.5455 -350.212949) (xy 25.584473 -350.251539) (xy 25.617519 -350.295312) (xy 25.643956 -350.343366)
			(xy 25.663239 -350.39471) (xy 25.674971 -350.448287) (xy 25.678909 -350.502991) (xy 25.674973 -350.557696)
			(xy 25.663244 -350.611273) (xy 25.643963 -350.662619) (xy 25.617529 -350.710674) (xy 25.584485 -350.754448)
			(xy 25.545513 -350.79304) (xy 25.501416 -350.825652) (xy 25.47747 -350.839024) (xy 25.469612 -350.843702)
			(xy 25.457606 -350.857477) (xy 25.451201 -350.874591) (xy 25.4508 -350.883728) (xy 25.4508 -351.178622)
			(xy 26.253694 -351.178622) (xy 26.254195 -351.151148) (xy 26.262083 -351.096769) (xy 26.2777 -351.044087)
			(xy 26.300722 -350.994194) (xy 26.33067 -350.948124) (xy 26.348436 -350.927162) (xy 26.34869 -350.926908)
			(xy 26.354278 -350.919823) (xy 26.360524 -350.902905) (xy 26.360882 -350.893888) (xy 26.360882 -350.826324)
			(xy 26.360517 -350.817308) (xy 26.354275 -350.800391) (xy 26.34869 -350.793304) (xy 26.348182 -350.792796)
			(xy 26.330448 -350.77185) (xy 26.300566 -350.725817) (xy 26.2776 -350.675972) (xy 26.262026 -350.623347)
			(xy 26.254165 -350.569031) (xy 26.253694 -350.54159) (xy 26.25418 -350.514339) (xy 26.261936 -350.460391)
			(xy 26.277291 -350.408096) (xy 26.299933 -350.358519) (xy 26.329399 -350.312669) (xy 26.36509 -350.271478)
			(xy 26.406281 -350.235787) (xy 26.452131 -350.206321) (xy 26.501708 -350.183679) (xy 26.554003 -350.168324)
			(xy 26.607951 -350.160568) (xy 26.662453 -350.160568) (xy 26.716401 -350.168324) (xy 26.768696 -350.183679)
			(xy 26.818273 -350.206321) (xy 26.864123 -350.235787) (xy 26.905314 -350.271478) (xy 26.941005 -350.312669)
			(xy 26.970471 -350.358519) (xy 26.993113 -350.408096) (xy 27.008468 -350.460391) (xy 27.016224 -350.514339)
			(xy 27.01671 -350.54159) (xy 27.016215 -350.569064) (xy 27.008325 -350.623443) (xy 26.992707 -350.676126)
			(xy 26.969684 -350.726018) (xy 26.939734 -350.772088) (xy 26.921968 -350.79305) (xy 26.921714 -350.793304)
			(xy 26.916121 -350.800386) (xy 26.909878 -350.817306) (xy 26.909522 -350.826324) (xy 26.909522 -350.893888)
			(xy 26.90988 -350.902905) (xy 26.916126 -350.919822) (xy 26.921714 -350.926908) (xy 26.922222 -350.927416)
			(xy 26.939962 -350.948356) (xy 26.969843 -350.994391) (xy 26.992808 -351.044238) (xy 27.008381 -351.096864)
			(xy 27.01624 -351.151181) (xy 27.01671 -351.178622) (xy 27.016224 -351.205873) (xy 27.008468 -351.259821)
			(xy 26.993113 -351.312116) (xy 26.970471 -351.361693) (xy 26.941005 -351.407543) (xy 26.905314 -351.448734)
			(xy 26.864123 -351.484425) (xy 26.818273 -351.513891) (xy 26.768696 -351.536533) (xy 26.716401 -351.551888)
			(xy 26.662453 -351.559644) (xy 26.607951 -351.559644) (xy 26.554003 -351.551888) (xy 26.501708 -351.536533)
			(xy 26.452131 -351.513891) (xy 26.406281 -351.484425) (xy 26.36509 -351.448734) (xy 26.329399 -351.407543)
			(xy 26.299933 -351.361693) (xy 26.277291 -351.312116) (xy 26.261936 -351.259821) (xy 26.25418 -351.205873)
			(xy 26.253694 -351.178622) (xy 25.4508 -351.178622) (xy 25.4508 -352.39706) (xy 25.450366 -352.407125)
			(xy 25.442636 -352.425714) (xy 25.435814 -352.433128) (xy 22.708108 -355.160834) (xy 22.700713 -355.167689)
			(xy 22.682114 -355.175437) (xy 22.67204 -355.17582) (xy 19.535394 -355.17582) (xy 19.525325 -355.176245)
			(xy 19.506724 -355.183963) (xy 19.499326 -355.190806) (xy 18.964402 -355.72573) (xy 18.95756 -355.73313)
			(xy 18.949836 -355.751728) (xy 18.949416 -355.761798) (xy 18.949416 -356.63632) (xy 21.67204 -356.63632)
			(xy 21.676111 -356.580698) (xy 21.688237 -356.526261) (xy 21.70816 -356.47417) (xy 21.735456 -356.425535)
			(xy 21.769542 -356.381392) (xy 21.809691 -356.342683) (xy 21.855049 -356.310232) (xy 21.904649 -356.284731)
			(xy 21.957433 -356.266724) (xy 22.012276 -356.256594) (xy 22.06801 -356.254557) (xy 22.123447 -356.260657)
			(xy 22.177404 -356.274763) (xy 22.228733 -356.296575) (xy 22.276339 -356.325629) (xy 22.319207 -356.361304)
			(xy 22.356424 -356.402841) (xy 22.387197 -356.449354) (xy 22.410869 -356.499851) (xy 22.426937 -356.553258)
			(xy 22.435057 -356.608434) (xy 22.435566 -356.63632) (xy 22.435057 -356.664206) (xy 22.426937 -356.719382)
			(xy 22.410869 -356.772789) (xy 22.387197 -356.823286) (xy 22.356424 -356.869799) (xy 22.319207 -356.911336)
			(xy 22.276339 -356.947011) (xy 22.228733 -356.976065) (xy 22.177404 -356.997877) (xy 22.123447 -357.011983)
			(xy 22.06801 -357.018083) (xy 22.012276 -357.016046) (xy 21.957433 -357.005916) (xy 21.904649 -356.987909)
			(xy 21.855049 -356.962408) (xy 21.809691 -356.929957) (xy 21.769542 -356.891248) (xy 21.735456 -356.847105)
			(xy 21.70816 -356.79847) (xy 21.688237 -356.746379) (xy 21.676111 -356.691942) (xy 21.67204 -356.63632)
			(xy 18.949416 -356.63632) (xy 18.949416 -357.295704) (xy 20.033994 -357.295704) (xy 20.038065 -357.240082)
			(xy 20.050191 -357.185645) (xy 20.070114 -357.133554) (xy 20.09741 -357.084919) (xy 20.131496 -357.040776)
			(xy 20.171645 -357.002067) (xy 20.217003 -356.969616) (xy 20.266603 -356.944115) (xy 20.319387 -356.926108)
			(xy 20.37423 -356.915978) (xy 20.429964 -356.913941) (xy 20.485401 -356.920041) (xy 20.539358 -356.934147)
			(xy 20.590687 -356.955959) (xy 20.638293 -356.985013) (xy 20.681161 -357.020688) (xy 20.718378 -357.062225)
			(xy 20.749151 -357.108738) (xy 20.772823 -357.159235) (xy 20.788891 -357.212642) (xy 20.797011 -357.267818)
			(xy 20.79752 -357.295704) (xy 20.797011 -357.32359) (xy 20.788891 -357.378766) (xy 20.772823 -357.432173)
			(xy 20.749151 -357.48267) (xy 20.718378 -357.529183) (xy 20.681161 -357.57072) (xy 20.638293 -357.606395)
			(xy 20.590687 -357.635449) (xy 20.539358 -357.657261) (xy 20.485401 -357.671367) (xy 20.429964 -357.677467)
			(xy 20.37423 -357.67543) (xy 20.319387 -357.6653) (xy 20.266603 -357.647293) (xy 20.217003 -357.621792)
			(xy 20.171645 -357.589341) (xy 20.131496 -357.550632) (xy 20.09741 -357.506489) (xy 20.070114 -357.457854)
			(xy 20.050191 -357.405763) (xy 20.038065 -357.351326) (xy 20.033994 -357.295704) (xy 18.949416 -357.295704)
			(xy 18.949416 -360.947462) (xy 18.949851 -360.957527) (xy 18.957583 -360.976113) (xy 18.964402 -360.98353)
			(xy 19.398996 -361.41787) (xy 19.406393 -361.42472) (xy 19.424991 -361.432461) (xy 19.435064 -361.432856)
			(xy 20.373594 -361.432856) (xy 20.380864 -361.432625) (xy 20.394802 -361.428491) (xy 20.401026 -361.424728)
			(xy 20.424223 -361.410347) (xy 20.473855 -361.387643) (xy 20.526217 -361.372245) (xy 20.580239 -361.364469)
			(xy 20.607528 -361.364022) (xy 20.634779 -361.364487) (xy 20.688725 -361.372248) (xy 20.741018 -361.387606)
			(xy 20.790593 -361.410251) (xy 20.83644 -361.43972) (xy 20.877627 -361.475414) (xy 20.913315 -361.516607)
			(xy 20.942777 -361.562458) (xy 20.965414 -361.612037) (xy 20.980765 -361.664332) (xy 20.988517 -361.718279)
			(xy 20.989036 -361.74553) (xy 20.988532 -361.773659) (xy 20.980266 -361.829306) (xy 20.963919 -361.883137)
			(xy 20.939844 -361.933983) (xy 20.908563 -361.980743) (xy 20.870755 -362.022402) (xy 20.82724 -362.058058)
			(xy 20.803362 -362.072936) (xy 20.802854 -362.072936) (xy 20.791932 -362.079794) (xy 20.778978 -362.102146)
			(xy 20.77593 -362.214414) (xy 20.787868 -362.237274) (xy 20.799044 -362.24464) (xy 20.821057 -362.259884)
			(xy 20.86099 -362.295553) (xy 20.895546 -362.336454) (xy 20.924045 -362.381783) (xy 20.945928 -362.430651)
			(xy 20.960765 -362.482098) (xy 20.968265 -362.535114) (xy 20.968716 -362.561886) (xy 20.968716 -362.56214)
			(xy 20.968202 -362.590392) (xy 20.959863 -362.646276) (xy 20.943372 -362.700319) (xy 20.919091 -362.751339)
			(xy 20.88755 -362.79822) (xy 20.868894 -362.819442) (xy 20.855178 -362.834682) (xy 20.856194 -362.875068)
			(xy 20.973288 -362.992162) (xy 20.981 -362.999142) (xy 21.000333 -363.006765) (xy 21.021104 -363.006095)
			(xy 21.030692 -363.002068) (xy 21.030946 -363.002068) (xy 21.056562 -362.990518) (xy 21.110336 -362.974223)
			(xy 21.165919 -362.965988) (xy 21.194014 -362.965492) (xy 21.221265 -362.965979) (xy 21.275211 -362.973737)
			(xy 21.327504 -362.989093) (xy 21.377079 -363.011735) (xy 21.422928 -363.041202) (xy 21.464117 -363.076893)
			(xy 21.499807 -363.118083) (xy 21.529272 -363.163933) (xy 21.551912 -363.213509) (xy 21.567266 -363.265803)
			(xy 21.575022 -363.319749) (xy 21.575522 -363.347) (xy 21.575024 -363.375095) (xy 21.566789 -363.430677)
			(xy 21.550497 -363.484453) (xy 21.538946 -363.510068) (xy 21.538946 -363.510322) (xy 21.534987 -363.519927)
			(xy 21.534327 -363.54067) (xy 21.54192 -363.559986) (xy 21.548852 -363.567726) (xy 21.579586 -363.59846)
			(xy 21.586987 -363.605297) (xy 21.605586 -363.613007) (xy 21.615654 -363.613446) (xy 21.642957 -363.613873)
			(xy 21.697014 -363.62158) (xy 21.749421 -363.636914) (xy 21.799106 -363.659562) (xy 21.845056 -363.689061)
			(xy 21.886331 -363.72481) (xy 21.922089 -363.766077) (xy 21.951598 -363.81202) (xy 21.974257 -363.861701)
			(xy 21.989602 -363.914104) (xy 21.997321 -363.96816) (xy 21.99767 -363.995462) (xy 21.998172 -364.005514)
			(xy 22.005889 -364.02408) (xy 22.012656 -364.03153) (xy 22.333712 -364.352586) (xy 22.340555 -364.359985)
			(xy 22.348271 -364.378584) (xy 22.348698 -364.388654) (xy 22.348698 -366.903) (xy 23.239982 -366.903)
			(xy 23.244053 -366.847378) (xy 23.256179 -366.792941) (xy 23.276102 -366.74085) (xy 23.303398 -366.692215)
			(xy 23.337484 -366.648072) (xy 23.377633 -366.609363) (xy 23.422991 -366.576912) (xy 23.472591 -366.551411)
			(xy 23.525375 -366.533404) (xy 23.580218 -366.523274) (xy 23.635952 -366.521237) (xy 23.691389 -366.527337)
			(xy 23.745346 -366.541443) (xy 23.796675 -366.563255) (xy 23.844281 -366.592309) (xy 23.887149 -366.627984)
			(xy 23.924366 -366.669521) (xy 23.955139 -366.716034) (xy 23.978811 -366.766531) (xy 23.994879 -366.819938)
			(xy 24.002999 -366.875114) (xy 24.003508 -366.903) (xy 24.002999 -366.930886) (xy 23.994879 -366.986062)
			(xy 23.978811 -367.039469) (xy 23.955139 -367.089966) (xy 23.924366 -367.136479) (xy 23.887149 -367.178016)
			(xy 23.844281 -367.213691) (xy 23.796675 -367.242745) (xy 23.745346 -367.264557) (xy 23.691389 -367.278663)
			(xy 23.635952 -367.284763) (xy 23.580218 -367.282726) (xy 23.525375 -367.272596) (xy 23.472591 -367.254589)
			(xy 23.422991 -367.229088) (xy 23.377633 -367.196637) (xy 23.337484 -367.157928) (xy 23.303398 -367.113785)
			(xy 23.276102 -367.06515) (xy 23.256179 -367.013059) (xy 23.244053 -366.958622) (xy 23.239982 -366.903)
			(xy 22.348698 -366.903) (xy 22.348698 -368.110516) (xy 22.354794 -368.116612) (xy 23.148544 -368.116612)
			(xy 23.159873 -368.116004) (xy 23.180318 -368.106243) (xy 23.187914 -368.097816) (xy 23.245064 -368.027966)
			(xy 23.250398 -368.006122) (xy 23.248112 -367.994692) (xy 23.244546 -367.975973) (xy 23.240731 -367.938055)
			(xy 23.240492 -367.919) (xy 23.240978 -367.891749) (xy 23.248734 -367.837801) (xy 23.264089 -367.785506)
			(xy 23.286731 -367.735929) (xy 23.316197 -367.690079) (xy 23.351888 -367.648888) (xy 23.393079 -367.613197)
			(xy 23.438929 -367.583731) (xy 23.488506 -367.561089) (xy 23.540801 -367.545734) (xy 23.594749 -367.537978)
			(xy 23.649251 -367.537978) (xy 23.703199 -367.545734) (xy 23.755494 -367.561089) (xy 23.805071 -367.583731)
			(xy 23.850921 -367.613197) (xy 23.892112 -367.648888) (xy 23.927803 -367.690079) (xy 23.957269 -367.735929)
			(xy 23.979911 -367.785506) (xy 23.995266 -367.837801) (xy 24.003022 -367.891749) (xy 24.003508 -367.919)
			(xy 24.003033 -367.946091) (xy 23.995365 -367.999728) (xy 23.980184 -368.05174) (xy 23.957794 -368.10108)
			(xy 23.928647 -368.146755) (xy 23.89333 -368.187846) (xy 23.852553 -368.223524) (xy 23.807137 -368.253073)
			(xy 23.782782 -368.264948) (xy 23.771933 -368.270795) (xy 23.756928 -368.290297) (xy 23.75408 -368.302286)
			(xy 23.739602 -368.384074) (xy 23.738159 -368.396337) (xy 23.745577 -368.419847) (xy 23.753826 -368.429032)
			(xy 24.793702 -369.468908) (xy 24.801101 -369.475753) (xy 24.819699 -369.483486) (xy 24.82977 -369.483894)
			(xy 26.24582 -369.483894) (xy 26.255825 -369.483402) (xy 26.274308 -369.475739) (xy 26.288454 -369.461587)
			(xy 26.296107 -369.443099) (xy 26.29662 -369.433094) (xy 26.29662 -368.33937) (xy 26.296218 -368.329884)
			(xy 26.289317 -368.312208) (xy 26.276496 -368.29822) (xy 26.268172 -368.29365) (xy 26.18613 -368.253772)
			(xy 26.177368 -368.249918) (xy 26.158302 -368.248381) (xy 26.140006 -368.25396) (xy 26.132282 -368.259614)
			(xy 26.112037 -368.274991) (xy 26.068249 -368.300818) (xy 26.021418 -368.320603) (xy 25.972375 -368.333994)
			(xy 25.921989 -368.340753) (xy 25.89657 -368.341148) (xy 25.869319 -368.34066) (xy 25.815373 -368.3329)
			(xy 25.763079 -368.317543) (xy 25.713503 -368.294901) (xy 25.667654 -368.265434) (xy 25.626464 -368.229743)
			(xy 25.590772 -368.188554) (xy 25.561304 -368.142706) (xy 25.53866 -368.09313) (xy 25.523302 -368.040837)
			(xy 25.515541 -367.986891) (xy 25.515062 -367.95964) (xy 25.515519 -367.933149) (xy 25.522855 -367.880676)
			(xy 25.537376 -367.829721) (xy 25.558805 -367.781265) (xy 25.586729 -367.736237) (xy 25.620611 -367.695504)
			(xy 25.659801 -367.659848) (xy 25.703545 -367.629954) (xy 25.751003 -367.606397) (xy 25.801263 -367.589629)
			(xy 25.853359 -367.579973) (xy 25.879806 -367.578386) (xy 25.895046 -367.577878) (xy 25.919684 -367.560352)
			(xy 25.9588 -367.459514) (xy 25.961975 -367.450191) (xy 25.961721 -367.430517) (xy 25.95404 -367.412403)
			(xy 25.94737 -367.405158) (xy 25.03678 -366.494822) (xy 25.023035 -366.48037) (xy 25.000893 -366.447204)
			(xy 24.985634 -366.41036) (xy 24.977845 -366.371251) (xy 24.977344 -366.351312) (xy 24.977344 -365.515652)
			(xy 24.976911 -365.505587) (xy 24.969178 -365.487) (xy 24.962358 -365.479584) (xy 24.087582 -364.605062)
			(xy 24.073779 -364.590563) (xy 24.051541 -364.557284) (xy 24.036215 -364.520309) (xy 24.028387 -364.481056)
			(xy 24.027892 -364.461044) (xy 24.027892 -362.579158) (xy 24.027509 -362.569595) (xy 24.020506 -362.5518)
			(xy 24.007429 -362.537846) (xy 23.998936 -362.533438) (xy 23.916132 -362.493814) (xy 23.907376 -362.490074)
			(xy 23.888401 -362.488689) (xy 23.870216 -362.494282) (xy 23.862538 -362.49991) (xy 23.862284 -362.500164)
			(xy 23.841817 -362.516219) (xy 23.797355 -362.54322) (xy 23.749635 -362.563926) (xy 23.699543 -362.577952)
			(xy 23.648009 -362.585038) (xy 23.622 -362.585508) (xy 23.594749 -362.585022) (xy 23.540801 -362.577266)
			(xy 23.488506 -362.561911) (xy 23.438929 -362.539269) (xy 23.393079 -362.509803) (xy 23.351888 -362.474112)
			(xy 23.316197 -362.432921) (xy 23.286731 -362.387071) (xy 23.264089 -362.337494) (xy 23.248734 -362.285199)
			(xy 23.240978 -362.231251) (xy 23.240978 -362.176749) (xy 23.248734 -362.122801) (xy 23.264089 -362.070506)
			(xy 23.286731 -362.020929) (xy 23.316197 -361.975079) (xy 23.351888 -361.933888) (xy 23.393079 -361.898197)
			(xy 23.438929 -361.868731) (xy 23.488506 -361.846089) (xy 23.540801 -361.830734) (xy 23.594749 -361.822978)
			(xy 23.622 -361.822492) (xy 23.647982 -361.822971) (xy 23.699456 -361.8301) (xy 23.749487 -361.844144)
			(xy 23.797151 -361.864844) (xy 23.841567 -361.891818) (xy 23.86203 -361.907836) (xy 23.862538 -361.90809)
			(xy 23.870209 -361.913753) (xy 23.8884 -361.919423) (xy 23.907401 -361.918014) (xy 23.916132 -361.914186)
			(xy 23.998936 -361.874562) (xy 24.00737 -361.870077) (xy 24.020392 -361.85612) (xy 24.02745 -361.838384)
			(xy 24.027892 -361.828842) (xy 24.027892 -361.436158) (xy 24.027509 -361.426595) (xy 24.020506 -361.4088)
			(xy 24.007429 -361.394846) (xy 23.998936 -361.390438) (xy 23.916132 -361.350814) (xy 23.907376 -361.347074)
			(xy 23.888401 -361.345689) (xy 23.870216 -361.351282) (xy 23.862538 -361.35691) (xy 23.862284 -361.357164)
			(xy 23.841817 -361.373219) (xy 23.797355 -361.40022) (xy 23.749635 -361.420926) (xy 23.699543 -361.434952)
			(xy 23.648009 -361.442038) (xy 23.622 -361.442508) (xy 23.594749 -361.442022) (xy 23.540801 -361.434266)
			(xy 23.488506 -361.418911) (xy 23.438929 -361.396269) (xy 23.393079 -361.366803) (xy 23.351888 -361.331112)
			(xy 23.316197 -361.289921) (xy 23.286731 -361.244071) (xy 23.264089 -361.194494) (xy 23.248734 -361.142199)
			(xy 23.240978 -361.088251) (xy 23.240978 -361.033749) (xy 23.248734 -360.979801) (xy 23.264089 -360.927506)
			(xy 23.286731 -360.877929) (xy 23.316197 -360.832079) (xy 23.351888 -360.790888) (xy 23.393079 -360.755197)
			(xy 23.438929 -360.725731) (xy 23.488506 -360.703089) (xy 23.540801 -360.687734) (xy 23.594749 -360.679978)
			(xy 23.622 -360.679492) (xy 23.647982 -360.679971) (xy 23.699456 -360.6871) (xy 23.749487 -360.701144)
			(xy 23.797151 -360.721844) (xy 23.841567 -360.748818) (xy 23.86203 -360.764836) (xy 23.862538 -360.76509)
			(xy 23.870209 -360.770753) (xy 23.8884 -360.776423) (xy 23.907401 -360.775014) (xy 23.916132 -360.771186)
			(xy 23.998936 -360.731562) (xy 24.00737 -360.727077) (xy 24.020392 -360.71312) (xy 24.02745 -360.695384)
			(xy 24.027892 -360.685842) (xy 24.027892 -360.293158) (xy 24.027509 -360.283595) (xy 24.020506 -360.2658)
			(xy 24.007429 -360.251846) (xy 23.998936 -360.247438) (xy 23.916132 -360.207814) (xy 23.907376 -360.204074)
			(xy 23.888401 -360.202689) (xy 23.870216 -360.208282) (xy 23.862538 -360.21391) (xy 23.862284 -360.214164)
			(xy 23.841817 -360.230219) (xy 23.797355 -360.25722) (xy 23.749635 -360.277926) (xy 23.699543 -360.291952)
			(xy 23.648009 -360.299038) (xy 23.622 -360.299508) (xy 23.594749 -360.299022) (xy 23.540801 -360.291266)
			(xy 23.488506 -360.275911) (xy 23.438929 -360.253269) (xy 23.393079 -360.223803) (xy 23.351888 -360.188112)
			(xy 23.316197 -360.146921) (xy 23.286731 -360.101071) (xy 23.264089 -360.051494) (xy 23.248734 -359.999199)
			(xy 23.240978 -359.945251) (xy 23.240978 -359.890749) (xy 23.248734 -359.836801) (xy 23.264089 -359.784506)
			(xy 23.286731 -359.734929) (xy 23.316197 -359.689079) (xy 23.351888 -359.647888) (xy 23.393079 -359.612197)
			(xy 23.438929 -359.582731) (xy 23.488506 -359.560089) (xy 23.540801 -359.544734) (xy 23.594749 -359.536978)
			(xy 23.622 -359.536492) (xy 23.647982 -359.536971) (xy 23.699456 -359.5441) (xy 23.749487 -359.558144)
			(xy 23.797151 -359.578844) (xy 23.841567 -359.605818) (xy 23.86203 -359.621836) (xy 23.862538 -359.62209)
			(xy 23.870209 -359.627753) (xy 23.8884 -359.633423) (xy 23.907401 -359.632014) (xy 23.916132 -359.628186)
			(xy 23.998936 -359.588562) (xy 24.00737 -359.584077) (xy 24.020392 -359.57012) (xy 24.02745 -359.552384)
			(xy 24.027892 -359.542842) (xy 24.027892 -359.16362) (xy 24.027536 -359.154253) (xy 24.020786 -359.136778)
			(xy 24.00816 -359.122939) (xy 23.999952 -359.118408) (xy 23.906226 -359.07091) (xy 23.877778 -359.073196)
			(xy 23.866094 -359.081832) (xy 23.841346 -359.099406) (xy 23.787444 -359.127309) (xy 23.729801 -359.146314)
			(xy 23.669874 -359.15594) (xy 23.639526 -359.156508) (xy 23.612272 -359.156046) (xy 23.558318 -359.148292)
			(xy 23.506017 -359.132939) (xy 23.456434 -359.110298) (xy 23.410577 -359.08083) (xy 23.369382 -359.045137)
			(xy 23.333685 -359.003943) (xy 23.304215 -358.958089) (xy 23.28157 -358.908507) (xy 23.266213 -358.856207)
			(xy 23.258455 -358.802254) (xy 23.258455 -358.747746) (xy 23.266213 -358.693793) (xy 23.28157 -358.641493)
			(xy 23.304215 -358.591911) (xy 23.333685 -358.546057) (xy 23.369382 -358.504863) (xy 23.410577 -358.46917)
			(xy 23.456434 -358.439702) (xy 23.506017 -358.417061) (xy 23.558318 -358.401708) (xy 23.612272 -358.393954)
			(xy 23.639526 -358.393492) (xy 23.66987 -358.394101) (xy 23.729788 -358.403745) (xy 23.787428 -358.42274)
			(xy 23.841341 -358.450606) (xy 23.866094 -358.468168) (xy 23.877778 -358.476804) (xy 23.906226 -358.47909)
			(xy 23.999952 -358.431592) (xy 24.008101 -358.426993) (xy 24.020657 -358.413142) (xy 24.027452 -358.395725)
			(xy 24.027892 -358.38638) (xy 24.027892 -358.007158) (xy 24.027509 -357.997595) (xy 24.020506 -357.9798)
			(xy 24.007429 -357.965846) (xy 23.998936 -357.961438) (xy 23.916132 -357.921814) (xy 23.907376 -357.918074)
			(xy 23.888401 -357.916689) (xy 23.870216 -357.922282) (xy 23.862538 -357.92791) (xy 23.862284 -357.928164)
			(xy 23.841817 -357.944219) (xy 23.797355 -357.97122) (xy 23.749635 -357.991926) (xy 23.699543 -358.005952)
			(xy 23.648009 -358.013038) (xy 23.622 -358.013508) (xy 23.594749 -358.013022) (xy 23.540801 -358.005266)
			(xy 23.488506 -357.989911) (xy 23.438929 -357.967269) (xy 23.393079 -357.937803) (xy 23.351888 -357.902112)
			(xy 23.316197 -357.860921) (xy 23.286731 -357.815071) (xy 23.264089 -357.765494) (xy 23.248734 -357.713199)
			(xy 23.240978 -357.659251) (xy 23.240978 -357.604749) (xy 23.248734 -357.550801) (xy 23.264089 -357.498506)
			(xy 23.286731 -357.448929) (xy 23.316197 -357.403079) (xy 23.351888 -357.361888) (xy 23.393079 -357.326197)
			(xy 23.438929 -357.296731) (xy 23.488506 -357.274089) (xy 23.540801 -357.258734) (xy 23.594749 -357.250978)
			(xy 23.622 -357.250492) (xy 23.647982 -357.250971) (xy 23.699456 -357.2581) (xy 23.749487 -357.272144)
			(xy 23.797151 -357.292844) (xy 23.841567 -357.319818) (xy 23.86203 -357.335836) (xy 23.862538 -357.33609)
			(xy 23.870209 -357.341753) (xy 23.8884 -357.347423) (xy 23.907401 -357.346014) (xy 23.916132 -357.342186)
			(xy 23.998936 -357.302562) (xy 24.00737 -357.298077) (xy 24.020392 -357.28412) (xy 24.02745 -357.266384)
			(xy 24.027892 -357.256842) (xy 24.027892 -355.029262) (xy 24.028345 -355.009243) (xy 24.036152 -354.969974)
			(xy 24.051477 -354.932986) (xy 24.07373 -354.899703) (xy 24.087582 -354.885244) (xy 27.766772 -351.206308)
			(xy 27.773784 -351.198513) (xy 27.781361 -351.178988) (xy 27.780494 -351.158061) (xy 27.776424 -351.148396)
			(xy 27.734768 -351.062036) (xy 27.729727 -351.052799) (xy 27.713784 -351.039099) (xy 27.693703 -351.032887)
			(xy 27.683206 -351.033588) (xy 27.672323 -351.034772) (xy 27.650465 -351.036044) (xy 27.639518 -351.036128)
			(xy 27.612263 -351.035666) (xy 27.558307 -351.027911) (xy 27.506004 -351.012556) (xy 27.456419 -350.989913)
			(xy 27.410561 -350.960444) (xy 27.369364 -350.924748) (xy 27.333667 -350.883553) (xy 27.304196 -350.837697)
			(xy 27.281551 -350.788113) (xy 27.266193 -350.735811) (xy 27.258435 -350.681855) (xy 27.258435 -350.627345)
			(xy 27.266193 -350.573389) (xy 27.281551 -350.521087) (xy 27.304196 -350.471503) (xy 27.333667 -350.425647)
			(xy 27.369364 -350.384452) (xy 27.410561 -350.348756) (xy 27.456419 -350.319287) (xy 27.506004 -350.296644)
			(xy 27.558307 -350.281289) (xy 27.612263 -350.273534) (xy 27.639518 -350.273112) (xy 27.639772 -350.273112)
			(xy 27.664973 -350.273539) (xy 27.714932 -350.280207) (xy 27.763582 -350.29338) (xy 27.810081 -350.312828)
			(xy 27.83205 -350.325182) (xy 27.841956 -350.331024) (xy 27.8638 -350.333056) (xy 27.958542 -350.299528)
			(xy 27.97429 -350.284034) (xy 27.978354 -350.27362) (xy 27.989049 -350.246844) (xy 28.017336 -350.196606)
			(xy 28.052867 -350.1512) (xy 28.09483 -350.111663) (xy 28.142268 -350.078896) (xy 28.1941 -350.053646)
			(xy 28.249143 -350.03649) (xy 28.306142 -350.027818) (xy 28.33497 -350.02724) (xy 28.362223 -350.027701)
			(xy 28.416175 -350.035455) (xy 28.468473 -350.050809) (xy 28.518054 -350.07345) (xy 28.563908 -350.102918)
			(xy 28.6051 -350.138613) (xy 28.640792 -350.179807) (xy 28.670258 -350.225662) (xy 28.692897 -350.275244)
			(xy 28.705617 -350.318578) (xy 30.846522 -350.318578) (xy 30.847034 -350.291005) (xy 30.854976 -350.236434)
			(xy 30.870691 -350.183575) (xy 30.893852 -350.133528) (xy 30.923977 -350.087337) (xy 30.960438 -350.045965)
			(xy 30.981142 -350.027748) (xy 30.989203 -350.02018) (xy 30.998563 -350.000178) (xy 30.999176 -349.98914)
			(xy 30.999176 -349.911416) (xy 30.998607 -349.900367) (xy 30.989243 -349.880345) (xy 30.981142 -349.872808)
			(xy 30.96044 -349.854587) (xy 30.923967 -349.813221) (xy 30.893833 -349.767034) (xy 30.870665 -349.716988)
			(xy 30.854947 -349.664126) (xy 30.847007 -349.609552) (xy 30.846522 -349.581978) (xy 30.846934 -349.554723)
			(xy 30.854695 -349.500769) (xy 30.870056 -349.448468) (xy 30.892703 -349.398886) (xy 30.922176 -349.353031)
			(xy 30.957875 -349.311838) (xy 30.999073 -349.276145) (xy 31.044932 -349.246678) (xy 31.094517 -349.224037)
			(xy 31.14682 -349.208684) (xy 31.200775 -349.200931) (xy 31.22803 -349.20047) (xy 31.228538 -349.20047)
			(xy 31.26232 -349.201994) (xy 31.27248 -349.20301) (xy 31.291784 -349.196914) (xy 31.354776 -349.144082)
			(xy 31.362049 -349.137342) (xy 31.371341 -349.11985) (xy 31.37281 -349.110046) (xy 31.37281 -349.109284)
			(xy 31.375762 -349.081135) (xy 31.388956 -349.026097) (xy 31.410141 -348.973613) (xy 31.438849 -348.924837)
			(xy 31.474452 -348.88084) (xy 31.516166 -348.842588) (xy 31.563076 -348.810921) (xy 31.614151 -348.786535)
			(xy 31.668269 -348.769966) (xy 31.724241 -348.761577) (xy 31.75254 -348.76105) (xy 31.752794 -348.76105)
			(xy 31.770813 -348.761277) (xy 31.806688 -348.764707) (xy 31.824422 -348.767908) (xy 31.834074 -348.769686)
			(xy 31.853124 -348.76613) (xy 31.928054 -348.718124) (xy 31.939484 -348.702376) (xy 31.94177 -348.692978)
			(xy 31.949225 -348.665951) (xy 31.970848 -348.614227) (xy 31.999805 -348.566223) (xy 32.035473 -348.522971)
			(xy 32.077085 -348.485403) (xy 32.123745 -348.454326) (xy 32.174449 -348.43041) (xy 32.228107 -348.414169)
			(xy 32.283563 -348.405952) (xy 32.311594 -348.40545) (xy 32.338843 -348.405983) (xy 32.392787 -348.413738)
			(xy 32.445078 -348.42909) (xy 32.494653 -348.451727) (xy 32.540501 -348.481189) (xy 32.58169 -348.516876)
			(xy 32.617382 -348.55806) (xy 32.64685 -348.603905) (xy 32.669493 -348.653477) (xy 32.684852 -348.705766)
			(xy 32.692613 -348.759709) (xy 32.693102 -348.786958) (xy 32.692607 -348.814531) (xy 32.68466 -348.869103)
			(xy 32.668941 -348.921962) (xy 32.645776 -348.972008) (xy 32.615649 -349.018199) (xy 32.579187 -349.059571)
			(xy 32.558482 -349.077788) (xy 32.550409 -349.085345) (xy 32.541054 -349.105355) (xy 32.540448 -349.116396)
			(xy 32.540448 -349.19412) (xy 32.541045 -349.205166) (xy 32.550388 -349.225188) (xy 32.558482 -349.232728)
			(xy 32.579206 -349.250925) (xy 32.615676 -349.292296) (xy 32.645807 -349.338489) (xy 32.668971 -349.38854)
			(xy 32.684684 -349.441405) (xy 32.692619 -349.495982) (xy 32.693102 -349.523558) (xy 32.692607 -349.551131)
			(xy 32.68466 -349.605703) (xy 32.684086 -349.607632) (xy 33.774378 -349.607632) (xy 33.778449 -349.55201)
			(xy 33.790575 -349.497573) (xy 33.810498 -349.445482) (xy 33.837794 -349.396847) (xy 33.87188 -349.352704)
			(xy 33.912029 -349.313995) (xy 33.957387 -349.281544) (xy 34.006987 -349.256043) (xy 34.059771 -349.238036)
			(xy 34.114614 -349.227906) (xy 34.170348 -349.225869) (xy 34.225785 -349.231969) (xy 34.279742 -349.246075)
			(xy 34.331071 -349.267887) (xy 34.378677 -349.296941) (xy 34.421545 -349.332616) (xy 34.458762 -349.374153)
			(xy 34.489535 -349.420666) (xy 34.513207 -349.471163) (xy 34.529275 -349.52457) (xy 34.537395 -349.579746)
			(xy 34.537904 -349.607632) (xy 34.537395 -349.635518) (xy 34.529275 -349.690694) (xy 34.513207 -349.744101)
			(xy 34.489535 -349.794598) (xy 34.458762 -349.841111) (xy 34.421545 -349.882648) (xy 34.378677 -349.918323)
			(xy 34.331071 -349.947377) (xy 34.279742 -349.969189) (xy 34.225785 -349.983295) (xy 34.170348 -349.989395)
			(xy 34.114614 -349.987358) (xy 34.059771 -349.977228) (xy 34.006987 -349.959221) (xy 33.957387 -349.93372)
			(xy 33.912029 -349.901269) (xy 33.87188 -349.86256) (xy 33.837794 -349.818417) (xy 33.810498 -349.769782)
			(xy 33.790575 -349.717691) (xy 33.778449 -349.663254) (xy 33.774378 -349.607632) (xy 32.684086 -349.607632)
			(xy 32.668941 -349.658562) (xy 32.645776 -349.708608) (xy 32.615649 -349.754799) (xy 32.579187 -349.796171)
			(xy 32.558482 -349.814388) (xy 32.550409 -349.821945) (xy 32.541054 -349.841955) (xy 32.540448 -349.852996)
			(xy 32.540448 -349.93072) (xy 32.541045 -349.941766) (xy 32.550388 -349.961788) (xy 32.558482 -349.969328)
			(xy 32.579206 -349.987525) (xy 32.615676 -350.028896) (xy 32.645807 -350.075089) (xy 32.668971 -350.12514)
			(xy 32.684684 -350.178005) (xy 32.692619 -350.232582) (xy 32.693102 -350.260158) (xy 32.692606 -350.28741)
			(xy 32.684854 -350.34136) (xy 32.669503 -350.393658) (xy 32.646865 -350.443238) (xy 32.617401 -350.489092)
			(xy 32.605367 -350.502982) (xy 33.195258 -350.502982) (xy 33.199329 -350.44736) (xy 33.211455 -350.392923)
			(xy 33.231378 -350.340832) (xy 33.258674 -350.292197) (xy 33.29276 -350.248054) (xy 33.332909 -350.209345)
			(xy 33.378267 -350.176894) (xy 33.427867 -350.151393) (xy 33.480651 -350.133386) (xy 33.535494 -350.123256)
			(xy 33.591228 -350.121219) (xy 33.646665 -350.127319) (xy 33.700622 -350.141425) (xy 33.751951 -350.163237)
			(xy 33.799557 -350.192291) (xy 33.842425 -350.227966) (xy 33.879642 -350.269503) (xy 33.910415 -350.316016)
			(xy 33.934087 -350.366513) (xy 33.950155 -350.41992) (xy 33.958275 -350.475096) (xy 33.958784 -350.502982)
			(xy 33.958275 -350.530868) (xy 33.950155 -350.586044) (xy 33.934087 -350.639451) (xy 33.910415 -350.689948)
			(xy 33.879642 -350.736461) (xy 33.842425 -350.777998) (xy 33.799557 -350.813673) (xy 33.751951 -350.842727)
			(xy 33.700622 -350.864539) (xy 33.646665 -350.878645) (xy 33.591228 -350.884745) (xy 33.535494 -350.882708)
			(xy 33.480651 -350.872578) (xy 33.427867 -350.854571) (xy 33.378267 -350.82907) (xy 33.332909 -350.796619)
			(xy 33.29276 -350.75791) (xy 33.258674 -350.713767) (xy 33.231378 -350.665132) (xy 33.211455 -350.613041)
			(xy 33.199329 -350.558604) (xy 33.195258 -350.502982) (xy 32.605367 -350.502982) (xy 32.581711 -350.530285)
			(xy 32.540521 -350.565979) (xy 32.49467 -350.595448) (xy 32.445092 -350.618091) (xy 32.392795 -350.633447)
			(xy 32.338846 -350.641203) (xy 32.311594 -350.641666) (xy 32.283737 -350.641174) (xy 32.228619 -350.633048)
			(xy 32.175267 -350.617) (xy 32.124813 -350.59337) (xy 32.078327 -350.56266) (xy 32.036798 -350.52552)
			(xy 32.001106 -350.482741) (xy 31.972009 -350.435229) (xy 31.950124 -350.383993) (xy 31.942532 -350.357186)
			(xy 31.940246 -350.348296) (xy 31.929578 -350.333056) (xy 31.857696 -350.285304) (xy 31.839662 -350.28124)
			(xy 31.830518 -350.28251) (xy 31.817501 -350.284175) (xy 31.791317 -350.285958) (xy 31.778194 -350.286066)
			(xy 31.764045 -350.285973) (xy 31.735822 -350.283938) (xy 31.721806 -350.282002) (xy 31.7119 -350.280478)
			(xy 31.692088 -350.285304) (xy 31.617666 -350.341184) (xy 31.607506 -350.35871) (xy 31.606236 -350.36887)
			(xy 31.60215 -350.396023) (xy 31.587174 -350.448852) (xy 31.564781 -350.498989) (xy 31.535432 -350.545399)
			(xy 31.499735 -350.587122) (xy 31.458425 -350.623298) (xy 31.412357 -350.653179) (xy 31.362481 -350.676149)
			(xy 31.309828 -350.691732) (xy 31.255485 -350.699607) (xy 31.22803 -350.700086) (xy 31.200777 -350.699617)
			(xy 31.146825 -350.691863) (xy 31.094526 -350.67651) (xy 31.044944 -350.653869) (xy 30.99909 -350.624402)
			(xy 30.957897 -350.588709) (xy 30.922202 -350.547516) (xy 30.892735 -350.501663) (xy 30.870093 -350.452082)
			(xy 30.854738 -350.399783) (xy 30.846984 -350.345831) (xy 30.846522 -350.318578) (xy 28.705617 -350.318578)
			(xy 28.708249 -350.327543) (xy 28.716 -350.381495) (xy 28.716478 -350.408748) (xy 28.715831 -350.440312)
			(xy 28.705449 -350.502581) (xy 28.68496 -350.562291) (xy 28.670504 -350.590358) (xy 28.665678 -350.599248)
			(xy 28.663646 -350.618806) (xy 28.686506 -350.697292) (xy 28.689752 -350.706711) (xy 28.70217 -350.722265)
			(xy 28.710636 -350.727518) (xy 28.73573 -350.742074) (xy 28.781597 -350.777591) (xy 28.821561 -350.81964)
			(xy 28.854703 -350.867252) (xy 28.880258 -350.91933) (xy 28.897638 -350.974676) (xy 28.906443 -351.032015)
			(xy 28.906978 -351.06102) (xy 28.906513 -351.088271) (xy 28.898754 -351.142218) (xy 28.888063 -351.178622)
			(xy 34.534094 -351.178622) (xy 34.534595 -351.151148) (xy 34.542483 -351.096769) (xy 34.5581 -351.044087)
			(xy 34.581122 -350.994194) (xy 34.61107 -350.948124) (xy 34.628836 -350.927162) (xy 34.62909 -350.926908)
			(xy 34.634678 -350.919823) (xy 34.640924 -350.902905) (xy 34.641282 -350.893888) (xy 34.641282 -350.826324)
			(xy 34.640917 -350.817308) (xy 34.634675 -350.800391) (xy 34.62909 -350.793304) (xy 34.628582 -350.792796)
			(xy 34.610848 -350.77185) (xy 34.580966 -350.725817) (xy 34.558 -350.675972) (xy 34.542426 -350.623347)
			(xy 34.534565 -350.569031) (xy 34.534094 -350.54159) (xy 34.53458 -350.514339) (xy 34.542336 -350.460391)
			(xy 34.557691 -350.408096) (xy 34.580333 -350.358519) (xy 34.609799 -350.312669) (xy 34.64549 -350.271478)
			(xy 34.686681 -350.235787) (xy 34.732531 -350.206321) (xy 34.782108 -350.183679) (xy 34.834403 -350.168324)
			(xy 34.888351 -350.160568) (xy 34.942853 -350.160568) (xy 34.996801 -350.168324) (xy 35.049096 -350.183679)
			(xy 35.098673 -350.206321) (xy 35.144523 -350.235787) (xy 35.185714 -350.271478) (xy 35.221405 -350.312669)
			(xy 35.250871 -350.358519) (xy 35.273513 -350.408096) (xy 35.288868 -350.460391) (xy 35.296624 -350.514339)
			(xy 35.29711 -350.54159) (xy 35.296615 -350.569064) (xy 35.288725 -350.623443) (xy 35.273107 -350.676126)
			(xy 35.250084 -350.726018) (xy 35.220134 -350.772088) (xy 35.202368 -350.79305) (xy 35.202114 -350.793304)
			(xy 35.196521 -350.800386) (xy 35.190278 -350.817306) (xy 35.189922 -350.826324) (xy 35.189922 -350.893888)
			(xy 35.19028 -350.902905) (xy 35.196526 -350.919822) (xy 35.202114 -350.926908) (xy 35.202622 -350.927416)
			(xy 35.220362 -350.948356) (xy 35.250243 -350.994391) (xy 35.273208 -351.044238) (xy 35.288781 -351.096864)
			(xy 35.29664 -351.151181) (xy 35.29711 -351.178622) (xy 35.296624 -351.205873) (xy 35.288868 -351.259821)
			(xy 35.273513 -351.312116) (xy 35.250871 -351.361693) (xy 35.221405 -351.407543) (xy 35.185714 -351.448734)
			(xy 35.144523 -351.484425) (xy 35.098673 -351.513891) (xy 35.049096 -351.536533) (xy 34.996801 -351.551888)
			(xy 34.942853 -351.559644) (xy 34.888351 -351.559644) (xy 34.834403 -351.551888) (xy 34.782108 -351.536533)
			(xy 34.732531 -351.513891) (xy 34.686681 -351.484425) (xy 34.64549 -351.448734) (xy 34.609799 -351.407543)
			(xy 34.580333 -351.361693) (xy 34.557691 -351.312116) (xy 34.542336 -351.259821) (xy 34.53458 -351.205873)
			(xy 34.534094 -351.178622) (xy 28.888063 -351.178622) (xy 28.883396 -351.194512) (xy 28.860752 -351.244088)
			(xy 28.831283 -351.289936) (xy 28.795589 -351.331124) (xy 28.754396 -351.366813) (xy 28.708544 -351.396276)
			(xy 28.658965 -351.418913) (xy 28.606669 -351.434264) (xy 28.552721 -351.442017) (xy 28.52547 -351.442528)
			(xy 28.49763 -351.442028) (xy 28.44254 -351.433945) (xy 28.389211 -351.41794) (xy 28.338774 -351.394353)
			(xy 28.292301 -351.363685) (xy 28.271216 -351.3455) (xy 28.263722 -351.33939) (xy 28.245565 -351.332787)
			(xy 28.226253 -351.333358) (xy 28.208518 -351.341022) (xy 28.201366 -351.347532) (xy 24.450294 -355.098604)
			(xy 24.443449 -355.106003) (xy 24.435717 -355.124601) (xy 24.435308 -355.134672) (xy 24.435308 -363.606842)
			(xy 24.435691 -363.616405) (xy 24.442694 -363.6342) (xy 24.455771 -363.648154) (xy 24.464264 -363.652562)
			(xy 24.547068 -363.692186) (xy 24.555824 -363.695926) (xy 24.574799 -363.697311) (xy 24.592984 -363.691718)
			(xy 24.600662 -363.68609) (xy 24.600916 -363.685836) (xy 24.621383 -363.669781) (xy 24.665845 -363.64278)
			(xy 24.713565 -363.622074) (xy 24.763657 -363.608048) (xy 24.815191 -363.600962) (xy 24.8412 -363.600492)
			(xy 24.868451 -363.600978) (xy 24.922399 -363.608734) (xy 24.974694 -363.624089) (xy 25.024271 -363.646731)
			(xy 25.070121 -363.676197) (xy 25.111312 -363.711888) (xy 25.147003 -363.753079) (xy 25.176469 -363.798929)
			(xy 25.199111 -363.848506) (xy 25.214466 -363.900801) (xy 25.222222 -363.954749) (xy 25.222222 -364.009251)
			(xy 25.214466 -364.063199) (xy 25.199111 -364.115494) (xy 25.176469 -364.165071) (xy 25.147003 -364.210921)
			(xy 25.111312 -364.252112) (xy 25.070121 -364.287803) (xy 25.024271 -364.317269) (xy 24.974694 -364.339911)
			(xy 24.922399 -364.355266) (xy 24.868451 -364.363022) (xy 24.8412 -364.363508) (xy 24.814912 -364.363067)
			(xy 24.762836 -364.355844) (xy 24.712245 -364.341535) (xy 24.6641 -364.320411) (xy 24.619314 -364.292873)
			(xy 24.578736 -364.259443) (xy 24.543135 -364.220755) (xy 24.527764 -364.199424) (xy 24.520152 -364.189753)
			(xy 24.498392 -364.178338) (xy 24.486108 -364.17758) (xy 24.465026 -364.17758) (xy 24.435308 -364.207298)
			(xy 24.435308 -364.355634) (xy 24.435738 -364.365701) (xy 24.443462 -364.384296) (xy 24.450294 -364.391702)
			(xy 24.802592 -364.744) (xy 25.399492 -364.744) (xy 25.399972 -364.71724) (xy 25.407447 -364.664245)
			(xy 25.42225 -364.612813) (xy 25.444091 -364.563953) (xy 25.472542 -364.518622) (xy 25.507045 -364.477709)
			(xy 25.546924 -364.442015) (xy 25.56891 -364.426754) (xy 25.580028 -364.418875) (xy 25.597849 -364.398266)
			(xy 25.609593 -364.373682) (xy 25.614427 -364.34687) (xy 25.612007 -364.319732) (xy 25.602505 -364.294198)
			(xy 25.586597 -364.27208) (xy 25.576276 -364.263178) (xy 25.554506 -364.244975) (xy 25.516101 -364.2032)
			(xy 25.484308 -364.156197) (xy 25.45983 -364.105002) (xy 25.443208 -364.050746) (xy 25.434807 -363.994625)
			(xy 25.43429 -363.966252) (xy 25.434776 -363.939001) (xy 25.442532 -363.885053) (xy 25.457887 -363.832758)
			(xy 25.480529 -363.783181) (xy 25.509995 -363.737331) (xy 25.545686 -363.69614) (xy 25.586877 -363.660449)
			(xy 25.632727 -363.630983) (xy 25.682304 -363.608341) (xy 25.734599 -363.592986) (xy 25.788547 -363.58523)
			(xy 25.843049 -363.58523) (xy 25.896997 -363.592986) (xy 25.949292 -363.608341) (xy 25.998869 -363.630983)
			(xy 26.044719 -363.660449) (xy 26.08591 -363.69614) (xy 26.121601 -363.737331) (xy 26.151067 -363.783181)
			(xy 26.173709 -363.832758) (xy 26.189064 -363.885053) (xy 26.19682 -363.939001) (xy 26.197306 -363.966252)
			(xy 26.196866 -363.993013) (xy 26.189384 -364.04601) (xy 26.174574 -364.097443) (xy 26.152727 -364.146303)
			(xy 26.12427 -364.191634) (xy 26.089761 -364.232546) (xy 26.049877 -364.268238) (xy 26.027888 -364.283498)
			(xy 26.016815 -364.291436) (xy 25.998996 -364.312032) (xy 25.98725 -364.336603) (xy 25.982411 -364.363403)
			(xy 25.984822 -364.390531) (xy 25.994313 -364.416058) (xy 26.010208 -364.438172) (xy 26.020522 -364.447074)
			(xy 26.042268 -364.465304) (xy 26.080676 -364.507073) (xy 26.112471 -364.55407) (xy 26.136953 -364.60526)
			(xy 26.153581 -364.659512) (xy 26.161987 -364.715629) (xy 26.162508 -364.744) (xy 26.162022 -364.771251)
			(xy 26.154266 -364.825199) (xy 26.138911 -364.877494) (xy 26.116269 -364.927071) (xy 26.086803 -364.972921)
			(xy 26.051112 -365.014112) (xy 26.009921 -365.049803) (xy 25.964071 -365.079269) (xy 25.914494 -365.101911)
			(xy 25.862199 -365.117266) (xy 25.808251 -365.125022) (xy 25.753749 -365.125022) (xy 25.699801 -365.117266)
			(xy 25.647506 -365.101911) (xy 25.597929 -365.079269) (xy 25.552079 -365.049803) (xy 25.510888 -365.014112)
			(xy 25.475197 -364.972921) (xy 25.445731 -364.927071) (xy 25.423089 -364.877494) (xy 25.407734 -364.825199)
			(xy 25.399978 -364.771251) (xy 25.399492 -364.744) (xy 24.802592 -364.744) (xy 25.324816 -365.266224)
			(xy 25.338558 -365.280677) (xy 25.360693 -365.313844) (xy 25.375943 -365.350688) (xy 25.383724 -365.389797)
			(xy 25.384252 -365.409734) (xy 25.384252 -365.76) (xy 25.627074 -365.76) (xy 25.631145 -365.704378)
			(xy 25.643271 -365.649941) (xy 25.663194 -365.59785) (xy 25.69049 -365.549215) (xy 25.724576 -365.505072)
			(xy 25.764725 -365.466363) (xy 25.810083 -365.433912) (xy 25.859683 -365.408411) (xy 25.912467 -365.390404)
			(xy 25.96731 -365.380274) (xy 26.023044 -365.378237) (xy 26.078481 -365.384337) (xy 26.132438 -365.398443)
			(xy 26.183767 -365.420255) (xy 26.231373 -365.449309) (xy 26.274241 -365.484984) (xy 26.311458 -365.526521)
			(xy 26.342231 -365.573034) (xy 26.365903 -365.623531) (xy 26.381971 -365.676938) (xy 26.390091 -365.732114)
			(xy 26.3906 -365.76) (xy 26.390091 -365.787886) (xy 26.381971 -365.843062) (xy 26.365903 -365.896469)
			(xy 26.342231 -365.946966) (xy 26.311458 -365.993479) (xy 26.274241 -366.035016) (xy 26.231373 -366.070691)
			(xy 26.183767 -366.099745) (xy 26.132438 -366.121557) (xy 26.078481 -366.135663) (xy 26.023044 -366.141763)
			(xy 25.96731 -366.139726) (xy 25.912467 -366.129596) (xy 25.859683 -366.111589) (xy 25.810083 -366.086088)
			(xy 25.764725 -366.053637) (xy 25.724576 -366.014928) (xy 25.69049 -365.970785) (xy 25.663194 -365.92215)
			(xy 25.643271 -365.870059) (xy 25.631145 -365.815622) (xy 25.627074 -365.76) (xy 25.384252 -365.76)
			(xy 25.384252 -366.245394) (xy 25.384675 -366.255464) (xy 25.392394 -366.274065) (xy 25.399238 -366.281462)
			(xy 26.61793 -367.4999) (xy 26.625292 -367.506735) (xy 26.643806 -367.514494) (xy 26.66388 -367.514557)
			(xy 26.673302 -367.511076) (xy 26.687526 -367.505234) (xy 26.704544 -367.479834) (xy 26.704544 -365.777272)
			(xy 26.704114 -365.767205) (xy 26.696386 -365.748614) (xy 26.689558 -365.741204) (xy 26.386536 -365.438182)
			(xy 26.372791 -365.42373) (xy 26.350649 -365.390565) (xy 26.335393 -365.353721) (xy 26.32761 -365.314611)
			(xy 26.3271 -365.294672) (xy 26.3271 -363.04982) (xy 26.326707 -363.040297) (xy 26.319752 -363.022567)
			(xy 26.306798 -363.008605) (xy 26.298398 -363.0041) (xy 26.202894 -362.957618) (xy 26.174192 -362.960666)
			(xy 26.162762 -362.96981) (xy 26.142525 -362.985139) (xy 26.098769 -363.010882) (xy 26.051987 -363.030601)
			(xy 26.003006 -363.043948) (xy 25.952688 -363.050688) (xy 25.927304 -363.05109) (xy 25.900052 -363.050627)
			(xy 25.846103 -363.042871) (xy 25.793808 -363.027516) (xy 25.744229 -363.004875) (xy 25.698378 -362.975408)
			(xy 25.657187 -362.939716) (xy 25.621494 -362.898525) (xy 25.592027 -362.852674) (xy 25.569386 -362.803096)
			(xy 25.55403 -362.7508) (xy 25.546273 -362.696852) (xy 25.546273 -362.642348) (xy 25.55403 -362.5884)
			(xy 25.569386 -362.536104) (xy 25.592027 -362.486526) (xy 25.621494 -362.440675) (xy 25.657187 -362.399484)
			(xy 25.698378 -362.363792) (xy 25.744229 -362.334325) (xy 25.793808 -362.311684) (xy 25.846103 -362.296329)
			(xy 25.900052 -362.288573) (xy 25.927304 -362.288074) (xy 25.952687 -362.288491) (xy 26.003005 -362.295223)
			(xy 26.051987 -362.308566) (xy 26.098767 -362.328286) (xy 26.142519 -362.354034) (xy 26.162762 -362.369354)
			(xy 26.174192 -362.378498) (xy 26.202894 -362.381546) (xy 26.298398 -362.335064) (xy 26.306804 -362.330568)
			(xy 26.319755 -362.316599) (xy 26.326718 -362.298868) (xy 26.3271 -362.289344) (xy 26.3271 -354.443284)
			(xy 26.327614 -354.423348) (xy 26.335423 -354.384248) (xy 26.350682 -354.34741) (xy 26.372809 -354.314241)
			(xy 26.386536 -354.299774) (xy 28.003754 -352.682556) (xy 28.018206 -352.66881) (xy 28.051372 -352.646666)
			(xy 28.088215 -352.631406) (xy 28.127325 -352.623613) (xy 28.147264 -352.62312) (xy 34.533078 -352.62312)
			(xy 34.543142 -352.622683) (xy 34.561728 -352.614951) (xy 34.569146 -352.608134) (xy 35.968178 -351.209102)
			(xy 35.974743 -351.20185) (xy 35.98233 -351.183837) (xy 35.982664 -351.164294) (xy 35.979608 -351.155)
			(xy 35.946334 -351.068132) (xy 35.94241 -351.05917) (xy 35.929075 -351.044878) (xy 35.911364 -351.036608)
			(xy 35.90163 -351.03562) (xy 35.901376 -351.03562) (xy 35.875026 -351.033884) (xy 35.823142 -351.024059)
			(xy 35.773108 -351.007173) (xy 35.725881 -350.983548) (xy 35.682362 -350.953638) (xy 35.643384 -350.918012)
			(xy 35.60969 -350.877352) (xy 35.581925 -350.832434) (xy 35.560619 -350.784116) (xy 35.546179 -350.733323)
			(xy 35.538881 -350.681023) (xy 35.53841 -350.65462) (xy 35.538872 -350.627367) (xy 35.546627 -350.573415)
			(xy 35.561981 -350.521115) (xy 35.584623 -350.471534) (xy 35.614091 -350.42568) (xy 35.649785 -350.384486)
			(xy 35.690978 -350.348792) (xy 35.736832 -350.319324) (xy 35.786413 -350.296682) (xy 35.838713 -350.281327)
			(xy 35.892665 -350.273572) (xy 35.919918 -350.273112) (xy 35.920172 -350.273112) (xy 35.945373 -350.273539)
			(xy 35.995332 -350.280207) (xy 36.043982 -350.29338) (xy 36.090481 -350.312828) (xy 36.11245 -350.325182)
			(xy 36.122356 -350.331024) (xy 36.1442 -350.333056) (xy 36.238942 -350.299528) (xy 36.25469 -350.284034)
			(xy 36.258754 -350.27362) (xy 36.269449 -350.246844) (xy 36.297736 -350.196606) (xy 36.333267 -350.1512)
			(xy 36.37523 -350.111663) (xy 36.422668 -350.078896) (xy 36.4745 -350.053646) (xy 36.529543 -350.03649)
			(xy 36.586542 -350.027818) (xy 36.61537 -350.02724) (xy 36.642623 -350.027701) (xy 36.696575 -350.035455)
			(xy 36.748873 -350.050809) (xy 36.798454 -350.07345) (xy 36.844308 -350.102918) (xy 36.8855 -350.138613)
			(xy 36.921192 -350.179807) (xy 36.950658 -350.225662) (xy 36.973297 -350.275244) (xy 36.986017 -350.318578)
			(xy 39.126922 -350.318578) (xy 39.127434 -350.291005) (xy 39.135376 -350.236434) (xy 39.151091 -350.183575)
			(xy 39.174252 -350.133528) (xy 39.204377 -350.087337) (xy 39.240838 -350.045965) (xy 39.261542 -350.027748)
			(xy 39.269603 -350.02018) (xy 39.278963 -350.000178) (xy 39.279576 -349.98914) (xy 39.279576 -349.911416)
			(xy 39.279007 -349.900367) (xy 39.269643 -349.880345) (xy 39.261542 -349.872808) (xy 39.24084 -349.854587)
			(xy 39.204367 -349.813221) (xy 39.174233 -349.767034) (xy 39.151065 -349.716988) (xy 39.135347 -349.664126)
			(xy 39.127407 -349.609552) (xy 39.126922 -349.581978) (xy 39.127334 -349.554723) (xy 39.135095 -349.500769)
			(xy 39.150456 -349.448468) (xy 39.173103 -349.398886) (xy 39.202576 -349.353031) (xy 39.238275 -349.311838)
			(xy 39.279473 -349.276145) (xy 39.325332 -349.246678) (xy 39.374917 -349.224037) (xy 39.42722 -349.208684)
			(xy 39.481175 -349.200931) (xy 39.50843 -349.20047) (xy 39.508938 -349.20047) (xy 39.54272 -349.201994)
			(xy 39.55288 -349.20301) (xy 39.572184 -349.196914) (xy 39.635176 -349.144082) (xy 39.642449 -349.137342)
			(xy 39.651741 -349.11985) (xy 39.65321 -349.110046) (xy 39.65321 -349.109284) (xy 39.656162 -349.081135)
			(xy 39.669356 -349.026097) (xy 39.690541 -348.973613) (xy 39.719249 -348.924837) (xy 39.754852 -348.88084)
			(xy 39.796566 -348.842588) (xy 39.843476 -348.810921) (xy 39.894551 -348.786535) (xy 39.948669 -348.769966)
			(xy 40.004641 -348.761577) (xy 40.03294 -348.76105) (xy 40.033194 -348.76105) (xy 40.051213 -348.761277)
			(xy 40.087088 -348.764707) (xy 40.104822 -348.767908) (xy 40.114474 -348.769686) (xy 40.133524 -348.76613)
			(xy 40.208454 -348.718124) (xy 40.219884 -348.702376) (xy 40.22217 -348.692978) (xy 40.229625 -348.665951)
			(xy 40.251248 -348.614227) (xy 40.280205 -348.566223) (xy 40.315873 -348.522971) (xy 40.357485 -348.485403)
			(xy 40.404145 -348.454326) (xy 40.454849 -348.43041) (xy 40.508507 -348.414169) (xy 40.563963 -348.405952)
			(xy 40.591994 -348.40545) (xy 40.619243 -348.405983) (xy 40.673187 -348.413738) (xy 40.725478 -348.42909)
			(xy 40.775053 -348.451727) (xy 40.820901 -348.481189) (xy 40.86209 -348.516876) (xy 40.897782 -348.55806)
			(xy 40.92725 -348.603905) (xy 40.949893 -348.653477) (xy 40.965252 -348.705766) (xy 40.973013 -348.759709)
			(xy 40.973502 -348.786958) (xy 40.973007 -348.814531) (xy 40.96506 -348.869103) (xy 40.949341 -348.921962)
			(xy 40.926176 -348.972008) (xy 40.896049 -349.018199) (xy 40.859587 -349.059571) (xy 40.838882 -349.077788)
			(xy 40.830809 -349.085345) (xy 40.821454 -349.105355) (xy 40.820848 -349.116396) (xy 40.820848 -349.19412)
			(xy 40.821445 -349.205166) (xy 40.830788 -349.225188) (xy 40.838882 -349.232728) (xy 40.859606 -349.250925)
			(xy 40.896076 -349.292296) (xy 40.926207 -349.338489) (xy 40.949371 -349.38854) (xy 40.965084 -349.441405)
			(xy 40.973019 -349.495982) (xy 40.973502 -349.523558) (xy 40.973007 -349.551131) (xy 40.96506 -349.605703)
			(xy 40.964486 -349.607632) (xy 42.080178 -349.607632) (xy 42.084249 -349.55201) (xy 42.096375 -349.497573)
			(xy 42.116298 -349.445482) (xy 42.143594 -349.396847) (xy 42.17768 -349.352704) (xy 42.217829 -349.313995)
			(xy 42.263187 -349.281544) (xy 42.312787 -349.256043) (xy 42.365571 -349.238036) (xy 42.420414 -349.227906)
			(xy 42.476148 -349.225869) (xy 42.531585 -349.231969) (xy 42.585542 -349.246075) (xy 42.636871 -349.267887)
			(xy 42.684477 -349.296941) (xy 42.727345 -349.332616) (xy 42.764562 -349.374153) (xy 42.795335 -349.420666)
			(xy 42.819007 -349.471163) (xy 42.835075 -349.52457) (xy 42.843195 -349.579746) (xy 42.843704 -349.607632)
			(xy 42.843195 -349.635518) (xy 42.835075 -349.690694) (xy 42.819007 -349.744101) (xy 42.795335 -349.794598)
			(xy 42.764562 -349.841111) (xy 42.727345 -349.882648) (xy 42.684477 -349.918323) (xy 42.636871 -349.947377)
			(xy 42.585542 -349.969189) (xy 42.531585 -349.983295) (xy 42.476148 -349.989395) (xy 42.420414 -349.987358)
			(xy 42.365571 -349.977228) (xy 42.312787 -349.959221) (xy 42.263187 -349.93372) (xy 42.217829 -349.901269)
			(xy 42.17768 -349.86256) (xy 42.143594 -349.818417) (xy 42.116298 -349.769782) (xy 42.096375 -349.717691)
			(xy 42.084249 -349.663254) (xy 42.080178 -349.607632) (xy 40.964486 -349.607632) (xy 40.949341 -349.658562)
			(xy 40.926176 -349.708608) (xy 40.896049 -349.754799) (xy 40.859587 -349.796171) (xy 40.838882 -349.814388)
			(xy 40.830809 -349.821945) (xy 40.821454 -349.841955) (xy 40.820848 -349.852996) (xy 40.820848 -349.93072)
			(xy 40.821445 -349.941766) (xy 40.830788 -349.961788) (xy 40.838882 -349.969328) (xy 40.859606 -349.987525)
			(xy 40.896076 -350.028896) (xy 40.926207 -350.075089) (xy 40.949371 -350.12514) (xy 40.965084 -350.178005)
			(xy 40.973019 -350.232582) (xy 40.973502 -350.260158) (xy 40.973006 -350.28741) (xy 40.965254 -350.34136)
			(xy 40.949903 -350.393658) (xy 40.927265 -350.443238) (xy 40.897801 -350.489092) (xy 40.885767 -350.502982)
			(xy 41.501058 -350.502982) (xy 41.505129 -350.44736) (xy 41.517255 -350.392923) (xy 41.537178 -350.340832)
			(xy 41.564474 -350.292197) (xy 41.59856 -350.248054) (xy 41.638709 -350.209345) (xy 41.684067 -350.176894)
			(xy 41.733667 -350.151393) (xy 41.786451 -350.133386) (xy 41.841294 -350.123256) (xy 41.897028 -350.121219)
			(xy 41.952465 -350.127319) (xy 42.006422 -350.141425) (xy 42.057751 -350.163237) (xy 42.105357 -350.192291)
			(xy 42.148225 -350.227966) (xy 42.185442 -350.269503) (xy 42.216215 -350.316016) (xy 42.239887 -350.366513)
			(xy 42.255955 -350.41992) (xy 42.264075 -350.475096) (xy 42.264584 -350.502982) (xy 42.264075 -350.530868)
			(xy 42.255955 -350.586044) (xy 42.239887 -350.639451) (xy 42.216215 -350.689948) (xy 42.185442 -350.736461)
			(xy 42.148225 -350.777998) (xy 42.105357 -350.813673) (xy 42.057751 -350.842727) (xy 42.006422 -350.864539)
			(xy 41.952465 -350.878645) (xy 41.897028 -350.884745) (xy 41.841294 -350.882708) (xy 41.786451 -350.872578)
			(xy 41.733667 -350.854571) (xy 41.684067 -350.82907) (xy 41.638709 -350.796619) (xy 41.59856 -350.75791)
			(xy 41.564474 -350.713767) (xy 41.537178 -350.665132) (xy 41.517255 -350.613041) (xy 41.505129 -350.558604)
			(xy 41.501058 -350.502982) (xy 40.885767 -350.502982) (xy 40.862111 -350.530285) (xy 40.820921 -350.565979)
			(xy 40.77507 -350.595448) (xy 40.725492 -350.618091) (xy 40.673195 -350.633447) (xy 40.619246 -350.641203)
			(xy 40.591994 -350.641666) (xy 40.564137 -350.641174) (xy 40.509019 -350.633048) (xy 40.455667 -350.617)
			(xy 40.405213 -350.59337) (xy 40.358727 -350.56266) (xy 40.317198 -350.52552) (xy 40.281506 -350.482741)
			(xy 40.252409 -350.435229) (xy 40.230524 -350.383993) (xy 40.222932 -350.357186) (xy 40.220646 -350.348296)
			(xy 40.209978 -350.333056) (xy 40.138096 -350.285304) (xy 40.120062 -350.28124) (xy 40.110918 -350.28251)
			(xy 40.097901 -350.284175) (xy 40.071717 -350.285958) (xy 40.058594 -350.286066) (xy 40.044445 -350.285973)
			(xy 40.016222 -350.283938) (xy 40.002206 -350.282002) (xy 39.9923 -350.280478) (xy 39.972488 -350.285304)
			(xy 39.898066 -350.341184) (xy 39.887906 -350.35871) (xy 39.886636 -350.36887) (xy 39.88255 -350.396023)
			(xy 39.867574 -350.448852) (xy 39.845181 -350.498989) (xy 39.815832 -350.545399) (xy 39.780135 -350.587122)
			(xy 39.738825 -350.623298) (xy 39.692757 -350.653179) (xy 39.642881 -350.676149) (xy 39.590228 -350.691732)
			(xy 39.535885 -350.699607) (xy 39.50843 -350.700086) (xy 39.481177 -350.699617) (xy 39.427225 -350.691863)
			(xy 39.374926 -350.67651) (xy 39.325344 -350.653869) (xy 39.27949 -350.624402) (xy 39.238297 -350.588709)
			(xy 39.202602 -350.547516) (xy 39.173135 -350.501663) (xy 39.150493 -350.452082) (xy 39.135138 -350.399783)
			(xy 39.127384 -350.345831) (xy 39.126922 -350.318578) (xy 36.986017 -350.318578) (xy 36.988649 -350.327543)
			(xy 36.9964 -350.381495) (xy 36.996878 -350.408748) (xy 36.996231 -350.440312) (xy 36.985849 -350.502581)
			(xy 36.96536 -350.562291) (xy 36.950904 -350.590358) (xy 36.946078 -350.599248) (xy 36.944046 -350.618806)
			(xy 36.966906 -350.697292) (xy 36.970152 -350.706711) (xy 36.98257 -350.722265) (xy 36.991036 -350.727518)
			(xy 37.01613 -350.742074) (xy 37.061997 -350.777591) (xy 37.101961 -350.81964) (xy 37.135103 -350.867252)
			(xy 37.160658 -350.91933) (xy 37.178038 -350.974676) (xy 37.186843 -351.032015) (xy 37.187378 -351.06102)
			(xy 37.186913 -351.088271) (xy 37.179154 -351.142218) (xy 37.168463 -351.178622) (xy 42.839894 -351.178622)
			(xy 42.840395 -351.151148) (xy 42.848283 -351.096769) (xy 42.8639 -351.044087) (xy 42.886922 -350.994194)
			(xy 42.91687 -350.948124) (xy 42.934636 -350.927162) (xy 42.93489 -350.926908) (xy 42.940478 -350.919823)
			(xy 42.946724 -350.902905) (xy 42.947082 -350.893888) (xy 42.947082 -350.826324) (xy 42.946717 -350.817308)
			(xy 42.940475 -350.800391) (xy 42.93489 -350.793304) (xy 42.934382 -350.792796) (xy 42.916648 -350.77185)
			(xy 42.886766 -350.725817) (xy 42.8638 -350.675972) (xy 42.848226 -350.623347) (xy 42.840365 -350.569031)
			(xy 42.839894 -350.54159) (xy 42.84038 -350.514339) (xy 42.848136 -350.460391) (xy 42.863491 -350.408096)
			(xy 42.886133 -350.358519) (xy 42.915599 -350.312669) (xy 42.95129 -350.271478) (xy 42.992481 -350.235787)
			(xy 43.038331 -350.206321) (xy 43.087908 -350.183679) (xy 43.140203 -350.168324) (xy 43.194151 -350.160568)
			(xy 43.248653 -350.160568) (xy 43.302601 -350.168324) (xy 43.354896 -350.183679) (xy 43.404473 -350.206321)
			(xy 43.450323 -350.235787) (xy 43.491514 -350.271478) (xy 43.527205 -350.312669) (xy 43.556671 -350.358519)
			(xy 43.579313 -350.408096) (xy 43.594668 -350.460391) (xy 43.602424 -350.514339) (xy 43.60291 -350.54159)
			(xy 43.602415 -350.569064) (xy 43.594525 -350.623443) (xy 43.578907 -350.676126) (xy 43.555884 -350.726018)
			(xy 43.525934 -350.772088) (xy 43.508168 -350.79305) (xy 43.507914 -350.793304) (xy 43.502321 -350.800386)
			(xy 43.496078 -350.817306) (xy 43.495722 -350.826324) (xy 43.495722 -350.893888) (xy 43.49608 -350.902905)
			(xy 43.502326 -350.919822) (xy 43.507914 -350.926908) (xy 43.508422 -350.927416) (xy 43.526162 -350.948356)
			(xy 43.556043 -350.994391) (xy 43.579008 -351.044238) (xy 43.594581 -351.096864) (xy 43.60244 -351.151181)
			(xy 43.60291 -351.178622) (xy 43.602424 -351.205873) (xy 43.594668 -351.259821) (xy 43.579313 -351.312116)
			(xy 43.556671 -351.361693) (xy 43.527205 -351.407543) (xy 43.491514 -351.448734) (xy 43.450323 -351.484425)
			(xy 43.404473 -351.513891) (xy 43.354896 -351.536533) (xy 43.302601 -351.551888) (xy 43.248653 -351.559644)
			(xy 43.194151 -351.559644) (xy 43.140203 -351.551888) (xy 43.087908 -351.536533) (xy 43.038331 -351.513891)
			(xy 42.992481 -351.484425) (xy 42.95129 -351.448734) (xy 42.915599 -351.407543) (xy 42.886133 -351.361693)
			(xy 42.863491 -351.312116) (xy 42.848136 -351.259821) (xy 42.84038 -351.205873) (xy 42.839894 -351.178622)
			(xy 37.168463 -351.178622) (xy 37.163796 -351.194512) (xy 37.141152 -351.244088) (xy 37.111683 -351.289936)
			(xy 37.075989 -351.331124) (xy 37.034796 -351.366813) (xy 36.988944 -351.396276) (xy 36.939365 -351.418913)
			(xy 36.887069 -351.434264) (xy 36.833121 -351.442017) (xy 36.80587 -351.442528) (xy 36.777545 -351.442016)
			(xy 36.721517 -351.433645) (xy 36.667344 -351.417078) (xy 36.616218 -351.392678) (xy 36.569265 -351.360983)
			(xy 36.54806 -351.342198) (xy 36.540694 -351.335594) (xy 36.52266 -351.328736) (xy 36.442396 -351.330514)
			(xy 36.43267 -351.331196) (xy 36.41478 -351.338906) (xy 36.407598 -351.3455) (xy 34.782506 -352.970592)
			(xy 34.768054 -352.984338) (xy 34.734889 -353.00648) (xy 34.698045 -353.021738) (xy 34.658935 -353.029525)
			(xy 34.638996 -353.030028) (xy 28.253182 -353.030028) (xy 28.243114 -353.030455) (xy 28.224517 -353.038177)
			(xy 28.217114 -353.045014) (xy 26.748994 -354.513134) (xy 26.742154 -354.520535) (xy 26.734433 -354.539133)
			(xy 26.734008 -354.549202) (xy 26.734008 -355.2444) (xy 28.446982 -355.2444) (xy 28.451053 -355.188778)
			(xy 28.463179 -355.134341) (xy 28.483102 -355.08225) (xy 28.510398 -355.033615) (xy 28.544484 -354.989472)
			(xy 28.584633 -354.950763) (xy 28.629991 -354.918312) (xy 28.679591 -354.892811) (xy 28.732375 -354.874804)
			(xy 28.787218 -354.864674) (xy 28.842952 -354.862637) (xy 28.898389 -354.868737) (xy 28.952346 -354.882843)
			(xy 29.003675 -354.904655) (xy 29.051281 -354.933709) (xy 29.094149 -354.969384) (xy 29.131366 -355.010921)
			(xy 29.162139 -355.057434) (xy 29.185811 -355.107931) (xy 29.201879 -355.161338) (xy 29.209999 -355.216514)
			(xy 29.210508 -355.2444) (xy 29.209999 -355.272286) (xy 29.201879 -355.327462) (xy 29.185811 -355.380869)
			(xy 29.162139 -355.431366) (xy 29.131366 -355.477879) (xy 29.094149 -355.519416) (xy 29.051281 -355.555091)
			(xy 29.003675 -355.584145) (xy 28.952346 -355.605957) (xy 28.898389 -355.620063) (xy 28.842952 -355.626163)
			(xy 28.787218 -355.624126) (xy 28.732375 -355.613996) (xy 28.679591 -355.595989) (xy 28.629991 -355.570488)
			(xy 28.584633 -355.538037) (xy 28.544484 -355.499328) (xy 28.510398 -355.455185) (xy 28.483102 -355.40655)
			(xy 28.463179 -355.354459) (xy 28.451053 -355.300022) (xy 28.446982 -355.2444) (xy 26.734008 -355.2444)
			(xy 26.734008 -356.3874) (xy 27.964382 -356.3874) (xy 27.968453 -356.331778) (xy 27.980579 -356.277341)
			(xy 28.000502 -356.22525) (xy 28.027798 -356.176615) (xy 28.061884 -356.132472) (xy 28.102033 -356.093763)
			(xy 28.147391 -356.061312) (xy 28.196991 -356.035811) (xy 28.249775 -356.017804) (xy 28.304618 -356.007674)
			(xy 28.360352 -356.005637) (xy 28.415789 -356.011737) (xy 28.469746 -356.025843) (xy 28.521075 -356.047655)
			(xy 28.568681 -356.076709) (xy 28.611549 -356.112384) (xy 28.648766 -356.153921) (xy 28.679539 -356.200434)
			(xy 28.703211 -356.250931) (xy 28.719279 -356.304338) (xy 28.727399 -356.359514) (xy 28.727908 -356.3874)
			(xy 28.727399 -356.415286) (xy 28.719279 -356.470462) (xy 28.703211 -356.523869) (xy 28.679539 -356.574366)
			(xy 28.648766 -356.620879) (xy 28.611549 -356.662416) (xy 28.568681 -356.698091) (xy 28.521075 -356.727145)
			(xy 28.469746 -356.748957) (xy 28.415789 -356.763063) (xy 28.360352 -356.769163) (xy 28.304618 -356.767126)
			(xy 28.249775 -356.756996) (xy 28.196991 -356.738989) (xy 28.147391 -356.713488) (xy 28.102033 -356.681037)
			(xy 28.061884 -356.642328) (xy 28.027798 -356.598185) (xy 28.000502 -356.54955) (xy 27.980579 -356.497459)
			(xy 27.968453 -356.443022) (xy 27.964382 -356.3874) (xy 26.734008 -356.3874) (xy 26.734008 -357.48595)
			(xy 27.558492 -357.48595) (xy 27.558978 -357.458699) (xy 27.566734 -357.404751) (xy 27.582089 -357.352456)
			(xy 27.604731 -357.302879) (xy 27.634197 -357.257029) (xy 27.669888 -357.215838) (xy 27.711079 -357.180147)
			(xy 27.756929 -357.150681) (xy 27.806506 -357.128039) (xy 27.858801 -357.112684) (xy 27.912749 -357.104928)
			(xy 27.967251 -357.104928) (xy 28.021199 -357.112684) (xy 28.073494 -357.128039) (xy 28.123071 -357.150681)
			(xy 28.168921 -357.180147) (xy 28.210112 -357.215838) (xy 28.245803 -357.257029) (xy 28.275269 -357.302879)
			(xy 28.297911 -357.352456) (xy 28.313266 -357.404751) (xy 28.321022 -357.458699) (xy 28.321508 -357.48595)
			(xy 28.320903 -357.515135) (xy 28.312012 -357.572824) (xy 28.294445 -357.628489) (xy 28.268611 -357.680831)
			(xy 28.235112 -357.728632) (xy 28.194729 -357.770778) (xy 28.171902 -357.788972) (xy 28.161264 -357.797592)
			(xy 28.144733 -357.819409) (xy 28.134603 -357.844838) (xy 28.131606 -357.872047) (xy 28.135959 -357.899071)
			(xy 28.147346 -357.923963) (xy 28.164946 -357.944927) (xy 28.175966 -357.953056) (xy 28.197369 -357.968418)
			(xy 28.23617 -358.004055) (xy 28.269701 -358.044691) (xy 28.297324 -358.089552) (xy 28.318514 -358.137786)
			(xy 28.332869 -358.188476) (xy 28.340115 -358.240658) (xy 28.340558 -358.267) (xy 28.340072 -358.294251)
			(xy 28.332316 -358.348199) (xy 28.316961 -358.400494) (xy 28.294319 -358.450071) (xy 28.264853 -358.495921)
			(xy 28.229162 -358.537112) (xy 28.187971 -358.572803) (xy 28.142121 -358.602269) (xy 28.092544 -358.624911)
			(xy 28.040249 -358.640266) (xy 27.986301 -358.648022) (xy 27.931799 -358.648022) (xy 27.877851 -358.640266)
			(xy 27.825556 -358.624911) (xy 27.775979 -358.602269) (xy 27.730129 -358.572803) (xy 27.688938 -358.537112)
			(xy 27.653247 -358.495921) (xy 27.623781 -358.450071) (xy 27.601139 -358.400494) (xy 27.585784 -358.348199)
			(xy 27.578028 -358.294251) (xy 27.577542 -358.267) (xy 27.578092 -358.237813) (xy 27.586992 -358.18012)
			(xy 27.604568 -358.124454) (xy 27.630413 -358.072111) (xy 27.663922 -358.024312) (xy 27.704316 -357.982169)
			(xy 27.727148 -357.963978) (xy 27.737729 -357.955296) (xy 27.754252 -357.933492) (xy 27.76438 -357.908077)
			(xy 27.767381 -357.880884) (xy 27.763041 -357.853872) (xy 27.751672 -357.828989) (xy 27.734092 -357.808026)
			(xy 27.723084 -357.799894) (xy 27.701646 -357.784578) (xy 27.662848 -357.748932) (xy 27.629322 -357.708287)
			(xy 27.601704 -357.663419) (xy 27.580519 -357.615178) (xy 27.566171 -357.564481) (xy 27.558932 -357.512294)
			(xy 27.558492 -357.48595) (xy 26.734008 -357.48595) (xy 26.734008 -365.188754) (xy 26.734441 -365.19882)
			(xy 26.74217 -365.217409) (xy 26.748994 -365.224822) (xy 27.05227 -365.527844) (xy 27.064336 -365.540402)
			(xy 27.084414 -365.568854) (xy 27.099341 -365.600316) (xy 27.10434 -365.616998) (xy 27.108912 -365.633508)
			(xy 27.13609 -365.654082) (xy 27.153108 -365.654082) (xy 27.163127 -365.653661) (xy 27.181638 -365.645989)
			(xy 27.195804 -365.631816) (xy 27.203466 -365.613301) (xy 27.203908 -365.603282) (xy 27.203908 -360.69778)
			(xy 27.20436 -360.677761) (xy 27.212164 -360.63849) (xy 27.227488 -360.601501) (xy 27.24974 -360.568216)
			(xy 27.263598 -360.553762) (xy 28.581858 -359.235756) (xy 28.588702 -359.228357) (xy 28.596427 -359.209758)
			(xy 28.596844 -359.199688) (xy 28.596844 -357.504492) (xy 28.597357 -357.484556) (xy 28.605163 -357.445453)
			(xy 28.620418 -357.408612) (xy 28.64254 -357.375437) (xy 28.65628 -357.360982) (xy 29.53131 -356.485952)
			(xy 29.538158 -356.478555) (xy 29.54589 -356.459956) (xy 29.546296 -356.449884) (xy 29.546296 -356.114604)
			(xy 29.546755 -356.094588) (xy 29.554572 -356.055325) (xy 29.569904 -356.018345) (xy 29.592162 -355.98507)
			(xy 29.605986 -355.970586) (xy 32.037782 -353.53879) (xy 32.052282 -353.52499) (xy 32.085563 -353.502759)
			(xy 32.122537 -353.48744) (xy 32.161789 -353.47962) (xy 32.1818 -353.4791) (xy 38.01872 -353.4791)
			(xy 38.028789 -353.478673) (xy 38.047388 -353.470954) (xy 38.054788 -353.464114) (xy 38.844982 -352.67392)
			(xy 38.859433 -352.660173) (xy 38.892598 -352.638027) (xy 38.929442 -352.622766) (xy 38.968553 -352.614976)
			(xy 38.988492 -352.614484) (xy 42.620438 -352.614484) (xy 42.630505 -352.614054) (xy 42.649098 -352.606328)
			(xy 42.656506 -352.599498) (xy 44.092114 -351.16389) (xy 44.100346 -351.154689) (xy 44.107794 -351.131191)
			(xy 44.106338 -351.118932) (xy 44.09186 -351.03689) (xy 44.089013 -351.025107) (xy 44.074295 -351.00589)
			(xy 44.063666 -351.00006) (xy 44.063412 -350.999806) (xy 44.039194 -350.987898) (xy 43.994084 -350.958277)
			(xy 43.953596 -350.922599) (xy 43.918536 -350.881573) (xy 43.889604 -350.836018) (xy 43.867376 -350.786842)
			(xy 43.852297 -350.735026) (xy 43.844665 -350.681603) (xy 43.84421 -350.65462) (xy 43.844672 -350.627367)
			(xy 43.852427 -350.573415) (xy 43.867781 -350.521115) (xy 43.890423 -350.471534) (xy 43.919891 -350.42568)
			(xy 43.955585 -350.384486) (xy 43.996778 -350.348792) (xy 44.042632 -350.319324) (xy 44.092213 -350.296682)
			(xy 44.144513 -350.281327) (xy 44.198465 -350.273572) (xy 44.225718 -350.273112) (xy 44.225972 -350.273112)
			(xy 44.251173 -350.273539) (xy 44.301132 -350.280207) (xy 44.349782 -350.29338) (xy 44.396281 -350.312828)
			(xy 44.41825 -350.325182) (xy 44.428156 -350.331024) (xy 44.45 -350.333056) (xy 44.544742 -350.299528)
			(xy 44.56049 -350.284034) (xy 44.564554 -350.27362) (xy 44.575249 -350.246844) (xy 44.603536 -350.196606)
			(xy 44.639067 -350.1512) (xy 44.68103 -350.111663) (xy 44.728468 -350.078896) (xy 44.7803 -350.053646)
			(xy 44.835343 -350.03649) (xy 44.892342 -350.027818) (xy 44.92117 -350.02724) (xy 44.948423 -350.027701)
			(xy 45.002375 -350.035455) (xy 45.054673 -350.050809) (xy 45.104254 -350.07345) (xy 45.150108 -350.102918)
			(xy 45.1913 -350.138613) (xy 45.226992 -350.179807) (xy 45.256458 -350.225662) (xy 45.279097 -350.275244)
			(xy 45.291817 -350.318578) (xy 47.432722 -350.318578) (xy 47.433234 -350.291005) (xy 47.441176 -350.236434)
			(xy 47.456891 -350.183575) (xy 47.480052 -350.133528) (xy 47.510177 -350.087337) (xy 47.546638 -350.045965)
			(xy 47.567342 -350.027748) (xy 47.575403 -350.02018) (xy 47.584763 -350.000178) (xy 47.585376 -349.98914)
			(xy 47.585376 -349.911416) (xy 47.584807 -349.900367) (xy 47.575443 -349.880345) (xy 47.567342 -349.872808)
			(xy 47.54664 -349.854587) (xy 47.510167 -349.813221) (xy 47.480033 -349.767034) (xy 47.456865 -349.716988)
			(xy 47.441147 -349.664126) (xy 47.433207 -349.609552) (xy 47.432722 -349.581978) (xy 47.433134 -349.554723)
			(xy 47.440895 -349.500769) (xy 47.456256 -349.448468) (xy 47.478903 -349.398886) (xy 47.508376 -349.353031)
			(xy 47.544075 -349.311838) (xy 47.585273 -349.276145) (xy 47.631132 -349.246678) (xy 47.680717 -349.224037)
			(xy 47.73302 -349.208684) (xy 47.786975 -349.200931) (xy 47.81423 -349.20047) (xy 47.814738 -349.20047)
			(xy 47.84852 -349.201994) (xy 47.85868 -349.20301) (xy 47.877984 -349.196914) (xy 47.940976 -349.144082)
			(xy 47.948249 -349.137342) (xy 47.957541 -349.11985) (xy 47.95901 -349.110046) (xy 47.95901 -349.109284)
			(xy 47.961962 -349.081135) (xy 47.975156 -349.026097) (xy 47.996341 -348.973613) (xy 48.025049 -348.924837)
			(xy 48.060652 -348.88084) (xy 48.102366 -348.842588) (xy 48.149276 -348.810921) (xy 48.200351 -348.786535)
			(xy 48.254469 -348.769966) (xy 48.310441 -348.761577) (xy 48.33874 -348.76105) (xy 48.338994 -348.76105)
			(xy 48.357013 -348.761277) (xy 48.392888 -348.764707) (xy 48.410622 -348.767908) (xy 48.420274 -348.769686)
			(xy 48.439324 -348.76613) (xy 48.514254 -348.718124) (xy 48.525684 -348.702376) (xy 48.52797 -348.692978)
			(xy 48.535425 -348.665951) (xy 48.557048 -348.614227) (xy 48.586005 -348.566223) (xy 48.621673 -348.522971)
			(xy 48.663285 -348.485403) (xy 48.709945 -348.454326) (xy 48.760649 -348.43041) (xy 48.814307 -348.414169)
			(xy 48.869763 -348.405952) (xy 48.897794 -348.40545) (xy 48.925043 -348.405983) (xy 48.978987 -348.413738)
			(xy 49.031278 -348.42909) (xy 49.080853 -348.451727) (xy 49.126701 -348.481189) (xy 49.16789 -348.516876)
			(xy 49.203582 -348.55806) (xy 49.23305 -348.603905) (xy 49.255693 -348.653477) (xy 49.271052 -348.705766)
			(xy 49.278813 -348.759709) (xy 49.279302 -348.786958) (xy 49.278807 -348.814531) (xy 49.27086 -348.869103)
			(xy 49.255141 -348.921962) (xy 49.231976 -348.972008) (xy 49.201849 -349.018199) (xy 49.165387 -349.059571)
			(xy 49.144682 -349.077788) (xy 49.136609 -349.085345) (xy 49.127254 -349.105355) (xy 49.126648 -349.116396)
			(xy 49.126648 -349.19412) (xy 49.127245 -349.205166) (xy 49.136588 -349.225188) (xy 49.144682 -349.232728)
			(xy 49.165406 -349.250925) (xy 49.201876 -349.292296) (xy 49.232007 -349.338489) (xy 49.255171 -349.38854)
			(xy 49.270884 -349.441405) (xy 49.278819 -349.495982) (xy 49.279302 -349.523558) (xy 49.278807 -349.551131)
			(xy 49.27086 -349.605703) (xy 49.270286 -349.607632) (xy 50.436778 -349.607632) (xy 50.440849 -349.55201)
			(xy 50.452975 -349.497573) (xy 50.472898 -349.445482) (xy 50.500194 -349.396847) (xy 50.53428 -349.352704)
			(xy 50.574429 -349.313995) (xy 50.619787 -349.281544) (xy 50.669387 -349.256043) (xy 50.722171 -349.238036)
			(xy 50.777014 -349.227906) (xy 50.832748 -349.225869) (xy 50.888185 -349.231969) (xy 50.942142 -349.246075)
			(xy 50.993471 -349.267887) (xy 51.041077 -349.296941) (xy 51.083945 -349.332616) (xy 51.121162 -349.374153)
			(xy 51.151935 -349.420666) (xy 51.175607 -349.471163) (xy 51.191675 -349.52457) (xy 51.199795 -349.579746)
			(xy 51.200304 -349.607632) (xy 51.199795 -349.635518) (xy 51.191675 -349.690694) (xy 51.175607 -349.744101)
			(xy 51.151935 -349.794598) (xy 51.121162 -349.841111) (xy 51.083945 -349.882648) (xy 51.041077 -349.918323)
			(xy 50.993471 -349.947377) (xy 50.942142 -349.969189) (xy 50.888185 -349.983295) (xy 50.832748 -349.989395)
			(xy 50.777014 -349.987358) (xy 50.722171 -349.977228) (xy 50.669387 -349.959221) (xy 50.619787 -349.93372)
			(xy 50.574429 -349.901269) (xy 50.53428 -349.86256) (xy 50.500194 -349.818417) (xy 50.472898 -349.769782)
			(xy 50.452975 -349.717691) (xy 50.440849 -349.663254) (xy 50.436778 -349.607632) (xy 49.270286 -349.607632)
			(xy 49.255141 -349.658562) (xy 49.231976 -349.708608) (xy 49.201849 -349.754799) (xy 49.165387 -349.796171)
			(xy 49.144682 -349.814388) (xy 49.136609 -349.821945) (xy 49.127254 -349.841955) (xy 49.126648 -349.852996)
			(xy 49.126648 -349.93072) (xy 49.127245 -349.941766) (xy 49.136588 -349.961788) (xy 49.144682 -349.969328)
			(xy 49.165406 -349.987525) (xy 49.201876 -350.028896) (xy 49.232007 -350.075089) (xy 49.255171 -350.12514)
			(xy 49.270884 -350.178005) (xy 49.278819 -350.232582) (xy 49.279302 -350.260158) (xy 49.278806 -350.28741)
			(xy 49.271054 -350.34136) (xy 49.255703 -350.393658) (xy 49.233065 -350.443238) (xy 49.203601 -350.489092)
			(xy 49.191567 -350.502982) (xy 49.857658 -350.502982) (xy 49.861729 -350.44736) (xy 49.873855 -350.392923)
			(xy 49.893778 -350.340832) (xy 49.921074 -350.292197) (xy 49.95516 -350.248054) (xy 49.995309 -350.209345)
			(xy 50.040667 -350.176894) (xy 50.090267 -350.151393) (xy 50.143051 -350.133386) (xy 50.197894 -350.123256)
			(xy 50.253628 -350.121219) (xy 50.309065 -350.127319) (xy 50.363022 -350.141425) (xy 50.414351 -350.163237)
			(xy 50.461957 -350.192291) (xy 50.504825 -350.227966) (xy 50.542042 -350.269503) (xy 50.572815 -350.316016)
			(xy 50.596487 -350.366513) (xy 50.612555 -350.41992) (xy 50.620675 -350.475096) (xy 50.621184 -350.502982)
			(xy 50.620675 -350.530868) (xy 50.612555 -350.586044) (xy 50.596487 -350.639451) (xy 50.572815 -350.689948)
			(xy 50.542042 -350.736461) (xy 50.504825 -350.777998) (xy 50.461957 -350.813673) (xy 50.414351 -350.842727)
			(xy 50.363022 -350.864539) (xy 50.309065 -350.878645) (xy 50.253628 -350.884745) (xy 50.197894 -350.882708)
			(xy 50.143051 -350.872578) (xy 50.090267 -350.854571) (xy 50.040667 -350.82907) (xy 49.995309 -350.796619)
			(xy 49.95516 -350.75791) (xy 49.921074 -350.713767) (xy 49.893778 -350.665132) (xy 49.873855 -350.613041)
			(xy 49.861729 -350.558604) (xy 49.857658 -350.502982) (xy 49.191567 -350.502982) (xy 49.167911 -350.530285)
			(xy 49.126721 -350.565979) (xy 49.08087 -350.595448) (xy 49.031292 -350.618091) (xy 48.978995 -350.633447)
			(xy 48.925046 -350.641203) (xy 48.897794 -350.641666) (xy 48.869937 -350.641174) (xy 48.814819 -350.633048)
			(xy 48.761467 -350.617) (xy 48.711013 -350.59337) (xy 48.664527 -350.56266) (xy 48.622998 -350.52552)
			(xy 48.587306 -350.482741) (xy 48.558209 -350.435229) (xy 48.536324 -350.383993) (xy 48.528732 -350.357186)
			(xy 48.526446 -350.348296) (xy 48.515778 -350.333056) (xy 48.443896 -350.285304) (xy 48.425862 -350.28124)
			(xy 48.416718 -350.28251) (xy 48.403701 -350.284175) (xy 48.377517 -350.285958) (xy 48.364394 -350.286066)
			(xy 48.350245 -350.285973) (xy 48.322022 -350.283938) (xy 48.308006 -350.282002) (xy 48.2981 -350.280478)
			(xy 48.278288 -350.285304) (xy 48.203866 -350.341184) (xy 48.193706 -350.35871) (xy 48.192436 -350.36887)
			(xy 48.18835 -350.396023) (xy 48.173374 -350.448852) (xy 48.150981 -350.498989) (xy 48.121632 -350.545399)
			(xy 48.085935 -350.587122) (xy 48.044625 -350.623298) (xy 47.998557 -350.653179) (xy 47.948681 -350.676149)
			(xy 47.896028 -350.691732) (xy 47.841685 -350.699607) (xy 47.81423 -350.700086) (xy 47.786977 -350.699617)
			(xy 47.733025 -350.691863) (xy 47.680726 -350.67651) (xy 47.631144 -350.653869) (xy 47.58529 -350.624402)
			(xy 47.544097 -350.588709) (xy 47.508402 -350.547516) (xy 47.478935 -350.501663) (xy 47.456293 -350.452082)
			(xy 47.440938 -350.399783) (xy 47.433184 -350.345831) (xy 47.432722 -350.318578) (xy 45.291817 -350.318578)
			(xy 45.294449 -350.327543) (xy 45.3022 -350.381495) (xy 45.302678 -350.408748) (xy 45.302031 -350.440312)
			(xy 45.291649 -350.502581) (xy 45.27116 -350.562291) (xy 45.256704 -350.590358) (xy 45.251878 -350.599248)
			(xy 45.249846 -350.618806) (xy 45.272706 -350.697292) (xy 45.275952 -350.706711) (xy 45.28837 -350.722265)
			(xy 45.296836 -350.727518) (xy 45.32193 -350.742074) (xy 45.367797 -350.777591) (xy 45.407761 -350.81964)
			(xy 45.440903 -350.867252) (xy 45.466458 -350.91933) (xy 45.483838 -350.974676) (xy 45.492643 -351.032015)
			(xy 45.493178 -351.06102) (xy 45.492713 -351.088271) (xy 45.484954 -351.142218) (xy 45.474263 -351.178622)
			(xy 51.196494 -351.178622) (xy 51.196995 -351.151148) (xy 51.204883 -351.096769) (xy 51.2205 -351.044087)
			(xy 51.243522 -350.994194) (xy 51.27347 -350.948124) (xy 51.291236 -350.927162) (xy 51.29149 -350.926908)
			(xy 51.297078 -350.919823) (xy 51.303324 -350.902905) (xy 51.303682 -350.893888) (xy 51.303682 -350.826324)
			(xy 51.303317 -350.817308) (xy 51.297075 -350.800391) (xy 51.29149 -350.793304) (xy 51.290982 -350.792796)
			(xy 51.273248 -350.77185) (xy 51.243366 -350.725817) (xy 51.2204 -350.675972) (xy 51.204826 -350.623347)
			(xy 51.196965 -350.569031) (xy 51.196494 -350.54159) (xy 51.19698 -350.514339) (xy 51.204736 -350.460391)
			(xy 51.220091 -350.408096) (xy 51.242733 -350.358519) (xy 51.272199 -350.312669) (xy 51.30789 -350.271478)
			(xy 51.349081 -350.235787) (xy 51.394931 -350.206321) (xy 51.444508 -350.183679) (xy 51.496803 -350.168324)
			(xy 51.550751 -350.160568) (xy 51.605253 -350.160568) (xy 51.659201 -350.168324) (xy 51.711496 -350.183679)
			(xy 51.761073 -350.206321) (xy 51.806923 -350.235787) (xy 51.848114 -350.271478) (xy 51.883805 -350.312669)
			(xy 51.913271 -350.358519) (xy 51.935913 -350.408096) (xy 51.951268 -350.460391) (xy 51.959024 -350.514339)
			(xy 51.95951 -350.54159) (xy 51.959015 -350.569064) (xy 51.951125 -350.623443) (xy 51.935507 -350.676126)
			(xy 51.912484 -350.726018) (xy 51.882534 -350.772088) (xy 51.864768 -350.79305) (xy 51.864514 -350.793304)
			(xy 51.858921 -350.800386) (xy 51.852678 -350.817306) (xy 51.852322 -350.826324) (xy 51.852322 -350.893888)
			(xy 51.85268 -350.902905) (xy 51.858926 -350.919822) (xy 51.864514 -350.926908) (xy 51.865022 -350.927416)
			(xy 51.882762 -350.948356) (xy 51.912643 -350.994391) (xy 51.935608 -351.044238) (xy 51.951181 -351.096864)
			(xy 51.95904 -351.151181) (xy 51.95951 -351.178622) (xy 51.959024 -351.205873) (xy 51.951268 -351.259821)
			(xy 51.935913 -351.312116) (xy 51.913271 -351.361693) (xy 51.883805 -351.407543) (xy 51.848114 -351.448734)
			(xy 51.806923 -351.484425) (xy 51.761073 -351.513891) (xy 51.711496 -351.536533) (xy 51.659201 -351.551888)
			(xy 51.605253 -351.559644) (xy 51.550751 -351.559644) (xy 51.496803 -351.551888) (xy 51.444508 -351.536533)
			(xy 51.394931 -351.513891) (xy 51.349081 -351.484425) (xy 51.30789 -351.448734) (xy 51.272199 -351.407543)
			(xy 51.242733 -351.361693) (xy 51.220091 -351.312116) (xy 51.204736 -351.259821) (xy 51.19698 -351.205873)
			(xy 51.196494 -351.178622) (xy 45.474263 -351.178622) (xy 45.469596 -351.194512) (xy 45.446952 -351.244088)
			(xy 45.417483 -351.289936) (xy 45.381789 -351.331124) (xy 45.340596 -351.366813) (xy 45.294744 -351.396276)
			(xy 45.245165 -351.418913) (xy 45.192869 -351.434264) (xy 45.138921 -351.442017) (xy 45.11167 -351.442528)
			(xy 45.081727 -351.44194) (xy 45.022577 -351.432576) (xy 44.965617 -351.414083) (xy 44.912247 -351.386916)
			(xy 44.863779 -351.351742) (xy 44.821403 -351.309425) (xy 44.803314 -351.285556) (xy 44.795699 -351.276202)
			(xy 44.774212 -351.265321) (xy 44.762166 -351.264728) (xy 44.588176 -351.264728) (xy 44.578108 -351.265156)
			(xy 44.559513 -351.27288) (xy 44.552108 -351.279714) (xy 42.869866 -352.961956) (xy 42.855414 -352.975702)
			(xy 42.822249 -352.997848) (xy 42.785405 -353.013111) (xy 42.746295 -353.020908) (xy 42.726356 -353.021392)
			(xy 39.09441 -353.021392) (xy 39.084339 -353.021813) (xy 39.065731 -353.029524) (xy 39.058342 -353.036378)
			(xy 38.268148 -353.826826) (xy 38.253648 -353.840627) (xy 38.220368 -353.862862) (xy 38.183394 -353.878185)
			(xy 38.144142 -353.88601) (xy 38.12413 -353.886516) (xy 32.28721 -353.886516) (xy 32.277139 -353.886938)
			(xy 32.258534 -353.894651) (xy 32.251142 -353.901502) (xy 30.298644 -355.854) (xy 31.291782 -355.854)
			(xy 31.295853 -355.798378) (xy 31.307979 -355.743941) (xy 31.327902 -355.69185) (xy 31.355198 -355.643215)
			(xy 31.389284 -355.599072) (xy 31.429433 -355.560363) (xy 31.474791 -355.527912) (xy 31.524391 -355.502411)
			(xy 31.577175 -355.484404) (xy 31.632018 -355.474274) (xy 31.687752 -355.472237) (xy 31.743189 -355.478337)
			(xy 31.797146 -355.492443) (xy 31.848475 -355.514255) (xy 31.896081 -355.543309) (xy 31.938949 -355.578984)
			(xy 31.976166 -355.620521) (xy 32.006939 -355.667034) (xy 32.030611 -355.717531) (xy 32.046679 -355.770938)
			(xy 32.054799 -355.826114) (xy 32.055308 -355.854) (xy 32.434782 -355.854) (xy 32.438853 -355.798378)
			(xy 32.450979 -355.743941) (xy 32.470902 -355.69185) (xy 32.498198 -355.643215) (xy 32.532284 -355.599072)
			(xy 32.572433 -355.560363) (xy 32.617791 -355.527912) (xy 32.667391 -355.502411) (xy 32.720175 -355.484404)
			(xy 32.775018 -355.474274) (xy 32.830752 -355.472237) (xy 32.886189 -355.478337) (xy 32.940146 -355.492443)
			(xy 32.991475 -355.514255) (xy 33.039081 -355.543309) (xy 33.081949 -355.578984) (xy 33.119166 -355.620521)
			(xy 33.149939 -355.667034) (xy 33.173611 -355.717531) (xy 33.189679 -355.770938) (xy 33.197799 -355.826114)
			(xy 33.198308 -355.854) (xy 33.197799 -355.881886) (xy 33.189679 -355.937062) (xy 33.173611 -355.990469)
			(xy 33.149939 -356.040966) (xy 33.119166 -356.087479) (xy 33.081949 -356.129016) (xy 33.039081 -356.164691)
			(xy 32.991475 -356.193745) (xy 32.940146 -356.215557) (xy 32.886189 -356.229663) (xy 32.830752 -356.235763)
			(xy 32.775018 -356.233726) (xy 32.720175 -356.223596) (xy 32.667391 -356.205589) (xy 32.617791 -356.180088)
			(xy 32.572433 -356.147637) (xy 32.532284 -356.108928) (xy 32.498198 -356.064785) (xy 32.470902 -356.01615)
			(xy 32.450979 -355.964059) (xy 32.438853 -355.909622) (xy 32.434782 -355.854) (xy 32.055308 -355.854)
			(xy 32.054799 -355.881886) (xy 32.046679 -355.937062) (xy 32.030611 -355.990469) (xy 32.006939 -356.040966)
			(xy 31.976166 -356.087479) (xy 31.938949 -356.129016) (xy 31.896081 -356.164691) (xy 31.848475 -356.193745)
			(xy 31.797146 -356.215557) (xy 31.743189 -356.229663) (xy 31.687752 -356.235763) (xy 31.632018 -356.233726)
			(xy 31.577175 -356.223596) (xy 31.524391 -356.205589) (xy 31.474791 -356.180088) (xy 31.429433 -356.147637)
			(xy 31.389284 -356.108928) (xy 31.355198 -356.064785) (xy 31.327902 -356.01615) (xy 31.307979 -355.964059)
			(xy 31.295853 -355.909622) (xy 31.291782 -355.854) (xy 30.298644 -355.854) (xy 29.968698 -356.183946)
			(xy 29.961859 -356.191347) (xy 29.954142 -356.209945) (xy 29.953712 -356.220014) (xy 29.953712 -356.5525)
			(xy 30.618682 -356.5525) (xy 30.622753 -356.496878) (xy 30.634879 -356.442441) (xy 30.654802 -356.39035)
			(xy 30.682098 -356.341715) (xy 30.716184 -356.297572) (xy 30.756333 -356.258863) (xy 30.801691 -356.226412)
			(xy 30.851291 -356.200911) (xy 30.904075 -356.182904) (xy 30.958918 -356.172774) (xy 31.014652 -356.170737)
			(xy 31.070089 -356.176837) (xy 31.124046 -356.190943) (xy 31.175375 -356.212755) (xy 31.222981 -356.241809)
			(xy 31.265849 -356.277484) (xy 31.303066 -356.319021) (xy 31.333839 -356.365534) (xy 31.357511 -356.416031)
			(xy 31.373579 -356.469438) (xy 31.381699 -356.524614) (xy 31.382208 -356.5525) (xy 31.381699 -356.580386)
			(xy 31.373579 -356.635562) (xy 31.357511 -356.688969) (xy 31.333839 -356.739466) (xy 31.303066 -356.785979)
			(xy 31.265849 -356.827516) (xy 31.222981 -356.863191) (xy 31.175375 -356.892245) (xy 31.124046 -356.914057)
			(xy 31.070089 -356.928163) (xy 31.014652 -356.934263) (xy 30.958918 -356.932226) (xy 30.904075 -356.922096)
			(xy 30.851291 -356.904089) (xy 30.801691 -356.878588) (xy 30.756333 -356.846137) (xy 30.716184 -356.807428)
			(xy 30.682098 -356.763285) (xy 30.654802 -356.71465) (xy 30.634879 -356.662559) (xy 30.622753 -356.608122)
			(xy 30.618682 -356.5525) (xy 29.953712 -356.5525) (xy 29.953712 -356.555294) (xy 29.953253 -356.575311)
			(xy 29.945438 -356.614574) (xy 29.930106 -356.651555) (xy 29.907848 -356.68483) (xy 29.894022 -356.699312)
			(xy 29.018738 -357.574342) (xy 29.011894 -357.581741) (xy 29.004169 -357.60034) (xy 29.003752 -357.61041)
			(xy 29.003752 -357.6574) (xy 30.275782 -357.6574) (xy 30.279853 -357.601778) (xy 30.291979 -357.547341)
			(xy 30.311902 -357.49525) (xy 30.339198 -357.446615) (xy 30.373284 -357.402472) (xy 30.413433 -357.363763)
			(xy 30.458791 -357.331312) (xy 30.508391 -357.305811) (xy 30.561175 -357.287804) (xy 30.616018 -357.277674)
			(xy 30.671752 -357.275637) (xy 30.727189 -357.281737) (xy 30.781146 -357.295843) (xy 30.832475 -357.317655)
			(xy 30.880081 -357.346709) (xy 30.922949 -357.382384) (xy 30.960166 -357.423921) (xy 30.990939 -357.470434)
			(xy 31.014611 -357.520931) (xy 31.030679 -357.574338) (xy 31.038799 -357.629514) (xy 31.039308 -357.6574)
			(xy 31.038799 -357.685286) (xy 31.030679 -357.740462) (xy 31.014611 -357.793869) (xy 30.990939 -357.844366)
			(xy 30.960166 -357.890879) (xy 30.922949 -357.932416) (xy 30.880081 -357.968091) (xy 30.832475 -357.997145)
			(xy 30.781146 -358.018957) (xy 30.727189 -358.033063) (xy 30.671752 -358.039163) (xy 30.616018 -358.037126)
			(xy 30.561175 -358.026996) (xy 30.508391 -358.008989) (xy 30.458791 -357.983488) (xy 30.413433 -357.951037)
			(xy 30.373284 -357.912328) (xy 30.339198 -357.868185) (xy 30.311902 -357.81955) (xy 30.291979 -357.767459)
			(xy 30.279853 -357.713022) (xy 30.275782 -357.6574) (xy 29.003752 -357.6574) (xy 29.003752 -358.267)
			(xy 29.259782 -358.267) (xy 29.263853 -358.211378) (xy 29.275979 -358.156941) (xy 29.295902 -358.10485)
			(xy 29.323198 -358.056215) (xy 29.357284 -358.012072) (xy 29.397433 -357.973363) (xy 29.442791 -357.940912)
			(xy 29.492391 -357.915411) (xy 29.545175 -357.897404) (xy 29.600018 -357.887274) (xy 29.655752 -357.885237)
			(xy 29.711189 -357.891337) (xy 29.765146 -357.905443) (xy 29.816475 -357.927255) (xy 29.864081 -357.956309)
			(xy 29.906949 -357.991984) (xy 29.944166 -358.033521) (xy 29.974939 -358.080034) (xy 29.998611 -358.130531)
			(xy 30.014679 -358.183938) (xy 30.022799 -358.239114) (xy 30.023308 -358.267) (xy 30.022799 -358.294886)
			(xy 30.014679 -358.350062) (xy 29.998611 -358.403469) (xy 29.974939 -358.453966) (xy 29.944166 -358.500479)
			(xy 29.906949 -358.542016) (xy 29.864081 -358.577691) (xy 29.816475 -358.606745) (xy 29.765146 -358.628557)
			(xy 29.711189 -358.642663) (xy 29.655752 -358.648763) (xy 29.600018 -358.646726) (xy 29.545175 -358.636596)
			(xy 29.492391 -358.618589) (xy 29.442791 -358.593088) (xy 29.397433 -358.560637) (xy 29.357284 -358.521928)
			(xy 29.323198 -358.477785) (xy 29.295902 -358.42915) (xy 29.275979 -358.377059) (xy 29.263853 -358.322622)
			(xy 29.259782 -358.267) (xy 29.003752 -358.267) (xy 29.003752 -359.305606) (xy 29.00324 -359.325543)
			(xy 28.995433 -359.364646) (xy 28.980178 -359.401487) (xy 28.958056 -359.434662) (xy 28.944316 -359.449116)
			(xy 28.805632 -359.5878) (xy 29.259782 -359.5878) (xy 29.263853 -359.532178) (xy 29.275979 -359.477741)
			(xy 29.295902 -359.42565) (xy 29.323198 -359.377015) (xy 29.357284 -359.332872) (xy 29.397433 -359.294163)
			(xy 29.442791 -359.261712) (xy 29.492391 -359.236211) (xy 29.545175 -359.218204) (xy 29.600018 -359.208074)
			(xy 29.655752 -359.206037) (xy 29.711189 -359.212137) (xy 29.765146 -359.226243) (xy 29.816475 -359.248055)
			(xy 29.864081 -359.277109) (xy 29.906949 -359.312784) (xy 29.944166 -359.354321) (xy 29.974939 -359.400834)
			(xy 29.998611 -359.451331) (xy 30.014679 -359.504738) (xy 30.022799 -359.559914) (xy 30.023308 -359.5878)
			(xy 30.022799 -359.615686) (xy 30.014679 -359.670862) (xy 29.998611 -359.724269) (xy 29.974939 -359.774766)
			(xy 29.944166 -359.821279) (xy 29.906949 -359.862816) (xy 29.864081 -359.898491) (xy 29.816475 -359.927545)
			(xy 29.765146 -359.949357) (xy 29.711189 -359.963463) (xy 29.655752 -359.969563) (xy 29.600018 -359.967526)
			(xy 29.545175 -359.957396) (xy 29.492391 -359.939389) (xy 29.442791 -359.913888) (xy 29.397433 -359.881437)
			(xy 29.357284 -359.842728) (xy 29.323198 -359.798585) (xy 29.295902 -359.74995) (xy 29.275979 -359.697859)
			(xy 29.263853 -359.643422) (xy 29.259782 -359.5878) (xy 28.805632 -359.5878) (xy 27.62631 -360.767122)
			(xy 27.619466 -360.774521) (xy 27.611738 -360.793119) (xy 27.611324 -360.80319) (xy 27.611324 -361.742228)
			(xy 27.611817 -361.75223) (xy 27.619483 -361.770708) (xy 27.633635 -361.784847) (xy 27.652121 -361.792493)
			(xy 27.662124 -361.793028) (xy 27.681428 -361.793028) (xy 27.71013 -361.767628) (xy 27.712416 -361.748324)
			(xy 27.715698 -361.725866) (xy 27.730829 -361.683087) (xy 27.755002 -361.644686) (xy 27.770582 -361.628182)
			(xy 28.049982 -361.348782) (xy 28.05739 -361.341604) (xy 28.073424 -361.328626) (xy 28.081986 -361.322874)
			(xy 28.086304 -361.32008) (xy 28.89758 -360.50855) (xy 28.912081 -360.494752) (xy 28.945363 -360.472525)
			(xy 28.982337 -360.457208) (xy 29.021588 -360.44939) (xy 29.041598 -360.44886) (xy 29.855668 -360.44886)
			(xy 29.865732 -360.448423) (xy 29.884314 -360.440687) (xy 29.891736 -360.433874) (xy 30.746954 -359.578656)
			(xy 30.753798 -359.571257) (xy 30.761524 -359.552659) (xy 30.76194 -359.542588) (xy 30.76194 -358.690672)
			(xy 30.762393 -358.670653) (xy 30.770199 -358.631385) (xy 30.785526 -358.594397) (xy 30.807781 -358.561116)
			(xy 30.82163 -358.546654) (xy 32.440626 -356.927658) (xy 32.455126 -356.913856) (xy 32.488405 -356.891618)
			(xy 32.52538 -356.876292) (xy 32.564632 -356.868463) (xy 32.584644 -356.867968) (xy 32.832802 -356.867968)
			(xy 32.842871 -356.867544) (xy 32.861472 -356.859825) (xy 32.86887 -356.852982) (xy 33.495742 -356.226364)
			(xy 33.502589 -356.218966) (xy 33.510319 -356.200368) (xy 33.510728 -356.190296) (xy 33.510728 -355.232716)
			(xy 33.511239 -355.212779) (xy 33.519044 -355.173676) (xy 33.534301 -355.136836) (xy 33.556427 -355.103664)
			(xy 33.570164 -355.089206) (xy 34.163762 -354.495608) (xy 34.178213 -354.48186) (xy 34.211378 -354.459712)
			(xy 34.248221 -354.444449) (xy 34.287332 -354.436656) (xy 34.307272 -354.436172) (xy 38.348412 -354.436172)
			(xy 38.358481 -354.435746) (xy 38.377079 -354.428025) (xy 38.38448 -354.421186) (xy 39.221664 -353.583748)
			(xy 39.236117 -353.570003) (xy 39.269283 -353.547862) (xy 39.306126 -353.532604) (xy 39.345235 -353.524813)
			(xy 39.365174 -353.524312) (xy 42.787824 -353.524312) (xy 42.797893 -353.523885) (xy 42.816492 -353.516166)
			(xy 42.823892 -353.509326) (xy 43.710606 -352.622358) (xy 43.725105 -352.608554) (xy 43.758384 -352.586314)
			(xy 43.795358 -352.570983) (xy 43.834611 -352.563151) (xy 43.854624 -352.562668) (xy 51.550824 -352.562668)
			(xy 51.560892 -352.56224) (xy 51.579487 -352.554516) (xy 51.586892 -352.547682) (xy 53.079904 -351.05467)
			(xy 53.08727 -351.038668) (xy 53.088032 -351.029524) (xy 53.090644 -351.003348) (xy 53.102153 -350.952016)
			(xy 53.12061 -350.902755) (xy 53.132736 -350.87941) (xy 53.137562 -350.87052) (xy 53.139594 -350.850962)
			(xy 53.116734 -350.772476) (xy 53.113486 -350.763058) (xy 53.101068 -350.747505) (xy 53.092604 -350.74225)
			(xy 53.085238 -350.738186) (xy 53.075332 -350.732344) (xy 53.053488 -350.730312) (xy 52.958746 -350.76384)
			(xy 52.942998 -350.779334) (xy 52.938934 -350.789748) (xy 52.928241 -350.816525) (xy 52.899955 -350.866766)
			(xy 52.864426 -350.912174) (xy 52.822463 -350.951713) (xy 52.775024 -350.984482) (xy 52.723191 -351.009733)
			(xy 52.668147 -351.026889) (xy 52.611146 -351.03556) (xy 52.582318 -351.036128) (xy 52.555063 -351.035666)
			(xy 52.501107 -351.027911) (xy 52.448804 -351.012556) (xy 52.399219 -350.989913) (xy 52.353361 -350.960444)
			(xy 52.312164 -350.924748) (xy 52.276467 -350.883553) (xy 52.246996 -350.837697) (xy 52.224351 -350.788113)
			(xy 52.208993 -350.735811) (xy 52.201235 -350.681855) (xy 52.201235 -350.627345) (xy 52.208993 -350.573389)
			(xy 52.224351 -350.521087) (xy 52.246996 -350.471503) (xy 52.276467 -350.425647) (xy 52.312164 -350.384452)
			(xy 52.353361 -350.348756) (xy 52.399219 -350.319287) (xy 52.448804 -350.296644) (xy 52.501107 -350.281289)
			(xy 52.555063 -350.273534) (xy 52.582318 -350.273112) (xy 52.582572 -350.273112) (xy 52.607773 -350.273539)
			(xy 52.657732 -350.280207) (xy 52.706382 -350.29338) (xy 52.752881 -350.312828) (xy 52.77485 -350.325182)
			(xy 52.784756 -350.331024) (xy 52.8066 -350.333056) (xy 52.901342 -350.299528) (xy 52.91709 -350.284034)
			(xy 52.921154 -350.27362) (xy 52.931849 -350.246844) (xy 52.960136 -350.196606) (xy 52.995667 -350.1512)
			(xy 53.03763 -350.111663) (xy 53.085068 -350.078896) (xy 53.1369 -350.053646) (xy 53.191943 -350.03649)
			(xy 53.248942 -350.027818) (xy 53.27777 -350.02724) (xy 53.305023 -350.027701) (xy 53.358975 -350.035455)
			(xy 53.411273 -350.050809) (xy 53.460854 -350.07345) (xy 53.506708 -350.102918) (xy 53.5479 -350.138613)
			(xy 53.583592 -350.179807) (xy 53.613058 -350.225662) (xy 53.635697 -350.275244) (xy 53.648417 -350.318578)
			(xy 55.789322 -350.318578) (xy 55.789834 -350.291005) (xy 55.797776 -350.236434) (xy 55.813491 -350.183575)
			(xy 55.836652 -350.133528) (xy 55.866777 -350.087337) (xy 55.903238 -350.045965) (xy 55.923942 -350.027748)
			(xy 55.932003 -350.02018) (xy 55.941363 -350.000178) (xy 55.941976 -349.98914) (xy 55.941976 -349.911416)
			(xy 55.941407 -349.900367) (xy 55.932043 -349.880345) (xy 55.923942 -349.872808) (xy 55.90324 -349.854587)
			(xy 55.866767 -349.813221) (xy 55.836633 -349.767034) (xy 55.813465 -349.716988) (xy 55.797747 -349.664126)
			(xy 55.789807 -349.609552) (xy 55.789322 -349.581978) (xy 55.789734 -349.554723) (xy 55.797495 -349.500769)
			(xy 55.812856 -349.448468) (xy 55.835503 -349.398886) (xy 55.864976 -349.353031) (xy 55.900675 -349.311838)
			(xy 55.941873 -349.276145) (xy 55.987732 -349.246678) (xy 56.037317 -349.224037) (xy 56.08962 -349.208684)
			(xy 56.143575 -349.200931) (xy 56.17083 -349.20047) (xy 56.171338 -349.20047) (xy 56.20512 -349.201994)
			(xy 56.21528 -349.20301) (xy 56.234584 -349.196914) (xy 56.297576 -349.144082) (xy 56.304849 -349.137342)
			(xy 56.314141 -349.11985) (xy 56.31561 -349.110046) (xy 56.31561 -349.109284) (xy 56.318562 -349.081135)
			(xy 56.331756 -349.026097) (xy 56.352941 -348.973613) (xy 56.381649 -348.924837) (xy 56.417252 -348.88084)
			(xy 56.458966 -348.842588) (xy 56.505876 -348.810921) (xy 56.556951 -348.786535) (xy 56.611069 -348.769966)
			(xy 56.667041 -348.761577) (xy 56.69534 -348.76105) (xy 56.695594 -348.76105) (xy 56.713613 -348.761277)
			(xy 56.749488 -348.764707) (xy 56.767222 -348.767908) (xy 56.776874 -348.769686) (xy 56.795924 -348.76613)
			(xy 56.870854 -348.718124) (xy 56.882284 -348.702376) (xy 56.88457 -348.692978) (xy 56.892025 -348.665951)
			(xy 56.913648 -348.614227) (xy 56.942605 -348.566223) (xy 56.978273 -348.522971) (xy 57.019885 -348.485403)
			(xy 57.066545 -348.454326) (xy 57.117249 -348.43041) (xy 57.170907 -348.414169) (xy 57.226363 -348.405952)
			(xy 57.254394 -348.40545) (xy 57.281643 -348.405983) (xy 57.335587 -348.413738) (xy 57.387878 -348.42909)
			(xy 57.437453 -348.451727) (xy 57.483301 -348.481189) (xy 57.52449 -348.516876) (xy 57.560182 -348.55806)
			(xy 57.58965 -348.603905) (xy 57.612293 -348.653477) (xy 57.627652 -348.705766) (xy 57.635413 -348.759709)
			(xy 57.635902 -348.786958) (xy 57.635407 -348.814531) (xy 57.62746 -348.869103) (xy 57.611741 -348.921962)
			(xy 57.588576 -348.972008) (xy 57.558449 -349.018199) (xy 57.521987 -349.059571) (xy 57.501282 -349.077788)
			(xy 57.493209 -349.085345) (xy 57.483854 -349.105355) (xy 57.483248 -349.116396) (xy 57.483248 -349.19412)
			(xy 57.483845 -349.205166) (xy 57.493188 -349.225188) (xy 57.501282 -349.232728) (xy 57.522006 -349.250925)
			(xy 57.558476 -349.292296) (xy 57.588607 -349.338489) (xy 57.611771 -349.38854) (xy 57.627484 -349.441405)
			(xy 57.635419 -349.495982) (xy 57.635902 -349.523558) (xy 57.635407 -349.551131) (xy 57.62746 -349.605703)
			(xy 57.626886 -349.607632) (xy 58.767978 -349.607632) (xy 58.772049 -349.55201) (xy 58.784175 -349.497573)
			(xy 58.804098 -349.445482) (xy 58.831394 -349.396847) (xy 58.86548 -349.352704) (xy 58.905629 -349.313995)
			(xy 58.950987 -349.281544) (xy 59.000587 -349.256043) (xy 59.053371 -349.238036) (xy 59.108214 -349.227906)
			(xy 59.163948 -349.225869) (xy 59.219385 -349.231969) (xy 59.273342 -349.246075) (xy 59.324671 -349.267887)
			(xy 59.372277 -349.296941) (xy 59.415145 -349.332616) (xy 59.452362 -349.374153) (xy 59.483135 -349.420666)
			(xy 59.506807 -349.471163) (xy 59.522875 -349.52457) (xy 59.530995 -349.579746) (xy 59.531504 -349.607632)
			(xy 59.530995 -349.635518) (xy 59.522875 -349.690694) (xy 59.506807 -349.744101) (xy 59.483135 -349.794598)
			(xy 59.452362 -349.841111) (xy 59.415145 -349.882648) (xy 59.372277 -349.918323) (xy 59.324671 -349.947377)
			(xy 59.273342 -349.969189) (xy 59.219385 -349.983295) (xy 59.163948 -349.989395) (xy 59.108214 -349.987358)
			(xy 59.053371 -349.977228) (xy 59.000587 -349.959221) (xy 58.950987 -349.93372) (xy 58.905629 -349.901269)
			(xy 58.86548 -349.86256) (xy 58.831394 -349.818417) (xy 58.804098 -349.769782) (xy 58.784175 -349.717691)
			(xy 58.772049 -349.663254) (xy 58.767978 -349.607632) (xy 57.626886 -349.607632) (xy 57.611741 -349.658562)
			(xy 57.588576 -349.708608) (xy 57.558449 -349.754799) (xy 57.521987 -349.796171) (xy 57.501282 -349.814388)
			(xy 57.493209 -349.821945) (xy 57.483854 -349.841955) (xy 57.483248 -349.852996) (xy 57.483248 -349.93072)
			(xy 57.483845 -349.941766) (xy 57.493188 -349.961788) (xy 57.501282 -349.969328) (xy 57.522006 -349.987525)
			(xy 57.558476 -350.028896) (xy 57.588607 -350.075089) (xy 57.611771 -350.12514) (xy 57.627484 -350.178005)
			(xy 57.635419 -350.232582) (xy 57.635902 -350.260158) (xy 57.635406 -350.28741) (xy 57.627654 -350.34136)
			(xy 57.612303 -350.393658) (xy 57.589665 -350.443238) (xy 57.560201 -350.489092) (xy 57.548167 -350.502982)
			(xy 58.188858 -350.502982) (xy 58.192929 -350.44736) (xy 58.205055 -350.392923) (xy 58.224978 -350.340832)
			(xy 58.252274 -350.292197) (xy 58.28636 -350.248054) (xy 58.326509 -350.209345) (xy 58.371867 -350.176894)
			(xy 58.421467 -350.151393) (xy 58.474251 -350.133386) (xy 58.529094 -350.123256) (xy 58.584828 -350.121219)
			(xy 58.640265 -350.127319) (xy 58.694222 -350.141425) (xy 58.745551 -350.163237) (xy 58.793157 -350.192291)
			(xy 58.836025 -350.227966) (xy 58.873242 -350.269503) (xy 58.904015 -350.316016) (xy 58.927687 -350.366513)
			(xy 58.943755 -350.41992) (xy 58.951875 -350.475096) (xy 58.952384 -350.502982) (xy 58.951875 -350.530868)
			(xy 58.943755 -350.586044) (xy 58.927687 -350.639451) (xy 58.904015 -350.689948) (xy 58.873242 -350.736461)
			(xy 58.836025 -350.777998) (xy 58.793157 -350.813673) (xy 58.745551 -350.842727) (xy 58.694222 -350.864539)
			(xy 58.640265 -350.878645) (xy 58.584828 -350.884745) (xy 58.529094 -350.882708) (xy 58.474251 -350.872578)
			(xy 58.421467 -350.854571) (xy 58.371867 -350.82907) (xy 58.326509 -350.796619) (xy 58.28636 -350.75791)
			(xy 58.252274 -350.713767) (xy 58.224978 -350.665132) (xy 58.205055 -350.613041) (xy 58.192929 -350.558604)
			(xy 58.188858 -350.502982) (xy 57.548167 -350.502982) (xy 57.524511 -350.530285) (xy 57.483321 -350.565979)
			(xy 57.43747 -350.595448) (xy 57.387892 -350.618091) (xy 57.335595 -350.633447) (xy 57.281646 -350.641203)
			(xy 57.254394 -350.641666) (xy 57.226537 -350.641174) (xy 57.171419 -350.633048) (xy 57.118067 -350.617)
			(xy 57.067613 -350.59337) (xy 57.021127 -350.56266) (xy 56.979598 -350.52552) (xy 56.943906 -350.482741)
			(xy 56.914809 -350.435229) (xy 56.892924 -350.383993) (xy 56.885332 -350.357186) (xy 56.883046 -350.348296)
			(xy 56.872378 -350.333056) (xy 56.800496 -350.285304) (xy 56.782462 -350.28124) (xy 56.773318 -350.28251)
			(xy 56.760301 -350.284175) (xy 56.734117 -350.285958) (xy 56.720994 -350.286066) (xy 56.706845 -350.285973)
			(xy 56.678622 -350.283938) (xy 56.664606 -350.282002) (xy 56.6547 -350.280478) (xy 56.634888 -350.285304)
			(xy 56.560466 -350.341184) (xy 56.550306 -350.35871) (xy 56.549036 -350.36887) (xy 56.54495 -350.396023)
			(xy 56.529974 -350.448852) (xy 56.507581 -350.498989) (xy 56.478232 -350.545399) (xy 56.442535 -350.587122)
			(xy 56.401225 -350.623298) (xy 56.355157 -350.653179) (xy 56.305281 -350.676149) (xy 56.252628 -350.691732)
			(xy 56.198285 -350.699607) (xy 56.17083 -350.700086) (xy 56.143577 -350.699617) (xy 56.089625 -350.691863)
			(xy 56.037326 -350.67651) (xy 55.987744 -350.653869) (xy 55.94189 -350.624402) (xy 55.900697 -350.588709)
			(xy 55.865002 -350.547516) (xy 55.835535 -350.501663) (xy 55.812893 -350.452082) (xy 55.797538 -350.399783)
			(xy 55.789784 -350.345831) (xy 55.789322 -350.318578) (xy 53.648417 -350.318578) (xy 53.651049 -350.327543)
			(xy 53.6588 -350.381495) (xy 53.659278 -350.408748) (xy 53.658631 -350.440312) (xy 53.648249 -350.502581)
			(xy 53.62776 -350.562291) (xy 53.613304 -350.590358) (xy 53.608478 -350.599248) (xy 53.606446 -350.618806)
			(xy 53.629306 -350.697292) (xy 53.632552 -350.706711) (xy 53.64497 -350.722265) (xy 53.653436 -350.727518)
			(xy 53.67853 -350.742074) (xy 53.724397 -350.777591) (xy 53.764361 -350.81964) (xy 53.797503 -350.867252)
			(xy 53.823058 -350.91933) (xy 53.840438 -350.974676) (xy 53.849243 -351.032015) (xy 53.849778 -351.06102)
			(xy 53.849313 -351.088271) (xy 53.841554 -351.142218) (xy 53.830863 -351.178622) (xy 59.527694 -351.178622)
			(xy 59.528195 -351.151148) (xy 59.536083 -351.096769) (xy 59.5517 -351.044087) (xy 59.574722 -350.994194)
			(xy 59.60467 -350.948124) (xy 59.622436 -350.927162) (xy 59.62269 -350.926908) (xy 59.628278 -350.919823)
			(xy 59.634524 -350.902905) (xy 59.634882 -350.893888) (xy 59.634882 -350.826324) (xy 59.634517 -350.817308)
			(xy 59.628275 -350.800391) (xy 59.62269 -350.793304) (xy 59.622182 -350.792796) (xy 59.604448 -350.77185)
			(xy 59.574566 -350.725817) (xy 59.5516 -350.675972) (xy 59.536026 -350.623347) (xy 59.528165 -350.569031)
			(xy 59.527694 -350.54159) (xy 59.52818 -350.514339) (xy 59.535936 -350.460391) (xy 59.551291 -350.408096)
			(xy 59.573933 -350.358519) (xy 59.603399 -350.312669) (xy 59.63909 -350.271478) (xy 59.680281 -350.235787)
			(xy 59.726131 -350.206321) (xy 59.775708 -350.183679) (xy 59.828003 -350.168324) (xy 59.881951 -350.160568)
			(xy 59.936453 -350.160568) (xy 59.990401 -350.168324) (xy 60.042696 -350.183679) (xy 60.092273 -350.206321)
			(xy 60.138123 -350.235787) (xy 60.179314 -350.271478) (xy 60.215005 -350.312669) (xy 60.244471 -350.358519)
			(xy 60.267113 -350.408096) (xy 60.282468 -350.460391) (xy 60.290224 -350.514339) (xy 60.29071 -350.54159)
			(xy 60.290215 -350.569064) (xy 60.282325 -350.623443) (xy 60.266707 -350.676126) (xy 60.243684 -350.726018)
			(xy 60.213734 -350.772088) (xy 60.195968 -350.79305) (xy 60.195714 -350.793304) (xy 60.190121 -350.800386)
			(xy 60.183878 -350.817306) (xy 60.183522 -350.826324) (xy 60.183522 -350.893888) (xy 60.18388 -350.902905)
			(xy 60.190126 -350.919822) (xy 60.195714 -350.926908) (xy 60.196222 -350.927416) (xy 60.213962 -350.948356)
			(xy 60.243843 -350.994391) (xy 60.266808 -351.044238) (xy 60.282381 -351.096864) (xy 60.29024 -351.151181)
			(xy 60.29071 -351.178622) (xy 60.290224 -351.205873) (xy 60.282468 -351.259821) (xy 60.267113 -351.312116)
			(xy 60.244471 -351.361693) (xy 60.215005 -351.407543) (xy 60.179314 -351.448734) (xy 60.138123 -351.484425)
			(xy 60.092273 -351.513891) (xy 60.042696 -351.536533) (xy 59.990401 -351.551888) (xy 59.936453 -351.559644)
			(xy 59.881951 -351.559644) (xy 59.828003 -351.551888) (xy 59.775708 -351.536533) (xy 59.726131 -351.513891)
			(xy 59.680281 -351.484425) (xy 59.63909 -351.448734) (xy 59.603399 -351.407543) (xy 59.573933 -351.361693)
			(xy 59.551291 -351.312116) (xy 59.535936 -351.259821) (xy 59.52818 -351.205873) (xy 59.527694 -351.178622)
			(xy 53.830863 -351.178622) (xy 53.826196 -351.194512) (xy 53.803552 -351.244088) (xy 53.774083 -351.289936)
			(xy 53.738389 -351.331124) (xy 53.697196 -351.366813) (xy 53.651344 -351.396276) (xy 53.601765 -351.418913)
			(xy 53.549469 -351.434264) (xy 53.495521 -351.442017) (xy 53.46827 -351.442528) (xy 53.434044 -351.441792)
			(xy 53.366698 -351.429527) (xy 53.334412 -351.418144) (xy 53.334158 -351.418144) (xy 53.324925 -351.415141)
			(xy 53.305533 -351.415595) (xy 53.287714 -351.42326) (xy 53.280564 -351.429828) (xy 51.800252 -352.910394)
			(xy 51.785753 -352.924198) (xy 51.752474 -352.946436) (xy 51.715499 -352.961763) (xy 51.676246 -352.96959)
			(xy 51.656234 -352.970084) (xy 43.960034 -352.970084) (xy 43.949969 -352.970519) (xy 43.93138 -352.978248)
			(xy 43.923966 -352.98507) (xy 43.037252 -353.871784) (xy 43.022801 -353.885533) (xy 42.989638 -353.907685)
			(xy 42.952794 -353.922951) (xy 42.913682 -353.930747) (xy 42.893742 -353.93122) (xy 39.471092 -353.93122)
			(xy 39.461023 -353.931645) (xy 39.442422 -353.939364) (xy 39.435024 -353.946206) (xy 38.59784 -354.783644)
			(xy 38.583388 -354.797389) (xy 38.550222 -354.819532) (xy 38.513379 -354.834792) (xy 38.474269 -354.842583)
			(xy 38.45433 -354.84308) (xy 34.41319 -354.84308) (xy 34.40312 -354.843504) (xy 34.384516 -354.851219)
			(xy 34.377122 -354.858066) (xy 33.932622 -355.302566) (xy 33.925784 -355.309967) (xy 33.91807 -355.328566)
			(xy 33.917636 -355.338634) (xy 33.917636 -355.7524) (xy 34.669982 -355.7524) (xy 34.674053 -355.696778)
			(xy 34.686179 -355.642341) (xy 34.706102 -355.59025) (xy 34.733398 -355.541615) (xy 34.767484 -355.497472)
			(xy 34.807633 -355.458763) (xy 34.852991 -355.426312) (xy 34.902591 -355.400811) (xy 34.955375 -355.382804)
			(xy 35.010218 -355.372674) (xy 35.065952 -355.370637) (xy 35.121389 -355.376737) (xy 35.175346 -355.390843)
			(xy 35.226675 -355.412655) (xy 35.274281 -355.441709) (xy 35.317149 -355.477384) (xy 35.354366 -355.518921)
			(xy 35.385139 -355.565434) (xy 35.408811 -355.615931) (xy 35.424879 -355.669338) (xy 35.432999 -355.724514)
			(xy 35.433508 -355.7524) (xy 35.432999 -355.780286) (xy 35.424879 -355.835462) (xy 35.408811 -355.888869)
			(xy 35.385139 -355.939366) (xy 35.354366 -355.985879) (xy 35.317149 -356.027416) (xy 35.274281 -356.063091)
			(xy 35.226675 -356.092145) (xy 35.175346 -356.113957) (xy 35.121389 -356.128063) (xy 35.065952 -356.134163)
			(xy 35.010218 -356.132126) (xy 34.955375 -356.121996) (xy 34.902591 -356.103989) (xy 34.852991 -356.078488)
			(xy 34.807633 -356.046037) (xy 34.767484 -356.007328) (xy 34.733398 -355.963185) (xy 34.706102 -355.91455)
			(xy 34.686179 -355.862459) (xy 34.674053 -355.808022) (xy 34.669982 -355.7524) (xy 33.917636 -355.7524)
			(xy 33.917636 -356.296214) (xy 33.917123 -356.31615) (xy 33.909315 -356.355252) (xy 33.894058 -356.392091)
			(xy 33.871934 -356.425264) (xy 33.8582 -356.439724) (xy 33.08223 -357.215694) (xy 33.06773 -357.229496)
			(xy 33.034451 -357.251731) (xy 32.997476 -357.267053) (xy 32.958224 -357.274876) (xy 32.938212 -357.275384)
			(xy 32.690054 -357.275384) (xy 32.679987 -357.275815) (xy 32.661393 -357.283539) (xy 32.653986 -357.29037)
			(xy 32.286956 -357.6574) (xy 33.857182 -357.6574) (xy 33.861253 -357.601778) (xy 33.873379 -357.547341)
			(xy 33.893302 -357.49525) (xy 33.920598 -357.446615) (xy 33.954684 -357.402472) (xy 33.994833 -357.363763)
			(xy 34.040191 -357.331312) (xy 34.089791 -357.305811) (xy 34.142575 -357.287804) (xy 34.197418 -357.277674)
			(xy 34.253152 -357.275637) (xy 34.308589 -357.281737) (xy 34.362546 -357.295843) (xy 34.413875 -357.317655)
			(xy 34.461481 -357.346709) (xy 34.504349 -357.382384) (xy 34.541566 -357.423921) (xy 34.572339 -357.470434)
			(xy 34.596011 -357.520931) (xy 34.612079 -357.574338) (xy 34.620199 -357.629514) (xy 34.620708 -357.6574)
			(xy 34.620199 -357.685286) (xy 34.612079 -357.740462) (xy 34.596011 -357.793869) (xy 34.572339 -357.844366)
			(xy 34.541566 -357.890879) (xy 34.504349 -357.932416) (xy 34.461481 -357.968091) (xy 34.413875 -357.997145)
			(xy 34.362546 -358.018957) (xy 34.308589 -358.033063) (xy 34.253152 -358.039163) (xy 34.197418 -358.037126)
			(xy 34.142575 -358.026996) (xy 34.089791 -358.008989) (xy 34.040191 -357.983488) (xy 33.994833 -357.951037)
			(xy 33.954684 -357.912328) (xy 33.920598 -357.868185) (xy 33.893302 -357.81955) (xy 33.873379 -357.767459)
			(xy 33.861253 -357.713022) (xy 33.857182 -357.6574) (xy 32.286956 -357.6574) (xy 31.184342 -358.760014)
			(xy 31.177493 -358.767411) (xy 31.169757 -358.78601) (xy 31.169356 -358.796082) (xy 31.169356 -359.156)
			(xy 31.621982 -359.156) (xy 31.626053 -359.100378) (xy 31.638179 -359.045941) (xy 31.658102 -358.99385)
			(xy 31.685398 -358.945215) (xy 31.719484 -358.901072) (xy 31.759633 -358.862363) (xy 31.804991 -358.829912)
			(xy 31.854591 -358.804411) (xy 31.907375 -358.786404) (xy 31.962218 -358.776274) (xy 32.017952 -358.774237)
			(xy 32.073389 -358.780337) (xy 32.127346 -358.794443) (xy 32.178675 -358.816255) (xy 32.226281 -358.845309)
			(xy 32.269149 -358.880984) (xy 32.306366 -358.922521) (xy 32.337139 -358.969034) (xy 32.360811 -359.019531)
			(xy 32.376879 -359.072938) (xy 32.384999 -359.128114) (xy 32.385508 -359.156) (xy 32.384999 -359.183886)
			(xy 32.376879 -359.239062) (xy 32.360811 -359.292469) (xy 32.337139 -359.342966) (xy 32.306366 -359.389479)
			(xy 32.269149 -359.431016) (xy 32.226281 -359.466691) (xy 32.178675 -359.495745) (xy 32.127346 -359.517557)
			(xy 32.073389 -359.531663) (xy 32.017952 -359.537763) (xy 31.962218 -359.535726) (xy 31.907375 -359.525596)
			(xy 31.854591 -359.507589) (xy 31.804991 -359.482088) (xy 31.759633 -359.449637) (xy 31.719484 -359.410928)
			(xy 31.685398 -359.366785) (xy 31.658102 -359.31815) (xy 31.638179 -359.266059) (xy 31.626053 -359.211622)
			(xy 31.621982 -359.156) (xy 31.169356 -359.156) (xy 31.169356 -359.647998) (xy 31.168896 -359.668014)
			(xy 31.161078 -359.707275) (xy 31.145743 -359.744253) (xy 31.123481 -359.777523) (xy 31.109666 -359.792016)
			(xy 30.729682 -360.172) (xy 31.621982 -360.172) (xy 31.626053 -360.116378) (xy 31.638179 -360.061941)
			(xy 31.658102 -360.00985) (xy 31.685398 -359.961215) (xy 31.719484 -359.917072) (xy 31.759633 -359.878363)
			(xy 31.804991 -359.845912) (xy 31.854591 -359.820411) (xy 31.907375 -359.802404) (xy 31.962218 -359.792274)
			(xy 32.017952 -359.790237) (xy 32.073389 -359.796337) (xy 32.127346 -359.810443) (xy 32.178675 -359.832255)
			(xy 32.226281 -359.861309) (xy 32.269149 -359.896984) (xy 32.306366 -359.938521) (xy 32.337139 -359.985034)
			(xy 32.360811 -360.035531) (xy 32.376879 -360.088938) (xy 32.384999 -360.144114) (xy 32.385508 -360.172)
			(xy 32.384999 -360.199886) (xy 32.376879 -360.255062) (xy 32.360811 -360.308469) (xy 32.337139 -360.358966)
			(xy 32.306366 -360.405479) (xy 32.269149 -360.447016) (xy 32.226281 -360.482691) (xy 32.178675 -360.511745)
			(xy 32.127346 -360.533557) (xy 32.073389 -360.547663) (xy 32.017952 -360.553763) (xy 31.962218 -360.551726)
			(xy 31.907375 -360.541596) (xy 31.854591 -360.523589) (xy 31.804991 -360.498088) (xy 31.759633 -360.465637)
			(xy 31.719484 -360.426928) (xy 31.685398 -360.382785) (xy 31.658102 -360.33415) (xy 31.638179 -360.282059)
			(xy 31.626053 -360.227622) (xy 31.621982 -360.172) (xy 30.729682 -360.172) (xy 30.105096 -360.796586)
			(xy 30.090599 -360.810393) (xy 30.057321 -360.83264) (xy 30.020346 -360.847975) (xy 29.981092 -360.855811)
			(xy 29.961078 -360.856276) (xy 29.147008 -360.856276) (xy 29.136937 -360.856697) (xy 29.118328 -360.864407)
			(xy 29.11094 -360.871262) (xy 28.345384 -361.636818) (xy 28.337978 -361.643998) (xy 28.321947 -361.65698)
			(xy 28.31338 -361.662726) (xy 28.309062 -361.66552) (xy 28.13304 -361.841542) (xy 28.12626 -361.848966)
			(xy 28.118654 -361.867562) (xy 28.118308 -361.87761) (xy 28.118308 -368.58321) (xy 28.118801 -368.593303)
			(xy 28.126683 -368.611893) (xy 28.14111 -368.626019) (xy 28.150312 -368.6302) (xy 28.237942 -368.665252)
			(xy 28.247446 -368.668567) (xy 28.267556 -368.668248) (xy 28.286005 -368.660236) (xy 28.293314 -368.653314)
			(xy 28.293568 -368.65306) (xy 28.311634 -368.634632) (xy 28.351871 -368.602319) (xy 28.396099 -368.575729)
			(xy 28.44351 -368.555348) (xy 28.493237 -368.54155) (xy 28.544371 -368.534585) (xy 28.570174 -368.534188)
			(xy 28.600115 -368.53478) (xy 28.659261 -368.54415) (xy 28.716216 -368.562648) (xy 28.76958 -368.589819)
			(xy 28.818041 -368.624997) (xy 28.86041 -368.667316) (xy 28.87853 -368.69116) (xy 28.886143 -368.700521)
			(xy 28.907628 -368.711423) (xy 28.919678 -368.711988) (xy 28.997656 -368.711988) (xy 29.021323 -368.712668)
			(xy 29.067386 -368.723567) (xy 29.088842 -368.733578) (xy 29.10332 -368.740944) (xy 29.135832 -368.73561)
			(xy 29.147516 -368.723926) (xy 29.154158 -368.71648) (xy 29.16167 -368.698016) (xy 29.161611 -368.678083)
			(xy 29.153988 -368.659664) (xy 29.147262 -368.652298) (xy 28.948634 -368.45367) (xy 28.926028 -368.446304)
			(xy 28.913836 -368.448336) (xy 28.899073 -368.4505) (xy 28.86932 -368.452791) (xy 28.8544 -368.452908)
			(xy 28.827149 -368.452422) (xy 28.773201 -368.444666) (xy 28.720906 -368.429311) (xy 28.671329 -368.406669)
			(xy 28.625479 -368.377203) (xy 28.584288 -368.341512) (xy 28.548597 -368.300321) (xy 28.519131 -368.254471)
			(xy 28.496489 -368.204894) (xy 28.481134 -368.152599) (xy 28.473378 -368.098651) (xy 28.473378 -368.044149)
			(xy 28.481134 -367.990201) (xy 28.496489 -367.937906) (xy 28.519131 -367.888329) (xy 28.548597 -367.842479)
			(xy 28.584288 -367.801288) (xy 28.625479 -367.765597) (xy 28.671329 -367.736131) (xy 28.720906 -367.713489)
			(xy 28.773201 -367.698134) (xy 28.827149 -367.690378) (xy 28.8544 -367.689892) (xy 28.854908 -367.689892)
			(xy 28.880779 -367.690338) (xy 28.932042 -367.697359) (xy 28.981886 -367.711244) (xy 29.029397 -367.731739)
			(xy 29.051758 -367.744756) (xy 29.063696 -367.75009) (xy 29.084016 -367.755932) (xy 29.094024 -367.755442)
			(xy 29.112516 -367.74778) (xy 29.126671 -367.733629) (xy 29.134339 -367.71514) (xy 29.134816 -367.705132)
			(xy 29.134816 -367.702338) (xy 29.134308 -367.691416) (xy 29.134308 -362.14685) (xy 29.134763 -362.126832)
			(xy 29.142572 -362.087565) (xy 29.157899 -362.050579) (xy 29.180154 -362.017299) (xy 29.193998 -362.002832)
			(xy 30.199838 -360.996992) (xy 30.214289 -360.983243) (xy 30.247453 -360.961093) (xy 30.284296 -360.945826)
			(xy 30.323408 -360.938029) (xy 30.343348 -360.937556) (xy 32.421322 -360.937556) (xy 32.431389 -360.937128)
			(xy 32.449984 -360.929403) (xy 32.45739 -360.92257) (xy 36.80714 -356.572566) (xy 36.82164 -356.558764)
			(xy 36.854919 -356.536528) (xy 36.891894 -356.521203) (xy 36.931146 -356.513377) (xy 36.951158 -356.512876)
			(xy 37.61105 -356.512876) (xy 37.621116 -356.512443) (xy 37.639705 -356.504713) (xy 37.647118 -356.49789)
			(xy 39.425626 -354.719382) (xy 39.440125 -354.705578) (xy 39.473404 -354.683338) (xy 39.510378 -354.66801)
			(xy 39.549631 -354.66018) (xy 39.569644 -354.659692) (xy 42.834814 -354.659692) (xy 42.844883 -354.659266)
			(xy 42.863483 -354.651547) (xy 42.870882 -354.644706) (xy 44.142406 -353.373182) (xy 44.156904 -353.359377)
			(xy 44.190183 -353.337134) (xy 44.227157 -353.321801) (xy 44.266411 -353.313968) (xy 44.286424 -353.313492)
			(xy 58.884312 -353.313492) (xy 58.894381 -353.313066) (xy 58.912982 -353.305348) (xy 58.92038 -353.298506)
			(xy 60.948824 -351.270062) (xy 60.963323 -351.256259) (xy 60.996603 -351.234021) (xy 61.033577 -351.218694)
			(xy 61.07283 -351.210864) (xy 61.092842 -351.210372) (xy 61.341 -351.210372) (xy 61.35107 -351.209948)
			(xy 61.369671 -351.202231) (xy 61.377068 -351.195386) (xy 61.416946 -351.155508) (xy 61.424312 -351.132394)
			(xy 61.422534 -351.120456) (xy 61.420373 -351.105693) (xy 61.418089 -351.07594) (xy 61.417962 -351.06102)
			(xy 61.418612 -351.029456) (xy 61.428997 -350.967189) (xy 61.449487 -350.90748) (xy 61.463936 -350.87941)
			(xy 61.468762 -350.87052) (xy 61.470794 -350.850962) (xy 61.447934 -350.772476) (xy 61.444686 -350.763058)
			(xy 61.432268 -350.747505) (xy 61.423804 -350.74225) (xy 61.416438 -350.738186) (xy 61.406532 -350.732344)
			(xy 61.384688 -350.730312) (xy 61.289946 -350.76384) (xy 61.274198 -350.779334) (xy 61.270134 -350.789748)
			(xy 61.259441 -350.816525) (xy 61.231155 -350.866766) (xy 61.195626 -350.912174) (xy 61.153663 -350.951713)
			(xy 61.106224 -350.984482) (xy 61.054391 -351.009733) (xy 60.999347 -351.026889) (xy 60.942346 -351.03556)
			(xy 60.913518 -351.036128) (xy 60.886263 -351.035666) (xy 60.832307 -351.027911) (xy 60.780004 -351.012556)
			(xy 60.730419 -350.989913) (xy 60.684561 -350.960444) (xy 60.643364 -350.924748) (xy 60.607667 -350.883553)
			(xy 60.578196 -350.837697) (xy 60.555551 -350.788113) (xy 60.540193 -350.735811) (xy 60.532435 -350.681855)
			(xy 60.532435 -350.627345) (xy 60.540193 -350.573389) (xy 60.555551 -350.521087) (xy 60.578196 -350.471503)
			(xy 60.607667 -350.425647) (xy 60.643364 -350.384452) (xy 60.684561 -350.348756) (xy 60.730419 -350.319287)
			(xy 60.780004 -350.296644) (xy 60.832307 -350.281289) (xy 60.886263 -350.273534) (xy 60.913518 -350.273112)
			(xy 60.913772 -350.273112) (xy 60.938973 -350.273539) (xy 60.988932 -350.280207) (xy 61.037582 -350.29338)
			(xy 61.084081 -350.312828) (xy 61.10605 -350.325182) (xy 61.115956 -350.331024) (xy 61.1378 -350.333056)
			(xy 61.232542 -350.299528) (xy 61.24829 -350.284034) (xy 61.252354 -350.27362) (xy 61.263049 -350.246844)
			(xy 61.291336 -350.196606) (xy 61.326867 -350.1512) (xy 61.36883 -350.111663) (xy 61.416268 -350.078896)
			(xy 61.4681 -350.053646) (xy 61.523143 -350.03649) (xy 61.580142 -350.027818) (xy 61.60897 -350.02724)
			(xy 61.636223 -350.027701) (xy 61.690175 -350.035455) (xy 61.742473 -350.050809) (xy 61.792054 -350.07345)
			(xy 61.837908 -350.102918) (xy 61.8791 -350.138613) (xy 61.914792 -350.179807) (xy 61.944258 -350.225662)
			(xy 61.966897 -350.275244) (xy 61.979617 -350.318578) (xy 64.120522 -350.318578) (xy 64.121034 -350.291005)
			(xy 64.128976 -350.236434) (xy 64.144691 -350.183575) (xy 64.167852 -350.133528) (xy 64.197977 -350.087337)
			(xy 64.234438 -350.045965) (xy 64.255142 -350.027748) (xy 64.263203 -350.02018) (xy 64.272563 -350.000178)
			(xy 64.273176 -349.98914) (xy 64.273176 -349.911416) (xy 64.272607 -349.900367) (xy 64.263243 -349.880345)
			(xy 64.255142 -349.872808) (xy 64.23444 -349.854587) (xy 64.197967 -349.813221) (xy 64.167833 -349.767034)
			(xy 64.144665 -349.716988) (xy 64.128947 -349.664126) (xy 64.121007 -349.609552) (xy 64.120522 -349.581978)
			(xy 64.120934 -349.554723) (xy 64.128695 -349.500769) (xy 64.144056 -349.448468) (xy 64.166703 -349.398886)
			(xy 64.196176 -349.353031) (xy 64.231875 -349.311838) (xy 64.273073 -349.276145) (xy 64.318932 -349.246678)
			(xy 64.368517 -349.224037) (xy 64.42082 -349.208684) (xy 64.474775 -349.200931) (xy 64.50203 -349.20047)
			(xy 64.502538 -349.20047) (xy 64.53632 -349.201994) (xy 64.54648 -349.20301) (xy 64.565784 -349.196914)
			(xy 64.628776 -349.144082) (xy 64.636049 -349.137342) (xy 64.645341 -349.11985) (xy 64.64681 -349.110046)
			(xy 64.64681 -349.109284) (xy 64.649762 -349.081135) (xy 64.662956 -349.026097) (xy 64.684141 -348.973613)
			(xy 64.712849 -348.924837) (xy 64.748452 -348.88084) (xy 64.790166 -348.842588) (xy 64.837076 -348.810921)
			(xy 64.888151 -348.786535) (xy 64.942269 -348.769966) (xy 64.998241 -348.761577) (xy 65.02654 -348.76105)
			(xy 65.026794 -348.76105) (xy 65.044813 -348.761277) (xy 65.080688 -348.764707) (xy 65.098422 -348.767908)
			(xy 65.108074 -348.769686) (xy 65.127124 -348.76613) (xy 65.202054 -348.718124) (xy 65.213484 -348.702376)
			(xy 65.21577 -348.692978) (xy 65.223225 -348.665951) (xy 65.244848 -348.614227) (xy 65.273805 -348.566223)
			(xy 65.309473 -348.522971) (xy 65.351085 -348.485403) (xy 65.397745 -348.454326) (xy 65.448449 -348.43041)
			(xy 65.502107 -348.414169) (xy 65.557563 -348.405952) (xy 65.585594 -348.40545) (xy 65.612843 -348.405983)
			(xy 65.666787 -348.413738) (xy 65.719078 -348.42909) (xy 65.768653 -348.451727) (xy 65.814501 -348.481189)
			(xy 65.85569 -348.516876) (xy 65.891382 -348.55806) (xy 65.92085 -348.603905) (xy 65.943493 -348.653477)
			(xy 65.958852 -348.705766) (xy 65.966613 -348.759709) (xy 65.967102 -348.786958) (xy 65.966607 -348.814531)
			(xy 65.95866 -348.869103) (xy 65.942941 -348.921962) (xy 65.919776 -348.972008) (xy 65.889649 -349.018199)
			(xy 65.853187 -349.059571) (xy 65.832482 -349.077788) (xy 65.824409 -349.085345) (xy 65.815054 -349.105355)
			(xy 65.814448 -349.116396) (xy 65.814448 -349.19412) (xy 65.815045 -349.205166) (xy 65.824388 -349.225188)
			(xy 65.832482 -349.232728) (xy 65.853206 -349.250925) (xy 65.889676 -349.292296) (xy 65.919807 -349.338489)
			(xy 65.942971 -349.38854) (xy 65.958684 -349.441405) (xy 65.966619 -349.495982) (xy 65.967102 -349.523558)
			(xy 65.966607 -349.551131) (xy 65.95866 -349.605703) (xy 65.942941 -349.658562) (xy 65.919776 -349.708608)
			(xy 65.889649 -349.754799) (xy 65.853187 -349.796171) (xy 65.832482 -349.814388) (xy 65.824409 -349.821945)
			(xy 65.815054 -349.841955) (xy 65.814448 -349.852996) (xy 65.814448 -349.93072) (xy 65.815045 -349.941766)
			(xy 65.824388 -349.961788) (xy 65.832482 -349.969328) (xy 65.853206 -349.987525) (xy 65.889676 -350.028896)
			(xy 65.919807 -350.075089) (xy 65.942971 -350.12514) (xy 65.958684 -350.178005) (xy 65.966619 -350.232582)
			(xy 65.967102 -350.260158) (xy 65.966606 -350.28741) (xy 65.958854 -350.34136) (xy 65.943503 -350.393658)
			(xy 65.920865 -350.443238) (xy 65.891401 -350.489092) (xy 65.855711 -350.530285) (xy 65.814521 -350.565979)
			(xy 65.76867 -350.595448) (xy 65.719092 -350.618091) (xy 65.666795 -350.633447) (xy 65.612846 -350.641203)
			(xy 65.585594 -350.641666) (xy 65.557737 -350.641174) (xy 65.502619 -350.633048) (xy 65.449267 -350.617)
			(xy 65.398813 -350.59337) (xy 65.352327 -350.56266) (xy 65.310798 -350.52552) (xy 65.275106 -350.482741)
			(xy 65.246009 -350.435229) (xy 65.224124 -350.383993) (xy 65.216532 -350.357186) (xy 65.214246 -350.348296)
			(xy 65.203578 -350.333056) (xy 65.131696 -350.285304) (xy 65.113662 -350.28124) (xy 65.104518 -350.28251)
			(xy 65.091501 -350.284175) (xy 65.065317 -350.285958) (xy 65.052194 -350.286066) (xy 65.038045 -350.285973)
			(xy 65.009822 -350.283938) (xy 64.995806 -350.282002) (xy 64.9859 -350.280478) (xy 64.966088 -350.285304)
			(xy 64.891666 -350.341184) (xy 64.881506 -350.35871) (xy 64.880236 -350.36887) (xy 64.87615 -350.396023)
			(xy 64.861174 -350.448852) (xy 64.838781 -350.498989) (xy 64.809432 -350.545399) (xy 64.773735 -350.587122)
			(xy 64.732425 -350.623298) (xy 64.686357 -350.653179) (xy 64.636481 -350.676149) (xy 64.583828 -350.691732)
			(xy 64.529485 -350.699607) (xy 64.50203 -350.700086) (xy 64.474777 -350.699617) (xy 64.420825 -350.691863)
			(xy 64.368526 -350.67651) (xy 64.318944 -350.653869) (xy 64.27309 -350.624402) (xy 64.231897 -350.588709)
			(xy 64.196202 -350.547516) (xy 64.166735 -350.501663) (xy 64.144093 -350.452082) (xy 64.128738 -350.399783)
			(xy 64.120984 -350.345831) (xy 64.120522 -350.318578) (xy 61.979617 -350.318578) (xy 61.982249 -350.327543)
			(xy 61.99 -350.381495) (xy 61.990478 -350.408748) (xy 61.989831 -350.440312) (xy 61.979449 -350.502581)
			(xy 61.95896 -350.562291) (xy 61.944504 -350.590358) (xy 61.939678 -350.599248) (xy 61.937646 -350.618806)
			(xy 61.960506 -350.697292) (xy 61.963752 -350.706711) (xy 61.97617 -350.722265) (xy 61.984636 -350.727518)
			(xy 62.00973 -350.742074) (xy 62.055597 -350.777591) (xy 62.095561 -350.81964) (xy 62.128703 -350.867252)
			(xy 62.154258 -350.91933) (xy 62.171638 -350.974676) (xy 62.180443 -351.032015) (xy 62.180978 -351.06102)
			(xy 62.180513 -351.088271) (xy 62.172754 -351.142218) (xy 62.157396 -351.194512) (xy 62.134752 -351.244088)
			(xy 62.105283 -351.289936) (xy 62.069589 -351.331124) (xy 62.028396 -351.366813) (xy 61.982544 -351.396276)
			(xy 61.932965 -351.418913) (xy 61.880669 -351.434264) (xy 61.826721 -351.442017) (xy 61.79947 -351.442528)
			(xy 61.78455 -351.442403) (xy 61.754798 -351.440114) (xy 61.740034 -351.437956) (xy 61.728096 -351.436178)
			(xy 61.704982 -351.443544) (xy 61.590428 -351.558098) (xy 61.575928 -351.571899) (xy 61.542649 -351.594134)
			(xy 61.505674 -351.609456) (xy 61.466422 -351.617277) (xy 61.44641 -351.617788) (xy 61.198252 -351.617788)
			(xy 61.188185 -351.618219) (xy 61.169592 -351.625945) (xy 61.162184 -351.632774) (xy 59.13374 -353.661218)
			(xy 59.11924 -353.675019) (xy 59.08596 -353.697254) (xy 59.048986 -353.712576) (xy 59.009734 -353.720399)
			(xy 58.989722 -353.720908) (xy 44.391834 -353.720908) (xy 44.381769 -353.721343) (xy 44.363183 -353.729076)
			(xy 44.355766 -353.735894) (xy 43.084242 -355.007418) (xy 43.069742 -355.021219) (xy 43.036462 -355.043454)
			(xy 42.999488 -355.058777) (xy 42.960236 -355.066601) (xy 42.940224 -355.067108) (xy 39.675054 -355.067108)
			(xy 39.664988 -355.06754) (xy 39.646396 -355.075267) (xy 39.638986 -355.082094) (xy 37.860478 -356.860602)
			(xy 37.84598 -356.874407) (xy 37.812701 -356.896649) (xy 37.775727 -356.91198) (xy 37.736473 -356.919811)
			(xy 37.71646 -356.920292) (xy 37.056568 -356.920292) (xy 37.0465 -356.920721) (xy 37.027903 -356.928442)
			(xy 37.0205 -356.935278) (xy 34.645527 -359.310251) (xy 35.686978 -359.310251) (xy 35.686978 -359.255749)
			(xy 35.694734 -359.201801) (xy 35.710089 -359.149506) (xy 35.732731 -359.099929) (xy 35.762197 -359.054079)
			(xy 35.797888 -359.012888) (xy 35.839079 -358.977197) (xy 35.884929 -358.947731) (xy 35.934506 -358.925089)
			(xy 35.986801 -358.909734) (xy 36.040749 -358.901978) (xy 36.068 -358.901492) (xy 36.096113 -358.902001)
			(xy 36.151727 -358.910272) (xy 36.205524 -358.926621) (xy 36.256337 -358.950693) (xy 36.303064 -358.981965)
			(xy 36.344692 -359.019761) (xy 36.362894 -359.041192) (xy 36.370771 -359.049649) (xy 36.391733 -359.059293)
			(xy 36.40328 -359.059734) (xy 36.495482 -359.057194) (xy 36.516056 -359.046526) (xy 36.523168 -359.037128)
			(xy 36.541324 -359.013594) (xy 36.583643 -358.971861) (xy 36.631921 -358.937195) (xy 36.68499 -358.910434)
			(xy 36.741567 -358.892225) (xy 36.800283 -358.883009) (xy 36.83 -358.882442) (xy 36.857255 -358.882828)
			(xy 36.91121 -358.890585) (xy 36.963511 -358.905943) (xy 37.013095 -358.928587) (xy 37.058951 -358.958057)
			(xy 37.100147 -358.993753) (xy 37.135843 -359.034949) (xy 37.165313 -359.080805) (xy 37.187957 -359.130389)
			(xy 37.203315 -359.18269) (xy 37.211072 -359.236645) (xy 37.211072 -359.291155) (xy 37.203315 -359.34511)
			(xy 37.187957 -359.397411) (xy 37.165313 -359.446995) (xy 37.135843 -359.492851) (xy 37.100147 -359.534047)
			(xy 37.058951 -359.569743) (xy 37.013095 -359.599213) (xy 36.963511 -359.621857) (xy 36.91121 -359.637215)
			(xy 36.857255 -359.644972) (xy 36.83 -359.645458) (xy 36.801888 -359.644931) (xy 36.746275 -359.636661)
			(xy 36.692479 -359.620314) (xy 36.641667 -359.596246) (xy 36.594939 -359.564978) (xy 36.553309 -359.527187)
			(xy 36.535106 -359.505758) (xy 36.527237 -359.497293) (xy 36.506268 -359.487656) (xy 36.49472 -359.487216)
			(xy 36.402518 -359.489756) (xy 36.381944 -359.500424) (xy 36.374832 -359.509822) (xy 36.35669 -359.533367)
			(xy 36.314367 -359.575097) (xy 36.266085 -359.60976) (xy 36.213014 -359.636519) (xy 36.156435 -359.654726)
			(xy 36.097718 -359.663941) (xy 36.068 -359.664508) (xy 36.040749 -359.664022) (xy 35.986801 -359.656266)
			(xy 35.934506 -359.640911) (xy 35.884929 -359.618269) (xy 35.839079 -359.588803) (xy 35.797888 -359.553112)
			(xy 35.762197 -359.511921) (xy 35.732731 -359.466071) (xy 35.710089 -359.416494) (xy 35.694734 -359.364199)
			(xy 35.686978 -359.310251) (xy 34.645527 -359.310251) (xy 32.67075 -361.285028) (xy 32.656298 -361.298775)
			(xy 32.623133 -361.320921) (xy 32.58629 -361.336184) (xy 32.547179 -361.343978) (xy 32.52724 -361.344464)
			(xy 30.449266 -361.344464) (xy 30.4392 -361.344895) (xy 30.42061 -361.352625) (xy 30.413198 -361.35945)
			(xy 29.55671 -362.216192) (xy 29.549861 -362.22359) (xy 29.542122 -362.242188) (xy 29.541724 -362.25226)
			(xy 29.541724 -367.586006) (xy 29.542149 -367.596075) (xy 29.549867 -367.614676) (xy 29.55671 -367.622074)
			(xy 29.598112 -367.663476) (xy 29.621226 -367.670842) (xy 29.633164 -367.669064) (xy 29.647927 -367.6669)
			(xy 29.67768 -367.664609) (xy 29.6926 -367.664492) (xy 29.719851 -367.664978) (xy 29.773799 -367.672734)
			(xy 29.826094 -367.688089) (xy 29.875671 -367.710731) (xy 29.921521 -367.740197) (xy 29.962712 -367.775888)
			(xy 29.998403 -367.817079) (xy 30.027869 -367.862929) (xy 30.050511 -367.912506) (xy 30.065866 -367.964801)
			(xy 30.073622 -368.018749) (xy 30.074108 -368.046) (xy 30.07362 -368.073605) (xy 30.065664 -368.12824)
			(xy 30.049917 -368.181158) (xy 30.026709 -368.231254) (xy 29.996523 -368.277483) (xy 29.959991 -368.318879)
			(xy 29.939234 -368.337084) (xy 29.931109 -368.344678) (xy 29.921778 -368.364837) (xy 29.9212 -368.375946)
			(xy 29.9212 -368.396774) (xy 29.950918 -368.426492) (xy 30.0736 -368.426492) (xy 30.08367 -368.426069)
			(xy 30.102274 -368.418353) (xy 30.109668 -368.411506) (xy 30.345126 -368.176302) (xy 30.351981 -368.168907)
			(xy 30.359728 -368.150308) (xy 30.360112 -368.140234) (xy 30.360112 -366.876076) (xy 30.360626 -366.856141)
			(xy 30.368437 -366.817041) (xy 30.383698 -366.780206) (xy 30.405827 -366.747038) (xy 30.419548 -366.732566)
			(xy 30.833822 -366.318292) (xy 30.840676 -366.310897) (xy 30.848419 -366.292298) (xy 30.848808 -366.282224)
			(xy 30.848808 -364.530386) (xy 30.84926 -364.510366) (xy 30.857063 -364.471096) (xy 30.872385 -364.434105)
			(xy 30.894637 -364.400819) (xy 30.908498 -364.386368) (xy 35.20694 -360.087926) (xy 35.221438 -360.074121)
			(xy 35.254716 -360.051879) (xy 35.291691 -360.036549) (xy 35.330945 -360.02872) (xy 35.350958 -360.028236)
			(xy 37.093906 -360.028236) (xy 37.103974 -360.02781) (xy 37.122571 -360.020087) (xy 37.129974 -360.01325)
			(xy 38.288722 -358.854502) (xy 38.295577 -358.847107) (xy 38.303325 -358.828508) (xy 38.303708 -358.818434)
			(xy 38.303708 -357.42245) (xy 38.304163 -357.402432) (xy 38.311972 -357.363165) (xy 38.327299 -357.326179)
			(xy 38.349554 -357.292899) (xy 38.363398 -357.278432) (xy 40.340534 -355.301296) (xy 40.354985 -355.287546)
			(xy 40.388149 -355.265395) (xy 40.424992 -355.250128) (xy 40.464104 -355.242329) (xy 40.484044 -355.24186)
			(xy 43.17238 -355.24186) (xy 43.182443 -355.241421) (xy 43.201022 -355.233682) (xy 43.208448 -355.226874)
			(xy 44.092368 -354.3427) (xy 44.10682 -354.328953) (xy 44.139984 -354.306807) (xy 44.176828 -354.291545)
			(xy 44.215939 -354.283753) (xy 44.235878 -354.283264) (xy 63.093092 -354.283264) (xy 63.103162 -354.282842)
			(xy 63.121765 -354.275125) (xy 63.12916 -354.268278) (xy 66.723006 -350.674178) (xy 66.729848 -350.666778)
			(xy 66.737574 -350.64818) (xy 66.737992 -350.63811) (xy 66.737992 -342.27516) (xy 66.738446 -342.255141)
			(xy 66.746252 -342.215873) (xy 66.761578 -342.178885) (xy 66.783831 -342.145602) (xy 66.797682 -342.131142)
			(xy 69.401944 -339.52688) (xy 69.416395 -339.513132) (xy 69.44956 -339.490984) (xy 69.486403 -339.47572)
			(xy 69.525514 -339.467924) (xy 69.545454 -339.467444) (xy 69.610732 -339.467444) (xy 69.620798 -339.467013)
			(xy 69.639389 -339.459285) (xy 69.6468 -339.452458) (xy 69.903086 -339.195918) (xy 69.915528 -339.183986)
			(xy 69.943661 -339.164067) (xy 69.974748 -339.149176) (xy 69.991224 -339.144102) (xy 69.999682 -339.141434)
			(xy 70.014113 -339.131144) (xy 70.019418 -339.124036) (xy 70.023482 -339.118194) (xy 70.00748 -339.064346)
			(xy 70.004034 -339.054117) (xy 69.99008 -339.037677) (xy 69.980556 -339.032596) (xy 69.950838 -339.017102)
			(xy 69.940932 -339.01126) (xy 69.919088 -339.009228) (xy 69.824346 -339.042756) (xy 69.808598 -339.05825)
			(xy 69.804534 -339.068664) (xy 69.79384 -339.09544) (xy 69.765553 -339.145679) (xy 69.730023 -339.191085)
			(xy 69.68806 -339.230623) (xy 69.640621 -339.26339) (xy 69.588789 -339.28864) (xy 69.533745 -339.305795)
			(xy 69.476746 -339.314466) (xy 69.447918 -339.315044) (xy 69.420662 -339.314582) (xy 69.366704 -339.306827)
			(xy 69.314399 -339.291471) (xy 69.264812 -339.268827) (xy 69.218952 -339.239357) (xy 69.177753 -339.20366)
			(xy 69.142054 -339.162463) (xy 69.112582 -339.116604) (xy 69.089936 -339.067018) (xy 69.074577 -339.014714)
			(xy 69.066819 -338.960756) (xy 69.066819 -338.906244) (xy 69.074577 -338.852286) (xy 69.089936 -338.799982)
			(xy 69.112582 -338.750396) (xy 69.142054 -338.704537) (xy 69.177753 -338.66334) (xy 69.218952 -338.627643)
			(xy 69.264812 -338.598173) (xy 69.314399 -338.575529) (xy 69.366704 -338.560173) (xy 69.420662 -338.552418)
			(xy 69.447918 -338.552028) (xy 69.448172 -338.552028) (xy 69.473373 -338.552455) (xy 69.523332 -338.559123)
			(xy 69.571982 -338.572296) (xy 69.61848 -338.591745) (xy 69.64045 -338.604098) (xy 69.650356 -338.60994)
			(xy 69.6722 -338.611972) (xy 69.766942 -338.578444) (xy 69.78269 -338.56295) (xy 69.786754 -338.552536)
			(xy 69.797448 -338.52576) (xy 69.825734 -338.475519) (xy 69.861264 -338.430112) (xy 69.903227 -338.390573)
			(xy 69.950666 -338.357804) (xy 70.002498 -338.332553) (xy 70.057542 -338.315396) (xy 70.114542 -338.306724)
			(xy 70.14337 -338.306156) (xy 70.170624 -338.30664) (xy 70.224576 -338.314393) (xy 70.276877 -338.329745)
			(xy 70.32646 -338.352384) (xy 70.372317 -338.381849) (xy 70.413514 -338.41754) (xy 70.449212 -338.45873)
			(xy 70.478685 -338.504582) (xy 70.501332 -338.554161) (xy 70.51406 -338.597494) (xy 72.654922 -338.597494)
			(xy 72.655376 -338.569919) (xy 72.66333 -338.515345) (xy 72.679057 -338.462485) (xy 72.702229 -338.412439)
			(xy 72.732364 -338.366249) (xy 72.768834 -338.324879) (xy 72.789542 -338.306664) (xy 72.79764 -338.29913)
			(xy 72.80698 -338.279102) (xy 72.807576 -338.268056) (xy 72.807576 -338.190332) (xy 72.806997 -338.179284)
			(xy 72.79764 -338.159262) (xy 72.789542 -338.151724) (xy 72.768848 -338.133494) (xy 72.732374 -338.092131)
			(xy 72.702239 -338.045945) (xy 72.67907 -337.9959) (xy 72.66335 -337.943041) (xy 72.655408 -337.888468)
			(xy 72.654922 -337.860894) (xy 72.65535 -337.83364) (xy 72.663108 -337.779686) (xy 72.678467 -337.727386)
			(xy 72.701112 -337.677803) (xy 72.730584 -337.631949) (xy 72.766281 -337.590755) (xy 72.807478 -337.555062)
			(xy 72.853335 -337.525595) (xy 72.902919 -337.502954) (xy 72.955221 -337.487601) (xy 73.009176 -337.479847)
			(xy 73.03643 -337.479386) (xy 73.036938 -337.479386) (xy 73.07072 -337.48091) (xy 73.08088 -337.481926)
			(xy 73.100184 -337.47583) (xy 73.163176 -337.422998) (xy 73.170481 -337.416288) (xy 73.179755 -337.398774)
			(xy 73.18121 -337.388962) (xy 73.18121 -337.3882) (xy 73.184175 -337.360053) (xy 73.197368 -337.305015)
			(xy 73.21855 -337.252531) (xy 73.247257 -337.203755) (xy 73.282858 -337.159757) (xy 73.32457 -337.121505)
			(xy 73.371479 -337.089837) (xy 73.422553 -337.065451) (xy 73.47667 -337.048882) (xy 73.532642 -337.040493)
			(xy 73.56094 -337.039966) (xy 73.561194 -337.039966) (xy 73.579213 -337.040192) (xy 73.615088 -337.043623)
			(xy 73.632822 -337.046824) (xy 73.642474 -337.048602) (xy 73.661524 -337.045046) (xy 73.736454 -336.99704)
			(xy 73.747884 -336.981292) (xy 73.75017 -336.971894) (xy 73.757635 -336.94487) (xy 73.779256 -336.893146)
			(xy 73.808211 -336.845141) (xy 73.843878 -336.801889) (xy 73.885489 -336.76432) (xy 73.932148 -336.733243)
			(xy 73.982851 -336.709327) (xy 74.036508 -336.693085) (xy 74.091964 -336.684868) (xy 74.119994 -336.684366)
			(xy 74.147244 -336.684883) (xy 74.201189 -336.692638) (xy 74.253482 -336.707991) (xy 74.303057 -336.73063)
			(xy 74.348906 -336.760093) (xy 74.390096 -336.795781) (xy 74.425788 -336.836968) (xy 74.455255 -336.882815)
			(xy 74.477897 -336.932388) (xy 74.493255 -336.98468) (xy 74.501014 -337.038624) (xy 74.501502 -337.065874)
			(xy 74.501018 -337.093448) (xy 74.493069 -337.14802) (xy 74.477347 -337.200879) (xy 74.454181 -337.250925)
			(xy 74.424052 -337.297115) (xy 74.387588 -337.338488) (xy 74.366882 -337.356704) (xy 74.358802 -337.364255)
			(xy 74.349451 -337.38427) (xy 74.348848 -337.395312) (xy 74.348848 -337.473036) (xy 74.349437 -337.484083)
			(xy 74.358786 -337.504105) (xy 74.366882 -337.511644) (xy 74.387566 -337.529885) (xy 74.424039 -337.571247)
			(xy 74.454175 -337.617431) (xy 74.477346 -337.667473) (xy 74.493068 -337.72033) (xy 74.501013 -337.774901)
			(xy 74.501502 -337.802474) (xy 74.501018 -337.830048) (xy 74.493824 -337.879436) (xy 75.657962 -337.879436)
			(xy 75.662033 -337.823814) (xy 75.674159 -337.769377) (xy 75.694082 -337.717286) (xy 75.721378 -337.668651)
			(xy 75.755464 -337.624508) (xy 75.795613 -337.585799) (xy 75.840971 -337.553348) (xy 75.890571 -337.527847)
			(xy 75.943355 -337.50984) (xy 75.998198 -337.49971) (xy 76.053932 -337.497673) (xy 76.109369 -337.503773)
			(xy 76.163326 -337.517879) (xy 76.214655 -337.539691) (xy 76.262261 -337.568745) (xy 76.305129 -337.60442)
			(xy 76.342346 -337.645957) (xy 76.373119 -337.69247) (xy 76.396791 -337.742967) (xy 76.412859 -337.796374)
			(xy 76.420979 -337.85155) (xy 76.421488 -337.879436) (xy 76.420979 -337.907322) (xy 76.412859 -337.962498)
			(xy 76.396791 -338.015905) (xy 76.373119 -338.066402) (xy 76.342346 -338.112915) (xy 76.305129 -338.154452)
			(xy 76.262261 -338.190127) (xy 76.214655 -338.219181) (xy 76.163326 -338.240993) (xy 76.109369 -338.255099)
			(xy 76.053932 -338.261199) (xy 75.998198 -338.259162) (xy 75.943355 -338.249032) (xy 75.890571 -338.231025)
			(xy 75.840971 -338.205524) (xy 75.795613 -338.173073) (xy 75.755464 -338.134364) (xy 75.721378 -338.090221)
			(xy 75.694082 -338.041586) (xy 75.674159 -337.989495) (xy 75.662033 -337.935058) (xy 75.657962 -337.879436)
			(xy 74.493824 -337.879436) (xy 74.493069 -337.88462) (xy 74.477347 -337.937479) (xy 74.454181 -337.987525)
			(xy 74.424052 -338.033715) (xy 74.387588 -338.075088) (xy 74.366882 -338.093304) (xy 74.358802 -338.100855)
			(xy 74.349451 -338.12087) (xy 74.348848 -338.131912) (xy 74.348848 -338.209636) (xy 74.349437 -338.220683)
			(xy 74.358786 -338.240705) (xy 74.366882 -338.248244) (xy 74.387566 -338.266485) (xy 74.424039 -338.307847)
			(xy 74.454175 -338.354031) (xy 74.477346 -338.404073) (xy 74.493068 -338.45693) (xy 74.501013 -338.511501)
			(xy 74.501502 -338.539074) (xy 74.50102 -338.566326) (xy 74.493267 -338.620277) (xy 74.477914 -338.672575)
			(xy 74.455274 -338.722155) (xy 74.425808 -338.768009) (xy 74.419936 -338.774786) (xy 75.078842 -338.774786)
			(xy 75.082913 -338.719164) (xy 75.095039 -338.664727) (xy 75.114962 -338.612636) (xy 75.142258 -338.564001)
			(xy 75.176344 -338.519858) (xy 75.216493 -338.481149) (xy 75.261851 -338.448698) (xy 75.311451 -338.423197)
			(xy 75.364235 -338.40519) (xy 75.419078 -338.39506) (xy 75.474812 -338.393023) (xy 75.530249 -338.399123)
			(xy 75.584206 -338.413229) (xy 75.635535 -338.435041) (xy 75.683141 -338.464095) (xy 75.726009 -338.49977)
			(xy 75.763226 -338.541307) (xy 75.793999 -338.58782) (xy 75.817671 -338.638317) (xy 75.833739 -338.691724)
			(xy 75.841859 -338.7469) (xy 75.842368 -338.774786) (xy 75.841859 -338.802672) (xy 75.833739 -338.857848)
			(xy 75.817671 -338.911255) (xy 75.793999 -338.961752) (xy 75.763226 -339.008265) (xy 75.726009 -339.049802)
			(xy 75.683141 -339.085477) (xy 75.635535 -339.114531) (xy 75.584206 -339.136343) (xy 75.530249 -339.150449)
			(xy 75.474812 -339.156549) (xy 75.419078 -339.154512) (xy 75.364235 -339.144382) (xy 75.311451 -339.126375)
			(xy 75.261851 -339.100874) (xy 75.216493 -339.068423) (xy 75.176344 -339.029714) (xy 75.142258 -338.985571)
			(xy 75.114962 -338.936936) (xy 75.095039 -338.884845) (xy 75.082913 -338.830408) (xy 75.078842 -338.774786)
			(xy 74.419936 -338.774786) (xy 74.390116 -338.809202) (xy 74.348925 -338.844896) (xy 74.303073 -338.874364)
			(xy 74.253494 -338.897007) (xy 74.201197 -338.912363) (xy 74.147246 -338.920119) (xy 74.119994 -338.920582)
			(xy 74.092138 -338.920078) (xy 74.037021 -338.911953) (xy 73.983669 -338.895906) (xy 73.933216 -338.872277)
			(xy 73.886731 -338.841568) (xy 73.845201 -338.80443) (xy 73.809509 -338.761652) (xy 73.780411 -338.714142)
			(xy 73.758525 -338.662908) (xy 73.750932 -338.636102) (xy 73.748646 -338.627212) (xy 73.737978 -338.611972)
			(xy 73.666096 -338.56422) (xy 73.648062 -338.560156) (xy 73.638918 -338.561426) (xy 73.625901 -338.563091)
			(xy 73.599717 -338.564874) (xy 73.586594 -338.564982) (xy 73.572445 -338.564889) (xy 73.544222 -338.562854)
			(xy 73.530206 -338.560918) (xy 73.5203 -338.559394) (xy 73.500488 -338.56422) (xy 73.426066 -338.6201)
			(xy 73.415906 -338.637626) (xy 73.414636 -338.647786) (xy 73.410562 -338.674941) (xy 73.395584 -338.727771)
			(xy 73.373189 -338.777907) (xy 73.343839 -338.824317) (xy 73.30814 -338.86604) (xy 73.266829 -338.902215)
			(xy 73.22076 -338.932096) (xy 73.170883 -338.955065) (xy 73.118229 -338.970648) (xy 73.063886 -338.978523)
			(xy 73.03643 -338.979002) (xy 73.009178 -338.978517) (xy 72.955227 -338.970764) (xy 72.902929 -338.955411)
			(xy 72.853349 -338.932772) (xy 72.807495 -338.903306) (xy 72.766302 -338.867615) (xy 72.730608 -338.826424)
			(xy 72.70114 -338.780572) (xy 72.678497 -338.730993) (xy 72.663141 -338.678696) (xy 72.655385 -338.624746)
			(xy 72.654922 -338.597494) (xy 70.51406 -338.597494) (xy 70.516693 -338.606459) (xy 70.524456 -338.66041)
			(xy 70.524878 -338.687664) (xy 70.52423 -338.719228) (xy 70.513845 -338.781495) (xy 70.493354 -338.841205)
			(xy 70.478904 -338.869274) (xy 70.474078 -338.878164) (xy 70.472046 -338.897722) (xy 70.494906 -338.976208)
			(xy 70.498154 -338.985625) (xy 70.510575 -339.001175) (xy 70.519036 -339.006434) (xy 70.544129 -339.020991)
			(xy 70.589995 -339.056508) (xy 70.629957 -339.098557) (xy 70.663097 -339.146169) (xy 70.68865 -339.198248)
			(xy 70.706028 -339.253593) (xy 70.714831 -339.310931) (xy 70.715378 -339.339936) (xy 70.714889 -339.367185)
			(xy 70.707128 -339.421127) (xy 70.698522 -339.450426) (xy 76.417678 -339.450426) (xy 76.418185 -339.422952)
			(xy 76.426073 -339.368574) (xy 76.441688 -339.315892) (xy 76.464708 -339.265999) (xy 76.494655 -339.219929)
			(xy 76.51242 -339.198966) (xy 76.512674 -339.198712) (xy 76.51827 -339.191632) (xy 76.524509 -339.17471)
			(xy 76.524866 -339.165692) (xy 76.524866 -339.098128) (xy 76.524503 -339.089112) (xy 76.51826 -339.072194)
			(xy 76.512674 -339.065108) (xy 76.512166 -339.0646) (xy 76.494447 -339.043642) (xy 76.46456 -338.997613)
			(xy 76.44159 -338.947771) (xy 76.426012 -338.895148) (xy 76.418149 -338.840834) (xy 76.417678 -338.813394)
			(xy 76.418164 -338.786143) (xy 76.42592 -338.732195) (xy 76.441275 -338.6799) (xy 76.463917 -338.630323)
			(xy 76.493383 -338.584473) (xy 76.529074 -338.543282) (xy 76.570265 -338.507591) (xy 76.616115 -338.478125)
			(xy 76.665692 -338.455483) (xy 76.717987 -338.440128) (xy 76.771935 -338.432372) (xy 76.826437 -338.432372)
			(xy 76.880385 -338.440128) (xy 76.93268 -338.455483) (xy 76.982257 -338.478125) (xy 77.028107 -338.507591)
			(xy 77.069298 -338.543282) (xy 77.104989 -338.584473) (xy 77.134455 -338.630323) (xy 77.157097 -338.6799)
			(xy 77.172452 -338.732195) (xy 77.180208 -338.786143) (xy 77.180694 -338.813394) (xy 77.180206 -338.840869)
			(xy 77.172314 -338.895248) (xy 77.156695 -338.947931) (xy 77.133671 -338.997823) (xy 77.103719 -339.043892)
			(xy 77.085952 -339.064854) (xy 77.085698 -339.065108) (xy 77.080102 -339.072188) (xy 77.073861 -339.08911)
			(xy 77.073506 -339.098128) (xy 77.073506 -339.165692) (xy 77.073865 -339.174709) (xy 77.080111 -339.191626)
			(xy 77.085698 -339.198712) (xy 77.086206 -339.19922) (xy 77.103946 -339.220161) (xy 77.133827 -339.266195)
			(xy 77.156792 -339.316042) (xy 77.172365 -339.368668) (xy 77.180224 -339.422985) (xy 77.180694 -339.450426)
			(xy 77.180208 -339.477677) (xy 77.172452 -339.531625) (xy 77.157097 -339.58392) (xy 77.134455 -339.633497)
			(xy 77.104989 -339.679347) (xy 77.069298 -339.720538) (xy 77.028107 -339.756229) (xy 76.982257 -339.785695)
			(xy 76.93268 -339.808337) (xy 76.880385 -339.823692) (xy 76.826437 -339.831448) (xy 76.771935 -339.831448)
			(xy 76.717987 -339.823692) (xy 76.665692 -339.808337) (xy 76.616115 -339.785695) (xy 76.570265 -339.756229)
			(xy 76.529074 -339.720538) (xy 76.493383 -339.679347) (xy 76.463917 -339.633497) (xy 76.441275 -339.58392)
			(xy 76.42592 -339.531625) (xy 76.418164 -339.477677) (xy 76.417678 -339.450426) (xy 70.698522 -339.450426)
			(xy 70.69177 -339.473416) (xy 70.669126 -339.522986) (xy 70.639659 -339.56883) (xy 70.603967 -339.610013)
			(xy 70.562777 -339.645698) (xy 70.516928 -339.675158) (xy 70.467354 -339.697793) (xy 70.415062 -339.713142)
			(xy 70.361119 -339.720894) (xy 70.33387 -339.721444) (xy 70.308453 -339.721022) (xy 70.258069 -339.714266)
			(xy 70.209029 -339.700878) (xy 70.162202 -339.681094) (xy 70.118417 -339.655266) (xy 70.098158 -339.63991)
			(xy 70.082918 -339.627972) (xy 70.044818 -339.630258) (xy 69.86016 -339.814916) (xy 69.845709 -339.828664)
			(xy 69.812544 -339.850814) (xy 69.775701 -339.866079) (xy 69.73659 -339.873875) (xy 69.71665 -339.874352)
			(xy 69.651372 -339.874352) (xy 69.641305 -339.874782) (xy 69.622713 -339.882509) (xy 69.615304 -339.889338)
			(xy 67.160394 -342.344502) (xy 67.153548 -342.351901) (xy 67.145816 -342.370499) (xy 67.145408 -342.38057)
			(xy 67.145408 -350.74352) (xy 67.144956 -350.763539) (xy 67.137153 -350.80281) (xy 67.12183 -350.839801)
			(xy 67.099579 -350.873087) (xy 67.085718 -350.887538) (xy 63.34252 -354.630736) (xy 63.328067 -354.64448)
			(xy 63.294901 -354.66662) (xy 63.258058 -354.681877) (xy 63.218948 -354.689665) (xy 63.19901 -354.690172)
			(xy 44.341796 -354.690172) (xy 44.331725 -354.690595) (xy 44.313119 -354.698307) (xy 44.305728 -354.705158)
			(xy 43.421808 -355.589332) (xy 43.407355 -355.603075) (xy 43.374188 -355.625214) (xy 43.337345 -355.640469)
			(xy 43.298236 -355.648255) (xy 43.278298 -355.648768) (xy 40.589962 -355.648768) (xy 40.579894 -355.649197)
			(xy 40.561297 -355.656918) (xy 40.553894 -355.663754) (xy 38.72611 -357.491792) (xy 38.719261 -357.49919)
			(xy 38.711522 -357.517788) (xy 38.711124 -357.52786) (xy 38.711124 -358.923844) (xy 38.710669 -358.943862)
			(xy 38.702859 -358.983128) (xy 38.687529 -359.020111) (xy 38.665269 -359.053387) (xy 38.651434 -359.067862)
			(xy 37.343334 -360.375962) (xy 37.328833 -360.38976) (xy 37.295551 -360.411989) (xy 37.258577 -360.427307)
			(xy 37.219327 -360.435127) (xy 37.199316 -360.435652) (xy 35.456368 -360.435652) (xy 35.446302 -360.436082)
			(xy 35.42771 -360.443811) (xy 35.4203 -360.450638) (xy 31.27121 -364.599728) (xy 31.264367 -364.607128)
			(xy 31.256641 -364.625726) (xy 31.256224 -364.635796) (xy 31.256224 -366.387634) (xy 31.25577 -366.407652)
			(xy 31.247962 -366.446919) (xy 31.232633 -366.483904) (xy 31.210374 -366.517182) (xy 31.196534 -366.531652)
			(xy 30.782006 -366.945926) (xy 30.775163 -366.953326) (xy 30.767437 -366.971924) (xy 30.76702 -366.981994)
			(xy 30.76702 -368.246152) (xy 30.766503 -368.266086) (xy 30.758688 -368.305184) (xy 30.743426 -368.342017)
			(xy 30.721297 -368.375183) (xy 30.707584 -368.389662) (xy 30.323028 -368.774218) (xy 30.308528 -368.788018)
			(xy 30.275248 -368.810251) (xy 30.238273 -368.825571) (xy 30.199021 -368.833392) (xy 30.17901 -368.833908)
			(xy 29.4132 -368.833908) (xy 29.389534 -368.833223) (xy 29.343476 -368.822315) (xy 29.322014 -368.812318)
			(xy 29.307536 -368.804952) (xy 29.275024 -368.810286) (xy 29.26334 -368.82197) (xy 29.256652 -368.829381)
			(xy 29.249048 -368.847817) (xy 29.249043 -368.86776) (xy 29.256639 -368.886199) (xy 29.26334 -368.893598)
			(xy 29.3497 -368.979958) (xy 29.357097 -368.986809) (xy 29.375695 -368.99455) (xy 29.385768 -368.994944)
			(xy 31.851092 -368.994944) (xy 31.861104 -368.994458) (xy 31.879606 -368.986801) (xy 31.893772 -368.97265)
			(xy 31.901448 -368.954155) (xy 31.901892 -368.944144) (xy 31.901892 -367.173256) (xy 31.902408 -367.153321)
			(xy 31.910222 -367.114224) (xy 31.925484 -367.077389) (xy 31.947613 -367.044223) (xy 31.961328 -367.029746)
			(xy 33.055306 -365.936022) (xy 33.06214 -365.928619) (xy 33.069845 -365.910021) (xy 33.070292 -365.899954)
			(xy 33.070292 -363.696504) (xy 33.070804 -363.676568) (xy 33.07861 -363.637465) (xy 33.093866 -363.600624)
			(xy 33.115991 -363.567451) (xy 33.129728 -363.552994) (xy 35.637216 -361.045506) (xy 35.651714 -361.0317)
			(xy 35.684992 -361.009456) (xy 35.721967 -360.994124) (xy 35.761221 -360.986291) (xy 35.781234 -360.985816)
			(xy 37.530278 -360.985816) (xy 37.540342 -360.985379) (xy 37.558928 -360.977647) (xy 37.566346 -360.97083)
			(xy 39.266114 -359.271062) (xy 39.272964 -359.263666) (xy 39.280698 -359.245066) (xy 39.2811 -359.234994)
			(xy 39.2811 -357.55453) (xy 39.281557 -357.534513) (xy 39.289369 -357.495248) (xy 39.304698 -357.458264)
			(xy 39.326955 -357.424986) (xy 39.34079 -357.410512) (xy 40.78351 -355.967792) (xy 40.797963 -355.954049)
			(xy 40.831129 -355.93191) (xy 40.867973 -355.916657) (xy 40.907082 -355.908873) (xy 40.92702 -355.908356)
			(xy 44.037758 -355.908356) (xy 44.047823 -355.907921) (xy 44.066407 -355.900187) (xy 44.073826 -355.89337)
			(xy 44.647358 -355.319584) (xy 44.66181 -355.305837) (xy 44.694975 -355.283691) (xy 44.731818 -355.268429)
			(xy 44.770929 -355.260635) (xy 44.790868 -355.260148) (xy 64.232028 -355.260148) (xy 64.242095 -355.259718)
			(xy 64.260687 -355.251991) (xy 64.268096 -355.245162) (xy 76.370942 -343.142316) (xy 76.377781 -343.134916)
			(xy 76.385494 -343.116317) (xy 76.385928 -343.106248) (xy 76.385928 -341.05977) (xy 76.386443 -341.039835)
			(xy 76.394256 -341.000737) (xy 76.409519 -340.963903) (xy 76.431649 -340.930737) (xy 76.445364 -340.91626)
			(xy 77.880464 -339.481414) (xy 77.887211 -339.473945) (xy 77.894868 -339.455352) (xy 77.894827 -339.435245)
			(xy 77.891386 -339.425788) (xy 77.85481 -339.33892) (xy 77.850446 -339.329892) (xy 77.836158 -339.315853)
			(xy 77.817585 -339.308348) (xy 77.807566 -339.307932) (xy 77.803502 -339.307932) (xy 77.776247 -339.307469)
			(xy 77.722293 -339.299712) (xy 77.669991 -339.284355) (xy 77.620408 -339.261711) (xy 77.574551 -339.232241)
			(xy 77.533356 -339.196546) (xy 77.49766 -339.15535) (xy 77.46819 -339.109494) (xy 77.445546 -339.059911)
			(xy 77.430188 -339.007609) (xy 77.422431 -338.953655) (xy 77.422431 -338.899145) (xy 77.430188 -338.845191)
			(xy 77.445546 -338.792889) (xy 77.46819 -338.743306) (xy 77.49766 -338.69745) (xy 77.533356 -338.656254)
			(xy 77.574551 -338.620559) (xy 77.620408 -338.591089) (xy 77.669991 -338.568445) (xy 77.722293 -338.553088)
			(xy 77.776247 -338.545331) (xy 77.803502 -338.544916) (xy 77.803756 -338.544916) (xy 77.828957 -338.545342)
			(xy 77.878917 -338.552008) (xy 77.927568 -338.565179) (xy 77.974068 -338.584626) (xy 77.996034 -338.596986)
			(xy 78.00594 -338.602828) (xy 78.027784 -338.60486) (xy 78.122526 -338.571332) (xy 78.138274 -338.555838)
			(xy 78.142338 -338.545424) (xy 78.153032 -338.518648) (xy 78.181319 -338.468407) (xy 78.216849 -338.423)
			(xy 78.258812 -338.38346) (xy 78.30625 -338.350691) (xy 78.358082 -338.325439) (xy 78.413126 -338.30828)
			(xy 78.470126 -338.299606) (xy 78.498954 -338.299044) (xy 78.526209 -338.299527) (xy 78.580164 -338.307278)
			(xy 78.632467 -338.322628) (xy 78.682053 -338.345266) (xy 78.727913 -338.37473) (xy 78.769112 -338.410421)
			(xy 78.804813 -338.451612) (xy 78.834289 -338.497464) (xy 78.856939 -338.547045) (xy 78.869669 -338.590382)
			(xy 81.010506 -338.590382) (xy 81.011026 -338.562809) (xy 81.018967 -338.508239) (xy 81.034681 -338.45538)
			(xy 81.057841 -338.405334) (xy 81.087964 -338.359143) (xy 81.124423 -338.317769) (xy 81.145126 -338.299552)
			(xy 81.153227 -338.292021) (xy 81.162566 -338.271991) (xy 81.16316 -338.260944) (xy 81.16316 -338.18322)
			(xy 81.162593 -338.17217) (xy 81.153228 -338.152149) (xy 81.145126 -338.144612) (xy 81.124423 -338.126392)
			(xy 81.087951 -338.085026) (xy 81.057817 -338.038838) (xy 81.03465 -337.988792) (xy 81.018932 -337.93593)
			(xy 81.010991 -337.881356) (xy 81.010506 -337.853782) (xy 81.010961 -337.82653) (xy 81.01872 -337.77258)
			(xy 81.034079 -337.720284) (xy 81.056723 -337.670706) (xy 81.086192 -337.624855) (xy 81.121887 -337.583664)
			(xy 81.16308 -337.547973) (xy 81.208934 -337.518507) (xy 81.258514 -337.495867) (xy 81.310811 -337.480514)
			(xy 81.364762 -337.472759) (xy 81.392014 -337.472274) (xy 81.392522 -337.472274) (xy 81.426304 -337.473798)
			(xy 81.436464 -337.474814) (xy 81.455768 -337.468718) (xy 81.51876 -337.415886) (xy 81.526045 -337.409158)
			(xy 81.535327 -337.391657) (xy 81.536794 -337.38185) (xy 81.536794 -337.381088) (xy 81.539765 -337.352942)
			(xy 81.552958 -337.297905) (xy 81.574141 -337.245422) (xy 81.602848 -337.196647) (xy 81.638448 -337.15265)
			(xy 81.68016 -337.114398) (xy 81.727067 -337.08273) (xy 81.77814 -337.058344) (xy 81.832256 -337.041773)
			(xy 81.888226 -337.033382) (xy 81.916524 -337.032854) (xy 81.916778 -337.032854) (xy 81.934798 -337.033069)
			(xy 81.970672 -337.036507) (xy 81.988406 -337.039712) (xy 81.998058 -337.04149) (xy 82.017108 -337.037934)
			(xy 82.092038 -336.989928) (xy 82.103468 -336.97418) (xy 82.105754 -336.964782) (xy 82.113135 -336.937733)
			(xy 82.134764 -336.886004) (xy 82.163729 -336.837996) (xy 82.199406 -336.794743) (xy 82.241027 -336.757175)
			(xy 82.287697 -336.726101) (xy 82.338412 -336.70219) (xy 82.392079 -336.685957) (xy 82.447544 -336.67775)
			(xy 82.475578 -336.677254) (xy 82.502827 -336.677799) (xy 82.556771 -336.685551) (xy 82.609062 -336.700902)
			(xy 82.658636 -336.723537) (xy 82.704485 -336.752998) (xy 82.745674 -336.788683) (xy 82.781366 -336.829867)
			(xy 82.810834 -336.875711) (xy 82.833477 -336.925282) (xy 82.848836 -336.977571) (xy 82.856597 -337.031513)
			(xy 82.857086 -337.058762) (xy 82.856599 -337.086336) (xy 82.848652 -337.140908) (xy 82.832931 -337.193768)
			(xy 82.809765 -337.243814) (xy 82.779636 -337.290004) (xy 82.743172 -337.331376) (xy 82.722466 -337.349592)
			(xy 82.714389 -337.357145) (xy 82.705037 -337.377158) (xy 82.704432 -337.3882) (xy 82.704432 -337.465924)
			(xy 82.705033 -337.47697) (xy 82.714374 -337.496991) (xy 82.722466 -337.504532) (xy 82.743189 -337.52273)
			(xy 82.77966 -337.564101) (xy 82.809791 -337.610293) (xy 82.832955 -337.660344) (xy 82.848669 -337.713209)
			(xy 82.856604 -337.767786) (xy 82.857086 -337.795362) (xy 82.856599 -337.822936) (xy 82.85048 -337.864958)
			(xy 84.015578 -337.864958) (xy 84.019649 -337.809336) (xy 84.031775 -337.754899) (xy 84.051698 -337.702808)
			(xy 84.078994 -337.654173) (xy 84.11308 -337.61003) (xy 84.153229 -337.571321) (xy 84.198587 -337.53887)
			(xy 84.248187 -337.513369) (xy 84.300971 -337.495362) (xy 84.355814 -337.485232) (xy 84.411548 -337.483195)
			(xy 84.466985 -337.489295) (xy 84.520942 -337.503401) (xy 84.572271 -337.525213) (xy 84.619877 -337.554267)
			(xy 84.662745 -337.589942) (xy 84.699962 -337.631479) (xy 84.730735 -337.677992) (xy 84.754407 -337.728489)
			(xy 84.770475 -337.781896) (xy 84.778595 -337.837072) (xy 84.779104 -337.864958) (xy 84.778595 -337.892844)
			(xy 84.770475 -337.94802) (xy 84.754407 -338.001427) (xy 84.730735 -338.051924) (xy 84.699962 -338.098437)
			(xy 84.662745 -338.139974) (xy 84.619877 -338.175649) (xy 84.572271 -338.204703) (xy 84.520942 -338.226515)
			(xy 84.466985 -338.240621) (xy 84.411548 -338.246721) (xy 84.355814 -338.244684) (xy 84.300971 -338.234554)
			(xy 84.248187 -338.216547) (xy 84.198587 -338.191046) (xy 84.153229 -338.158595) (xy 84.11308 -338.119886)
			(xy 84.078994 -338.075743) (xy 84.051698 -338.027108) (xy 84.031775 -337.975017) (xy 84.019649 -337.92058)
			(xy 84.015578 -337.864958) (xy 82.85048 -337.864958) (xy 82.848652 -337.877508) (xy 82.832931 -337.930368)
			(xy 82.809765 -337.980414) (xy 82.779636 -338.026604) (xy 82.743172 -338.067976) (xy 82.722466 -338.086192)
			(xy 82.714389 -338.093745) (xy 82.705037 -338.113758) (xy 82.704432 -338.1248) (xy 82.704432 -338.202524)
			(xy 82.705033 -338.21357) (xy 82.714374 -338.233591) (xy 82.722466 -338.241132) (xy 82.743189 -338.25933)
			(xy 82.77966 -338.300701) (xy 82.809791 -338.346893) (xy 82.832955 -338.396944) (xy 82.848669 -338.449809)
			(xy 82.856604 -338.504386) (xy 82.857086 -338.531962) (xy 82.856609 -338.559215) (xy 82.848857 -338.613167)
			(xy 82.833505 -338.665465) (xy 82.810865 -338.715047) (xy 82.78178 -338.760308) (xy 83.436458 -338.760308)
			(xy 83.440529 -338.704686) (xy 83.452655 -338.650249) (xy 83.472578 -338.598158) (xy 83.499874 -338.549523)
			(xy 83.53396 -338.50538) (xy 83.574109 -338.466671) (xy 83.619467 -338.43422) (xy 83.669067 -338.408719)
			(xy 83.721851 -338.390712) (xy 83.776694 -338.380582) (xy 83.832428 -338.378545) (xy 83.887865 -338.384645)
			(xy 83.941822 -338.398751) (xy 83.993151 -338.420563) (xy 84.040757 -338.449617) (xy 84.083625 -338.485292)
			(xy 84.120842 -338.526829) (xy 84.151615 -338.573342) (xy 84.175287 -338.623839) (xy 84.191355 -338.677246)
			(xy 84.199475 -338.732422) (xy 84.199984 -338.760308) (xy 84.199475 -338.788194) (xy 84.191355 -338.84337)
			(xy 84.175287 -338.896777) (xy 84.151615 -338.947274) (xy 84.120842 -338.993787) (xy 84.083625 -339.035324)
			(xy 84.040757 -339.070999) (xy 83.993151 -339.100053) (xy 83.941822 -339.121865) (xy 83.887865 -339.135971)
			(xy 83.832428 -339.142071) (xy 83.776694 -339.140034) (xy 83.721851 -339.129904) (xy 83.669067 -339.111897)
			(xy 83.619467 -339.086396) (xy 83.574109 -339.053945) (xy 83.53396 -339.015236) (xy 83.499874 -338.971093)
			(xy 83.472578 -338.922458) (xy 83.452655 -338.870367) (xy 83.440529 -338.81593) (xy 83.436458 -338.760308)
			(xy 82.78178 -338.760308) (xy 82.781399 -338.760901) (xy 82.745706 -338.802095) (xy 82.704514 -338.837789)
			(xy 82.658661 -338.867257) (xy 82.60908 -338.889899) (xy 82.556782 -338.905254) (xy 82.502831 -338.913008)
			(xy 82.475578 -338.91347) (xy 82.447721 -338.912989) (xy 82.392603 -338.904862) (xy 82.33925 -338.888812)
			(xy 82.288796 -338.86518) (xy 82.242311 -338.834468) (xy 82.200782 -338.797327) (xy 82.16509 -338.754547)
			(xy 82.135993 -338.707034) (xy 82.114108 -338.655797) (xy 82.106516 -338.62899) (xy 82.10423 -338.6201)
			(xy 82.093562 -338.60486) (xy 82.02168 -338.557108) (xy 82.003646 -338.553044) (xy 81.994502 -338.554314)
			(xy 81.981485 -338.555981) (xy 81.955301 -338.557762) (xy 81.942178 -338.55787) (xy 81.928029 -338.557779)
			(xy 81.899806 -338.555743) (xy 81.88579 -338.553806) (xy 81.875884 -338.552282) (xy 81.856072 -338.557108)
			(xy 81.78165 -338.612988) (xy 81.77149 -338.630514) (xy 81.77022 -338.640674) (xy 81.766152 -338.667831)
			(xy 81.751175 -338.720661) (xy 81.72878 -338.770799) (xy 81.69943 -338.817209) (xy 81.66373 -338.858933)
			(xy 81.622418 -338.895108) (xy 81.576348 -338.924989) (xy 81.52647 -338.947957) (xy 81.473815 -338.963539)
			(xy 81.41947 -338.971412) (xy 81.392014 -338.97189) (xy 81.364761 -338.971432) (xy 81.310809 -338.963676)
			(xy 81.25851 -338.948321) (xy 81.208928 -338.925679) (xy 81.163074 -338.896211) (xy 81.121881 -338.860516)
			(xy 81.086187 -338.819323) (xy 81.056719 -338.773468) (xy 81.034078 -338.723887) (xy 81.018723 -338.671587)
			(xy 81.010968 -338.617635) (xy 81.010506 -338.590382) (xy 78.869669 -338.590382) (xy 78.872302 -338.599344)
			(xy 78.880067 -338.653297) (xy 78.880462 -338.680552) (xy 78.879815 -338.712116) (xy 78.869434 -338.774386)
			(xy 78.848948 -338.834098) (xy 78.834488 -338.862162) (xy 78.829662 -338.871052) (xy 78.82763 -338.89061)
			(xy 78.85049 -338.969096) (xy 78.853736 -338.978516) (xy 78.866153 -338.994072) (xy 78.87462 -338.999322)
			(xy 78.899715 -339.013878) (xy 78.945583 -339.049394) (xy 78.985549 -339.091442) (xy 79.018691 -339.139054)
			(xy 79.044247 -339.191133) (xy 79.061627 -339.246479) (xy 79.070432 -339.303819) (xy 79.070962 -339.332824)
			(xy 79.070497 -339.360075) (xy 79.062737 -339.41402) (xy 79.056297 -339.435948) (xy 84.775294 -339.435948)
			(xy 84.775751 -339.408472) (xy 84.78365 -339.354092) (xy 84.799277 -339.301409) (xy 84.822308 -339.251517)
			(xy 84.852266 -339.205449) (xy 84.870036 -339.184488) (xy 84.87029 -339.184234) (xy 84.875867 -339.177141)
			(xy 84.88212 -339.160229) (xy 84.882482 -339.151214) (xy 84.882482 -339.08365) (xy 84.882105 -339.074635)
			(xy 84.875872 -339.057718) (xy 84.87029 -339.05063) (xy 84.869782 -339.050122) (xy 84.85206 -339.029167)
			(xy 84.822176 -338.983136) (xy 84.799208 -338.933293) (xy 84.783631 -338.88067) (xy 84.775767 -338.826356)
			(xy 84.775294 -338.798916) (xy 84.77578 -338.771665) (xy 84.783536 -338.717717) (xy 84.798891 -338.665422)
			(xy 84.821533 -338.615845) (xy 84.850999 -338.569995) (xy 84.88669 -338.528804) (xy 84.927881 -338.493113)
			(xy 84.973731 -338.463647) (xy 85.023308 -338.441005) (xy 85.075603 -338.42565) (xy 85.129551 -338.417894)
			(xy 85.184053 -338.417894) (xy 85.238001 -338.42565) (xy 85.290296 -338.441005) (xy 85.339873 -338.463647)
			(xy 85.385723 -338.493113) (xy 85.426914 -338.528804) (xy 85.462605 -338.569995) (xy 85.492071 -338.615845)
			(xy 85.514713 -338.665422) (xy 85.530068 -338.717717) (xy 85.537824 -338.771665) (xy 85.53831 -338.798916)
			(xy 85.537831 -338.826391) (xy 85.529937 -338.880771) (xy 85.514315 -338.933453) (xy 85.491289 -338.983346)
			(xy 85.461336 -339.029414) (xy 85.443568 -339.050376) (xy 85.443314 -339.05063) (xy 85.437752 -339.057734)
			(xy 85.43149 -339.074637) (xy 85.431122 -339.08365) (xy 85.431122 -339.151214) (xy 85.431467 -339.160232)
			(xy 85.437722 -339.177149) (xy 85.443314 -339.184234) (xy 85.443822 -339.184742) (xy 85.461575 -339.205673)
			(xy 85.491454 -339.25171) (xy 85.514416 -339.301559) (xy 85.529986 -339.354188) (xy 85.537842 -339.408506)
			(xy 85.53831 -339.435948) (xy 85.537824 -339.463199) (xy 85.530068 -339.517147) (xy 85.514713 -339.569442)
			(xy 85.492071 -339.619019) (xy 85.462605 -339.664869) (xy 85.426914 -339.70606) (xy 85.385723 -339.741751)
			(xy 85.339873 -339.771217) (xy 85.290296 -339.793859) (xy 85.238001 -339.809214) (xy 85.184053 -339.81697)
			(xy 85.129551 -339.81697) (xy 85.075603 -339.809214) (xy 85.023308 -339.793859) (xy 84.973731 -339.771217)
			(xy 84.927881 -339.741751) (xy 84.88669 -339.70606) (xy 84.850999 -339.664869) (xy 84.821533 -339.619019)
			(xy 84.798891 -339.569442) (xy 84.783536 -339.517147) (xy 84.77578 -339.463199) (xy 84.775294 -339.435948)
			(xy 79.056297 -339.435948) (xy 79.047378 -339.466313) (xy 79.024734 -339.515887) (xy 78.995265 -339.561734)
			(xy 78.95957 -339.60292) (xy 78.918378 -339.638607) (xy 78.872525 -339.668068) (xy 78.822947 -339.690703)
			(xy 78.770652 -339.706052) (xy 78.716705 -339.713802) (xy 78.689454 -339.714332) (xy 78.662787 -339.71389)
			(xy 78.609974 -339.706464) (xy 78.558711 -339.69175) (xy 78.509999 -339.670034) (xy 78.46479 -339.641741)
			(xy 78.44409 -339.624924) (xy 78.443836 -339.62467) (xy 78.436377 -339.619008) (xy 78.418656 -339.613007)
			(xy 78.409292 -339.612986) (xy 78.340458 -339.616034) (xy 78.331017 -339.6168) (xy 78.313674 -339.624381)
			(xy 78.306676 -339.630766) (xy 76.807822 -341.12962) (xy 76.800976 -341.137019) (xy 76.793246 -341.155617)
			(xy 76.792836 -341.165688) (xy 76.792836 -343.212166) (xy 76.792327 -343.232104) (xy 76.784527 -343.271211)
			(xy 76.769276 -343.308056) (xy 76.747156 -343.341236) (xy 76.7334 -343.355676) (xy 64.481456 -355.60762)
			(xy 64.467005 -355.621368) (xy 64.43384 -355.643516) (xy 64.396997 -355.65878) (xy 64.357886 -355.666576)
			(xy 64.337946 -355.667056) (xy 44.896786 -355.667056) (xy 44.886718 -355.667483) (xy 44.868123 -355.675207)
			(xy 44.860718 -355.682042) (xy 44.287186 -356.255828) (xy 44.272732 -356.26957) (xy 44.239565 -356.291706)
			(xy 44.202722 -356.306957) (xy 44.163613 -356.314739) (xy 44.143676 -356.315264) (xy 41.032938 -356.315264)
			(xy 41.022874 -356.3157) (xy 41.004292 -356.323438) (xy 40.99687 -356.33025) (xy 39.703502 -357.623872)
			(xy 39.696667 -357.631274) (xy 39.688958 -357.649873) (xy 39.688516 -357.65994) (xy 39.688516 -358.549194)
			(xy 40.988234 -358.549194) (xy 40.988686 -358.523273) (xy 40.995718 -358.471911) (xy 41.009638 -358.421973)
			(xy 41.030189 -358.374379) (xy 41.056993 -358.330005) (xy 41.089557 -358.289667) (xy 41.108122 -358.271572)
			(xy 41.11498 -358.264968) (xy 41.123108 -358.24795) (xy 41.129712 -358.16032) (xy 41.124124 -358.142286)
			(xy 41.118028 -358.134666) (xy 41.102545 -358.114386) (xy 41.076567 -358.070471) (xy 41.056669 -358.023487)
			(xy 41.043203 -357.974273) (xy 41.03641 -357.923704) (xy 41.035986 -357.898192) (xy 41.036451 -357.870822)
			(xy 41.044269 -357.816643) (xy 41.059759 -357.76414) (xy 41.082601 -357.714393) (xy 41.112325 -357.668426)
			(xy 41.129966 -357.647494) (xy 41.13022 -357.64724) (xy 41.135798 -357.640148) (xy 41.142049 -357.623235)
			(xy 41.142412 -357.61422) (xy 41.142412 -357.547164) (xy 41.14207 -357.538146) (xy 41.135812 -357.521229)
			(xy 41.13022 -357.514144) (xy 41.129966 -357.514144) (xy 41.129966 -357.51389) (xy 41.112303 -357.492977)
			(xy 41.082596 -357.446998) (xy 41.059765 -357.397246) (xy 41.04428 -357.344741) (xy 41.036457 -357.290562)
			(xy 41.035986 -357.263192) (xy 41.036472 -357.235941) (xy 41.044228 -357.181993) (xy 41.059583 -357.129698)
			(xy 41.082225 -357.080121) (xy 41.111691 -357.034271) (xy 41.147382 -356.99308) (xy 41.188573 -356.957389)
			(xy 41.234423 -356.927923) (xy 41.284 -356.905281) (xy 41.336295 -356.889926) (xy 41.390243 -356.88217)
			(xy 41.444745 -356.88217) (xy 41.498693 -356.889926) (xy 41.550988 -356.905281) (xy 41.600565 -356.927923)
			(xy 41.646415 -356.957389) (xy 41.687606 -356.99308) (xy 41.723297 -357.034271) (xy 41.752763 -357.080121)
			(xy 41.775405 -357.129698) (xy 41.79076 -357.181993) (xy 41.798516 -357.235941) (xy 41.799002 -357.263192)
			(xy 41.798531 -357.290562) (xy 41.790714 -357.344741) (xy 41.775226 -357.397244) (xy 41.752386 -357.446991)
			(xy 41.722663 -357.492958) (xy 41.705022 -357.51389) (xy 41.704768 -357.514144) (xy 41.699195 -357.52124)
			(xy 41.692941 -357.53815) (xy 41.692576 -357.547164) (xy 41.692576 -357.61422) (xy 41.692928 -357.623237)
			(xy 41.69918 -357.640154) (xy 41.704768 -357.64724) (xy 41.705022 -357.64724) (xy 41.705022 -357.647494)
			(xy 41.722675 -357.668415) (xy 41.752384 -357.714391) (xy 41.775217 -357.764141) (xy 41.790705 -357.816644)
			(xy 41.79853 -357.870822) (xy 41.799002 -357.898192) (xy 41.798529 -357.924112) (xy 41.7915 -357.975473)
			(xy 41.777584 -358.02541) (xy 41.757036 -358.073004) (xy 41.730236 -358.117379) (xy 41.697676 -358.157718)
			(xy 41.679114 -358.175814) (xy 41.672256 -358.182418) (xy 41.664128 -358.199436) (xy 41.657524 -358.287066)
			(xy 41.663112 -358.3051) (xy 41.669208 -358.31272) (xy 41.684676 -358.333012) (xy 41.710657 -358.376923)
			(xy 41.73056 -358.423903) (xy 41.744029 -358.473115) (xy 41.749099 -358.51084) (xy 43.554396 -358.51084)
			(xy 43.554825 -358.484919) (xy 43.561863 -358.433556) (xy 43.575788 -358.383618) (xy 43.596343 -358.336024)
			(xy 43.623151 -358.29165) (xy 43.655718 -358.251313) (xy 43.674284 -358.233218) (xy 43.681142 -358.226614)
			(xy 43.68927 -358.209596) (xy 43.695874 -358.121966) (xy 43.690286 -358.103932) (xy 43.68419 -358.096312)
			(xy 43.668737 -358.07601) (xy 43.642753 -358.032102) (xy 43.622847 -357.985124) (xy 43.609375 -357.935914)
			(xy 43.602575 -357.885348) (xy 43.602148 -357.859838) (xy 43.602625 -357.832468) (xy 43.610438 -357.778289)
			(xy 43.625924 -357.725785) (xy 43.648764 -357.676038) (xy 43.678487 -357.630072) (xy 43.696128 -357.60914)
			(xy 43.696382 -357.608886) (xy 43.701978 -357.601806) (xy 43.708219 -357.584884) (xy 43.708574 -357.575866)
			(xy 43.708574 -357.50881) (xy 43.708218 -357.499793) (xy 43.70197 -357.482876) (xy 43.696382 -357.47579)
			(xy 43.696128 -357.47579) (xy 43.696128 -357.475536) (xy 43.678497 -357.454598) (xy 43.648783 -357.408627)
			(xy 43.625945 -357.358881) (xy 43.610452 -357.306382) (xy 43.602623 -357.252207) (xy 43.602148 -357.224838)
			(xy 43.602634 -357.197587) (xy 43.61039 -357.143639) (xy 43.625745 -357.091344) (xy 43.648387 -357.041767)
			(xy 43.677853 -356.995917) (xy 43.713544 -356.954726) (xy 43.754735 -356.919035) (xy 43.800585 -356.889569)
			(xy 43.850162 -356.866927) (xy 43.902457 -356.851572) (xy 43.956405 -356.843816) (xy 44.010907 -356.843816)
			(xy 44.064855 -356.851572) (xy 44.11715 -356.866927) (xy 44.166727 -356.889569) (xy 44.212577 -356.919035)
			(xy 44.253768 -356.954726) (xy 44.289459 -356.995917) (xy 44.318925 -357.041767) (xy 44.341567 -357.091344)
			(xy 44.356922 -357.143639) (xy 44.364678 -357.197587) (xy 44.365164 -357.224838) (xy 44.36467 -357.252207)
			(xy 44.356861 -357.306386) (xy 44.341378 -357.358889) (xy 44.318543 -357.408636) (xy 44.288823 -357.454604)
			(xy 44.271184 -357.475536) (xy 44.27093 -357.47579) (xy 44.265333 -357.482869) (xy 44.259095 -357.499792)
			(xy 44.258738 -357.50881) (xy 44.258738 -357.575866) (xy 44.259103 -357.584882) (xy 44.265344 -357.6018)
			(xy 44.27093 -357.608886) (xy 44.271184 -357.608886) (xy 44.271184 -357.60914) (xy 44.288806 -357.630086)
			(xy 44.318521 -357.676055) (xy 44.34136 -357.725799) (xy 44.356855 -357.778296) (xy 44.364688 -357.83247)
			(xy 44.365164 -357.859838) (xy 44.364733 -357.885759) (xy 44.357697 -357.937123) (xy 44.343774 -357.987061)
			(xy 44.323218 -358.034655) (xy 44.29641 -358.079029) (xy 44.272612 -358.108504) (xy 47.49927 -358.108504)
			(xy 47.499749 -358.082584) (xy 47.506778 -358.031224) (xy 47.520694 -357.981287) (xy 47.54124 -357.933694)
			(xy 47.568039 -357.889318) (xy 47.600597 -357.848979) (xy 47.619158 -357.830882) (xy 47.626016 -357.824278)
			(xy 47.634144 -357.80726) (xy 47.640748 -357.71963) (xy 47.63516 -357.701596) (xy 47.629064 -357.693976)
			(xy 47.613591 -357.673689) (xy 47.587611 -357.629776) (xy 47.567709 -357.582795) (xy 47.554241 -357.533581)
			(xy 47.547447 -357.483013) (xy 47.547022 -357.457502) (xy 47.547484 -357.430132) (xy 47.555302 -357.375952)
			(xy 47.570792 -357.323449) (xy 47.593634 -357.273702) (xy 47.62336 -357.227735) (xy 47.641002 -357.206804)
			(xy 47.641256 -357.20655) (xy 47.646834 -357.199458) (xy 47.653085 -357.182545) (xy 47.653448 -357.17353)
			(xy 47.653448 -357.106474) (xy 47.653115 -357.097454) (xy 47.646852 -357.080537) (xy 47.641256 -357.073454)
			(xy 47.641002 -357.073454) (xy 47.641002 -357.0732) (xy 47.62335 -357.052279) (xy 47.59364 -357.006303)
			(xy 47.570806 -356.956553) (xy 47.555318 -356.90405) (xy 47.547494 -356.849872) (xy 47.547022 -356.822502)
			(xy 47.547457 -356.795248) (xy 47.555215 -356.741294) (xy 47.570572 -356.688994) (xy 47.593217 -356.639412)
			(xy 47.622687 -356.593557) (xy 47.658384 -356.552364) (xy 47.69958 -356.51667) (xy 47.745437 -356.487203)
			(xy 47.79502 -356.464562) (xy 47.847322 -356.449209) (xy 47.901276 -356.441455) (xy 47.92853 -356.440994)
			(xy 47.957165 -356.441498) (xy 48.01379 -356.450062) (xy 48.0685 -356.466994) (xy 48.120064 -356.491913)
			(xy 48.167324 -356.52426) (xy 48.209219 -356.563306) (xy 48.244806 -356.608177) (xy 48.259492 -356.632764)
			(xy 48.264243 -356.640338) (xy 48.277941 -356.651811) (xy 48.294752 -356.657867) (xy 48.303688 -356.658164)
			(xy 48.391572 -356.658164) (xy 48.4005 -356.657828) (xy 48.417292 -356.651761) (xy 48.430994 -356.640315)
			(xy 48.435768 -356.632764) (xy 48.450459 -356.608179) (xy 48.486042 -356.563306) (xy 48.527934 -356.524256)
			(xy 48.575194 -356.491909) (xy 48.626758 -356.466992) (xy 48.681469 -356.450064) (xy 48.738095 -356.441506)
			(xy 48.76673 -356.440994) (xy 48.794101 -356.441444) (xy 48.848281 -356.449266) (xy 48.900784 -356.464759)
			(xy 48.95053 -356.487604) (xy 48.996497 -356.517332) (xy 49.017428 -356.534974) (xy 49.017682 -356.535228)
			(xy 49.024767 -356.540816) (xy 49.041685 -356.547061) (xy 49.050702 -356.54742) (xy 49.117758 -356.54742)
			(xy 49.126772 -356.547039) (xy 49.143689 -356.540808) (xy 49.150778 -356.535228) (xy 49.150778 -356.534974)
			(xy 49.151032 -356.534974) (xy 49.171965 -356.517333) (xy 49.217933 -356.487609) (xy 49.267679 -356.464763)
			(xy 49.320181 -356.449267) (xy 49.374359 -356.441438) (xy 49.429101 -356.441438) (xy 49.483279 -356.449267)
			(xy 49.535781 -356.464763) (xy 49.585527 -356.487609) (xy 49.631495 -356.517333) (xy 49.652428 -356.534974)
			(xy 49.652682 -356.535228) (xy 49.659767 -356.540816) (xy 49.676685 -356.547061) (xy 49.685702 -356.54742)
			(xy 49.752758 -356.54742) (xy 49.761772 -356.547039) (xy 49.778689 -356.540808) (xy 49.785778 -356.535228)
			(xy 49.785778 -356.534974) (xy 49.786032 -356.534974) (xy 49.806965 -356.517333) (xy 49.852933 -356.487609)
			(xy 49.902679 -356.464763) (xy 49.955181 -356.449267) (xy 50.009359 -356.441438) (xy 50.064101 -356.441438)
			(xy 50.118279 -356.449267) (xy 50.170781 -356.464763) (xy 50.220527 -356.487609) (xy 50.266495 -356.517333)
			(xy 50.287428 -356.534974) (xy 50.287682 -356.535228) (xy 50.294767 -356.540816) (xy 50.311685 -356.547061)
			(xy 50.320702 -356.54742) (xy 50.387758 -356.54742) (xy 50.396772 -356.547039) (xy 50.413689 -356.540808)
			(xy 50.420778 -356.535228) (xy 50.420778 -356.534974) (xy 50.421032 -356.534974) (xy 50.441976 -356.517349)
			(xy 50.487946 -356.487636) (xy 50.53769 -356.464798) (xy 50.590188 -356.449303) (xy 50.644362 -356.441471)
			(xy 50.67173 -356.440994) (xy 50.698982 -356.44145) (xy 50.752931 -356.449211) (xy 50.805226 -356.46457)
			(xy 50.854804 -356.487214) (xy 50.900654 -356.516684) (xy 50.941844 -356.552379) (xy 50.977535 -356.593571)
			(xy 51.007001 -356.639424) (xy 51.029642 -356.689004) (xy 51.044996 -356.7413) (xy 51.052752 -356.79525)
			(xy 51.053238 -356.822502) (xy 51.052788 -356.849873) (xy 51.044969 -356.904053) (xy 51.029477 -356.956557)
			(xy 51.006631 -357.006304) (xy 50.976902 -357.052269) (xy 50.959258 -357.0732) (xy 50.959004 -357.073454)
			(xy 50.953431 -357.08055) (xy 50.947176 -357.097459) (xy 50.946812 -357.106474) (xy 50.946812 -357.17353)
			(xy 50.947152 -357.182549) (xy 50.953411 -357.199466) (xy 50.959004 -357.20655) (xy 50.959258 -357.20655)
			(xy 50.959258 -357.206804) (xy 50.976906 -357.227729) (xy 51.006618 -357.273703) (xy 51.029453 -357.323452)
			(xy 51.044942 -357.375955) (xy 51.052766 -357.430132) (xy 51.053238 -357.457502) (xy 51.052761 -357.483422)
			(xy 51.045731 -357.534782) (xy 51.031815 -357.584719) (xy 51.011268 -357.632312) (xy 50.984469 -357.676687)
			(xy 50.951911 -357.717027) (xy 50.93335 -357.735124) (xy 50.926492 -357.741728) (xy 50.918364 -357.758746)
			(xy 50.91176 -357.846376) (xy 50.917348 -357.86441) (xy 50.923444 -357.87203) (xy 50.938921 -357.892314)
			(xy 50.964901 -357.936228) (xy 50.984801 -357.98321) (xy 50.998268 -358.032424) (xy 51.005062 -358.082993)
			(xy 51.005486 -358.108504) (xy 51.005048 -358.135758) (xy 50.99729 -358.189711) (xy 50.981933 -358.242011)
			(xy 50.959288 -358.291592) (xy 50.929818 -358.337446) (xy 50.894121 -358.37864) (xy 50.852926 -358.414333)
			(xy 50.807069 -358.4438) (xy 50.757486 -358.466442) (xy 50.705185 -358.481796) (xy 50.651232 -358.48955)
			(xy 50.623978 -358.490012) (xy 50.596607 -358.489556) (xy 50.542428 -358.481735) (xy 50.489925 -358.466244)
			(xy 50.440178 -358.4434) (xy 50.394212 -358.413674) (xy 50.37328 -358.396032) (xy 50.373026 -358.395778)
			(xy 50.365938 -358.390194) (xy 50.349022 -358.383946) (xy 50.340006 -358.383586) (xy 50.27295 -358.383586)
			(xy 50.263936 -358.38397) (xy 50.247019 -358.390199) (xy 50.23993 -358.395778) (xy 50.23993 -358.396032)
			(xy 50.239676 -358.396032) (xy 50.218743 -358.413673) (xy 50.172775 -358.443397) (xy 50.123029 -358.466243)
			(xy 50.070527 -358.481739) (xy 50.016349 -358.489568) (xy 49.961607 -358.489568) (xy 49.907429 -358.481739)
			(xy 49.854927 -358.466243) (xy 49.805181 -358.443397) (xy 49.759213 -358.413673) (xy 49.73828 -358.396032)
			(xy 49.738026 -358.395778) (xy 49.730938 -358.390194) (xy 49.714022 -358.383946) (xy 49.705006 -358.383586)
			(xy 49.63795 -358.383586) (xy 49.628936 -358.38397) (xy 49.612019 -358.390199) (xy 49.60493 -358.395778)
			(xy 49.60493 -358.396032) (xy 49.604676 -358.396032) (xy 49.583743 -358.413673) (xy 49.537775 -358.443397)
			(xy 49.488029 -358.466243) (xy 49.435527 -358.481739) (xy 49.381349 -358.489568) (xy 49.326607 -358.489568)
			(xy 49.272429 -358.481739) (xy 49.219927 -358.466243) (xy 49.170181 -358.443397) (xy 49.124213 -358.413673)
			(xy 49.10328 -358.396032) (xy 49.103026 -358.395778) (xy 49.095938 -358.390194) (xy 49.079022 -358.383946)
			(xy 49.070006 -358.383586) (xy 49.00295 -358.383586) (xy 48.993936 -358.38397) (xy 48.977019 -358.390199)
			(xy 48.96993 -358.395778) (xy 48.96993 -358.396032) (xy 48.969676 -358.396032) (xy 48.94873 -358.413654)
			(xy 48.902761 -358.443367) (xy 48.853017 -358.466206) (xy 48.800519 -358.481701) (xy 48.746346 -358.489535)
			(xy 48.718978 -358.490012) (xy 48.690344 -358.489499) (xy 48.633719 -358.480936) (xy 48.57901 -358.464005)
			(xy 48.527446 -358.439088) (xy 48.480185 -358.406743) (xy 48.43829 -358.367697) (xy 48.402702 -358.322829)
			(xy 48.388016 -358.298242) (xy 48.383258 -358.290673) (xy 48.369563 -358.279199) (xy 48.352755 -358.273141)
			(xy 48.34382 -358.272842) (xy 48.255936 -358.272842) (xy 48.247008 -358.273181) (xy 48.230216 -358.279246)
			(xy 48.216514 -358.290691) (xy 48.21174 -358.298242) (xy 48.197046 -358.322824) (xy 48.161463 -358.367698)
			(xy 48.119571 -358.406747) (xy 48.072312 -358.439094) (xy 48.020748 -358.464012) (xy 47.966039 -358.480941)
			(xy 47.909413 -358.4895) (xy 47.880778 -358.490012) (xy 47.853526 -358.489543) (xy 47.799578 -358.481783)
			(xy 47.747283 -358.466426) (xy 47.697706 -358.443782) (xy 47.651856 -358.414314) (xy 47.610666 -358.378621)
			(xy 47.574975 -358.337429) (xy 47.545509 -358.291578) (xy 47.522868 -358.242) (xy 47.507513 -358.189704)
			(xy 47.499756 -358.135756) (xy 47.49927 -358.108504) (xy 44.272612 -358.108504) (xy 44.263842 -358.119366)
			(xy 44.245276 -358.13746) (xy 44.238418 -358.144064) (xy 44.23029 -358.161082) (xy 44.223686 -358.248712)
			(xy 44.229274 -358.266746) (xy 44.23537 -358.274366) (xy 44.250822 -358.294669) (xy 44.276804 -358.338578)
			(xy 44.296709 -358.385555) (xy 44.310182 -358.434765) (xy 44.316984 -358.48533) (xy 44.317412 -358.51084)
			(xy 44.316847 -358.539303) (xy 44.308379 -358.595597) (xy 44.291638 -358.650006) (xy 44.266995 -358.701322)
			(xy 44.234998 -358.748406) (xy 44.216066 -358.769666) (xy 44.208954 -358.77754) (xy 44.202096 -358.797352)
			(xy 44.209716 -358.893618) (xy 44.219622 -358.91216) (xy 44.228258 -358.918764) (xy 44.250665 -358.936951)
			(xy 44.290263 -358.978928) (xy 44.323086 -359.026392) (xy 44.348384 -359.078259) (xy 44.36558 -359.133345)
			(xy 44.374282 -359.190392) (xy 44.374816 -359.219246) (xy 44.37433 -359.246497) (xy 44.366574 -359.300445)
			(xy 44.351219 -359.35274) (xy 44.328577 -359.402317) (xy 44.299111 -359.448167) (xy 44.26342 -359.489358)
			(xy 44.222229 -359.525049) (xy 44.176379 -359.554515) (xy 44.126802 -359.577157) (xy 44.074507 -359.592512)
			(xy 44.020559 -359.600268) (xy 43.966057 -359.600268) (xy 43.912109 -359.592512) (xy 43.859814 -359.577157)
			(xy 43.810237 -359.554515) (xy 43.764387 -359.525049) (xy 43.723196 -359.489358) (xy 43.687505 -359.448167)
			(xy 43.658039 -359.402317) (xy 43.635397 -359.35274) (xy 43.620042 -359.300445) (xy 43.612286 -359.246497)
			(xy 43.6118 -359.219246) (xy 43.612354 -359.190782) (xy 43.620824 -359.134488) (xy 43.637567 -359.080079)
			(xy 43.662213 -359.028763) (xy 43.694212 -358.98168) (xy 43.713146 -358.96042) (xy 43.720258 -358.952546)
			(xy 43.727116 -358.932734) (xy 43.719496 -358.836468) (xy 43.70959 -358.817926) (xy 43.700954 -358.811322)
			(xy 43.678543 -358.79314) (xy 43.638944 -358.751162) (xy 43.606122 -358.703697) (xy 43.580824 -358.65183)
			(xy 43.563629 -358.596743) (xy 43.554929 -358.539694) (xy 43.554396 -358.51084) (xy 41.749099 -358.51084)
			(xy 41.750825 -358.523683) (xy 41.75125 -358.549194) (xy 41.750733 -358.577659) (xy 41.742256 -358.633955)
			(xy 41.725505 -358.688366) (xy 41.700851 -358.739682) (xy 41.668842 -358.786762) (xy 41.649904 -358.80802)
			(xy 41.642792 -358.815894) (xy 41.635934 -358.835706) (xy 41.643554 -358.931972) (xy 41.65346 -358.950514)
			(xy 41.662096 -358.957118) (xy 41.684516 -358.97529) (xy 41.724116 -359.017269) (xy 41.756939 -359.064735)
			(xy 41.782236 -359.116605) (xy 41.799428 -359.171694) (xy 41.808123 -359.228745) (xy 41.808654 -359.2576)
			(xy 41.808168 -359.284851) (xy 41.800412 -359.338799) (xy 41.785057 -359.391094) (xy 41.762415 -359.440671)
			(xy 41.732949 -359.486521) (xy 41.697258 -359.527712) (xy 41.656067 -359.563403) (xy 41.610217 -359.592869)
			(xy 41.56064 -359.615511) (xy 41.508345 -359.630866) (xy 41.454397 -359.638622) (xy 41.399895 -359.638622)
			(xy 41.345947 -359.630866) (xy 41.293652 -359.615511) (xy 41.244075 -359.592869) (xy 41.198225 -359.563403)
			(xy 41.157034 -359.527712) (xy 41.121343 -359.486521) (xy 41.091877 -359.440671) (xy 41.069235 -359.391094)
			(xy 41.05388 -359.338799) (xy 41.046124 -359.284851) (xy 41.045638 -359.2576) (xy 41.046154 -359.229135)
			(xy 41.054632 -359.172839) (xy 41.071384 -359.118428) (xy 41.096038 -359.067113) (xy 41.128046 -359.020032)
			(xy 41.146984 -358.998774) (xy 41.154096 -358.9909) (xy 41.160954 -358.971088) (xy 41.153334 -358.874822)
			(xy 41.143428 -358.85628) (xy 41.134792 -358.849676) (xy 41.112367 -358.831511) (xy 41.072767 -358.78953)
			(xy 41.039945 -358.742062) (xy 41.01465 -358.690191) (xy 40.997459 -358.635101) (xy 40.988764 -358.578049)
			(xy 40.988234 -358.549194) (xy 39.688516 -358.549194) (xy 39.688516 -359.340404) (xy 39.688066 -359.360424)
			(xy 39.680265 -359.399697) (xy 39.664945 -359.43669) (xy 39.642696 -359.469979) (xy 39.628826 -359.484422)
			(xy 37.779706 -361.333542) (xy 37.765205 -361.347339) (xy 37.731923 -361.369565) (xy 37.694948 -361.38488)
			(xy 37.655698 -361.392696) (xy 37.635688 -361.393232) (xy 35.886644 -361.393232) (xy 35.876579 -361.393666)
			(xy 35.857992 -361.401398) (xy 35.850576 -361.408218) (xy 35.181722 -362.077) (xy 37.946582 -362.077)
			(xy 37.950653 -362.021378) (xy 37.962779 -361.966941) (xy 37.982702 -361.91485) (xy 38.009998 -361.866215)
			(xy 38.044084 -361.822072) (xy 38.084233 -361.783363) (xy 38.129591 -361.750912) (xy 38.179191 -361.725411)
			(xy 38.231975 -361.707404) (xy 38.286818 -361.697274) (xy 38.342552 -361.695237) (xy 38.397989 -361.701337)
			(xy 38.451946 -361.715443) (xy 38.503275 -361.737255) (xy 38.550881 -361.766309) (xy 38.593749 -361.801984)
			(xy 38.630966 -361.843521) (xy 38.661739 -361.890034) (xy 38.685411 -361.940531) (xy 38.701479 -361.993938)
			(xy 38.709599 -362.049114) (xy 38.710108 -362.077) (xy 38.709599 -362.104886) (xy 38.701479 -362.160062)
			(xy 38.685411 -362.213469) (xy 38.661739 -362.263966) (xy 38.630966 -362.310479) (xy 38.593749 -362.352016)
			(xy 38.550881 -362.387691) (xy 38.503275 -362.416745) (xy 38.451946 -362.438557) (xy 38.397989 -362.452663)
			(xy 38.342552 -362.458763) (xy 38.286818 -362.456726) (xy 38.231975 -362.446596) (xy 38.179191 -362.428589)
			(xy 38.129591 -362.403088) (xy 38.084233 -362.370637) (xy 38.044084 -362.331928) (xy 38.009998 -362.287785)
			(xy 37.982702 -362.23915) (xy 37.962779 -362.187059) (xy 37.950653 -362.132622) (xy 37.946582 -362.077)
			(xy 35.181722 -362.077) (xy 34.165612 -363.093) (xy 35.558982 -363.093) (xy 35.563053 -363.037378)
			(xy 35.575179 -362.982941) (xy 35.595102 -362.93085) (xy 35.622398 -362.882215) (xy 35.656484 -362.838072)
			(xy 35.696633 -362.799363) (xy 35.741991 -362.766912) (xy 35.791591 -362.741411) (xy 35.844375 -362.723404)
			(xy 35.899218 -362.713274) (xy 35.954952 -362.711237) (xy 36.010389 -362.717337) (xy 36.064346 -362.731443)
			(xy 36.115675 -362.753255) (xy 36.163281 -362.782309) (xy 36.206149 -362.817984) (xy 36.238634 -362.85424)
			(xy 46.115224 -362.85424) (xy 46.115708 -362.82687) (xy 46.12352 -362.772692) (xy 46.139005 -362.720189)
			(xy 46.161843 -362.670441) (xy 46.191564 -362.624474) (xy 46.209204 -362.603542) (xy 46.209458 -362.603288)
			(xy 46.215063 -362.596214) (xy 46.221297 -362.579287) (xy 46.22165 -362.570268) (xy 46.22165 -362.503212)
			(xy 46.221298 -362.494194) (xy 46.215048 -362.477277) (xy 46.209458 -362.470192) (xy 46.209204 -362.470192)
			(xy 46.209204 -362.469938) (xy 46.191603 -362.448973) (xy 46.161879 -362.40301) (xy 46.139032 -362.353269)
			(xy 46.123534 -362.300772) (xy 46.115702 -362.246599) (xy 46.115698 -362.191862) (xy 46.123521 -362.137687)
			(xy 46.139011 -362.085187) (xy 46.16185 -362.035443) (xy 46.191567 -361.989475) (xy 46.209204 -361.968542)
			(xy 46.209458 -361.968288) (xy 46.215063 -361.961214) (xy 46.221297 -361.944287) (xy 46.22165 -361.935268)
			(xy 46.22165 -361.868212) (xy 46.221298 -361.859194) (xy 46.215048 -361.842277) (xy 46.209458 -361.835192)
			(xy 46.209204 -361.835192) (xy 46.209204 -361.834938) (xy 46.191603 -361.813973) (xy 46.161879 -361.76801)
			(xy 46.139032 -361.718269) (xy 46.123534 -361.665772) (xy 46.115702 -361.611599) (xy 46.115698 -361.556862)
			(xy 46.123521 -361.502687) (xy 46.139011 -361.450187) (xy 46.16185 -361.400443) (xy 46.191567 -361.354475)
			(xy 46.209204 -361.333542) (xy 46.209458 -361.333288) (xy 46.215063 -361.326214) (xy 46.221297 -361.309287)
			(xy 46.22165 -361.300268) (xy 46.22165 -361.233212) (xy 46.221298 -361.224194) (xy 46.215048 -361.207277)
			(xy 46.209458 -361.200192) (xy 46.209204 -361.200192) (xy 46.209204 -361.199938) (xy 46.191603 -361.178973)
			(xy 46.161879 -361.13301) (xy 46.139032 -361.083269) (xy 46.123534 -361.030772) (xy 46.115702 -360.976599)
			(xy 46.115698 -360.921862) (xy 46.123521 -360.867687) (xy 46.139011 -360.815187) (xy 46.16185 -360.765443)
			(xy 46.191567 -360.719475) (xy 46.209204 -360.698542) (xy 46.209458 -360.698288) (xy 46.215063 -360.691214)
			(xy 46.221297 -360.674287) (xy 46.22165 -360.665268) (xy 46.22165 -360.598212) (xy 46.221298 -360.589194)
			(xy 46.215048 -360.572277) (xy 46.209458 -360.565192) (xy 46.209204 -360.565192) (xy 46.209204 -360.564938)
			(xy 46.191603 -360.543973) (xy 46.161879 -360.49801) (xy 46.139032 -360.448269) (xy 46.123534 -360.395772)
			(xy 46.115702 -360.341599) (xy 46.115698 -360.286862) (xy 46.123521 -360.232687) (xy 46.139011 -360.180187)
			(xy 46.16185 -360.130443) (xy 46.191567 -360.084475) (xy 46.209204 -360.063542) (xy 46.209458 -360.063288)
			(xy 46.215063 -360.056214) (xy 46.221297 -360.039287) (xy 46.22165 -360.030268) (xy 46.22165 -359.963212)
			(xy 46.221298 -359.954194) (xy 46.215048 -359.937277) (xy 46.209458 -359.930192) (xy 46.209204 -359.930192)
			(xy 46.209204 -359.929938) (xy 46.19157 -359.909002) (xy 46.161857 -359.86303) (xy 46.13902 -359.813284)
			(xy 46.123528 -359.760784) (xy 46.115699 -359.706609) (xy 46.115224 -359.67924) (xy 46.115693 -359.651987)
			(xy 46.123445 -359.598034) (xy 46.138798 -359.545735) (xy 46.161438 -359.496152) (xy 46.190905 -359.450298)
			(xy 46.226598 -359.409104) (xy 46.267791 -359.373409) (xy 46.313645 -359.343942) (xy 46.363227 -359.3213)
			(xy 46.415526 -359.305947) (xy 46.469479 -359.298193) (xy 46.496732 -359.297732) (xy 46.524103 -359.298172)
			(xy 46.578284 -359.305995) (xy 46.630788 -359.321489) (xy 46.680534 -359.344337) (xy 46.726499 -359.374068)
			(xy 46.74743 -359.391712) (xy 46.747684 -359.391966) (xy 46.754765 -359.39756) (xy 46.771686 -359.4038)
			(xy 46.780704 -359.404158) (xy 46.84776 -359.404158) (xy 46.856776 -359.403791) (xy 46.873694 -359.397551)
			(xy 46.88078 -359.391966) (xy 46.88078 -359.391712) (xy 46.881034 -359.391712) (xy 46.901967 -359.374071)
			(xy 46.947935 -359.344347) (xy 46.997681 -359.321501) (xy 47.050183 -359.306005) (xy 47.104361 -359.298176)
			(xy 47.159103 -359.298176) (xy 47.213281 -359.306005) (xy 47.265783 -359.321501) (xy 47.315529 -359.344347)
			(xy 47.361497 -359.374071) (xy 47.38243 -359.391712) (xy 47.382684 -359.391966) (xy 47.389765 -359.39756)
			(xy 47.406686 -359.4038) (xy 47.415704 -359.404158) (xy 47.48276 -359.404158) (xy 47.491776 -359.403791)
			(xy 47.508694 -359.397551) (xy 47.51578 -359.391966) (xy 47.51578 -359.391712) (xy 47.516034 -359.391712)
			(xy 47.536982 -359.374092) (xy 47.58295 -359.344377) (xy 47.632694 -359.321537) (xy 47.685191 -359.306042)
			(xy 47.739364 -359.298209) (xy 47.766732 -359.297732) (xy 47.793558 -359.298162) (xy 47.846678 -359.305703)
			(xy 47.898219 -359.320605) (xy 47.947167 -359.342574) (xy 47.992559 -359.371178) (xy 48.033501 -359.405853)
			(xy 48.069187 -359.445917) (xy 48.098914 -359.490581) (xy 48.122097 -359.538966) (xy 48.13828 -359.590119)
			(xy 48.14316 -359.616502) (xy 48.144938 -359.627424) (xy 48.156876 -359.645458) (xy 48.240442 -359.697274)
			(xy 48.262032 -359.700068) (xy 48.272446 -359.69702) (xy 48.299366 -359.689407) (xy 48.354711 -359.681252)
			(xy 48.382682 -359.680764) (xy 48.410053 -359.681225) (xy 48.464233 -359.689042) (xy 48.516736 -359.704531)
			(xy 48.566483 -359.727374) (xy 48.612449 -359.757101) (xy 48.63338 -359.774744) (xy 48.633634 -359.774998)
			(xy 48.640735 -359.780563) (xy 48.657641 -359.786823) (xy 48.666654 -359.78719) (xy 48.73371 -359.78719)
			(xy 48.742728 -359.78684) (xy 48.759645 -359.780588) (xy 48.76673 -359.774998) (xy 48.76673 -359.774744)
			(xy 48.766984 -359.774744) (xy 48.787917 -359.757103) (xy 48.833885 -359.727379) (xy 48.883631 -359.704533)
			(xy 48.936133 -359.689037) (xy 48.990311 -359.681208) (xy 49.045053 -359.681208) (xy 49.099231 -359.689037)
			(xy 49.151733 -359.704533) (xy 49.201479 -359.727379) (xy 49.247447 -359.757103) (xy 49.26838 -359.774744)
			(xy 49.268634 -359.774998) (xy 49.275735 -359.780563) (xy 49.292641 -359.786823) (xy 49.301654 -359.78719)
			(xy 49.36871 -359.78719) (xy 49.377728 -359.78684) (xy 49.394645 -359.780588) (xy 49.40173 -359.774998)
			(xy 49.40173 -359.774744) (xy 49.401984 -359.774744) (xy 49.422917 -359.757103) (xy 49.468885 -359.727379)
			(xy 49.518631 -359.704533) (xy 49.571133 -359.689037) (xy 49.625311 -359.681208) (xy 49.680053 -359.681208)
			(xy 49.734231 -359.689037) (xy 49.786733 -359.704533) (xy 49.836479 -359.727379) (xy 49.882447 -359.757103)
			(xy 49.90338 -359.774744) (xy 49.903634 -359.774998) (xy 49.910735 -359.780563) (xy 49.927641 -359.786823)
			(xy 49.936654 -359.78719) (xy 50.00371 -359.78719) (xy 50.012728 -359.78684) (xy 50.029645 -359.780588)
			(xy 50.03673 -359.774998) (xy 50.03673 -359.774744) (xy 50.036984 -359.774744) (xy 50.057917 -359.757106)
			(xy 50.103889 -359.727392) (xy 50.153636 -359.704555) (xy 50.206137 -359.689064) (xy 50.260313 -359.681237)
			(xy 50.287682 -359.680764) (xy 50.288444 -359.680764) (xy 50.318219 -359.681365) (xy 50.377036 -359.690673)
			(xy 50.405538 -359.699306) (xy 50.415444 -359.702608) (xy 50.436526 -359.700576) (xy 50.519584 -359.655364)
			(xy 50.532284 -359.639108) (xy 50.535078 -359.628948) (xy 50.542719 -359.602235) (xy 50.564657 -359.551191)
			(xy 50.59377 -359.50387) (xy 50.629442 -359.461274) (xy 50.670916 -359.424306) (xy 50.717316 -359.393746)
			(xy 50.76766 -359.370244) (xy 50.82088 -359.354295) (xy 50.875852 -359.346237) (xy 50.903632 -359.345738)
			(xy 50.932527 -359.346241) (xy 50.989656 -359.354951) (xy 51.044816 -359.372184) (xy 51.096745 -359.397542)
			(xy 51.120802 -359.413556) (xy 51.128422 -359.41889) (xy 51.146964 -359.423462) (xy 51.233578 -359.411778)
			(xy 51.249834 -359.402888) (xy 51.256184 -359.395522) (xy 51.274429 -359.374664) (xy 51.315856 -359.33786)
			(xy 51.362173 -359.30744) (xy 51.412405 -359.284044) (xy 51.465495 -359.268163) (xy 51.520323 -359.260134)
			(xy 51.54803 -359.259632) (xy 51.573982 -359.26006) (xy 51.625404 -359.267112) (xy 51.675397 -359.281066)
			(xy 51.723038 -359.301667) (xy 51.767447 -359.328534) (xy 51.807806 -359.36117) (xy 51.825906 -359.379774)
			(xy 51.825906 -359.380028) (xy 51.832847 -359.386731) (xy 51.85034 -359.394831) (xy 51.859942 -359.395776)
			(xy 51.939698 -359.400348) (xy 51.957986 -359.394252) (xy 51.965606 -359.387902) (xy 51.986326 -359.370947)
			(xy 52.031651 -359.34245) (xy 52.080513 -359.320564) (xy 52.131953 -359.305717) (xy 52.184963 -359.298202)
			(xy 52.211732 -359.297732) (xy 52.239103 -359.298172) (xy 52.293284 -359.305995) (xy 52.345788 -359.321489)
			(xy 52.395534 -359.344337) (xy 52.441499 -359.374068) (xy 52.46243 -359.391712) (xy 52.462684 -359.391966)
			(xy 52.469765 -359.39756) (xy 52.486686 -359.4038) (xy 52.495704 -359.404158) (xy 52.56276 -359.404158)
			(xy 52.571776 -359.403791) (xy 52.588694 -359.397551) (xy 52.59578 -359.391966) (xy 52.59578 -359.391712)
			(xy 52.596034 -359.391712) (xy 52.616982 -359.374092) (xy 52.66295 -359.344377) (xy 52.712694 -359.321537)
			(xy 52.765191 -359.306042) (xy 52.819364 -359.298209) (xy 52.846732 -359.297732) (xy 52.873988 -359.298125)
			(xy 52.927943 -359.305888) (xy 52.980245 -359.32125) (xy 53.029828 -359.343899) (xy 53.075683 -359.373374)
			(xy 53.116876 -359.409075) (xy 53.152569 -359.450275) (xy 53.182036 -359.496136) (xy 53.204675 -359.545723)
			(xy 53.220028 -359.598027) (xy 53.22778 -359.651984) (xy 53.22824 -359.67924) (xy 53.22824 -359.679748)
			(xy 53.227695 -359.707631) (xy 53.219541 -359.762798) (xy 53.203442 -359.81619) (xy 53.179741 -359.866669)
			(xy 53.148944 -359.91316) (xy 53.130704 -359.934256) (xy 53.124354 -359.941114) (xy 53.117496 -359.958894)
			(xy 53.11775 -360.045762) (xy 53.124354 -360.063034) (xy 53.130704 -360.070146) (xy 53.149106 -360.091278)
			(xy 53.180168 -360.137913) (xy 53.204071 -360.188592) (xy 53.2203 -360.242224) (xy 53.228505 -360.297653)
			(xy 53.229002 -360.32567) (xy 53.228517 -360.352922) (xy 53.220764 -360.406873) (xy 53.205411 -360.459171)
			(xy 53.182772 -360.508751) (xy 53.153306 -360.554605) (xy 53.117615 -360.595798) (xy 53.076424 -360.631492)
			(xy 53.030572 -360.66096) (xy 52.980993 -360.683603) (xy 52.928696 -360.698959) (xy 52.874746 -360.706715)
			(xy 52.847494 -360.707178) (xy 52.819383 -360.706684) (xy 52.763768 -360.698437) (xy 52.709964 -360.682124)
			(xy 52.659135 -360.658096) (xy 52.612379 -360.626873) (xy 52.591208 -360.608372) (xy 52.58435 -360.602276)
			(xy 52.567586 -360.595418) (xy 52.481734 -360.593894) (xy 52.464716 -360.599736) (xy 52.457604 -360.605832)
			(xy 52.4369 -360.622757) (xy 52.391624 -360.651213) (xy 52.342812 -360.673053) (xy 52.291423 -360.687848)
			(xy 52.23847 -360.695308) (xy 52.211732 -360.695748) (xy 52.185781 -360.695285) (xy 52.13436 -360.688242)
			(xy 52.084367 -360.674294) (xy 52.036727 -360.6537) (xy 51.992316 -360.626839) (xy 51.951956 -360.594207)
			(xy 51.933856 -360.575606) (xy 51.933856 -360.575352) (xy 51.926931 -360.568631) (xy 51.909426 -360.560541)
			(xy 51.89982 -360.559604) (xy 51.820064 -360.555032) (xy 51.801776 -360.561128) (xy 51.794156 -360.567478)
			(xy 51.773411 -360.584402) (xy 51.728093 -360.612904) (xy 51.679237 -360.634796) (xy 51.627803 -360.64965)
			(xy 51.574798 -360.657174) (xy 51.54803 -360.657648) (xy 51.519137 -360.6571) (xy 51.46201 -360.6484)
			(xy 51.40685 -360.631181) (xy 51.35492 -360.605836) (xy 51.33086 -360.58983) (xy 51.32324 -360.584496)
			(xy 51.304698 -360.579924) (xy 51.218084 -360.591608) (xy 51.201828 -360.600498) (xy 51.195478 -360.607864)
			(xy 51.17592 -360.629454) (xy 51.168882 -360.637388) (xy 51.161396 -360.657203) (xy 51.161442 -360.667808)
			(xy 51.166014 -360.753406) (xy 51.175666 -360.772456) (xy 51.183794 -360.77906) (xy 51.205176 -360.797302)
			(xy 51.242916 -360.838946) (xy 51.274139 -360.885676) (xy 51.298169 -360.936481) (xy 51.314486 -360.990261)
			(xy 51.322737 -361.045853) (xy 51.32324 -361.073954) (xy 51.322702 -361.101204) (xy 51.314952 -361.155151)
			(xy 51.299604 -361.207445) (xy 51.276969 -361.257023) (xy 51.247509 -361.302875) (xy 51.211823 -361.344067)
			(xy 51.170638 -361.379762) (xy 51.124792 -361.409231) (xy 51.075219 -361.431876) (xy 51.022927 -361.447236)
			(xy 50.968982 -361.454996) (xy 50.941732 -361.455462) (xy 50.941478 -361.455462) (xy 50.913612 -361.454993)
			(xy 50.858474 -361.446874) (xy 50.805111 -361.430798) (xy 50.77968 -361.419394) (xy 50.779426 -361.419394)
			(xy 50.769836 -361.415439) (xy 50.749119 -361.414792) (xy 50.739294 -361.418124) (xy 50.660554 -361.449112)
			(xy 50.646076 -361.46359) (xy 50.642012 -361.473496) (xy 50.630964 -361.499689) (xy 50.602339 -361.548798)
			(xy 50.56674 -361.593113) (xy 50.524956 -361.631652) (xy 50.477913 -361.663561) (xy 50.426655 -361.688132)
			(xy 50.372317 -361.70482) (xy 50.316104 -361.713257) (xy 50.287682 -361.71378) (xy 50.260311 -361.713329)
			(xy 50.206131 -361.705509) (xy 50.153628 -361.690016) (xy 50.103881 -361.667171) (xy 50.057915 -361.637443)
			(xy 50.036984 -361.6198) (xy 50.03673 -361.619546) (xy 50.029644 -361.613959) (xy 50.012727 -361.607714)
			(xy 50.00371 -361.607354) (xy 49.936654 -361.607354) (xy 49.927638 -361.607725) (xy 49.910721 -361.613962)
			(xy 49.903634 -361.619546) (xy 49.903634 -361.6198) (xy 49.90338 -361.6198) (xy 49.882447 -361.637441)
			(xy 49.836479 -361.667165) (xy 49.786733 -361.690011) (xy 49.734231 -361.705507) (xy 49.680053 -361.713336)
			(xy 49.625311 -361.713336) (xy 49.571133 -361.705507) (xy 49.518631 -361.690011) (xy 49.468885 -361.667165)
			(xy 49.422917 -361.637441) (xy 49.401984 -361.6198) (xy 49.40173 -361.619546) (xy 49.394644 -361.613959)
			(xy 49.377727 -361.607714) (xy 49.36871 -361.607354) (xy 49.301654 -361.607354) (xy 49.292638 -361.607725)
			(xy 49.275721 -361.613962) (xy 49.268634 -361.619546) (xy 49.268634 -361.6198) (xy 49.26838 -361.6198)
			(xy 49.247447 -361.637441) (xy 49.201479 -361.667165) (xy 49.151733 -361.690011) (xy 49.099231 -361.705507)
			(xy 49.045053 -361.713336) (xy 48.990311 -361.713336) (xy 48.936133 -361.705507) (xy 48.883631 -361.690011)
			(xy 48.833885 -361.667165) (xy 48.787917 -361.637441) (xy 48.766984 -361.6198) (xy 48.76673 -361.619546)
			(xy 48.759644 -361.613959) (xy 48.742727 -361.607714) (xy 48.73371 -361.607354) (xy 48.666654 -361.607354)
			(xy 48.657638 -361.607725) (xy 48.640721 -361.613962) (xy 48.633634 -361.619546) (xy 48.633634 -361.6198)
			(xy 48.63338 -361.6198) (xy 48.612429 -361.637415) (xy 48.566461 -361.667131) (xy 48.516718 -361.689971)
			(xy 48.464222 -361.705468) (xy 48.41005 -361.713302) (xy 48.382682 -361.71378) (xy 48.382174 -361.71378)
			(xy 48.358643 -361.713421) (xy 48.311942 -361.707594) (xy 48.266312 -361.696071) (xy 48.244252 -361.687872)
			(xy 48.243998 -361.687872) (xy 48.234838 -361.684775) (xy 48.215519 -361.684897) (xy 48.206406 -361.688126)
			(xy 48.14189 -361.714542) (xy 48.133064 -361.718588) (xy 48.119088 -361.732038) (xy 48.114712 -361.740704)
			(xy 48.102724 -361.766129) (xy 48.072367 -361.813437) (xy 48.05426 -361.834938) (xy 48.054006 -361.835192)
			(xy 48.048417 -361.842277) (xy 48.042172 -361.859195) (xy 48.041814 -361.868212) (xy 48.041814 -361.935268)
			(xy 48.042184 -361.944284) (xy 48.048422 -361.961201) (xy 48.054006 -361.968288) (xy 48.05426 -361.968288)
			(xy 48.05426 -361.968542) (xy 48.071879 -361.98949) (xy 48.101595 -362.035458) (xy 48.124436 -362.085201)
			(xy 48.139931 -362.137699) (xy 48.147764 -362.191872) (xy 48.14824 -362.21924) (xy 48.147759 -362.246491)
			(xy 48.139998 -362.300437) (xy 48.12464 -362.35273) (xy 48.101996 -362.402305) (xy 48.072529 -362.448154)
			(xy 48.036837 -362.489343) (xy 47.995647 -362.525034) (xy 47.949798 -362.5545) (xy 47.900222 -362.577143)
			(xy 47.847929 -362.5925) (xy 47.793983 -362.60026) (xy 47.766732 -362.600748) (xy 47.737254 -362.600203)
			(xy 47.679001 -362.591137) (xy 47.622836 -362.573217) (xy 47.570096 -362.546868) (xy 47.522039 -362.512719)
			(xy 47.50054 -362.492544) (xy 47.493193 -362.486026) (xy 47.475042 -362.478573) (xy 47.465234 -362.478066)
			(xy 47.411894 -362.478066) (xy 47.405036 -362.485432) (xy 47.398486 -362.492754) (xy 47.391052 -362.510924)
			(xy 47.390558 -362.520738) (xy 47.390558 -362.552742) (xy 47.391043 -362.562556) (xy 47.39849 -362.58072)
			(xy 47.405036 -362.588048) (xy 47.42523 -362.609529) (xy 47.459372 -362.657593) (xy 47.485715 -362.710337)
			(xy 47.503632 -362.766506) (xy 47.512694 -362.824762) (xy 47.51324 -362.85424) (xy 47.512759 -362.881491)
			(xy 47.504998 -362.935437) (xy 47.48964 -362.98773) (xy 47.466996 -363.037305) (xy 47.437529 -363.083154)
			(xy 47.401837 -363.124343) (xy 47.360647 -363.160034) (xy 47.314798 -363.1895) (xy 47.265222 -363.212143)
			(xy 47.212929 -363.2275) (xy 47.158983 -363.23526) (xy 47.131732 -363.235748) (xy 47.104362 -363.235276)
			(xy 47.050183 -363.227461) (xy 46.997679 -363.211974) (xy 46.947932 -363.189134) (xy 46.901965 -363.159409)
			(xy 46.881034 -363.141768) (xy 46.88078 -363.141514) (xy 46.873702 -363.135914) (xy 46.856779 -363.129675)
			(xy 46.84776 -363.129322) (xy 46.780704 -363.129322) (xy 46.771687 -363.129676) (xy 46.754769 -363.135925)
			(xy 46.747684 -363.141514) (xy 46.747684 -363.141768) (xy 46.74743 -363.141768) (xy 46.726493 -363.159402)
			(xy 46.680522 -363.189115) (xy 46.630776 -363.211953) (xy 46.578276 -363.227445) (xy 46.524101 -363.235274)
			(xy 46.496732 -363.235748) (xy 46.469483 -363.235192) (xy 46.41554 -363.227441) (xy 46.363249 -363.212092)
			(xy 46.313675 -363.189457) (xy 46.267826 -363.159998) (xy 46.226637 -363.124314) (xy 46.190945 -363.083131)
			(xy 46.161477 -363.037288) (xy 46.138833 -362.987718) (xy 46.123474 -362.93543) (xy 46.115713 -362.881489)
			(xy 46.115224 -362.85424) (xy 36.238634 -362.85424) (xy 36.243366 -362.859521) (xy 36.274139 -362.906034)
			(xy 36.297811 -362.956531) (xy 36.313879 -363.009938) (xy 36.321999 -363.065114) (xy 36.322508 -363.093)
			(xy 36.321999 -363.120886) (xy 36.313879 -363.176062) (xy 36.297811 -363.229469) (xy 36.274139 -363.279966)
			(xy 36.243366 -363.326479) (xy 36.206149 -363.368016) (xy 36.163281 -363.403691) (xy 36.115675 -363.432745)
			(xy 36.064346 -363.454557) (xy 36.010389 -363.468663) (xy 35.954952 -363.474763) (xy 35.899218 -363.472726)
			(xy 35.844375 -363.462596) (xy 35.791591 -363.444589) (xy 35.741991 -363.419088) (xy 35.696633 -363.386637)
			(xy 35.656484 -363.347928) (xy 35.622398 -363.303785) (xy 35.595102 -363.25515) (xy 35.575179 -363.203059)
			(xy 35.563053 -363.148622) (xy 35.558982 -363.093) (xy 34.165612 -363.093) (xy 33.530544 -363.728)
			(xy 34.161982 -363.728) (xy 34.166053 -363.672378) (xy 34.178179 -363.617941) (xy 34.198102 -363.56585)
			(xy 34.225398 -363.517215) (xy 34.259484 -363.473072) (xy 34.299633 -363.434363) (xy 34.344991 -363.401912)
			(xy 34.394591 -363.376411) (xy 34.447375 -363.358404) (xy 34.502218 -363.348274) (xy 34.557952 -363.346237)
			(xy 34.613389 -363.352337) (xy 34.667346 -363.366443) (xy 34.718675 -363.388255) (xy 34.766281 -363.417309)
			(xy 34.809149 -363.452984) (xy 34.846366 -363.494521) (xy 34.877139 -363.541034) (xy 34.900811 -363.591531)
			(xy 34.916879 -363.644938) (xy 34.924999 -363.700114) (xy 34.925508 -363.728) (xy 34.924999 -363.755886)
			(xy 34.916879 -363.811062) (xy 34.900811 -363.864469) (xy 34.877139 -363.914966) (xy 34.846366 -363.961479)
			(xy 34.809149 -364.003016) (xy 34.766281 -364.038691) (xy 34.718675 -364.067745) (xy 34.667346 -364.089557)
			(xy 34.613389 -364.103663) (xy 34.564886 -364.109) (xy 35.559492 -364.109) (xy 35.559978 -364.081749)
			(xy 35.567734 -364.027801) (xy 35.583089 -363.975506) (xy 35.605731 -363.925929) (xy 35.635197 -363.880079)
			(xy 35.670888 -363.838888) (xy 35.712079 -363.803197) (xy 35.757929 -363.773731) (xy 35.807506 -363.751089)
			(xy 35.859801 -363.735734) (xy 35.913749 -363.727978) (xy 35.968251 -363.727978) (xy 36.022199 -363.735734)
			(xy 36.074494 -363.751089) (xy 36.124071 -363.773731) (xy 36.169921 -363.803197) (xy 36.211112 -363.838888)
			(xy 36.246803 -363.880079) (xy 36.276269 -363.925929) (xy 36.298911 -363.975506) (xy 36.314266 -364.027801)
			(xy 36.322022 -364.081749) (xy 36.322508 -364.109) (xy 36.322005 -364.137749) (xy 36.313352 -364.194592)
			(xy 36.296272 -364.249494) (xy 36.271152 -364.301214) (xy 36.238559 -364.348581) (xy 36.199231 -364.390525)
			(xy 36.176966 -364.40872) (xy 36.176712 -364.40872) (xy 36.168019 -364.416374) (xy 36.158097 -364.437277)
			(xy 36.157662 -364.448852) (xy 36.157916 -364.529116) (xy 36.158472 -364.540686) (xy 36.168676 -364.561457)
			(xy 36.177474 -364.568994) (xy 36.177728 -364.568994) (xy 36.2004 -364.587168) (xy 36.203652 -364.590584)
			(xy 39.286178 -364.590584) (xy 39.290249 -364.534962) (xy 39.302375 -364.480525) (xy 39.322298 -364.428434)
			(xy 39.349594 -364.379799) (xy 39.38368 -364.335656) (xy 39.423829 -364.296947) (xy 39.469187 -364.264496)
			(xy 39.518787 -364.238995) (xy 39.571571 -364.220988) (xy 39.626414 -364.210858) (xy 39.682148 -364.208821)
			(xy 39.737585 -364.214921) (xy 39.791542 -364.229027) (xy 39.842871 -364.250839) (xy 39.890477 -364.279893)
			(xy 39.933345 -364.315568) (xy 39.970562 -364.357105) (xy 40.001335 -364.403618) (xy 40.025007 -364.454115)
			(xy 40.041075 -364.507522) (xy 40.049195 -364.562698) (xy 40.049704 -364.590584) (xy 40.049195 -364.61847)
			(xy 40.041075 -364.673646) (xy 40.025007 -364.727053) (xy 40.001335 -364.77755) (xy 39.970562 -364.824063)
			(xy 39.933345 -364.8656) (xy 39.890477 -364.901275) (xy 39.842871 -364.930329) (xy 39.791542 -364.952141)
			(xy 39.737585 -364.966247) (xy 39.682148 -364.972347) (xy 39.626414 -364.97031) (xy 39.571571 -364.96018)
			(xy 39.518787 -364.942173) (xy 39.469187 -364.916672) (xy 39.423829 -364.884221) (xy 39.38368 -364.845512)
			(xy 39.349594 -364.801369) (xy 39.322298 -364.752734) (xy 39.302375 -364.700643) (xy 39.290249 -364.646206)
			(xy 39.286178 -364.590584) (xy 36.203652 -364.590584) (xy 36.240465 -364.629252) (xy 36.273688 -364.676923)
			(xy 36.299301 -364.729078) (xy 36.316712 -364.784513) (xy 36.32552 -364.841947) (xy 36.326064 -364.871)
			(xy 36.325578 -364.898251) (xy 36.317822 -364.952199) (xy 36.302467 -365.004494) (xy 36.279825 -365.054071)
			(xy 36.250359 -365.099921) (xy 36.214668 -365.141112) (xy 36.173477 -365.176803) (xy 36.127627 -365.206269)
			(xy 36.07805 -365.228911) (xy 36.025755 -365.244266) (xy 35.971807 -365.252022) (xy 35.917305 -365.252022)
			(xy 35.863357 -365.244266) (xy 35.811062 -365.228911) (xy 35.761485 -365.206269) (xy 35.715635 -365.176803)
			(xy 35.674444 -365.141112) (xy 35.638753 -365.099921) (xy 35.609287 -365.054071) (xy 35.586645 -365.004494)
			(xy 35.57129 -364.952199) (xy 35.563534 -364.898251) (xy 35.563048 -364.871) (xy 35.56353 -364.84225)
			(xy 35.572184 -364.785405) (xy 35.589267 -364.730502) (xy 35.614391 -364.678781) (xy 35.646989 -364.631415)
			(xy 35.686323 -364.589473) (xy 35.70859 -364.57128) (xy 35.708844 -364.57128) (xy 35.717546 -364.563635)
			(xy 35.727461 -364.542724) (xy 35.727894 -364.531148) (xy 35.72764 -364.450884) (xy 35.7271 -364.439312)
			(xy 35.716886 -364.41854) (xy 35.708082 -364.411006) (xy 35.707828 -364.411006) (xy 35.685147 -364.392843)
			(xy 35.645085 -364.350755) (xy 35.611864 -364.303082) (xy 35.586253 -364.250925) (xy 35.568843 -364.195488)
			(xy 35.560036 -364.138053) (xy 35.559492 -364.109) (xy 34.564886 -364.109) (xy 34.557952 -364.109763)
			(xy 34.502218 -364.107726) (xy 34.447375 -364.097596) (xy 34.394591 -364.079589) (xy 34.344991 -364.054088)
			(xy 34.299633 -364.021637) (xy 34.259484 -363.982928) (xy 34.225398 -363.938785) (xy 34.198102 -363.89015)
			(xy 34.178179 -363.838059) (xy 34.166053 -363.783622) (xy 34.161982 -363.728) (xy 33.530544 -363.728)
			(xy 33.492186 -363.766354) (xy 33.485339 -363.773751) (xy 33.477611 -363.792351) (xy 33.4772 -363.802422)
			(xy 33.4772 -365.883698) (xy 34.673284 -365.883698) (xy 34.677355 -365.828076) (xy 34.689481 -365.773639)
			(xy 34.709404 -365.721548) (xy 34.7367 -365.672913) (xy 34.770786 -365.62877) (xy 34.810935 -365.590061)
			(xy 34.856293 -365.55761) (xy 34.905893 -365.532109) (xy 34.958677 -365.514102) (xy 35.01352 -365.503972)
			(xy 35.069254 -365.501935) (xy 35.124691 -365.508035) (xy 35.178648 -365.522141) (xy 35.229977 -365.543953)
			(xy 35.277583 -365.573007) (xy 35.320451 -365.608682) (xy 35.34641 -365.637654) (xy 39.929749 -365.637654)
			(xy 39.929749 -365.583146) (xy 39.937507 -365.529193) (xy 39.952864 -365.476893) (xy 39.975508 -365.427311)
			(xy 40.004978 -365.381456) (xy 40.040674 -365.340263) (xy 40.081869 -365.304568) (xy 40.127725 -365.2751)
			(xy 40.177308 -365.252458) (xy 40.229608 -365.237104) (xy 40.283562 -365.229348) (xy 40.310816 -365.228886)
			(xy 40.338124 -365.229343) (xy 40.392178 -365.237159) (xy 40.444565 -365.252601) (xy 40.494216 -365.275353)
			(xy 40.540117 -365.304951) (xy 40.58133 -365.34079) (xy 40.617013 -365.382137) (xy 40.646437 -365.428149)
			(xy 40.669002 -365.477886) (xy 40.684246 -365.530332) (xy 40.688514 -365.557308) (xy 40.690323 -365.566562)
			(xy 40.699564 -365.582978) (xy 40.706548 -365.589312) (xy 40.75938 -365.633) (xy 40.766929 -365.638764)
			(xy 40.784934 -365.64477) (xy 40.794432 -365.644684) (xy 40.813736 -365.644176) (xy 40.840309 -365.644685)
			(xy 40.89294 -365.652065) (xy 40.944038 -365.666678) (xy 40.992614 -365.68824) (xy 41.037727 -365.716335)
			(xy 41.078505 -365.750418) (xy 41.114158 -365.78983) (xy 41.129458 -365.811562) (xy 41.135046 -365.81969)
			(xy 41.151302 -365.830866) (xy 41.239948 -365.849154) (xy 41.259252 -365.845852) (xy 41.267634 -365.840518)
			(xy 41.290547 -365.826607) (xy 41.339456 -365.80467) (xy 41.390957 -365.789802) (xy 41.444032 -365.782297)
			(xy 41.470834 -365.781844) (xy 41.49808 -365.782428) (xy 41.552017 -365.790188) (xy 41.604301 -365.805544)
			(xy 41.653868 -365.828184) (xy 41.699708 -365.857648) (xy 41.740889 -365.893335) (xy 41.776573 -365.934519)
			(xy 41.806032 -365.980362) (xy 41.828668 -366.02993) (xy 41.844019 -366.082216) (xy 41.851774 -366.136154)
			(xy 41.851774 -366.190646) (xy 41.844019 -366.244584) (xy 41.828668 -366.29687) (xy 41.806032 -366.346438)
			(xy 41.776573 -366.392281) (xy 41.740889 -366.433465) (xy 41.699708 -366.469152) (xy 41.653868 -366.498616)
			(xy 41.604301 -366.521256) (xy 41.552017 -366.536612) (xy 41.49808 -366.544372) (xy 41.470834 -366.54486)
			(xy 41.43883 -366.54359) (xy 41.427908 -366.542574) (xy 41.407334 -366.549686) (xy 41.344342 -366.60963)
			(xy 41.337055 -366.617329) (xy 41.32892 -366.63688) (xy 41.328594 -366.647476) (xy 41.328594 -366.647984)
			(xy 41.328848 -366.659414) (xy 41.328848 -366.659922) (xy 41.328275 -366.687159) (xy 41.320494 -366.741074)
			(xy 41.305123 -366.793335) (xy 41.282474 -366.842877) (xy 41.253008 -366.888694) (xy 41.217324 -366.929853)
			(xy 41.176148 -366.965517) (xy 41.130317 -366.994962) (xy 41.080764 -367.017587) (xy 41.028496 -367.032933)
			(xy 40.974577 -367.040688) (xy 40.94734 -367.041176) (xy 40.920087 -367.040707) (xy 40.866134 -367.032955)
			(xy 40.813835 -367.017602) (xy 40.764252 -366.994962) (xy 40.718398 -366.965495) (xy 40.677204 -366.929802)
			(xy 40.641509 -366.888609) (xy 40.612042 -366.842755) (xy 40.5894 -366.793173) (xy 40.574047 -366.740874)
			(xy 40.566293 -366.686921) (xy 40.565832 -366.659668) (xy 40.56624 -366.634507) (xy 40.572854 -366.584621)
			(xy 40.585963 -366.536036) (xy 40.60534 -366.489593) (xy 40.617648 -366.467644) (xy 40.622474 -366.459516)
			(xy 40.625522 -366.440974) (xy 40.60952 -366.365028) (xy 40.607147 -366.356005) (xy 40.596996 -366.340372)
			(xy 40.589708 -366.334548) (xy 40.589454 -366.334294) (xy 40.569062 -366.318937) (xy 40.532164 -366.283659)
			(xy 40.500294 -366.243781) (xy 40.474019 -366.200014) (xy 40.453807 -366.153137) (xy 40.440019 -366.103986)
			(xy 40.436038 -366.07877) (xy 40.434224 -366.069518) (xy 40.424985 -366.053102) (xy 40.418004 -366.046766)
			(xy 40.365172 -366.003078) (xy 40.357639 -365.99729) (xy 40.339621 -365.991298) (xy 40.33012 -365.991394)
			(xy 40.310816 -365.991902) (xy 40.283562 -365.991452) (xy 40.229608 -365.983696) (xy 40.177308 -365.968342)
			(xy 40.127725 -365.9457) (xy 40.081869 -365.916232) (xy 40.040674 -365.880537) (xy 40.004978 -365.839344)
			(xy 39.975508 -365.793489) (xy 39.952864 -365.743907) (xy 39.937507 -365.691607) (xy 39.929749 -365.637654)
			(xy 35.34641 -365.637654) (xy 35.357668 -365.650219) (xy 35.388441 -365.696732) (xy 35.412113 -365.747229)
			(xy 35.428181 -365.800636) (xy 35.436301 -365.855812) (xy 35.43681 -365.883698) (xy 35.436301 -365.911584)
			(xy 35.428181 -365.96676) (xy 35.412113 -366.020167) (xy 35.391785 -366.06353) (xy 38.846504 -366.06353)
			(xy 38.850575 -366.007908) (xy 38.862701 -365.953471) (xy 38.882624 -365.90138) (xy 38.90992 -365.852745)
			(xy 38.944006 -365.808602) (xy 38.984155 -365.769893) (xy 39.029513 -365.737442) (xy 39.079113 -365.711941)
			(xy 39.131897 -365.693934) (xy 39.18674 -365.683804) (xy 39.242474 -365.681767) (xy 39.297911 -365.687867)
			(xy 39.351868 -365.701973) (xy 39.403197 -365.723785) (xy 39.450803 -365.752839) (xy 39.493671 -365.788514)
			(xy 39.530888 -365.830051) (xy 39.561661 -365.876564) (xy 39.585333 -365.927061) (xy 39.601401 -365.980468)
			(xy 39.609521 -366.035644) (xy 39.61003 -366.06353) (xy 39.609521 -366.091416) (xy 39.601401 -366.146592)
			(xy 39.585333 -366.199999) (xy 39.561661 -366.250496) (xy 39.530888 -366.297009) (xy 39.493671 -366.338546)
			(xy 39.450803 -366.374221) (xy 39.403197 -366.403275) (xy 39.351868 -366.425087) (xy 39.297911 -366.439193)
			(xy 39.242474 -366.445293) (xy 39.18674 -366.443256) (xy 39.131897 -366.433126) (xy 39.079113 -366.415119)
			(xy 39.029513 -366.389618) (xy 38.984155 -366.357167) (xy 38.944006 -366.318458) (xy 38.90992 -366.274315)
			(xy 38.882624 -366.22568) (xy 38.862701 -366.173589) (xy 38.850575 -366.119152) (xy 38.846504 -366.06353)
			(xy 35.391785 -366.06353) (xy 35.388441 -366.070664) (xy 35.357668 -366.117177) (xy 35.320451 -366.158714)
			(xy 35.277583 -366.194389) (xy 35.229977 -366.223443) (xy 35.178648 -366.245255) (xy 35.124691 -366.259361)
			(xy 35.069254 -366.265461) (xy 35.01352 -366.263424) (xy 34.958677 -366.253294) (xy 34.905893 -366.235287)
			(xy 34.856293 -366.209786) (xy 34.810935 -366.177335) (xy 34.770786 -366.138626) (xy 34.7367 -366.094483)
			(xy 34.709404 -366.045848) (xy 34.689481 -365.993757) (xy 34.677355 -365.93932) (xy 34.673284 -365.883698)
			(xy 33.4772 -365.883698) (xy 33.4772 -366.005872) (xy 33.476691 -366.025809) (xy 33.468888 -366.064915)
			(xy 33.453635 -366.101758) (xy 33.431511 -366.134934) (xy 33.417764 -366.149382) (xy 32.765595 -366.8014)
			(xy 33.425382 -366.8014) (xy 33.429453 -366.745778) (xy 33.441579 -366.691341) (xy 33.461502 -366.63925)
			(xy 33.488798 -366.590615) (xy 33.522884 -366.546472) (xy 33.563033 -366.507763) (xy 33.608391 -366.475312)
			(xy 33.657991 -366.449811) (xy 33.710775 -366.431804) (xy 33.765618 -366.421674) (xy 33.821352 -366.419637)
			(xy 33.876789 -366.425737) (xy 33.930746 -366.439843) (xy 33.982075 -366.461655) (xy 34.029681 -366.490709)
			(xy 34.072549 -366.526384) (xy 34.109766 -366.567921) (xy 34.140539 -366.614434) (xy 34.164211 -366.664931)
			(xy 34.180279 -366.718338) (xy 34.188399 -366.773514) (xy 34.188908 -366.8014) (xy 34.188399 -366.829286)
			(xy 34.180279 -366.884462) (xy 34.164211 -366.937869) (xy 34.140539 -366.988366) (xy 34.109766 -367.034879)
			(xy 34.072549 -367.076416) (xy 34.029681 -367.112091) (xy 33.982075 -367.141145) (xy 33.930746 -367.162957)
			(xy 33.876789 -367.177063) (xy 33.821352 -367.183163) (xy 33.765618 -367.181126) (xy 33.710775 -367.170996)
			(xy 33.657991 -367.152989) (xy 33.608391 -367.127488) (xy 33.563033 -367.095037) (xy 33.522884 -367.056328)
			(xy 33.488798 -367.012185) (xy 33.461502 -366.96355) (xy 33.441579 -366.911459) (xy 33.429453 -366.857022)
			(xy 33.425382 -366.8014) (xy 32.765595 -366.8014) (xy 32.323786 -367.243106) (xy 32.316931 -367.250501)
			(xy 32.309185 -367.2691) (xy 32.3088 -367.279174) (xy 32.3088 -367.284) (xy 35.050982 -367.284) (xy 35.055053 -367.228378)
			(xy 35.067179 -367.173941) (xy 35.087102 -367.12185) (xy 35.114398 -367.073215) (xy 35.148484 -367.029072)
			(xy 35.188633 -366.990363) (xy 35.233991 -366.957912) (xy 35.283591 -366.932411) (xy 35.336375 -366.914404)
			(xy 35.391218 -366.904274) (xy 35.446952 -366.902237) (xy 35.502389 -366.908337) (xy 35.556346 -366.922443)
			(xy 35.607675 -366.944255) (xy 35.655281 -366.973309) (xy 35.698149 -367.008984) (xy 35.735366 -367.050521)
			(xy 35.766139 -367.097034) (xy 35.789811 -367.147531) (xy 35.805879 -367.200938) (xy 35.813999 -367.256114)
			(xy 35.814508 -367.284) (xy 35.813999 -367.311886) (xy 35.805879 -367.367062) (xy 35.789811 -367.420469)
			(xy 35.766139 -367.470966) (xy 35.735366 -367.517479) (xy 35.698149 -367.559016) (xy 35.655281 -367.594691)
			(xy 35.607675 -367.623745) (xy 35.556346 -367.645557) (xy 35.502389 -367.659663) (xy 35.446952 -367.665763)
			(xy 35.391218 -367.663726) (xy 35.336375 -367.653596) (xy 35.283591 -367.635589) (xy 35.233991 -367.610088)
			(xy 35.188633 -367.577637) (xy 35.148484 -367.538928) (xy 35.114398 -367.494785) (xy 35.087102 -367.44615)
			(xy 35.067179 -367.394059) (xy 35.055053 -367.339622) (xy 35.050982 -367.284) (xy 32.3088 -367.284)
			(xy 32.3088 -369.198652) (xy 32.308321 -369.218589) (xy 32.300573 -369.257704) (xy 32.285364 -369.294564)
			(xy 32.263275 -369.327761) (xy 32.235151 -369.356027) (xy 32.202065 -369.378282) (xy 32.183832 -369.386358)
			(xy 32.169608 -369.3922) (xy 32.15259 -369.4176) (xy 32.15259 -369.433094) (xy 32.153077 -369.443103)
			(xy 32.160735 -369.461599) (xy 32.174888 -369.475756) (xy 32.193381 -369.48342) (xy 32.20339 -369.483894)
			(xy 32.305498 -369.483894) (xy 32.315397 -369.484413) (xy 32.322115 -369.487196) (xy 37.296342 -369.487196)
			(xy 37.300413 -369.431574) (xy 37.312539 -369.377137) (xy 37.332462 -369.325046) (xy 37.359758 -369.276411)
			(xy 37.393844 -369.232268) (xy 37.433993 -369.193559) (xy 37.479351 -369.161108) (xy 37.528951 -369.135607)
			(xy 37.581735 -369.1176) (xy 37.636578 -369.10747) (xy 37.692312 -369.105433) (xy 37.747749 -369.111533)
			(xy 37.801706 -369.125639) (xy 37.853035 -369.147451) (xy 37.900641 -369.176505) (xy 37.943509 -369.21218)
			(xy 37.980726 -369.253717) (xy 38.011499 -369.30023) (xy 38.035171 -369.350727) (xy 38.051239 -369.404134)
			(xy 38.059359 -369.45931) (xy 38.059868 -369.487196) (xy 38.059359 -369.515082) (xy 38.051239 -369.570258)
			(xy 38.035171 -369.623665) (xy 38.011499 -369.674162) (xy 37.980726 -369.720675) (xy 37.943509 -369.762212)
			(xy 37.900641 -369.797887) (xy 37.853035 -369.826941) (xy 37.801706 -369.848753) (xy 37.747749 -369.862859)
			(xy 37.692312 -369.868959) (xy 37.636578 -369.866922) (xy 37.581735 -369.856792) (xy 37.528951 -369.838785)
			(xy 37.479351 -369.813284) (xy 37.433993 -369.780833) (xy 37.393844 -369.742124) (xy 37.359758 -369.697981)
			(xy 37.332462 -369.649346) (xy 37.312539 -369.597255) (xy 37.300413 -369.542818) (xy 37.296342 -369.487196)
			(xy 32.322115 -369.487196) (xy 32.333693 -369.491992) (xy 32.341058 -369.498626) (xy 32.346646 -369.50396)
			(xy 32.354002 -369.51061) (xy 32.372302 -369.518201) (xy 32.382206 -369.518692) (xy 32.691578 -369.518692)
			(xy 32.711595 -369.519149) (xy 32.75086 -369.526962) (xy 32.787843 -369.542292) (xy 32.82112 -369.564549)
			(xy 32.835596 -369.578382) (xy 33.53435 -370.27739) (xy 33.541751 -370.28423) (xy 33.560349 -370.291948)
			(xy 33.570418 -370.292376) (xy 38.820344 -370.292376) (xy 38.830651 -370.291903) (xy 38.849598 -370.283787)
			(xy 38.863802 -370.26885) (xy 38.867842 -370.259356) (xy 38.90137 -370.169694) (xy 38.904453 -370.159906)
			(xy 38.903426 -370.139428) (xy 38.89451 -370.120964) (xy 38.887146 -370.113814) (xy 38.866893 -370.095616)
			(xy 38.831244 -370.054463) (xy 38.801811 -370.008658) (xy 38.779193 -369.959132) (xy 38.76385 -369.906892)
			(xy 38.756094 -369.853001) (xy 38.755574 -369.825778) (xy 38.756006 -369.799905) (xy 38.762999 -369.748635)
			(xy 38.776854 -369.698779) (xy 38.797317 -369.651252) (xy 38.824013 -369.606924) (xy 38.856452 -369.566609)
			(xy 38.89404 -369.531046) (xy 38.914832 -369.515644) (xy 38.923976 -369.50904) (xy 38.935152 -369.489482)
			(xy 38.942772 -369.389406) (xy 38.934898 -369.368324) (xy 38.92677 -369.36045) (xy 38.90894 -369.342441)
			(xy 38.877709 -369.302529) (xy 38.852037 -369.258834) (xy 38.832375 -369.212125) (xy 38.819068 -369.163225)
			(xy 38.812353 -369.112993) (xy 38.811962 -369.087654) (xy 38.812489 -369.058417) (xy 38.821407 -369.000627)
			(xy 38.839042 -368.944876) (xy 38.864982 -368.89247) (xy 38.898617 -368.844638) (xy 38.939159 -368.802502)
			(xy 38.985659 -368.767048) (xy 39.011098 -368.752628) (xy 39.011352 -368.752628) (xy 39.021622 -368.746137)
			(xy 39.035127 -368.725983) (xy 39.03726 -368.71402) (xy 39.048436 -368.619532) (xy 39.0398 -368.596164)
			(xy 39.030656 -368.588036) (xy 39.011232 -368.569856) (xy 38.977103 -368.529045) (xy 38.948973 -368.483889)
			(xy 38.927387 -368.435265) (xy 38.912762 -368.384113) (xy 38.905384 -368.331427) (xy 38.904926 -368.304826)
			(xy 38.905374 -368.278096) (xy 38.912836 -368.225159) (xy 38.927618 -368.173784) (xy 38.94943 -368.124976)
			(xy 38.977845 -368.079693) (xy 39.012305 -368.038822) (xy 39.052135 -368.003163) (xy 39.096555 -367.973417)
			(xy 39.144694 -367.950166) (xy 39.195608 -367.933865) (xy 39.2483 -367.924834) (xy 39.275004 -367.923572)
			(xy 39.286434 -367.923318) (xy 39.306246 -367.913158) (xy 39.36873 -367.834164) (xy 39.37381 -367.81232)
			(xy 39.371524 -367.801398) (xy 39.367835 -367.782372) (xy 39.363892 -367.743815) (xy 39.36365 -367.724436)
			(xy 39.36365 -367.724182) (xy 39.364136 -367.696931) (xy 39.371892 -367.642983) (xy 39.387247 -367.590688)
			(xy 39.409889 -367.541111) (xy 39.439355 -367.495261) (xy 39.475046 -367.45407) (xy 39.516237 -367.418379)
			(xy 39.562087 -367.388913) (xy 39.611664 -367.366271) (xy 39.663959 -367.350916) (xy 39.717907 -367.34316)
			(xy 39.772409 -367.34316) (xy 39.826357 -367.350916) (xy 39.878652 -367.366271) (xy 39.928229 -367.388913)
			(xy 39.974079 -367.418379) (xy 40.01527 -367.45407) (xy 40.050961 -367.495261) (xy 40.080427 -367.541111)
			(xy 40.103069 -367.590688) (xy 40.118424 -367.642983) (xy 40.12618 -367.696931) (xy 40.126666 -367.724182)
			(xy 40.126218 -367.750911) (xy 40.118754 -367.803847) (xy 40.103971 -367.855221) (xy 40.082159 -367.904027)
			(xy 40.053744 -367.949309) (xy 40.019284 -367.990179) (xy 39.979453 -368.025835) (xy 39.935034 -368.05558)
			(xy 39.886896 -368.07883) (xy 39.835982 -368.095129) (xy 39.783291 -368.104158) (xy 39.756588 -368.105436)
			(xy 39.745158 -368.10569) (xy 39.725346 -368.11585) (xy 39.662862 -368.194844) (xy 39.657782 -368.216688)
			(xy 39.660068 -368.22761) (xy 39.663756 -368.246636) (xy 39.667699 -368.285193) (xy 39.667942 -368.304572)
			(xy 39.667942 -368.304826) (xy 39.667416 -368.334064) (xy 39.658501 -368.391856) (xy 39.640868 -368.447609)
			(xy 39.61493 -368.500018) (xy 39.581296 -368.547852) (xy 39.540754 -368.589992) (xy 39.494255 -368.625448)
			(xy 39.468806 -368.639852) (xy 39.468552 -368.639852) (xy 39.458279 -368.646341) (xy 39.444765 -368.666494)
			(xy 39.442644 -368.67846) (xy 39.431468 -368.772948) (xy 39.440104 -368.796316) (xy 39.449248 -368.804444)
			(xy 39.468673 -368.822624) (xy 39.502803 -368.863434) (xy 39.530936 -368.90859) (xy 39.552524 -368.957214)
			(xy 39.567151 -369.008366) (xy 39.574532 -369.061053) (xy 39.574978 -369.087654) (xy 39.574544 -369.113525)
			(xy 39.567546 -369.164792) (xy 39.553687 -369.214644) (xy 39.53322 -369.262166) (xy 39.50652 -369.306488)
			(xy 39.474077 -369.346796) (xy 39.436487 -369.382352) (xy 39.41572 -369.397788) (xy 39.406576 -369.404392)
			(xy 39.3954 -369.42395) (xy 39.38778 -369.524026) (xy 39.395654 -369.545108) (xy 39.403782 -369.552982)
			(xy 39.421612 -369.570991) (xy 39.452843 -369.610902) (xy 39.478515 -369.654597) (xy 39.498176 -369.701306)
			(xy 39.51148 -369.750207) (xy 39.518193 -369.800439) (xy 39.51859 -369.825778) (xy 39.518087 -369.853)
			(xy 39.510311 -369.906888) (xy 39.494957 -369.959123) (xy 39.472336 -370.008647) (xy 39.442907 -370.054453)
			(xy 39.407267 -370.095613) (xy 39.387018 -370.113814) (xy 39.374826 -370.124482) (xy 39.367206 -370.154708)
			(xy 39.406322 -370.259356) (xy 39.41039 -370.268824) (xy 39.424612 -370.283711) (xy 39.443528 -370.29184)
			(xy 39.45382 -370.292376) (xy 39.641272 -370.292376) (xy 39.651336 -370.291939) (xy 39.669919 -370.284204)
			(xy 39.67734 -370.27739) (xy 40.236902 -369.717574) (xy 40.243744 -369.710174) (xy 40.251469 -369.691576)
			(xy 40.251888 -369.681506) (xy 40.251888 -368.56162) (xy 40.252345 -368.541603) (xy 40.260159 -368.502338)
			(xy 40.275489 -368.465355) (xy 40.297745 -368.432078) (xy 40.311578 -368.417602) (xy 44.71543 -364.01375)
			(xy 44.72993 -363.999948) (xy 44.76321 -363.977713) (xy 44.800184 -363.962387) (xy 44.839436 -363.95456)
			(xy 44.859448 -363.95406) (xy 57.048146 -363.95406) (xy 57.058212 -363.953627) (xy 57.0768 -363.945897)
			(xy 57.084214 -363.939074) (xy 80.118966 -340.904322) (xy 80.133465 -340.890519) (xy 80.166744 -340.868282)
			(xy 80.203719 -340.852957) (xy 80.242972 -340.845133) (xy 80.262984 -340.844632) (xy 84.79155 -340.844632)
			(xy 84.801617 -340.844201) (xy 84.820211 -340.836477) (xy 84.827618 -340.829646) (xy 86.19236 -339.465158)
			(xy 86.198855 -339.458022) (xy 86.206435 -339.440293) (xy 86.206953 -339.421019) (xy 86.204044 -339.411818)
			(xy 86.167468 -339.311234) (xy 86.143846 -339.293454) (xy 86.12886 -339.292184) (xy 86.100634 -339.289275)
			(xy 86.045427 -339.276171) (xy 85.992769 -339.255034) (xy 85.943824 -339.226329) (xy 85.899671 -339.19069)
			(xy 85.861285 -339.148904) (xy 85.829513 -339.101893) (xy 85.805055 -339.050693) (xy 85.788451 -338.996436)
			(xy 85.780068 -338.940317) (xy 85.77961 -338.911946) (xy 85.78007 -338.884691) (xy 85.787822 -338.830737)
			(xy 85.803174 -338.778434) (xy 85.825814 -338.728849) (xy 85.855281 -338.682992) (xy 85.890975 -338.641795)
			(xy 85.932169 -338.606098) (xy 85.978025 -338.576628) (xy 86.027608 -338.553984) (xy 86.079909 -338.538628)
			(xy 86.133864 -338.530872) (xy 86.161118 -338.530438) (xy 86.161372 -338.530438) (xy 86.186573 -338.530865)
			(xy 86.236532 -338.537534) (xy 86.285182 -338.550707) (xy 86.33168 -338.570156) (xy 86.35365 -338.582508)
			(xy 86.363556 -338.58835) (xy 86.3854 -338.590382) (xy 86.480142 -338.556854) (xy 86.49589 -338.54136)
			(xy 86.499954 -338.530946) (xy 86.510647 -338.504169) (xy 86.538933 -338.453928) (xy 86.574462 -338.408519)
			(xy 86.616425 -338.368979) (xy 86.663864 -338.336209) (xy 86.715697 -338.310958) (xy 86.770741 -338.2938)
			(xy 86.827742 -338.285127) (xy 86.85657 -338.284566) (xy 86.883825 -338.285027) (xy 86.937781 -338.29278)
			(xy 86.990084 -338.308133) (xy 87.039669 -338.330774) (xy 87.085528 -338.360241) (xy 87.126726 -338.395934)
			(xy 87.162426 -338.437127) (xy 87.191899 -338.482982) (xy 87.214547 -338.532564) (xy 87.227276 -338.575904)
			(xy 89.368122 -338.575904) (xy 89.368583 -338.548329) (xy 89.376535 -338.493756) (xy 89.392261 -338.440895)
			(xy 89.415432 -338.390849) (xy 89.445565 -338.34466) (xy 89.482034 -338.303289) (xy 89.502742 -338.285074)
			(xy 89.510836 -338.277536) (xy 89.520178 -338.257511) (xy 89.520776 -338.246466) (xy 89.520776 -338.168742)
			(xy 89.520192 -338.157694) (xy 89.510839 -338.137673) (xy 89.502742 -338.130134) (xy 89.482052 -338.111899)
			(xy 89.445579 -338.070536) (xy 89.415443 -338.024352) (xy 89.392273 -337.974308) (xy 89.376552 -337.921449)
			(xy 89.368609 -337.866878) (xy 89.368122 -337.839304) (xy 89.368559 -337.81205) (xy 89.376316 -337.758096)
			(xy 89.391673 -337.705796) (xy 89.414318 -337.656214) (xy 89.443788 -337.61036) (xy 89.479485 -337.569166)
			(xy 89.52068 -337.533472) (xy 89.566537 -337.504005) (xy 89.616121 -337.481364) (xy 89.668422 -337.466011)
			(xy 89.722376 -337.458257) (xy 89.74963 -337.457796) (xy 89.750138 -337.457796) (xy 89.78392 -337.45932)
			(xy 89.79408 -337.460336) (xy 89.813384 -337.45424) (xy 89.876376 -337.401408) (xy 89.883678 -337.394695)
			(xy 89.892954 -337.377183) (xy 89.89441 -337.367372) (xy 89.89441 -337.36661) (xy 89.8973 -337.338454)
			(xy 89.910505 -337.283414) (xy 89.931698 -337.230931) (xy 89.960416 -337.182155) (xy 89.996025 -337.138159)
			(xy 90.037746 -337.099908) (xy 90.084661 -337.068243) (xy 90.135741 -337.043859) (xy 90.189863 -337.027291)
			(xy 90.24584 -337.018903) (xy 90.27414 -337.018376) (xy 90.274394 -337.018376) (xy 90.292413 -337.018602)
			(xy 90.328288 -337.022033) (xy 90.346022 -337.025234) (xy 90.355674 -337.027012) (xy 90.374724 -337.023456)
			(xy 90.449654 -336.97545) (xy 90.461084 -336.959702) (xy 90.46337 -336.950304) (xy 90.470776 -336.923263)
			(xy 90.492409 -336.87154) (xy 90.521374 -336.823538) (xy 90.55705 -336.780288) (xy 90.598668 -336.742722)
			(xy 90.645333 -336.711648) (xy 90.696041 -336.687734) (xy 90.749702 -336.671494) (xy 90.805162 -336.663278)
			(xy 90.833194 -336.662776) (xy 90.860444 -336.663283) (xy 90.914391 -336.671039) (xy 90.958918 -336.684112)
			(xy 91.388946 -336.684112) (xy 91.389457 -336.656202) (xy 91.397589 -336.600977) (xy 91.41368 -336.547527)
			(xy 91.437389 -336.496992) (xy 91.468208 -336.450451) (xy 91.486482 -336.42935) (xy 91.492398 -336.422186)
			(xy 91.499038 -336.404851) (xy 91.499436 -336.395568) (xy 91.499436 -336.317844) (xy 91.492832 -336.300572)
			(xy 91.486482 -336.29346) (xy 91.468208 -336.272357) (xy 91.437381 -336.225819) (xy 91.413665 -336.175286)
			(xy 91.397567 -336.121835) (xy 91.389432 -336.066609) (xy 91.388946 -336.038698) (xy 91.389432 -336.011447)
			(xy 91.397188 -335.957499) (xy 91.412543 -335.905204) (xy 91.435185 -335.855627) (xy 91.464651 -335.809777)
			(xy 91.500342 -335.768586) (xy 91.541533 -335.732895) (xy 91.587383 -335.703429) (xy 91.63696 -335.680787)
			(xy 91.689255 -335.665432) (xy 91.743203 -335.657676) (xy 91.797705 -335.657676) (xy 91.851653 -335.665432)
			(xy 91.903948 -335.680787) (xy 91.953525 -335.703429) (xy 91.999375 -335.732895) (xy 92.040566 -335.768586)
			(xy 92.076257 -335.809777) (xy 92.105723 -335.855627) (xy 92.128365 -335.905204) (xy 92.14372 -335.957499)
			(xy 92.151476 -336.011447) (xy 92.151962 -336.038698) (xy 92.151455 -336.066608) (xy 92.143322 -336.121833)
			(xy 92.127229 -336.175283) (xy 92.10352 -336.225818) (xy 92.0727 -336.272359) (xy 92.054426 -336.29346)
			(xy 92.048507 -336.300622) (xy 92.041868 -336.317959) (xy 92.041472 -336.327242) (xy 92.041472 -336.404966)
			(xy 92.048076 -336.422238) (xy 92.054426 -336.42935) (xy 92.072706 -336.450448) (xy 92.103532 -336.496987)
			(xy 92.127247 -336.547522) (xy 92.143343 -336.600974) (xy 92.151477 -336.656201) (xy 92.151962 -336.684112)
			(xy 92.151476 -336.711363) (xy 92.14372 -336.765311) (xy 92.128365 -336.817606) (xy 92.105723 -336.867183)
			(xy 92.076257 -336.913033) (xy 92.040566 -336.954224) (xy 91.999375 -336.989915) (xy 91.956296 -337.0176)
			(xy 95.771147 -337.0176) (xy 95.775316 -336.961981) (xy 95.787728 -336.907605) (xy 95.808105 -336.855686)
			(xy 95.835994 -336.807385) (xy 95.870771 -336.76378) (xy 95.911658 -336.725845) (xy 95.957743 -336.694429)
			(xy 96.007996 -336.670233) (xy 96.061294 -336.653797) (xy 96.116447 -336.645488) (xy 96.144334 -336.644996)
			(xy 96.170756 -336.645435) (xy 96.223073 -336.65289) (xy 96.273811 -336.667659) (xy 96.321955 -336.689447)
			(xy 96.366539 -336.717817) (xy 96.386904 -336.734658) (xy 96.393762 -336.7405) (xy 96.41078 -336.74685)
			(xy 96.495108 -336.74685) (xy 96.512126 -336.7405) (xy 96.518984 -336.734658) (xy 96.53935 -336.717819)
			(xy 96.583936 -336.689454) (xy 96.63208 -336.667667) (xy 96.682817 -336.652896) (xy 96.735132 -336.645436)
			(xy 96.787976 -336.645436) (xy 96.840291 -336.652896) (xy 96.891028 -336.667667) (xy 96.939172 -336.689454)
			(xy 96.983758 -336.717819) (xy 97.004124 -336.734658) (xy 97.010982 -336.7405) (xy 97.028 -336.74685)
			(xy 97.112328 -336.74685) (xy 97.129346 -336.7405) (xy 97.136204 -336.734658) (xy 97.157001 -336.717486)
			(xy 97.202585 -336.688665) (xy 97.251853 -336.666726) (xy 97.277682 -336.658966) (xy 97.277936 -336.658966)
			(xy 97.288984 -336.655196) (xy 97.306315 -336.639591) (xy 97.31121 -336.628994) (xy 97.341182 -336.554064)
			(xy 97.344904 -336.542981) (xy 97.343072 -336.519703) (xy 97.337626 -336.50936) (xy 97.325246 -336.487715)
			(xy 97.305774 -336.441811) (xy 97.292598 -336.393719) (xy 97.285952 -336.3443) (xy 97.285556 -336.319368)
			(xy 97.286078 -336.291727) (xy 97.294232 -336.237048) (xy 97.31037 -336.184174) (xy 97.33414 -336.134262)
			(xy 97.365019 -336.088407) (xy 97.402331 -336.047615) (xy 97.423478 -336.029808) (xy 97.431902 -336.022209)
			(xy 97.441666 -336.001766) (xy 97.442274 -335.990438) (xy 97.442274 -335.911698) (xy 97.441624 -335.90038)
			(xy 97.431873 -335.879946) (xy 97.423478 -335.872328) (xy 97.402359 -335.854489) (xy 97.365045 -335.813702)
			(xy 97.334161 -335.767854) (xy 97.310383 -335.717949) (xy 97.294232 -335.665081) (xy 97.286062 -335.610408)
			(xy 97.285556 -335.582768) (xy 97.286077 -335.554883) (xy 97.294389 -335.499736) (xy 97.310827 -335.446444)
			(xy 97.335025 -335.396198) (xy 97.366441 -335.350119) (xy 97.404374 -335.309237) (xy 97.447976 -335.274465)
			(xy 97.496274 -335.24658) (xy 97.548189 -335.226205) (xy 97.60256 -335.213795) (xy 97.658174 -335.209628)
			(xy 97.713788 -335.213795) (xy 97.768159 -335.226205) (xy 97.820074 -335.24658) (xy 97.868372 -335.274465)
			(xy 97.911974 -335.309237) (xy 97.949907 -335.350119) (xy 97.981323 -335.396198) (xy 98.005521 -335.446444)
			(xy 98.021959 -335.499736) (xy 98.030271 -335.554883) (xy 98.030792 -335.582768) (xy 98.030314 -335.610411)
			(xy 98.022154 -335.665092) (xy 98.006008 -335.717969) (xy 97.98223 -335.767881) (xy 97.951342 -335.813734)
			(xy 97.914021 -335.854523) (xy 97.89287 -335.872328) (xy 97.884438 -335.87992) (xy 97.874676 -335.900368)
			(xy 97.874074 -335.911698) (xy 97.874074 -335.990438) (xy 97.874688 -336.001761) (xy 97.884463 -336.022195)
			(xy 97.89287 -336.029808) (xy 97.914017 -336.047616) (xy 97.951326 -336.088411) (xy 97.982205 -336.134266)
			(xy 98.005978 -336.184177) (xy 98.022124 -336.23705) (xy 98.030288 -336.291726) (xy 98.030792 -336.319368)
			(xy 98.030319 -336.346211) (xy 98.022619 -336.399341) (xy 98.007372 -336.450816) (xy 97.984896 -336.499569)
			(xy 97.955655 -336.544593) (xy 97.920256 -336.584953) (xy 97.879429 -336.619815) (xy 97.834023 -336.648456)
			(xy 97.784975 -336.670284) (xy 97.759266 -336.678016) (xy 97.759012 -336.678016) (xy 97.747956 -336.68177)
			(xy 97.730626 -336.697384) (xy 97.725738 -336.707988) (xy 97.695766 -336.782918) (xy 97.691997 -336.793989)
			(xy 97.693862 -336.817279) (xy 97.699322 -336.827622) (xy 97.711699 -336.849268) (xy 97.731171 -336.895173)
			(xy 97.744348 -336.943264) (xy 97.750995 -336.992682) (xy 97.751392 -337.017614) (xy 97.750979 -337.044233)
			(xy 97.7434 -337.09693) (xy 97.728399 -337.148011) (xy 97.70628 -337.196438) (xy 97.677495 -337.241224)
			(xy 97.642629 -337.281457) (xy 97.602392 -337.316319) (xy 97.557603 -337.345099) (xy 97.509174 -337.367213)
			(xy 97.458091 -337.382208) (xy 97.405393 -337.389782) (xy 97.378774 -337.390232) (xy 97.352352 -337.389782)
			(xy 97.300037 -337.382329) (xy 97.249298 -337.367562) (xy 97.201154 -337.345776) (xy 97.156569 -337.31741)
			(xy 97.136204 -337.30057) (xy 97.129346 -337.294728) (xy 97.112328 -337.288378) (xy 97.028 -337.288378)
			(xy 97.010982 -337.294728) (xy 97.004124 -337.30057) (xy 96.983758 -337.317409) (xy 96.939172 -337.345774)
			(xy 96.891028 -337.367561) (xy 96.840291 -337.382332) (xy 96.787976 -337.389792) (xy 96.735132 -337.389792)
			(xy 96.682817 -337.382332) (xy 96.63208 -337.367561) (xy 96.583936 -337.345774) (xy 96.53935 -337.317409)
			(xy 96.518984 -337.30057) (xy 96.512126 -337.294728) (xy 96.495108 -337.288378) (xy 96.41078 -337.288378)
			(xy 96.393762 -337.294728) (xy 96.386904 -337.30057) (xy 96.366533 -337.317402) (xy 96.321945 -337.345759)
			(xy 96.273802 -337.36754) (xy 96.223066 -337.382309) (xy 96.170755 -337.38977) (xy 96.144334 -337.390232)
			(xy 96.116447 -337.389712) (xy 96.061294 -337.381403) (xy 96.007996 -337.364967) (xy 95.957743 -337.340771)
			(xy 95.911658 -337.309355) (xy 95.870771 -337.27142) (xy 95.835994 -337.227815) (xy 95.808105 -337.179514)
			(xy 95.787728 -337.127595) (xy 95.775316 -337.073219) (xy 95.771147 -337.0176) (xy 91.956296 -337.0176)
			(xy 91.953525 -337.019381) (xy 91.903948 -337.042023) (xy 91.851653 -337.057378) (xy 91.797705 -337.065134)
			(xy 91.743203 -337.065134) (xy 91.689255 -337.057378) (xy 91.63696 -337.042023) (xy 91.587383 -337.019381)
			(xy 91.541533 -336.989915) (xy 91.500342 -336.954224) (xy 91.464651 -336.913033) (xy 91.435185 -336.867183)
			(xy 91.412543 -336.817606) (xy 91.397188 -336.765311) (xy 91.389432 -336.711363) (xy 91.388946 -336.684112)
			(xy 90.958918 -336.684112) (xy 90.966684 -336.686392) (xy 91.01626 -336.709031) (xy 91.06211 -336.738496)
			(xy 91.1033 -336.774185) (xy 91.138991 -336.815373) (xy 91.168458 -336.861221) (xy 91.1911 -336.910795)
			(xy 91.206457 -336.963088) (xy 91.214215 -337.017034) (xy 91.214702 -337.044284) (xy 91.214225 -337.071858)
			(xy 91.206274 -337.12643) (xy 91.190552 -337.17929) (xy 91.167384 -337.229336) (xy 91.137253 -337.275526)
			(xy 91.100788 -337.316898) (xy 91.080082 -337.335114) (xy 91.071997 -337.342661) (xy 91.062649 -337.362679)
			(xy 91.062048 -337.373722) (xy 91.062048 -337.451446) (xy 91.062631 -337.462494) (xy 91.071984 -337.482516)
			(xy 91.080082 -337.490054) (xy 91.100771 -337.50829) (xy 91.137243 -337.549653) (xy 91.167379 -337.595837)
			(xy 91.190549 -337.645881) (xy 91.20627 -337.698739) (xy 91.214214 -337.753311) (xy 91.214702 -337.780884)
			(xy 91.214225 -337.808458) (xy 91.206274 -337.86303) (xy 91.190591 -337.915758) (xy 92.346778 -337.915758)
			(xy 92.350849 -337.860136) (xy 92.362975 -337.805699) (xy 92.382898 -337.753608) (xy 92.410194 -337.704973)
			(xy 92.44428 -337.66083) (xy 92.484429 -337.622121) (xy 92.529787 -337.58967) (xy 92.579387 -337.564169)
			(xy 92.632171 -337.546162) (xy 92.687014 -337.536032) (xy 92.742748 -337.533995) (xy 92.798185 -337.540095)
			(xy 92.852142 -337.554201) (xy 92.903471 -337.576013) (xy 92.951077 -337.605067) (xy 92.993945 -337.640742)
			(xy 93.031162 -337.682279) (xy 93.061935 -337.728792) (xy 93.085607 -337.779289) (xy 93.101675 -337.832696)
			(xy 93.109795 -337.887872) (xy 93.110304 -337.915758) (xy 93.109795 -337.943644) (xy 93.101675 -337.99882)
			(xy 93.085607 -338.052227) (xy 93.061935 -338.102724) (xy 93.031162 -338.149237) (xy 92.993945 -338.190774)
			(xy 92.951077 -338.226449) (xy 92.903471 -338.255503) (xy 92.852142 -338.277315) (xy 92.798185 -338.291421)
			(xy 92.742748 -338.297521) (xy 92.687014 -338.295484) (xy 92.632171 -338.285354) (xy 92.579387 -338.267347)
			(xy 92.529787 -338.241846) (xy 92.484429 -338.209395) (xy 92.44428 -338.170686) (xy 92.410194 -338.126543)
			(xy 92.382898 -338.077908) (xy 92.362975 -338.025817) (xy 92.350849 -337.97138) (xy 92.346778 -337.915758)
			(xy 91.190591 -337.915758) (xy 91.190552 -337.91589) (xy 91.167384 -337.965936) (xy 91.137253 -338.012126)
			(xy 91.100788 -338.053498) (xy 91.080082 -338.071714) (xy 91.071997 -338.079261) (xy 91.062649 -338.099279)
			(xy 91.062048 -338.110322) (xy 91.062048 -338.188046) (xy 91.062631 -338.199094) (xy 91.071984 -338.219116)
			(xy 91.080082 -338.226654) (xy 91.100771 -338.24489) (xy 91.137243 -338.286253) (xy 91.167379 -338.332437)
			(xy 91.190549 -338.382481) (xy 91.20627 -338.435339) (xy 91.214214 -338.489911) (xy 91.214702 -338.517484)
			(xy 91.21423 -338.544737) (xy 91.206475 -338.598688) (xy 91.191121 -338.650986) (xy 91.168479 -338.700566)
			(xy 91.139013 -338.74642) (xy 91.10332 -338.787613) (xy 91.076206 -338.811108) (xy 91.767658 -338.811108)
			(xy 91.771729 -338.755486) (xy 91.783855 -338.701049) (xy 91.803778 -338.648958) (xy 91.831074 -338.600323)
			(xy 91.86516 -338.55618) (xy 91.905309 -338.517471) (xy 91.950667 -338.48502) (xy 92.000267 -338.459519)
			(xy 92.053051 -338.441512) (xy 92.107894 -338.431382) (xy 92.163628 -338.429345) (xy 92.219065 -338.435445)
			(xy 92.273022 -338.449551) (xy 92.324351 -338.471363) (xy 92.371957 -338.500417) (xy 92.414825 -338.536092)
			(xy 92.452042 -338.577629) (xy 92.482815 -338.624142) (xy 92.506487 -338.674639) (xy 92.522555 -338.728046)
			(xy 92.530675 -338.783222) (xy 92.531184 -338.811108) (xy 92.530675 -338.838994) (xy 92.522555 -338.89417)
			(xy 92.506487 -338.947577) (xy 92.482815 -338.998074) (xy 92.452042 -339.044587) (xy 92.414825 -339.086124)
			(xy 92.371957 -339.121799) (xy 92.324351 -339.150853) (xy 92.273022 -339.172665) (xy 92.219065 -339.186771)
			(xy 92.163628 -339.192871) (xy 92.107894 -339.190834) (xy 92.053051 -339.180704) (xy 92.000267 -339.162697)
			(xy 91.950667 -339.137196) (xy 91.905309 -339.104745) (xy 91.86516 -339.066036) (xy 91.831074 -339.021893)
			(xy 91.803778 -338.973258) (xy 91.783855 -338.921167) (xy 91.771729 -338.86673) (xy 91.767658 -338.811108)
			(xy 91.076206 -338.811108) (xy 91.062128 -338.823307) (xy 91.016275 -338.852775) (xy 90.966695 -338.875417)
			(xy 90.914397 -338.890773) (xy 90.860447 -338.898529) (xy 90.833194 -338.898992) (xy 90.805338 -338.89848)
			(xy 90.750222 -338.890356) (xy 90.696871 -338.874309) (xy 90.646418 -338.850681) (xy 90.599933 -338.819973)
			(xy 90.558404 -338.782836) (xy 90.522711 -338.740059) (xy 90.493612 -338.69255) (xy 90.471725 -338.641318)
			(xy 90.464132 -338.614512) (xy 90.461846 -338.605622) (xy 90.451178 -338.590382) (xy 90.379296 -338.54263)
			(xy 90.361262 -338.538566) (xy 90.352118 -338.539836) (xy 90.339101 -338.541502) (xy 90.312917 -338.543284)
			(xy 90.299794 -338.543392) (xy 90.285645 -338.543299) (xy 90.257422 -338.541264) (xy 90.243406 -338.539328)
			(xy 90.2335 -338.537804) (xy 90.213688 -338.54263) (xy 90.139266 -338.59851) (xy 90.129106 -338.616036)
			(xy 90.127836 -338.626196) (xy 90.12377 -338.653353) (xy 90.108791 -338.706182) (xy 90.086395 -338.756319)
			(xy 90.057043 -338.802728) (xy 90.021343 -338.844451) (xy 89.980032 -338.880626) (xy 89.933961 -338.910507)
			(xy 89.884084 -338.933475) (xy 89.83143 -338.949058) (xy 89.777086 -338.956933) (xy 89.74963 -338.957412)
			(xy 89.722378 -338.956917) (xy 89.668428 -338.949164) (xy 89.616131 -338.933812) (xy 89.566552 -338.911173)
			(xy 89.520699 -338.881709) (xy 89.479506 -338.846018) (xy 89.443812 -338.804829) (xy 89.414343 -338.758978)
			(xy 89.3917 -338.7094) (xy 89.376343 -338.657105) (xy 89.368586 -338.603156) (xy 89.368122 -338.575904)
			(xy 87.227276 -338.575904) (xy 87.229908 -338.584865) (xy 87.237669 -338.638819) (xy 87.238078 -338.666074)
			(xy 87.237429 -338.697638) (xy 87.227043 -338.759904) (xy 87.20655 -338.819613) (xy 87.192104 -338.847684)
			(xy 87.187278 -338.856574) (xy 87.185246 -338.876132) (xy 87.208106 -338.954618) (xy 87.211356 -338.964034)
			(xy 87.223778 -338.979581) (xy 87.232236 -338.984844) (xy 87.257329 -338.999401) (xy 87.303193 -339.034919)
			(xy 87.343155 -339.076968) (xy 87.376293 -339.12458) (xy 87.401845 -339.176659) (xy 87.419221 -339.232004)
			(xy 87.428023 -339.289342) (xy 87.428578 -339.318346) (xy 87.428089 -339.345594) (xy 87.420327 -339.399535)
			(xy 87.404967 -339.451823) (xy 87.389013 -339.486748) (xy 93.106494 -339.486748) (xy 93.106951 -339.459272)
			(xy 93.11485 -339.404892) (xy 93.130477 -339.352209) (xy 93.153508 -339.302317) (xy 93.183466 -339.256249)
			(xy 93.201236 -339.235288) (xy 93.20149 -339.235034) (xy 93.207067 -339.227941) (xy 93.21332 -339.211029)
			(xy 93.213682 -339.202014) (xy 93.213682 -339.13445) (xy 93.213305 -339.125435) (xy 93.207072 -339.108518)
			(xy 93.20149 -339.10143) (xy 93.200982 -339.100922) (xy 93.18326 -339.079967) (xy 93.153376 -339.033936)
			(xy 93.130408 -338.984093) (xy 93.114831 -338.93147) (xy 93.106967 -338.877156) (xy 93.106494 -338.849716)
			(xy 93.10698 -338.822465) (xy 93.114736 -338.768517) (xy 93.130091 -338.716222) (xy 93.152733 -338.666645)
			(xy 93.182199 -338.620795) (xy 93.21789 -338.579604) (xy 93.259081 -338.543913) (xy 93.304931 -338.514447)
			(xy 93.354508 -338.491805) (xy 93.406803 -338.47645) (xy 93.460751 -338.468694) (xy 93.515253 -338.468694)
			(xy 93.569201 -338.47645) (xy 93.621496 -338.491805) (xy 93.671073 -338.514447) (xy 93.716923 -338.543913)
			(xy 93.758114 -338.579604) (xy 93.793805 -338.620795) (xy 93.823271 -338.666645) (xy 93.845913 -338.716222)
			(xy 93.861268 -338.768517) (xy 93.869024 -338.822465) (xy 93.86951 -338.849716) (xy 93.869031 -338.877191)
			(xy 93.861137 -338.931571) (xy 93.845515 -338.984253) (xy 93.822489 -339.034146) (xy 93.792536 -339.080214)
			(xy 93.774768 -339.101176) (xy 93.774514 -339.10143) (xy 93.768952 -339.108534) (xy 93.76269 -339.125437)
			(xy 93.762322 -339.13445) (xy 93.762322 -339.202014) (xy 93.762667 -339.211032) (xy 93.768922 -339.227949)
			(xy 93.774514 -339.235034) (xy 93.775022 -339.235542) (xy 93.792775 -339.256473) (xy 93.822654 -339.30251)
			(xy 93.845616 -339.352359) (xy 93.861186 -339.404988) (xy 93.869042 -339.459306) (xy 93.86951 -339.486748)
			(xy 93.869024 -339.513999) (xy 93.861268 -339.567947) (xy 93.845913 -339.620242) (xy 93.823271 -339.669819)
			(xy 93.793805 -339.715669) (xy 93.758114 -339.75686) (xy 93.716923 -339.792551) (xy 93.671073 -339.822017)
			(xy 93.621496 -339.844659) (xy 93.569201 -339.860014) (xy 93.515253 -339.86777) (xy 93.460751 -339.86777)
			(xy 93.406803 -339.860014) (xy 93.354508 -339.844659) (xy 93.304931 -339.822017) (xy 93.259081 -339.792551)
			(xy 93.21789 -339.75686) (xy 93.182199 -339.715669) (xy 93.152733 -339.669819) (xy 93.130091 -339.620242)
			(xy 93.114736 -339.567947) (xy 93.10698 -339.513999) (xy 93.106494 -339.486748) (xy 87.389013 -339.486748)
			(xy 87.382323 -339.501392) (xy 87.352855 -339.547235) (xy 87.317163 -339.588417) (xy 87.275974 -339.624101)
			(xy 87.230126 -339.653559) (xy 87.180552 -339.676194) (xy 87.128261 -339.691543) (xy 87.074318 -339.699294)
			(xy 87.04707 -339.699854) (xy 87.017736 -339.699314) (xy 86.959761 -339.690332) (xy 86.903842 -339.672584)
			(xy 86.851299 -339.646487) (xy 86.803368 -339.612657) (xy 86.781894 -339.592666) (xy 86.774437 -339.586107)
			(xy 86.756004 -339.578775) (xy 86.74608 -339.578442) (xy 86.67496 -339.57895) (xy 86.665038 -339.579523)
			(xy 86.646741 -339.587236) (xy 86.6394 -339.593936) (xy 85.040978 -341.192358) (xy 85.026478 -341.20616)
			(xy 84.993198 -341.228396) (xy 84.956224 -341.243722) (xy 84.916972 -341.251551) (xy 84.89696 -341.252048)
			(xy 80.368394 -341.252048) (xy 80.358325 -341.252474) (xy 80.339727 -341.260195) (xy 80.332326 -341.267034)
			(xy 57.297574 -364.301786) (xy 57.283076 -364.315592) (xy 57.249798 -364.337835) (xy 57.212823 -364.353166)
			(xy 57.173569 -364.360997) (xy 57.153556 -364.361476) (xy 44.964858 -364.361476) (xy 44.954791 -364.361906)
			(xy 44.936195 -364.369629) (xy 44.92879 -364.376462) (xy 40.67429 -368.630962) (xy 40.667444 -368.63836)
			(xy 40.659718 -368.656959) (xy 40.659304 -368.66703) (xy 40.659304 -369.786916) (xy 40.658852 -369.806936)
			(xy 40.651049 -369.846207) (xy 40.635727 -369.883197) (xy 40.613476 -369.916484) (xy 40.599614 -369.930934)
			(xy 39.8907 -370.639848) (xy 39.876246 -370.65359) (xy 39.843079 -370.675726) (xy 39.806236 -370.690977)
			(xy 39.767127 -370.698761) (xy 39.74719 -370.699284) (xy 33.664398 -370.699284) (xy 33.65444 -370.699813)
			(xy 33.636048 -370.707465) (xy 33.621923 -370.721513) (xy 33.617662 -370.730526) (xy 33.614119 -370.739971)
			(xy 33.614018 -370.760128) (xy 33.621729 -370.778751) (xy 33.628584 -370.786152) (xy 33.73247 -370.890038)
			(xy 33.739869 -370.89688) (xy 33.758468 -370.904599) (xy 33.768538 -370.905024) (xy 39.8907 -370.905024)
			(xy 39.900771 -370.904602) (xy 39.919377 -370.89689) (xy 39.926768 -370.890038) (xy 40.753538 -370.063014)
			(xy 40.760378 -370.055614) (xy 40.76809 -370.037015) (xy 40.768524 -370.026946) (xy 40.768524 -368.925348)
			(xy 40.768979 -368.90533) (xy 40.776789 -368.866064) (xy 40.792118 -368.829079) (xy 40.814374 -368.7958)
			(xy 40.828214 -368.78133) (xy 44.759626 -364.849918) (xy 44.774124 -364.836112) (xy 44.807402 -364.813868)
			(xy 44.844377 -364.798537) (xy 44.883631 -364.790706) (xy 44.903644 -364.790228) (xy 57.791096 -364.790228)
			(xy 57.801167 -364.789806) (xy 57.819775 -364.782096) (xy 57.827164 -364.775242) (xy 80.853026 -341.74938)
			(xy 80.86748 -341.735639) (xy 80.900647 -341.713504) (xy 80.93749 -341.698255) (xy 80.976599 -341.690474)
			(xy 80.996536 -341.689944) (xy 92.308172 -341.689944) (xy 92.318235 -341.689506) (xy 92.336815 -341.681767)
			(xy 92.34424 -341.674958) (xy 94.505018 -339.513926) (xy 94.511418 -339.506942) (xy 94.518973 -339.489585)
			(xy 94.519699 -339.470669) (xy 94.516956 -339.461602) (xy 94.482666 -339.361272) (xy 94.46006 -339.343238)
			(xy 94.445582 -339.34146) (xy 94.418209 -339.337594) (xy 94.364893 -339.322988) (xy 94.314244 -339.300838)
			(xy 94.267323 -339.271608) (xy 94.225113 -339.235911) (xy 94.188499 -339.194494) (xy 94.158247 -339.148225)
			(xy 94.134991 -339.098074) (xy 94.119219 -339.045091) (xy 94.111261 -338.990387) (xy 94.11081 -338.962746)
			(xy 94.11127 -338.935491) (xy 94.119022 -338.881537) (xy 94.134374 -338.829234) (xy 94.157014 -338.779649)
			(xy 94.186481 -338.733792) (xy 94.222175 -338.692595) (xy 94.263369 -338.656898) (xy 94.309225 -338.627428)
			(xy 94.358808 -338.604784) (xy 94.411109 -338.589428) (xy 94.465064 -338.581672) (xy 94.492318 -338.581238)
			(xy 94.492572 -338.581238) (xy 94.517773 -338.581665) (xy 94.567732 -338.588334) (xy 94.616382 -338.601507)
			(xy 94.66288 -338.620956) (xy 94.68485 -338.633308) (xy 94.694756 -338.63915) (xy 94.7166 -338.641182)
			(xy 94.811342 -338.607654) (xy 94.82709 -338.59216) (xy 94.831154 -338.581746) (xy 94.841847 -338.554969)
			(xy 94.870133 -338.504728) (xy 94.905662 -338.459319) (xy 94.947625 -338.419779) (xy 94.995064 -338.387009)
			(xy 95.046897 -338.361758) (xy 95.101941 -338.3446) (xy 95.158942 -338.335927) (xy 95.18777 -338.335366)
			(xy 95.215025 -338.335827) (xy 95.268981 -338.34358) (xy 95.321284 -338.358933) (xy 95.370869 -338.381574)
			(xy 95.416728 -338.411041) (xy 95.457926 -338.446734) (xy 95.493626 -338.487927) (xy 95.523099 -338.533782)
			(xy 95.545747 -338.583364) (xy 95.558476 -338.626704) (xy 97.699322 -338.626704) (xy 97.699783 -338.599129)
			(xy 97.707735 -338.544556) (xy 97.723461 -338.491695) (xy 97.746632 -338.441649) (xy 97.776765 -338.39546)
			(xy 97.813234 -338.354089) (xy 97.833942 -338.335874) (xy 97.842036 -338.328336) (xy 97.851378 -338.308311)
			(xy 97.851976 -338.297266) (xy 97.851976 -338.219542) (xy 97.851392 -338.208494) (xy 97.842039 -338.188473)
			(xy 97.833942 -338.180934) (xy 97.813252 -338.162699) (xy 97.776779 -338.121336) (xy 97.746643 -338.075152)
			(xy 97.723473 -338.025108) (xy 97.707752 -337.972249) (xy 97.699809 -337.917678) (xy 97.699322 -337.890104)
			(xy 97.699759 -337.86285) (xy 97.707516 -337.808896) (xy 97.722873 -337.756596) (xy 97.745518 -337.707014)
			(xy 97.774988 -337.66116) (xy 97.810685 -337.619966) (xy 97.85188 -337.584272) (xy 97.897737 -337.554805)
			(xy 97.947321 -337.532164) (xy 97.999622 -337.516811) (xy 98.053576 -337.509057) (xy 98.08083 -337.508596)
			(xy 98.081338 -337.508596) (xy 98.11512 -337.51012) (xy 98.12528 -337.511136) (xy 98.144584 -337.50504)
			(xy 98.207576 -337.452208) (xy 98.214878 -337.445495) (xy 98.224154 -337.427983) (xy 98.22561 -337.418172)
			(xy 98.22561 -337.41741) (xy 98.228502 -337.389241) (xy 98.241716 -337.334178) (xy 98.262927 -337.281674)
			(xy 98.291666 -337.232882) (xy 98.327304 -337.188876) (xy 98.369056 -337.150622) (xy 98.416005 -337.118961)
			(xy 98.467119 -337.09459) (xy 98.521274 -337.078043) (xy 98.57728 -337.069685) (xy 98.605594 -337.069176)
			(xy 98.632844 -337.069683) (xy 98.686791 -337.077439) (xy 98.739084 -337.092792) (xy 98.78866 -337.115431)
			(xy 98.83451 -337.144896) (xy 98.8757 -337.180585) (xy 98.911391 -337.221773) (xy 98.940858 -337.267621)
			(xy 98.9635 -337.317195) (xy 98.978857 -337.369488) (xy 98.986615 -337.423434) (xy 98.987102 -337.450684)
			(xy 98.986613 -337.478546) (xy 98.978512 -337.533679) (xy 98.962482 -337.587049) (xy 98.938862 -337.63752)
			(xy 98.908154 -337.68402) (xy 98.871012 -337.725562) (xy 98.849942 -337.7438) (xy 98.840798 -337.75142)
			(xy 98.8314 -337.772502) (xy 98.834448 -337.864704) (xy 98.835391 -337.876182) (xy 98.846094 -337.896547)
			(xy 98.855022 -337.90382) (xy 98.855276 -337.904074) (xy 98.875807 -337.919521) (xy 98.91294 -337.95503)
			(xy 98.944972 -337.995202) (xy 98.971323 -338.039309) (xy 98.991515 -338.086554) (xy 99.005184 -338.136081)
			(xy 99.012082 -338.186995) (xy 99.012502 -338.212684) (xy 99.011987 -338.242127) (xy 99.002939 -338.300314)
			(xy 98.985057 -338.356419) (xy 98.958764 -338.409109) (xy 98.924687 -338.457133) (xy 98.904552 -338.478622)
			(xy 98.904298 -338.478876) (xy 98.896575 -338.487741) (xy 98.889414 -338.510104) (xy 98.890582 -338.521802)
			(xy 98.904806 -338.614004) (xy 98.918522 -338.633308) (xy 98.928936 -338.638896) (xy 98.954506 -338.6533)
			(xy 99.001281 -338.688741) (xy 99.042078 -338.730927) (xy 99.075934 -338.778862) (xy 99.102052 -338.831415)
			(xy 99.119814 -338.887348) (xy 99.128803 -338.945341) (xy 99.129342 -338.974684) (xy 99.128834 -339.003602)
			(xy 99.120106 -339.060774) (xy 99.102848 -339.115974) (xy 99.077454 -339.167936) (xy 99.044508 -339.21547)
			(xy 99.004763 -339.257485) (xy 98.982276 -339.275674) (xy 98.973486 -339.283298) (xy 98.963294 -339.304186)
			(xy 98.962718 -339.315806) (xy 98.962718 -339.395562) (xy 98.963229 -339.407198) (xy 98.973437 -339.428107)
			(xy 98.982276 -339.435694) (xy 99.004752 -339.453894) (xy 99.044488 -339.495912) (xy 99.077429 -339.543444)
			(xy 99.102819 -339.595404) (xy 99.120077 -339.6506) (xy 99.128807 -339.707768) (xy 99.129342 -339.736684)
			(xy 99.128807 -339.763933) (xy 99.121054 -339.817877) (xy 99.105702 -339.870169) (xy 99.083065 -339.919744)
			(xy 99.053604 -339.965593) (xy 99.017918 -340.006782) (xy 98.976733 -340.042474) (xy 98.930888 -340.071941)
			(xy 98.881316 -340.094585) (xy 98.829026 -340.109943) (xy 98.775083 -340.117703) (xy 98.747834 -340.118192)
			(xy 98.718894 -340.117667) (xy 98.661681 -340.108901) (xy 98.606448 -340.091596) (xy 98.554462 -340.066148)
			(xy 98.506915 -340.033142) (xy 98.464898 -339.993334) (xy 98.429374 -339.947637) (xy 98.401158 -339.897099)
			(xy 98.380898 -339.842881) (xy 98.374454 -339.814662) (xy 98.374454 -339.814408) (xy 98.37202 -339.80506)
			(xy 98.361327 -339.788995) (xy 98.353626 -339.783166) (xy 98.287332 -339.7377) (xy 98.26879 -339.733382)
			(xy 98.259138 -339.734906) (xy 98.25863 -339.734906) (xy 98.243871 -339.737128) (xy 98.214119 -339.739547)
			(xy 98.199194 -339.739732) (xy 98.171944 -339.739228) (xy 98.117998 -339.731471) (xy 98.065705 -339.716116)
			(xy 98.016129 -339.693476) (xy 97.97028 -339.664012) (xy 97.929091 -339.628322) (xy 97.893399 -339.587134)
			(xy 97.863932 -339.541287) (xy 97.84129 -339.491712) (xy 97.825933 -339.43942) (xy 97.818173 -339.385474)
			(xy 97.817686 -339.358224) (xy 97.818159 -339.330984) (xy 97.825925 -339.277061) (xy 97.841289 -339.224793)
			(xy 97.863937 -339.175245) (xy 97.893407 -339.129424) (xy 97.910904 -339.108542) (xy 97.917723 -339.099699)
			(xy 97.923796 -339.07824) (xy 97.922588 -339.06714) (xy 97.908364 -338.978748) (xy 97.895918 -338.96046)
			(xy 97.886012 -338.954618) (xy 97.862006 -338.939797) (xy 97.818266 -338.904163) (xy 97.780254 -338.862474)
			(xy 97.748798 -338.81564) (xy 97.724585 -338.764683) (xy 97.708143 -338.710714) (xy 97.699831 -338.654913)
			(xy 97.699322 -338.626704) (xy 95.558476 -338.626704) (xy 95.561108 -338.635665) (xy 95.568869 -338.689619)
			(xy 95.569278 -338.716874) (xy 95.568629 -338.748438) (xy 95.558243 -338.810704) (xy 95.53775 -338.870413)
			(xy 95.523304 -338.898484) (xy 95.518478 -338.907374) (xy 95.516446 -338.926932) (xy 95.539306 -339.005418)
			(xy 95.542556 -339.014834) (xy 95.554978 -339.030381) (xy 95.563436 -339.035644) (xy 95.588529 -339.050201)
			(xy 95.634393 -339.085719) (xy 95.674355 -339.127768) (xy 95.707493 -339.17538) (xy 95.733045 -339.227459)
			(xy 95.750421 -339.282804) (xy 95.759223 -339.340142) (xy 95.759778 -339.369146) (xy 95.759289 -339.396394)
			(xy 95.751527 -339.450335) (xy 95.736167 -339.502623) (xy 95.713523 -339.552192) (xy 95.684055 -339.598035)
			(xy 95.648363 -339.639217) (xy 95.607174 -339.674901) (xy 95.561326 -339.704359) (xy 95.511752 -339.726994)
			(xy 95.459461 -339.742343) (xy 95.405518 -339.750094) (xy 95.37827 -339.750654) (xy 95.352872 -339.750234)
			(xy 95.302526 -339.74349) (xy 95.25352 -339.730125) (xy 95.20672 -339.710377) (xy 95.162954 -339.684593)
			(xy 95.122997 -339.65323) (xy 95.104966 -339.635338) (xy 95.097854 -339.627972) (xy 95.079312 -339.620098)
			(xy 94.996762 -339.61959) (xy 94.986654 -339.619928) (xy 94.967927 -339.627523) (xy 94.96044 -339.634322)
			(xy 93.000783 -341.594186) (xy 99.664774 -341.594186) (xy 99.665262 -341.566275) (xy 99.673398 -341.511049)
			(xy 99.689495 -341.457599) (xy 99.713209 -341.407064) (xy 99.744033 -341.360524) (xy 99.76231 -341.339424)
			(xy 99.768198 -341.33224) (xy 99.774854 -341.31492) (xy 99.775264 -341.305642) (xy 99.775264 -341.227918)
			(xy 99.76866 -341.210646) (xy 99.76231 -341.203534) (xy 99.744028 -341.182437) (xy 99.713201 -341.135898)
			(xy 99.689486 -341.085363) (xy 99.673391 -341.031911) (xy 99.665258 -340.976684) (xy 99.664774 -340.948772)
			(xy 99.66526 -340.921521) (xy 99.673016 -340.867573) (xy 99.688371 -340.815278) (xy 99.711013 -340.765701)
			(xy 99.740479 -340.719851) (xy 99.77617 -340.67866) (xy 99.817361 -340.642969) (xy 99.863211 -340.613503)
			(xy 99.912788 -340.590861) (xy 99.965083 -340.575506) (xy 100.019031 -340.56775) (xy 100.073533 -340.56775)
			(xy 100.127481 -340.575506) (xy 100.179776 -340.590861) (xy 100.229353 -340.613503) (xy 100.275203 -340.642969)
			(xy 100.316394 -340.67866) (xy 100.352085 -340.719851) (xy 100.381551 -340.765701) (xy 100.404193 -340.815278)
			(xy 100.419548 -340.867573) (xy 100.427304 -340.921521) (xy 100.42779 -340.948772) (xy 100.42732 -340.976683)
			(xy 100.419177 -341.031909) (xy 100.403075 -341.08536) (xy 100.379358 -341.135894) (xy 100.348531 -341.182434)
			(xy 100.330254 -341.203534) (xy 100.324337 -341.210697) (xy 100.317699 -341.228033) (xy 100.3173 -341.237316)
			(xy 100.3173 -341.31504) (xy 100.323904 -341.332312) (xy 100.330254 -341.339424) (xy 100.348526 -341.360528)
			(xy 100.379353 -341.407066) (xy 100.403068 -341.4576) (xy 100.419166 -341.51105) (xy 100.427303 -341.566275)
			(xy 100.42779 -341.594186) (xy 100.427304 -341.621437) (xy 100.419548 -341.675385) (xy 100.404193 -341.72768)
			(xy 100.381551 -341.777257) (xy 100.352085 -341.823107) (xy 100.316394 -341.864298) (xy 100.275203 -341.899989)
			(xy 100.232084 -341.9277) (xy 104.047047 -341.9277) (xy 104.051215 -341.872088) (xy 104.063623 -341.817718)
			(xy 104.083996 -341.765805) (xy 104.111879 -341.717508) (xy 104.146648 -341.673905) (xy 104.187526 -341.635971)
			(xy 104.233602 -341.604553) (xy 104.283845 -341.580353) (xy 104.337134 -341.56391) (xy 104.392278 -341.555594)
			(xy 104.420162 -341.55507) (xy 104.446585 -341.555499) (xy 104.498901 -341.562957) (xy 104.54964 -341.577729)
			(xy 104.597784 -341.599519) (xy 104.642367 -341.62789) (xy 104.662732 -341.644732) (xy 104.66959 -341.650574)
			(xy 104.686608 -341.656924) (xy 104.770936 -341.656924) (xy 104.787954 -341.650574) (xy 104.794812 -341.644732)
			(xy 104.815178 -341.627893) (xy 104.859764 -341.599528) (xy 104.907908 -341.577741) (xy 104.958645 -341.56297)
			(xy 105.01096 -341.55551) (xy 105.063804 -341.55551) (xy 105.116119 -341.56297) (xy 105.166856 -341.577741)
			(xy 105.215 -341.599528) (xy 105.259586 -341.627893) (xy 105.279952 -341.644732) (xy 105.28681 -341.650574)
			(xy 105.303828 -341.656924) (xy 105.388156 -341.656924) (xy 105.405174 -341.650574) (xy 105.412032 -341.644732)
			(xy 105.432821 -341.627549) (xy 105.478409 -341.598732) (xy 105.527679 -341.576798) (xy 105.55351 -341.56904)
			(xy 105.553764 -341.56904) (xy 105.564805 -341.565251) (xy 105.58214 -341.549661) (xy 105.587038 -341.539068)
			(xy 105.61701 -341.464138) (xy 105.620746 -341.453059) (xy 105.618904 -341.429777) (xy 105.613454 -341.419434)
			(xy 105.601097 -341.397777) (xy 105.581621 -341.351876) (xy 105.568438 -341.303789) (xy 105.561785 -341.254373)
			(xy 105.561384 -341.229442) (xy 105.561878 -341.201799) (xy 105.570036 -341.14712) (xy 105.586179 -341.094244)
			(xy 105.609954 -341.044332) (xy 105.640839 -340.998478) (xy 105.678156 -340.957688) (xy 105.699306 -340.939882)
			(xy 105.707746 -340.932298) (xy 105.717501 -340.911844) (xy 105.718102 -340.900512) (xy 105.718102 -340.821772)
			(xy 105.717457 -340.810454) (xy 105.707701 -340.790021) (xy 105.699306 -340.782402) (xy 105.67818 -340.76457)
			(xy 105.640866 -340.723783) (xy 105.609982 -340.677933) (xy 105.586205 -340.628027) (xy 105.570056 -340.575157)
			(xy 105.561888 -340.520482) (xy 105.561384 -340.492842) (xy 105.561905 -340.464957) (xy 105.570217 -340.40981)
			(xy 105.586655 -340.356518) (xy 105.610853 -340.306272) (xy 105.642269 -340.260193) (xy 105.680202 -340.219311)
			(xy 105.723804 -340.184539) (xy 105.772102 -340.156654) (xy 105.824017 -340.136279) (xy 105.878388 -340.123869)
			(xy 105.934002 -340.119702) (xy 105.989616 -340.123869) (xy 106.043987 -340.136279) (xy 106.095902 -340.156654)
			(xy 106.1442 -340.184539) (xy 106.187802 -340.219311) (xy 106.225735 -340.260193) (xy 106.257151 -340.306272)
			(xy 106.281349 -340.356518) (xy 106.297787 -340.40981) (xy 106.306099 -340.464957) (xy 106.30662 -340.492842)
			(xy 106.306114 -340.520484) (xy 106.297958 -340.575163) (xy 106.281817 -340.628039) (xy 106.258045 -340.677951)
			(xy 106.227162 -340.723805) (xy 106.189847 -340.764596) (xy 106.168698 -340.782402) (xy 106.160266 -340.789993)
			(xy 106.150507 -340.810442) (xy 106.149902 -340.821772) (xy 106.149902 -340.900512) (xy 106.150554 -340.91183)
			(xy 106.160305 -340.932263) (xy 106.168698 -340.939882) (xy 106.189817 -340.957721) (xy 106.227132 -340.998508)
			(xy 106.258017 -341.044356) (xy 106.281795 -341.09426) (xy 106.297945 -341.147129) (xy 106.306114 -341.201802)
			(xy 106.30662 -341.229442) (xy 106.306104 -341.256283) (xy 106.298407 -341.30941) (xy 106.283166 -341.360883)
			(xy 106.260695 -341.409636) (xy 106.23146 -341.454658) (xy 106.196065 -341.495019) (xy 106.155245 -341.529882)
			(xy 106.109843 -341.558525) (xy 106.060801 -341.580356) (xy 106.035094 -341.58809) (xy 106.03484 -341.58809)
			(xy 106.023794 -341.591867) (xy 106.00646 -341.607465) (xy 106.001566 -341.618062) (xy 105.971594 -341.692992)
			(xy 105.967839 -341.704066) (xy 105.969694 -341.727353) (xy 105.97515 -341.737696) (xy 105.98752 -341.759346)
			(xy 106.006992 -341.805249) (xy 106.020171 -341.853339) (xy 106.026821 -341.902757) (xy 106.02722 -341.927688)
			(xy 106.026755 -341.954305) (xy 106.01918 -342.006999) (xy 106.004184 -342.058078) (xy 105.98207 -342.106502)
			(xy 105.95329 -342.151287) (xy 105.91843 -342.19152) (xy 105.878198 -342.226382) (xy 105.833415 -342.255163)
			(xy 105.784991 -342.277279) (xy 105.733912 -342.292277) (xy 105.681219 -342.299854) (xy 105.654602 -342.300306)
			(xy 105.62818 -342.299846) (xy 105.575865 -342.292396) (xy 105.525127 -342.277632) (xy 105.476982 -342.255848)
			(xy 105.432397 -342.227483) (xy 105.412032 -342.210644) (xy 105.405174 -342.204802) (xy 105.388156 -342.198452)
			(xy 105.303828 -342.198452) (xy 105.28681 -342.204802) (xy 105.279952 -342.210644) (xy 105.259586 -342.227483)
			(xy 105.215 -342.255848) (xy 105.166856 -342.277635) (xy 105.116119 -342.292406) (xy 105.063804 -342.299866)
			(xy 105.01096 -342.299866) (xy 104.958645 -342.292406) (xy 104.907908 -342.277635) (xy 104.859764 -342.255848)
			(xy 104.815178 -342.227483) (xy 104.794812 -342.210644) (xy 104.787954 -342.204802) (xy 104.770936 -342.198452)
			(xy 104.686608 -342.198452) (xy 104.66959 -342.204802) (xy 104.662732 -342.210644) (xy 104.642348 -342.227458)
			(xy 104.597764 -342.255819) (xy 104.549624 -342.277604) (xy 104.498891 -342.292377) (xy 104.446582 -342.299842)
			(xy 104.420162 -342.300306) (xy 104.392278 -342.299806) (xy 104.337134 -342.29149) (xy 104.283845 -342.275047)
			(xy 104.233602 -342.250847) (xy 104.187526 -342.219429) (xy 104.146648 -342.181495) (xy 104.111879 -342.137892)
			(xy 104.083996 -342.089595) (xy 104.063623 -342.037682) (xy 104.051215 -341.983312) (xy 104.047047 -341.9277)
			(xy 100.232084 -341.9277) (xy 100.229353 -341.929455) (xy 100.179776 -341.952097) (xy 100.127481 -341.967452)
			(xy 100.073533 -341.975208) (xy 100.019031 -341.975208) (xy 99.965083 -341.967452) (xy 99.912788 -341.952097)
			(xy 99.863211 -341.929455) (xy 99.817361 -341.899989) (xy 99.77617 -341.864298) (xy 99.740479 -341.823107)
			(xy 99.711013 -341.777257) (xy 99.688371 -341.72768) (xy 99.673016 -341.675385) (xy 99.66526 -341.621437)
			(xy 99.664774 -341.594186) (xy 93.000783 -341.594186) (xy 92.5576 -342.037416) (xy 92.543147 -342.05116)
			(xy 92.509981 -342.073299) (xy 92.473137 -342.088553) (xy 92.434028 -342.096338) (xy 92.41409 -342.096852)
			(xy 81.102454 -342.096852) (xy 81.092389 -342.097285) (xy 81.073801 -342.105017) (xy 81.066386 -342.111838)
			(xy 80.3524 -342.825832) (xy 100.622606 -342.825832) (xy 100.626677 -342.77021) (xy 100.638803 -342.715773)
			(xy 100.658726 -342.663682) (xy 100.686022 -342.615047) (xy 100.720108 -342.570904) (xy 100.760257 -342.532195)
			(xy 100.805615 -342.499744) (xy 100.855215 -342.474243) (xy 100.907999 -342.456236) (xy 100.962842 -342.446106)
			(xy 101.018576 -342.444069) (xy 101.074013 -342.450169) (xy 101.12797 -342.464275) (xy 101.179299 -342.486087)
			(xy 101.226905 -342.515141) (xy 101.269773 -342.550816) (xy 101.30699 -342.592353) (xy 101.337763 -342.638866)
			(xy 101.361435 -342.689363) (xy 101.377503 -342.74277) (xy 101.385623 -342.797946) (xy 101.386132 -342.825832)
			(xy 101.385623 -342.853718) (xy 101.377503 -342.908894) (xy 101.361435 -342.962301) (xy 101.337763 -343.012798)
			(xy 101.30699 -343.059311) (xy 101.269773 -343.100848) (xy 101.226905 -343.136523) (xy 101.179299 -343.165577)
			(xy 101.12797 -343.187389) (xy 101.074013 -343.201495) (xy 101.018576 -343.207595) (xy 100.962842 -343.205558)
			(xy 100.907999 -343.195428) (xy 100.855215 -343.177421) (xy 100.805615 -343.15192) (xy 100.760257 -343.119469)
			(xy 100.720108 -343.08076) (xy 100.686022 -343.036617) (xy 100.658726 -342.987982) (xy 100.638803 -342.935891)
			(xy 100.626677 -342.881454) (xy 100.622606 -342.825832) (xy 80.3524 -342.825832) (xy 58.040524 -365.137954)
			(xy 58.026023 -365.151752) (xy 57.992741 -365.17398) (xy 57.955767 -365.189297) (xy 57.916516 -365.197115)
			(xy 57.896506 -365.197644) (xy 45.009054 -365.197644) (xy 44.998989 -365.198077) (xy 44.9804 -365.205808)
			(xy 44.972986 -365.21263) (xy 41.190926 -368.99469) (xy 41.184075 -369.002087) (xy 41.176333 -369.020685)
			(xy 41.17594 -369.030758) (xy 41.17594 -370.132356) (xy 41.175484 -370.152373) (xy 41.167673 -370.191638)
			(xy 41.152342 -370.228621) (xy 41.130082 -370.261897) (xy 41.11625 -370.276374) (xy 40.140128 -371.252496)
			(xy 40.125676 -371.266243) (xy 40.092512 -371.288389) (xy 40.055668 -371.30365) (xy 40.016557 -371.311441)
			(xy 39.996618 -371.311932) (xy 34.277046 -371.311932) (xy 34.267096 -371.31247) (xy 34.248725 -371.320138)
			(xy 34.234627 -371.334192) (xy 34.23031 -371.343174) (xy 34.226755 -371.352621) (xy 34.226635 -371.372789)
			(xy 34.234342 -371.391427) (xy 34.241232 -371.3988) (xy 34.364422 -371.52199) (xy 34.371821 -371.528834)
			(xy 34.390419 -371.536562) (xy 34.40049 -371.536976) (xy 40.214804 -371.536976) (xy 40.224873 -371.536552)
			(xy 40.243475 -371.528833) (xy 40.250872 -371.52199) (xy 41.305226 -370.467382) (xy 41.312078 -370.459986)
			(xy 41.319817 -370.441387) (xy 41.320212 -370.431314) (xy 41.320212 -369.23599) (xy 41.320663 -369.21597)
			(xy 41.328466 -369.176699) (xy 41.343788 -369.139708) (xy 41.36604 -369.106422) (xy 41.379902 -369.091972)
			(xy 44.855638 -365.616236) (xy 44.870088 -365.602485) (xy 44.903251 -365.58033) (xy 44.940094 -365.56506)
			(xy 44.979207 -365.557261) (xy 44.999148 -365.5568) (xy 58.397394 -365.5568) (xy 58.407465 -365.556378)
			(xy 58.426071 -365.548665) (xy 58.433462 -365.541814) (xy 80.920082 -343.05494) (xy 80.934533 -343.041192)
			(xy 80.967697 -343.019043) (xy 81.004541 -343.003781) (xy 81.043652 -342.99599) (xy 81.063592 -342.995504)
			(xy 97.142046 -342.995504) (xy 97.16198 -342.99602) (xy 97.201078 -343.003835) (xy 97.237911 -343.019098)
			(xy 97.271076 -343.041228) (xy 97.285556 -343.05494) (xy 97.951798 -343.721182) (xy 100.043486 -343.721182)
			(xy 100.047557 -343.66556) (xy 100.059683 -343.611123) (xy 100.079606 -343.559032) (xy 100.106902 -343.510397)
			(xy 100.140988 -343.466254) (xy 100.181137 -343.427545) (xy 100.226495 -343.395094) (xy 100.276095 -343.369593)
			(xy 100.328879 -343.351586) (xy 100.383722 -343.341456) (xy 100.439456 -343.339419) (xy 100.494893 -343.345519)
			(xy 100.54885 -343.359625) (xy 100.600179 -343.381437) (xy 100.647785 -343.410491) (xy 100.690653 -343.446166)
			(xy 100.72787 -343.487703) (xy 100.758643 -343.534216) (xy 100.782315 -343.584713) (xy 100.798383 -343.63812)
			(xy 100.806503 -343.693296) (xy 100.807012 -343.721182) (xy 100.806503 -343.749068) (xy 100.798383 -343.804244)
			(xy 100.782315 -343.857651) (xy 100.758643 -343.908148) (xy 100.72787 -343.954661) (xy 100.690653 -343.996198)
			(xy 100.647785 -344.031873) (xy 100.600179 -344.060927) (xy 100.54885 -344.082739) (xy 100.494893 -344.096845)
			(xy 100.439456 -344.102945) (xy 100.383722 -344.100908) (xy 100.328879 -344.090778) (xy 100.276095 -344.072771)
			(xy 100.226495 -344.04727) (xy 100.181137 -344.014819) (xy 100.140988 -343.97611) (xy 100.106902 -343.931967)
			(xy 100.079606 -343.883332) (xy 100.059683 -343.831241) (xy 100.047557 -343.776804) (xy 100.043486 -343.721182)
			(xy 97.951798 -343.721182) (xy 98.627438 -344.396822) (xy 101.382322 -344.396822) (xy 101.382816 -344.369348)
			(xy 101.390705 -344.314968) (xy 101.406323 -344.262286) (xy 101.429346 -344.212393) (xy 101.459297 -344.166324)
			(xy 101.477064 -344.145362) (xy 101.477318 -344.145108) (xy 101.482909 -344.138025) (xy 101.489153 -344.121105)
			(xy 101.48951 -344.112088) (xy 101.48951 -344.044524) (xy 101.489139 -344.035509) (xy 101.482901 -344.018592)
			(xy 101.477318 -344.011504) (xy 101.47681 -344.010996) (xy 101.45908 -343.990047) (xy 101.429197 -343.944015)
			(xy 101.40623 -343.894171) (xy 101.390654 -343.841546) (xy 101.382793 -343.787231) (xy 101.382322 -343.75979)
			(xy 101.382808 -343.732539) (xy 101.390564 -343.678591) (xy 101.405919 -343.626296) (xy 101.428561 -343.576719)
			(xy 101.458027 -343.530869) (xy 101.493718 -343.489678) (xy 101.534909 -343.453987) (xy 101.580759 -343.424521)
			(xy 101.630336 -343.401879) (xy 101.682631 -343.386524) (xy 101.736579 -343.378768) (xy 101.791081 -343.378768)
			(xy 101.845029 -343.386524) (xy 101.897324 -343.401879) (xy 101.946901 -343.424521) (xy 101.992751 -343.453987)
			(xy 102.033942 -343.489678) (xy 102.069633 -343.530869) (xy 102.099099 -343.576719) (xy 102.121741 -343.626296)
			(xy 102.137096 -343.678591) (xy 102.144852 -343.732539) (xy 102.145338 -343.75979) (xy 102.144836 -343.787264)
			(xy 102.136947 -343.841643) (xy 102.12133 -343.894324) (xy 102.098309 -343.944217) (xy 102.068361 -343.990287)
			(xy 102.050596 -344.01125) (xy 102.050342 -344.011504) (xy 102.044741 -344.01858) (xy 102.038504 -344.035505)
			(xy 102.03815 -344.044524) (xy 102.03815 -344.112088) (xy 102.038502 -344.121106) (xy 102.044752 -344.138023)
			(xy 102.050342 -344.145108) (xy 102.05085 -344.145616) (xy 102.068579 -344.166566) (xy 102.098464 -344.212597)
			(xy 102.121432 -344.262441) (xy 102.137007 -344.315066) (xy 102.144868 -344.369381) (xy 102.145338 -344.396822)
			(xy 102.144852 -344.424073) (xy 102.137096 -344.478021) (xy 102.121741 -344.530316) (xy 102.099099 -344.579893)
			(xy 102.069633 -344.625743) (xy 102.033942 -344.666934) (xy 101.992751 -344.702625) (xy 101.946901 -344.732091)
			(xy 101.897324 -344.754733) (xy 101.845029 -344.770088) (xy 101.791081 -344.777844) (xy 101.736579 -344.777844)
			(xy 101.682631 -344.770088) (xy 101.630336 -344.754733) (xy 101.580759 -344.732091) (xy 101.534909 -344.702625)
			(xy 101.493718 -344.666934) (xy 101.458027 -344.625743) (xy 101.428561 -344.579893) (xy 101.405919 -344.530316)
			(xy 101.390564 -344.478021) (xy 101.382808 -344.424073) (xy 101.382322 -344.396822) (xy 98.627438 -344.396822)
			(xy 99.792282 -345.561666) (xy 99.799683 -345.568503) (xy 99.818282 -345.576213) (xy 99.82835 -345.576652)
			(xy 101.70795 -345.576652) (xy 101.718015 -345.576218) (xy 101.736602 -345.568486) (xy 101.744018 -345.561666)
			(xy 102.879652 -344.426286) (xy 102.886695 -344.418613) (xy 102.894426 -344.399298) (xy 102.893801 -344.378502)
			(xy 102.889812 -344.368882) (xy 102.849934 -344.282268) (xy 102.845098 -344.273036) (xy 102.829559 -344.259177)
			(xy 102.809799 -344.252614) (xy 102.799388 -344.253058) (xy 102.7684 -344.254328) (xy 102.768146 -344.254328)
			(xy 102.74089 -344.253868) (xy 102.686931 -344.246116) (xy 102.634625 -344.230763) (xy 102.585036 -344.208122)
			(xy 102.539175 -344.178654) (xy 102.497974 -344.142958) (xy 102.462274 -344.101762) (xy 102.4328 -344.055904)
			(xy 102.410153 -344.006319) (xy 102.394794 -343.954014) (xy 102.387035 -343.900056) (xy 102.387035 -343.845544)
			(xy 102.394794 -343.791586) (xy 102.410153 -343.739281) (xy 102.4328 -343.689696) (xy 102.462274 -343.643838)
			(xy 102.497974 -343.602642) (xy 102.539175 -343.566946) (xy 102.585036 -343.537478) (xy 102.634625 -343.514837)
			(xy 102.686931 -343.499484) (xy 102.74089 -343.491732) (xy 102.768146 -343.491312) (xy 102.7684 -343.491312)
			(xy 102.7936 -343.491741) (xy 102.843558 -343.498412) (xy 102.892207 -343.511588) (xy 102.938703 -343.531039)
			(xy 102.960678 -343.543382) (xy 102.970584 -343.549224) (xy 102.992428 -343.551256) (xy 103.08717 -343.517728)
			(xy 103.102918 -343.502234) (xy 103.106982 -343.49182) (xy 103.117676 -343.465042) (xy 103.145961 -343.414797)
			(xy 103.18149 -343.369385) (xy 103.223452 -343.32984) (xy 103.27089 -343.297064) (xy 103.322722 -343.271805)
			(xy 103.377767 -343.254639) (xy 103.434768 -343.245956) (xy 103.463598 -343.24544) (xy 103.49085 -343.245903)
			(xy 103.544798 -343.25366) (xy 103.597094 -343.269017) (xy 103.646671 -343.29166) (xy 103.692521 -343.321128)
			(xy 103.73371 -343.356823) (xy 103.769399 -343.398016) (xy 103.798862 -343.443869) (xy 103.801736 -343.450164)
			(xy 105.961942 -343.450164) (xy 105.962437 -343.42259) (xy 105.970382 -343.368018) (xy 105.9861 -343.315158)
			(xy 106.009264 -343.265112) (xy 106.039392 -343.218922) (xy 106.075856 -343.17755) (xy 106.096562 -343.159334)
			(xy 106.104632 -343.151775) (xy 106.113987 -343.131766) (xy 106.114596 -343.120726) (xy 106.114596 -343.043002)
			(xy 106.114028 -343.031953) (xy 106.104663 -343.011932) (xy 106.096562 -343.004394) (xy 106.075837 -342.986198)
			(xy 106.03937 -342.944825) (xy 106.00924 -342.898632) (xy 105.986077 -342.848581) (xy 105.970363 -342.795716)
			(xy 105.962426 -342.741139) (xy 105.961942 -342.713564) (xy 105.962322 -342.686308) (xy 105.970085 -342.632351)
			(xy 105.985448 -342.580049) (xy 106.008098 -342.530465) (xy 106.037575 -342.48461) (xy 106.073277 -342.443416)
			(xy 106.114479 -342.407723) (xy 106.160341 -342.378257) (xy 106.20993 -342.355618) (xy 106.262236 -342.340266)
			(xy 106.316194 -342.332515) (xy 106.34345 -342.332056) (xy 106.375072 -342.33266) (xy 106.437445 -342.343115)
			(xy 106.497234 -342.363729) (xy 106.525314 -342.378284) (xy 106.53395 -342.382856) (xy 106.553254 -342.385142)
			(xy 106.639868 -342.362028) (xy 106.655362 -342.350344) (xy 106.660442 -342.341962) (xy 106.676797 -342.316317)
			(xy 106.716359 -342.270121) (xy 106.739182 -342.250014) (xy 106.747248 -342.24245) (xy 106.756608 -342.222446)
			(xy 106.757216 -342.211406) (xy 106.757216 -342.133682) (xy 106.756629 -342.122634) (xy 106.74728 -342.102611)
			(xy 106.739182 -342.095074) (xy 106.718451 -342.076884) (xy 106.681983 -342.03551) (xy 106.651854 -341.989316)
			(xy 106.628692 -341.939264) (xy 106.61298 -341.886398) (xy 106.605045 -341.83182) (xy 106.604562 -341.804244)
			(xy 106.605048 -341.776993) (xy 106.612804 -341.723045) (xy 106.628159 -341.67075) (xy 106.650801 -341.621173)
			(xy 106.680267 -341.575323) (xy 106.715958 -341.534132) (xy 106.757149 -341.498441) (xy 106.802999 -341.468975)
			(xy 106.852576 -341.446333) (xy 106.904871 -341.430978) (xy 106.958819 -341.423222) (xy 107.013321 -341.423222)
			(xy 107.067269 -341.430978) (xy 107.119564 -341.446333) (xy 107.169141 -341.468975) (xy 107.214991 -341.498441)
			(xy 107.256182 -341.534132) (xy 107.291873 -341.575323) (xy 107.321339 -341.621173) (xy 107.343981 -341.67075)
			(xy 107.359336 -341.723045) (xy 107.367092 -341.776993) (xy 107.367578 -341.804244) (xy 107.367081 -341.831818)
			(xy 107.359136 -341.886389) (xy 107.343418 -341.939249) (xy 107.320254 -341.989295) (xy 107.290126 -342.035486)
			(xy 107.253663 -342.076858) (xy 107.232958 -342.095074) (xy 107.224887 -342.102633) (xy 107.215532 -342.122642)
			(xy 107.214924 -342.133682) (xy 107.214924 -342.211406) (xy 107.215537 -342.22245) (xy 107.22487 -342.242472)
			(xy 107.232958 -342.250014) (xy 107.253671 -342.268224) (xy 107.290143 -342.309592) (xy 107.320276 -342.355781)
			(xy 107.343442 -342.40583) (xy 107.359157 -342.458693) (xy 107.367094 -342.513269) (xy 107.367578 -342.540844)
			(xy 107.367008 -342.570786) (xy 107.357634 -342.629932) (xy 107.339138 -342.686889) (xy 107.311974 -342.740259)
			(xy 107.27681 -342.788732) (xy 107.256072 -342.810338) (xy 107.248971 -342.818108) (xy 107.241235 -342.837659)
			(xy 107.241086 -342.848184) (xy 107.244134 -342.922606) (xy 107.245046 -342.933142) (xy 107.254233 -342.952166)
			(xy 107.261914 -342.959436) (xy 107.282469 -342.977667) (xy 107.318675 -343.018991) (xy 107.34858 -343.065079)
			(xy 107.371568 -343.114979) (xy 107.387162 -343.167661) (xy 107.39504 -343.222034) (xy 107.395518 -343.249504)
			(xy 107.395049 -343.277078) (xy 107.387096 -343.331651) (xy 107.371371 -343.38451) (xy 107.348202 -343.434556)
			(xy 107.31807 -343.480746) (xy 107.281604 -343.522118) (xy 107.260898 -343.540334) (xy 107.252807 -343.547875)
			(xy 107.243462 -343.567897) (xy 107.242864 -343.578942) (xy 107.242864 -343.656666) (xy 107.243431 -343.667716)
			(xy 107.252795 -343.687738) (xy 107.260898 -343.695274) (xy 107.281599 -343.713496) (xy 107.318071 -343.754862)
			(xy 107.348204 -343.80105) (xy 107.371371 -343.851096) (xy 107.38709 -343.903957) (xy 107.395032 -343.95853)
			(xy 107.395518 -343.986104) (xy 107.395032 -344.013355) (xy 107.387276 -344.067303) (xy 107.371921 -344.119598)
			(xy 107.349279 -344.169175) (xy 107.319813 -344.215025) (xy 107.284122 -344.256216) (xy 107.242931 -344.291907)
			(xy 107.197081 -344.321373) (xy 107.147504 -344.344015) (xy 107.095209 -344.35937) (xy 107.041261 -344.367126)
			(xy 106.986759 -344.367126) (xy 106.932811 -344.35937) (xy 106.880516 -344.344015) (xy 106.830939 -344.321373)
			(xy 106.785089 -344.291907) (xy 106.743898 -344.256216) (xy 106.708207 -344.215025) (xy 106.678741 -344.169175)
			(xy 106.656099 -344.119598) (xy 106.640744 -344.067303) (xy 106.632988 -344.013355) (xy 106.632502 -343.986104)
			(xy 106.632502 -343.985342) (xy 106.632746 -343.966675) (xy 106.636431 -343.929523) (xy 106.639868 -343.911174)
			(xy 106.642662 -343.897204) (xy 106.63301 -343.870534) (xy 106.540046 -343.796366) (xy 106.512106 -343.79281)
			(xy 106.498898 -343.798652) (xy 106.474378 -343.809107) (xy 106.423142 -343.823814) (xy 106.370356 -343.831233)
			(xy 106.343704 -343.831672) (xy 106.34345 -343.831672) (xy 106.316197 -343.831198) (xy 106.262244 -343.823447)
			(xy 106.209944 -343.808095) (xy 106.160362 -343.785456) (xy 106.114507 -343.75599) (xy 106.073313 -343.720297)
			(xy 106.037618 -343.679104) (xy 106.008151 -343.63325) (xy 105.985509 -343.583669) (xy 105.970156 -343.531369)
			(xy 105.962403 -343.477417) (xy 105.961942 -343.450164) (xy 103.801736 -343.450164) (xy 103.8215 -343.49345)
			(xy 103.83685 -343.545747) (xy 103.8446 -343.599696) (xy 103.845106 -343.626948) (xy 103.844459 -343.658512)
			(xy 103.834078 -343.720781) (xy 103.81359 -343.780492) (xy 103.799132 -343.808558) (xy 103.794306 -343.817448)
			(xy 103.792274 -343.837006) (xy 103.815134 -343.915492) (xy 103.818382 -343.924909) (xy 103.830804 -343.940458)
			(xy 103.839264 -343.945718) (xy 103.864362 -343.960271) (xy 103.910237 -343.995784) (xy 103.950209 -344.037831)
			(xy 103.983357 -344.085442) (xy 104.008917 -344.137523) (xy 104.026301 -344.192871) (xy 104.035108 -344.250213)
			(xy 104.035606 -344.27922) (xy 104.035119 -344.30647) (xy 104.02736 -344.360416) (xy 104.012003 -344.412708)
			(xy 103.989361 -344.462283) (xy 103.959894 -344.50813) (xy 103.924202 -344.549318) (xy 103.883013 -344.585007)
			(xy 103.837163 -344.614471) (xy 103.787587 -344.637111) (xy 103.735294 -344.652465) (xy 103.681348 -344.66022)
			(xy 103.654098 -344.660728) (xy 103.625359 -344.660206) (xy 103.568533 -344.651582) (xy 103.513644 -344.634529)
			(xy 103.461935 -344.609434) (xy 103.414577 -344.576864) (xy 103.39324 -344.557604) (xy 103.378254 -344.543634)
			(xy 103.33736 -344.544142) (xy 101.957378 -345.924378) (xy 101.94288 -345.938184) (xy 101.909603 -345.960429)
			(xy 101.872628 -345.975762) (xy 101.833374 -345.983594) (xy 101.81336 -345.984068) (xy 99.72294 -345.984068)
			(xy 99.702923 -345.983612) (xy 99.663657 -345.9758) (xy 99.626674 -345.960471) (xy 99.593397 -345.938213)
			(xy 99.578922 -345.924378) (xy 97.072196 -343.417398) (xy 97.064797 -343.410552) (xy 97.046199 -343.40282)
			(xy 97.036128 -343.402412) (xy 81.16951 -343.402412) (xy 81.159439 -343.402834) (xy 81.140833 -343.410547)
			(xy 81.133442 -343.417398) (xy 79.313299 -345.237562) (xy 88.93302 -345.237562) (xy 88.933443 -345.210309)
			(xy 88.941205 -345.156357) (xy 88.956566 -345.104059) (xy 88.979214 -345.05448) (xy 89.008687 -345.008629)
			(xy 89.044385 -344.967438) (xy 89.085582 -344.931747) (xy 89.131438 -344.902282) (xy 89.181021 -344.879643)
			(xy 89.233322 -344.864291) (xy 89.287274 -344.856538) (xy 89.314528 -344.856054) (xy 89.339987 -344.856488)
			(xy 89.390452 -344.863253) (xy 89.439569 -344.876671) (xy 89.486464 -344.896505) (xy 89.530304 -344.922402)
			(xy 89.570308 -344.953902) (xy 89.58834 -344.971878) (xy 89.595447 -344.978501) (xy 89.613201 -344.986344)
			(xy 89.622884 -344.987118) (xy 89.702894 -344.989912) (xy 89.721436 -344.983308) (xy 89.728802 -344.976704)
			(xy 89.749893 -344.958526) (xy 89.796364 -344.927857) (xy 89.8468 -344.904269) (xy 89.900128 -344.888262)
			(xy 89.955217 -344.880177) (xy 89.983056 -344.879676) (xy 90.010426 -344.880149) (xy 90.064606 -344.887963)
			(xy 90.117109 -344.903449) (xy 90.166857 -344.92629) (xy 90.212823 -344.956014) (xy 90.233754 -344.973656)
			(xy 90.234008 -344.97391) (xy 90.241087 -344.979507) (xy 90.25801 -344.985747) (xy 90.267028 -344.986102)
			(xy 90.334084 -344.986102) (xy 90.3431 -344.985737) (xy 90.360017 -344.979495) (xy 90.367104 -344.97391)
			(xy 90.367104 -344.973656) (xy 90.367358 -344.973656) (xy 90.388289 -344.956016) (xy 90.434263 -344.926306)
			(xy 90.484011 -344.90347) (xy 90.536511 -344.887979) (xy 90.590687 -344.88015) (xy 90.618056 -344.879676)
			(xy 90.646973 -344.880197) (xy 90.704145 -344.888922) (xy 90.759345 -344.906177) (xy 90.811308 -344.931568)
			(xy 90.858841 -344.964513) (xy 90.900857 -345.004256) (xy 90.919046 -345.026742) (xy 90.926636 -345.035567)
			(xy 90.94755 -345.045739) (xy 90.959178 -345.0463) (xy 91.038934 -345.0463) (xy 91.050566 -345.045766)
			(xy 91.071476 -345.035573) (xy 91.079066 -345.026742) (xy 91.097287 -345.004284) (xy 91.139299 -344.964545)
			(xy 91.186827 -344.931602) (xy 91.238783 -344.906209) (xy 91.293976 -344.888947) (xy 91.351142 -344.880213)
			(xy 91.380056 -344.879676) (xy 91.407426 -344.880149) (xy 91.461606 -344.887963) (xy 91.514109 -344.903449)
			(xy 91.563857 -344.92629) (xy 91.609823 -344.956014) (xy 91.630754 -344.973656) (xy 91.631008 -344.97391)
			(xy 91.638087 -344.979507) (xy 91.65501 -344.985747) (xy 91.664028 -344.986102) (xy 91.731084 -344.986102)
			(xy 91.7401 -344.985737) (xy 91.757017 -344.979495) (xy 91.764104 -344.97391) (xy 91.764104 -344.973656)
			(xy 91.764358 -344.973656) (xy 91.785291 -344.956015) (xy 91.831259 -344.926291) (xy 91.881005 -344.903445)
			(xy 91.933507 -344.887949) (xy 91.987685 -344.88012) (xy 92.042427 -344.88012) (xy 92.096605 -344.887949)
			(xy 92.149107 -344.903445) (xy 92.198853 -344.926291) (xy 92.244821 -344.956015) (xy 92.265754 -344.973656)
			(xy 92.266008 -344.97391) (xy 92.273087 -344.979507) (xy 92.29001 -344.985747) (xy 92.299028 -344.986102)
			(xy 92.366084 -344.986102) (xy 92.3751 -344.985737) (xy 92.392017 -344.979495) (xy 92.399104 -344.97391)
			(xy 92.399104 -344.973656) (xy 92.399358 -344.973656) (xy 92.420289 -344.956016) (xy 92.466263 -344.926306)
			(xy 92.516011 -344.90347) (xy 92.568511 -344.887979) (xy 92.622687 -344.88015) (xy 92.650056 -344.879676)
			(xy 92.677307 -344.880196) (xy 92.731255 -344.887947) (xy 92.783551 -344.903296) (xy 92.83313 -344.925933)
			(xy 92.878982 -344.955395) (xy 92.920175 -344.991082) (xy 92.955869 -345.03227) (xy 92.985339 -345.078117)
			(xy 93.007983 -345.127693) (xy 93.02334 -345.179986) (xy 93.0311 -345.233933) (xy 93.031564 -345.261184)
			(xy 93.031019 -345.289629) (xy 93.022568 -345.345888) (xy 93.00585 -345.400266) (xy 92.981238 -345.451556)
			(xy 92.949277 -345.49862) (xy 92.910677 -345.540411) (xy 92.888816 -345.558618) (xy 92.880986 -345.565633)
			(xy 92.871273 -345.584249) (xy 92.87002 -345.594686) (xy 92.86494 -345.669362) (xy 92.864763 -345.679888)
			(xy 92.871843 -345.699691) (xy 92.878656 -345.707716) (xy 92.898109 -345.72907) (xy 92.930987 -345.776563)
			(xy 92.956328 -345.828471) (xy 92.973551 -345.883606) (xy 92.982263 -345.940709) (xy 92.982796 -345.96959)
			(xy 92.98234 -345.996725) (xy 92.974645 -346.050445) (xy 92.959409 -346.102532) (xy 92.936941 -346.151931)
			(xy 92.907694 -346.197645) (xy 92.89034 -346.21851) (xy 92.890086 -346.218764) (xy 92.884144 -346.226452)
			(xy 92.877994 -346.244864) (xy 92.878148 -346.254578) (xy 92.881958 -346.324936) (xy 92.882979 -346.334743)
			(xy 92.891491 -346.352511) (xy 92.898468 -346.35948) (xy 92.917459 -346.377615) (xy 92.950775 -346.418205)
			(xy 92.978215 -346.462976) (xy 92.999261 -346.511085) (xy 93.013517 -346.561624) (xy 93.020713 -346.61364)
			(xy 93.02115 -346.639896) (xy 93.020619 -346.667145) (xy 93.012864 -346.721089) (xy 92.997511 -346.77338)
			(xy 92.974874 -346.822955) (xy 92.945412 -346.868803) (xy 92.909725 -346.909992) (xy 92.86854 -346.945684)
			(xy 92.822695 -346.975152) (xy 92.773124 -346.997795) (xy 92.720834 -347.013154) (xy 92.666891 -347.020915)
			(xy 92.639642 -347.021404) (xy 92.612273 -347.020912) (xy 92.558095 -347.013101) (xy 92.505592 -346.997617)
			(xy 92.455845 -346.974781) (xy 92.409877 -346.945063) (xy 92.388944 -346.927424) (xy 92.38869 -346.92717)
			(xy 92.381613 -346.92157) (xy 92.364689 -346.915332) (xy 92.35567 -346.914978) (xy 92.288614 -346.914978)
			(xy 92.279598 -346.915347) (xy 92.262682 -346.921587) (xy 92.255594 -346.92717) (xy 92.255594 -346.927424)
			(xy 92.25534 -346.927424) (xy 92.234407 -346.945062) (xy 92.188434 -346.974773) (xy 92.138687 -346.997609)
			(xy 92.086186 -347.0131) (xy 92.032011 -347.020929) (xy 92.004642 -347.021404) (xy 91.978327 -347.020974)
			(xy 91.926197 -347.013731) (xy 91.875553 -346.999405) (xy 91.827355 -346.978265) (xy 91.782512 -346.950713)
			(xy 91.741874 -346.917268) (xy 91.723718 -346.898214) (xy 91.71619 -346.89082) (xy 91.696915 -346.882291)
			(xy 91.68638 -346.881704) (xy 91.611704 -346.881704) (xy 91.601153 -346.882221) (xy 91.581858 -346.890765)
			(xy 91.574366 -346.898214) (xy 91.556223 -346.917282) (xy 91.51559 -346.950737) (xy 91.470747 -346.978294)
			(xy 91.422544 -346.999431) (xy 91.371894 -347.013745) (xy 91.319759 -347.020967) (xy 91.293442 -347.021404)
			(xy 91.266073 -347.020912) (xy 91.211895 -347.013101) (xy 91.159392 -346.997617) (xy 91.109645 -346.974781)
			(xy 91.063677 -346.945063) (xy 91.042744 -346.927424) (xy 91.04249 -346.92717) (xy 91.035413 -346.92157)
			(xy 91.018489 -346.915332) (xy 91.00947 -346.914978) (xy 90.942414 -346.914978) (xy 90.933398 -346.915347)
			(xy 90.916482 -346.921587) (xy 90.909394 -346.92717) (xy 90.909394 -346.927424) (xy 90.90914 -346.927424)
			(xy 90.888207 -346.945065) (xy 90.842239 -346.974789) (xy 90.792493 -346.997635) (xy 90.739991 -347.013131)
			(xy 90.685813 -347.02096) (xy 90.631071 -347.02096) (xy 90.576893 -347.013131) (xy 90.524391 -346.997635)
			(xy 90.474645 -346.974789) (xy 90.428677 -346.945065) (xy 90.407744 -346.927424) (xy 90.40749 -346.92717)
			(xy 90.400413 -346.92157) (xy 90.383489 -346.915332) (xy 90.37447 -346.914978) (xy 90.307414 -346.914978)
			(xy 90.298398 -346.915347) (xy 90.281482 -346.921587) (xy 90.274394 -346.92717) (xy 90.274394 -346.927424)
			(xy 90.27414 -346.927424) (xy 90.253207 -346.945065) (xy 90.207239 -346.974789) (xy 90.157493 -346.997635)
			(xy 90.104991 -347.013131) (xy 90.050813 -347.02096) (xy 89.996071 -347.02096) (xy 89.941893 -347.013131)
			(xy 89.889391 -346.997635) (xy 89.839645 -346.974789) (xy 89.793677 -346.945065) (xy 89.772744 -346.927424)
			(xy 89.77249 -346.92717) (xy 89.765413 -346.92157) (xy 89.748489 -346.915332) (xy 89.73947 -346.914978)
			(xy 89.672414 -346.914978) (xy 89.663398 -346.915347) (xy 89.646482 -346.921587) (xy 89.639394 -346.92717)
			(xy 89.639394 -346.927424) (xy 89.63914 -346.927424) (xy 89.618207 -346.945062) (xy 89.572234 -346.974773)
			(xy 89.522487 -346.997609) (xy 89.469986 -347.0131) (xy 89.415811 -347.020929) (xy 89.388442 -347.021404)
			(xy 89.36119 -347.020906) (xy 89.30724 -347.013154) (xy 89.254943 -346.997803) (xy 89.205362 -346.975165)
			(xy 89.159509 -346.945701) (xy 89.118316 -346.910011) (xy 89.082621 -346.868822) (xy 89.053153 -346.822971)
			(xy 89.03051 -346.773393) (xy 89.015154 -346.721097) (xy 89.007397 -346.667148) (xy 89.006934 -346.639896)
			(xy 89.007433 -346.612763) (xy 89.015116 -346.559044) (xy 89.030342 -346.506957) (xy 89.0528 -346.457557)
			(xy 89.082039 -346.411842) (xy 89.09939 -346.390976) (xy 89.099644 -346.390722) (xy 89.105596 -346.383041)
			(xy 89.111739 -346.364624) (xy 89.111582 -346.354908) (xy 89.107772 -346.28455) (xy 89.1067 -346.274752)
			(xy 89.098224 -346.256981) (xy 89.091262 -346.250006) (xy 89.07227 -346.231872) (xy 89.038953 -346.191283)
			(xy 89.011512 -346.146511) (xy 88.990466 -346.098402) (xy 88.976211 -346.047862) (xy 88.969016 -345.995846)
			(xy 88.96858 -345.96959) (xy 88.968982 -345.943757) (xy 88.975961 -345.892564) (xy 88.989789 -345.842783)
			(xy 89.010214 -345.795326) (xy 89.036861 -345.751062) (xy 89.069241 -345.710801) (xy 89.087706 -345.69273)
			(xy 89.08796 -345.692476) (xy 89.095447 -345.684537) (xy 89.103483 -345.664272) (xy 89.103454 -345.65336)
			(xy 89.099644 -345.576144) (xy 89.098606 -345.565329) (xy 89.088744 -345.545991) (xy 89.080594 -345.538806)
			(xy 89.080086 -345.538552) (xy 89.057625 -345.520335) (xy 89.017889 -345.47832) (xy 88.984947 -345.430791)
			(xy 88.959555 -345.378835) (xy 88.942294 -345.323642) (xy 88.933559 -345.266476) (xy 88.93302 -345.237562)
			(xy 79.313299 -345.237562) (xy 75.651422 -348.89948) (xy 81.802478 -348.89948) (xy 81.802982 -348.871033)
			(xy 81.81144 -348.814772) (xy 81.828164 -348.760392) (xy 81.852784 -348.709102) (xy 81.884753 -348.66204)
			(xy 81.923361 -348.620251) (xy 81.945226 -348.602046) (xy 81.953061 -348.595036) (xy 81.962773 -348.576416)
			(xy 81.964022 -348.565978) (xy 81.969102 -348.491302) (xy 81.969289 -348.480776) (xy 81.962201 -348.460973)
			(xy 81.955386 -348.452948) (xy 81.93597 -348.431562) (xy 81.903085 -348.384078) (xy 81.877737 -348.332179)
			(xy 81.860505 -348.27705) (xy 81.851784 -348.219953) (xy 81.851246 -348.191074) (xy 81.851732 -348.163823)
			(xy 81.859488 -348.109875) (xy 81.874843 -348.05758) (xy 81.897485 -348.008003) (xy 81.926951 -347.962153)
			(xy 81.962642 -347.920962) (xy 82.003833 -347.885271) (xy 82.049683 -347.855805) (xy 82.09926 -347.833163)
			(xy 82.151555 -347.817808) (xy 82.205503 -347.810052) (xy 82.260005 -347.810052) (xy 82.313953 -347.817808)
			(xy 82.366248 -347.833163) (xy 82.415825 -347.855805) (xy 82.461675 -347.885271) (xy 82.502866 -347.920962)
			(xy 82.538557 -347.962153) (xy 82.568023 -348.008003) (xy 82.590665 -348.05758) (xy 82.60602 -348.109875)
			(xy 82.613776 -348.163823) (xy 82.614262 -348.191074) (xy 82.613711 -348.219519) (xy 82.605261 -348.275777)
			(xy 82.588544 -348.330155) (xy 82.563933 -348.381446) (xy 82.531973 -348.428509) (xy 82.493375 -348.470301)
			(xy 82.471514 -348.488508) (xy 82.463647 -348.495487) (xy 82.453955 -348.51413) (xy 82.452718 -348.524576)
			(xy 82.447638 -348.599252) (xy 82.447467 -348.609778) (xy 82.454543 -348.62958) (xy 82.461354 -348.637606)
			(xy 82.480802 -348.658964) (xy 82.513681 -348.706456) (xy 82.539022 -348.758363) (xy 82.556247 -348.813497)
			(xy 82.563515 -348.861126) (xy 84.464144 -348.861126) (xy 84.464693 -348.832681) (xy 84.473143 -348.776422)
			(xy 84.48986 -348.722044) (xy 84.514471 -348.670754) (xy 84.546432 -348.62369) (xy 84.585031 -348.581899)
			(xy 84.606892 -348.563692) (xy 84.61476 -348.556714) (xy 84.624452 -348.53807) (xy 84.625688 -348.527624)
			(xy 84.630768 -348.452948) (xy 84.630938 -348.442422) (xy 84.623863 -348.42262) (xy 84.617052 -348.414594)
			(xy 84.597605 -348.393235) (xy 84.564726 -348.345743) (xy 84.539384 -348.293837) (xy 84.522159 -348.238702)
			(xy 84.513446 -348.181601) (xy 84.512912 -348.15272) (xy 84.513398 -348.125469) (xy 84.521154 -348.071521)
			(xy 84.536509 -348.019226) (xy 84.559151 -347.969649) (xy 84.588617 -347.923799) (xy 84.624308 -347.882608)
			(xy 84.665499 -347.846917) (xy 84.711349 -347.817451) (xy 84.760926 -347.794809) (xy 84.813221 -347.779454)
			(xy 84.867169 -347.771698) (xy 84.921671 -347.771698) (xy 84.975619 -347.779454) (xy 85.027914 -347.794809)
			(xy 85.077491 -347.817451) (xy 85.123341 -347.846917) (xy 85.164532 -347.882608) (xy 85.200223 -347.923799)
			(xy 85.229689 -347.969649) (xy 85.252331 -348.019226) (xy 85.267686 -348.071521) (xy 85.275442 -348.125469)
			(xy 85.275928 -348.15272) (xy 85.275422 -348.181167) (xy 85.266964 -348.237428) (xy 85.25024 -348.291807)
			(xy 85.22562 -348.343098) (xy 85.193652 -348.39016) (xy 85.155045 -348.431949) (xy 85.13318 -348.450154)
			(xy 85.125346 -348.457165) (xy 85.115633 -348.475784) (xy 85.114384 -348.486222) (xy 85.109304 -348.560898)
			(xy 85.109116 -348.571424) (xy 85.116205 -348.591227) (xy 85.12302 -348.599252) (xy 85.142437 -348.620638)
			(xy 85.175321 -348.668121) (xy 85.200669 -348.720021) (xy 85.217901 -348.77515) (xy 85.226622 -348.832247)
			(xy 85.22716 -348.861126) (xy 85.226675 -348.88826) (xy 85.218989 -348.94198) (xy 85.20376 -348.994066)
			(xy 85.181298 -349.043466) (xy 85.152056 -349.089181) (xy 85.134704 -349.110046) (xy 85.13445 -349.1103)
			(xy 85.128487 -349.117974) (xy 85.122351 -349.136397) (xy 85.122512 -349.146114) (xy 85.126322 -349.216472)
			(xy 85.127385 -349.226271) (xy 85.135868 -349.244041) (xy 85.142832 -349.251016) (xy 85.161804 -349.26917)
			(xy 85.19512 -349.309756) (xy 85.222561 -349.354524) (xy 85.24361 -349.40263) (xy 85.257871 -349.453165)
			(xy 85.265073 -349.505178) (xy 85.265514 -349.531432) (xy 85.265084 -349.557607) (xy 85.257906 -349.609464)
			(xy 85.243704 -349.659852) (xy 85.222744 -349.707825) (xy 85.195421 -349.75248) (xy 85.162246 -349.792978)
			(xy 85.14334 -349.811086) (xy 85.135996 -349.818627) (xy 85.127606 -349.83791) (xy 85.127084 -349.848424)
			(xy 85.127084 -349.922846) (xy 85.127591 -349.933366) (xy 85.135975 -349.952657) (xy 85.14334 -349.960184)
			(xy 85.162244 -349.978296) (xy 85.195432 -350.018785) (xy 85.222764 -350.063437) (xy 85.243724 -350.11141)
			(xy 85.25792 -350.161801) (xy 85.265082 -350.213662) (xy 85.265514 -350.239838) (xy 85.265028 -350.267089)
			(xy 85.257272 -350.321037) (xy 85.241917 -350.373332) (xy 85.219275 -350.422909) (xy 85.189809 -350.468759)
			(xy 85.154118 -350.50995) (xy 85.112927 -350.545641) (xy 85.067077 -350.575107) (xy 85.0175 -350.597749)
			(xy 84.965205 -350.613104) (xy 84.911257 -350.62086) (xy 84.856755 -350.62086) (xy 84.802807 -350.613104)
			(xy 84.750512 -350.597749) (xy 84.700935 -350.575107) (xy 84.655085 -350.545641) (xy 84.613894 -350.50995)
			(xy 84.578203 -350.468759) (xy 84.548737 -350.422909) (xy 84.526095 -350.373332) (xy 84.51074 -350.321037)
			(xy 84.502984 -350.267089) (xy 84.502498 -350.239838) (xy 84.502904 -350.213662) (xy 84.510086 -350.161804)
			(xy 84.524293 -350.111415) (xy 84.545257 -350.063443) (xy 84.572585 -350.018788) (xy 84.605763 -349.978291)
			(xy 84.624672 -349.960184) (xy 84.632031 -349.952655) (xy 84.640412 -349.933363) (xy 84.640928 -349.922846)
			(xy 84.640928 -349.848424) (xy 84.640462 -349.837899) (xy 84.632052 -349.818606) (xy 84.624672 -349.811086)
			(xy 84.605736 -349.793006) (xy 84.572555 -349.752508) (xy 84.545229 -349.707849) (xy 84.524274 -349.65987)
			(xy 84.510085 -349.609474) (xy 84.502927 -349.55761) (xy 84.502498 -349.531432) (xy 84.502968 -349.504298)
			(xy 84.51066 -349.450578) (xy 84.525892 -349.398491) (xy 84.548357 -349.349092) (xy 84.577601 -349.303377)
			(xy 84.594954 -349.282512) (xy 84.595208 -349.282258) (xy 84.60114 -349.274563) (xy 84.607296 -349.256157)
			(xy 84.607146 -349.246444) (xy 84.603336 -349.176086) (xy 84.602306 -349.166281) (xy 84.593801 -349.148512)
			(xy 84.586826 -349.141542) (xy 84.567845 -349.123397) (xy 84.534528 -349.08281) (xy 84.507087 -349.03804)
			(xy 84.486039 -348.989933) (xy 84.471781 -348.939396) (xy 84.464582 -348.887381) (xy 84.464144 -348.861126)
			(xy 82.563515 -348.861126) (xy 82.56496 -348.870599) (xy 82.565494 -348.89948) (xy 82.565032 -348.926614)
			(xy 82.557339 -348.980335) (xy 82.542105 -349.032421) (xy 82.519638 -349.081821) (xy 82.490392 -349.127535)
			(xy 82.473038 -349.1484) (xy 82.472784 -349.148654) (xy 82.466846 -349.156345) (xy 82.460694 -349.174754)
			(xy 82.460846 -349.184468) (xy 82.464656 -349.254826) (xy 82.465682 -349.264632) (xy 82.47419 -349.282401)
			(xy 82.481166 -349.28937) (xy 82.500152 -349.307511) (xy 82.533468 -349.348099) (xy 82.560909 -349.392869)
			(xy 82.581956 -349.440977) (xy 82.596213 -349.491515) (xy 82.60341 -349.543531) (xy 82.603848 -349.569786)
			(xy 82.603378 -349.597599) (xy 82.595301 -349.652636) (xy 82.579317 -349.705916) (xy 82.555764 -349.756309)
			(xy 82.525142 -349.802748) (xy 82.4881 -349.844246) (xy 82.445423 -349.879925) (xy 82.421984 -349.894906)
			(xy 82.410554 -349.901764) (xy 82.397854 -349.924624) (xy 82.3976 -350.0247) (xy 82.397893 -350.033379)
			(xy 82.403646 -350.049756) (xy 82.414528 -350.063278) (xy 82.42173 -350.068134) (xy 82.421984 -350.068134)
			(xy 82.445372 -350.083138) (xy 82.487977 -350.118807) (xy 82.524956 -350.16028) (xy 82.555528 -350.206678)
			(xy 82.579045 -350.257021) (xy 82.59501 -350.310243) (xy 82.603085 -350.365218) (xy 82.603594 -350.393)
			(xy 82.603108 -350.420251) (xy 82.595352 -350.474199) (xy 82.579997 -350.526494) (xy 82.557355 -350.576071)
			(xy 82.527889 -350.621921) (xy 82.492198 -350.663112) (xy 82.451007 -350.698803) (xy 82.405157 -350.728269)
			(xy 82.35558 -350.750911) (xy 82.303285 -350.766266) (xy 82.249337 -350.774022) (xy 82.194835 -350.774022)
			(xy 82.140887 -350.766266) (xy 82.088592 -350.750911) (xy 82.039015 -350.728269) (xy 81.993165 -350.698803)
			(xy 81.951974 -350.663112) (xy 81.916283 -350.621921) (xy 81.886817 -350.576071) (xy 81.864175 -350.526494)
			(xy 81.84882 -350.474199) (xy 81.841064 -350.420251) (xy 81.840578 -350.393) (xy 81.841025 -350.365186)
			(xy 81.849104 -350.310148) (xy 81.865092 -350.256867) (xy 81.888648 -350.206473) (xy 81.919274 -350.160034)
			(xy 81.95632 -350.118537) (xy 81.999001 -350.082859) (xy 82.022442 -350.06788) (xy 82.033872 -350.061022)
			(xy 82.046572 -350.038162) (xy 82.046826 -349.938086) (xy 82.046531 -349.929407) (xy 82.040776 -349.913032)
			(xy 82.029896 -349.899509) (xy 82.022696 -349.894652) (xy 82.022442 -349.894652) (xy 81.999053 -349.879648)
			(xy 81.956447 -349.84398) (xy 81.919467 -349.802508) (xy 81.888895 -349.756109) (xy 81.865378 -349.705766)
			(xy 81.849414 -349.652544) (xy 81.84134 -349.597568) (xy 81.840832 -349.569786) (xy 81.841326 -349.542653)
			(xy 81.84901 -349.488933) (xy 81.864237 -349.436847) (xy 81.886697 -349.387447) (xy 81.915937 -349.341731)
			(xy 81.933288 -349.320866) (xy 81.933542 -349.320612) (xy 81.939499 -349.312934) (xy 81.945639 -349.294515)
			(xy 81.94548 -349.284798) (xy 81.94167 -349.21444) (xy 81.940604 -349.204641) (xy 81.932123 -349.186871)
			(xy 81.92516 -349.179896) (xy 81.906163 -349.161767) (xy 81.872846 -349.121177) (xy 81.845406 -349.076404)
			(xy 81.824361 -349.028294) (xy 81.810107 -348.977753) (xy 81.802913 -348.925736) (xy 81.802478 -348.89948)
			(xy 75.651422 -348.89948) (xy 72.913079 -351.637854) (xy 74.429874 -351.637854) (xy 74.430361 -351.609407)
			(xy 74.438823 -351.553145) (xy 74.455551 -351.498765) (xy 74.480174 -351.447474) (xy 74.512146 -351.400413)
			(xy 74.550756 -351.358624) (xy 74.572622 -351.34042) (xy 74.580467 -351.333419) (xy 74.590174 -351.314793)
			(xy 74.591418 -351.304352) (xy 74.596498 -351.229676) (xy 74.596645 -351.219152) (xy 74.589585 -351.199351)
			(xy 74.582782 -351.191322) (xy 74.563353 -351.169947) (xy 74.53047 -351.12246) (xy 74.505125 -351.070558)
			(xy 74.487896 -351.015427) (xy 74.479178 -350.958328) (xy 74.478642 -350.929448) (xy 74.479128 -350.902197)
			(xy 74.486884 -350.848249) (xy 74.502239 -350.795954) (xy 74.524881 -350.746377) (xy 74.554347 -350.700527)
			(xy 74.590038 -350.659336) (xy 74.631229 -350.623645) (xy 74.677079 -350.594179) (xy 74.726656 -350.571537)
			(xy 74.778951 -350.556182) (xy 74.832899 -350.548426) (xy 74.887401 -350.548426) (xy 74.941349 -350.556182)
			(xy 74.993644 -350.571537) (xy 75.043221 -350.594179) (xy 75.089071 -350.623645) (xy 75.130262 -350.659336)
			(xy 75.165953 -350.700527) (xy 75.195419 -350.746377) (xy 75.218061 -350.795954) (xy 75.233416 -350.848249)
			(xy 75.241172 -350.902197) (xy 75.241658 -350.929448) (xy 75.24116 -350.957895) (xy 75.232699 -351.014156)
			(xy 75.215973 -351.068535) (xy 75.191351 -351.119825) (xy 75.159382 -351.166887) (xy 75.120775 -351.208677)
			(xy 75.09891 -351.226882) (xy 75.091053 -351.233871) (xy 75.081355 -351.252507) (xy 75.080114 -351.26295)
			(xy 75.075034 -351.337626) (xy 75.074878 -351.348151) (xy 75.081943 -351.367953) (xy 75.08875 -351.37598)
			(xy 75.108185 -351.39735) (xy 75.141066 -351.444838) (xy 75.16641 -351.496742) (xy 75.183637 -351.551874)
			(xy 75.190908 -351.5995) (xy 77.09154 -351.5995) (xy 77.092072 -351.571055) (xy 77.100526 -351.514795)
			(xy 77.117246 -351.460417) (xy 77.141861 -351.409126) (xy 77.173824 -351.362063) (xy 77.212426 -351.320272)
			(xy 77.234288 -351.302066) (xy 77.242125 -351.295058) (xy 77.251835 -351.276436) (xy 77.253084 -351.265998)
			(xy 77.258164 -351.191322) (xy 77.25835 -351.180796) (xy 77.251264 -351.160992) (xy 77.244448 -351.152968)
			(xy 77.224988 -351.13162) (xy 77.192111 -351.084126) (xy 77.166771 -351.032216) (xy 77.14955 -350.977079)
			(xy 77.14084 -350.919976) (xy 77.140308 -350.891094) (xy 77.140794 -350.863843) (xy 77.14855 -350.809895)
			(xy 77.163905 -350.7576) (xy 77.186547 -350.708023) (xy 77.216013 -350.662173) (xy 77.251704 -350.620982)
			(xy 77.292895 -350.585291) (xy 77.338745 -350.555825) (xy 77.388322 -350.533183) (xy 77.440617 -350.517828)
			(xy 77.494565 -350.510072) (xy 77.549067 -350.510072) (xy 77.603015 -350.517828) (xy 77.65531 -350.533183)
			(xy 77.704887 -350.555825) (xy 77.750737 -350.585291) (xy 77.791928 -350.620982) (xy 77.827619 -350.662173)
			(xy 77.857085 -350.708023) (xy 77.879727 -350.7576) (xy 77.895082 -350.809895) (xy 77.902838 -350.863843)
			(xy 77.903324 -350.891094) (xy 77.902801 -350.91954) (xy 77.894347 -350.9758) (xy 77.877626 -351.03018)
			(xy 77.85301 -351.08147) (xy 77.821044 -351.128533) (xy 77.78244 -351.170323) (xy 77.760576 -351.188528)
			(xy 77.752752 -351.195549) (xy 77.743033 -351.21416) (xy 77.74178 -351.224596) (xy 77.7367 -351.299272)
			(xy 77.736527 -351.309797) (xy 77.743605 -351.3296) (xy 77.750416 -351.337626) (xy 77.769867 -351.358982)
			(xy 77.802747 -351.406473) (xy 77.828089 -351.458381) (xy 77.845312 -351.513516) (xy 77.854023 -351.570619)
			(xy 77.854556 -351.5995) (xy 77.854057 -351.626633) (xy 77.846374 -351.680352) (xy 77.831149 -351.732439)
			(xy 77.80869 -351.781839) (xy 77.779451 -351.827555) (xy 77.7621 -351.84842) (xy 77.761846 -351.848674)
			(xy 77.755895 -351.856356) (xy 77.749752 -351.874772) (xy 77.749908 -351.884488) (xy 77.753718 -351.954846)
			(xy 77.754795 -351.964643) (xy 77.763268 -351.982414) (xy 77.770228 -351.98939) (xy 77.789235 -352.007508)
			(xy 77.822548 -352.048103) (xy 77.849984 -352.092878) (xy 77.871028 -352.14099) (xy 77.88528 -352.191532)
			(xy 77.892474 -352.24355) (xy 77.89291 -352.269806) (xy 77.892464 -352.295981) (xy 77.88529 -352.347837)
			(xy 77.871091 -352.398225) (xy 77.850134 -352.446197) (xy 77.822813 -352.490853) (xy 77.789641 -352.531352)
			(xy 77.770736 -352.54946) (xy 77.763403 -352.55701) (xy 77.755007 -352.576286) (xy 77.75448 -352.586798)
			(xy 77.75448 -352.66122) (xy 77.754974 -352.671742) (xy 77.763364 -352.691035) (xy 77.770736 -352.698558)
			(xy 77.789627 -352.716683) (xy 77.822816 -352.757169) (xy 77.850149 -352.801818) (xy 77.871113 -352.849789)
			(xy 77.885311 -352.900178) (xy 77.892477 -352.952036) (xy 77.89291 -352.978212) (xy 77.892424 -353.005463)
			(xy 77.884668 -353.059411) (xy 77.869313 -353.111706) (xy 77.846671 -353.161283) (xy 77.817205 -353.207133)
			(xy 77.781514 -353.248324) (xy 77.740323 -353.284015) (xy 77.694473 -353.313481) (xy 77.644896 -353.336123)
			(xy 77.592601 -353.351478) (xy 77.538653 -353.359234) (xy 77.484151 -353.359234) (xy 77.430203 -353.351478)
			(xy 77.377908 -353.336123) (xy 77.328331 -353.313481) (xy 77.282481 -353.284015) (xy 77.24129 -353.248324)
			(xy 77.205599 -353.207133) (xy 77.176133 -353.161283) (xy 77.153491 -353.111706) (xy 77.138136 -353.059411)
			(xy 77.13038 -353.005463) (xy 77.129894 -352.978212) (xy 77.130351 -352.952037) (xy 77.137522 -352.900182)
			(xy 77.151719 -352.849794) (xy 77.172674 -352.801822) (xy 77.199993 -352.757166) (xy 77.233163 -352.716666)
			(xy 77.252068 -352.698558) (xy 77.259393 -352.691002) (xy 77.267794 -352.67173) (xy 77.268324 -352.66122)
			(xy 77.268324 -352.586798) (xy 77.267873 -352.576271) (xy 77.259452 -352.556979) (xy 77.252068 -352.54946)
			(xy 77.233187 -352.531325) (xy 77.199997 -352.490841) (xy 77.172662 -352.446194) (xy 77.151697 -352.398226)
			(xy 77.137497 -352.347838) (xy 77.130328 -352.295981) (xy 77.129894 -352.269806) (xy 77.130385 -352.242672)
			(xy 77.138068 -352.188952) (xy 77.153294 -352.136865) (xy 77.175756 -352.087465) (xy 77.204998 -352.041751)
			(xy 77.22235 -352.020886) (xy 77.222604 -352.020632) (xy 77.228547 -352.012944) (xy 77.234697 -351.994533)
			(xy 77.234542 -351.984818) (xy 77.230732 -351.91446) (xy 77.229667 -351.904661) (xy 77.221186 -351.88689)
			(xy 77.214222 -351.879916) (xy 77.195227 -351.861784) (xy 77.161912 -351.821194) (xy 77.134473 -351.776422)
			(xy 77.113427 -351.728312) (xy 77.099172 -351.677772) (xy 77.091977 -351.625756) (xy 77.09154 -351.5995)
			(xy 75.190908 -351.5995) (xy 75.192354 -351.608974) (xy 75.19289 -351.637854) (xy 75.192414 -351.664988)
			(xy 75.184724 -351.718708) (xy 75.169494 -351.770794) (xy 75.14703 -351.820194) (xy 75.117787 -351.865909)
			(xy 75.100434 -351.886774) (xy 75.10018 -351.887028) (xy 75.094208 -351.894696) (xy 75.088076 -351.913123)
			(xy 75.088242 -351.922842) (xy 75.092052 -351.9932) (xy 75.093093 -352.003003) (xy 75.101591 -352.020773)
			(xy 75.108562 -352.027744) (xy 75.127534 -352.045898) (xy 75.160852 -352.086483) (xy 75.188295 -352.131251)
			(xy 75.209345 -352.179356) (xy 75.223604 -352.229892) (xy 75.230805 -352.281905) (xy 75.231244 -352.30816)
			(xy 75.230756 -352.335972) (xy 75.222682 -352.391008) (xy 75.206701 -352.444288) (xy 75.183151 -352.494681)
			(xy 75.152532 -352.54112) (xy 75.115492 -352.582619) (xy 75.072818 -352.618299) (xy 75.04938 -352.63328)
			(xy 75.03795 -352.640138) (xy 75.02525 -352.662998) (xy 75.024996 -352.763074) (xy 75.025309 -352.771752)
			(xy 75.031054 -352.788127) (xy 75.041928 -352.801651) (xy 75.049126 -352.806508) (xy 75.04938 -352.806508)
			(xy 75.072801 -352.821464) (xy 75.115406 -352.857141) (xy 75.152383 -352.898621) (xy 75.182951 -352.945028)
			(xy 75.206463 -352.995379) (xy 75.22242 -353.048608) (xy 75.230486 -353.103589) (xy 75.23099 -353.131374)
			(xy 75.230504 -353.158625) (xy 75.222748 -353.212573) (xy 75.207393 -353.264868) (xy 75.184751 -353.314445)
			(xy 75.155285 -353.360295) (xy 75.119594 -353.401486) (xy 75.078403 -353.437177) (xy 75.032553 -353.466643)
			(xy 74.982976 -353.489285) (xy 74.930681 -353.50464) (xy 74.876733 -353.512396) (xy 74.822231 -353.512396)
			(xy 74.768283 -353.50464) (xy 74.715988 -353.489285) (xy 74.666411 -353.466643) (xy 74.620561 -353.437177)
			(xy 74.57937 -353.401486) (xy 74.543679 -353.360295) (xy 74.514213 -353.314445) (xy 74.491571 -353.264868)
			(xy 74.476216 -353.212573) (xy 74.46846 -353.158625) (xy 74.467974 -353.131374) (xy 74.46848 -353.103562)
			(xy 74.476549 -353.048527) (xy 74.492526 -352.995247) (xy 74.516073 -352.944853) (xy 74.54669 -352.898414)
			(xy 74.583728 -352.856915) (xy 74.6264 -352.821235) (xy 74.649838 -352.806254) (xy 74.661268 -352.799396)
			(xy 74.673968 -352.776536) (xy 74.674222 -352.67646) (xy 74.673877 -352.667785) (xy 74.668146 -352.651412)
			(xy 74.657284 -352.637886) (xy 74.650092 -352.633026) (xy 74.649838 -352.633026) (xy 74.626436 -352.618041)
			(xy 74.583831 -352.58237) (xy 74.546852 -352.540894) (xy 74.516281 -352.494492) (xy 74.492766 -352.444146)
			(xy 74.476805 -352.390921) (xy 74.468734 -352.335943) (xy 74.468228 -352.30816) (xy 74.468708 -352.281026)
			(xy 74.476396 -352.227306) (xy 74.491626 -352.17522) (xy 74.514089 -352.12582) (xy 74.543331 -352.080105)
			(xy 74.560684 -352.05924) (xy 74.560938 -352.058986) (xy 74.566906 -352.051316) (xy 74.57304 -352.03289)
			(xy 74.572876 -352.023172) (xy 74.569066 -351.952814) (xy 74.568013 -351.943013) (xy 74.559523 -351.925243)
			(xy 74.552556 -351.91827) (xy 74.533594 -351.900106) (xy 74.500274 -351.859523) (xy 74.47283 -351.814758)
			(xy 74.451778 -351.766655) (xy 74.437517 -351.71612) (xy 74.430314 -351.664108) (xy 74.429874 -351.637854)
			(xy 72.913079 -351.637854) (xy 58.646822 -365.904272) (xy 58.632371 -365.91802) (xy 58.599207 -365.940167)
			(xy 58.562363 -365.955429) (xy 58.523252 -365.963221) (xy 58.503312 -365.963708) (xy 45.105066 -365.963708)
			(xy 45.094999 -365.964138) (xy 45.076404 -365.971862) (xy 45.068998 -365.978694) (xy 41.742614 -369.305332)
			(xy 41.735771 -369.312732) (xy 41.728046 -369.33133) (xy 41.727628 -369.3414) (xy 41.727628 -370.536724)
			(xy 41.727175 -370.556742) (xy 41.719368 -370.596011) (xy 41.704041 -370.632997) (xy 41.681783 -370.666277)
			(xy 41.667938 -370.680742) (xy 40.464232 -371.884448) (xy 40.449779 -371.898192) (xy 40.416613 -371.920334)
			(xy 40.37977 -371.935591) (xy 40.340661 -371.943381) (xy 40.320722 -371.943884) (xy 34.908998 -371.943884)
			(xy 34.89904 -371.944413) (xy 34.880648 -371.952065) (xy 34.866523 -371.966113) (xy 34.862262 -371.975126)
			(xy 34.858719 -371.984571) (xy 34.858618 -372.004728) (xy 34.866329 -372.023351) (xy 34.873184 -372.030752)
			(xy 35.056318 -372.213886) (xy 35.063596 -372.220566) (xy 35.081763 -372.228277) (xy 35.091624 -372.228872)
			(xy 35.091878 -372.228872) (xy 35.183025 -372.229874) (xy 35.365115 -372.238689) (xy 35.546663 -372.255271)
			(xy 35.727337 -372.279589) (xy 35.906808 -372.3116) (xy 36.084749 -372.351243) (xy 36.260834 -372.398448)
			(xy 36.434744 -372.453128) (xy 36.60616 -372.515184) (xy 36.774771 -372.584502) (xy 36.940268 -372.660955)
			(xy 37.10235 -372.744406) (xy 37.260721 -372.8347) (xy 37.415093 -372.931674) (xy 37.565183 -373.03515)
			(xy 37.638228 -373.089678) (xy 37.64497 -373.094343) (xy 37.660516 -373.099518) (xy 37.668708 -373.099838)
		)
		(stroke
			(width 0)
			(type solid)
		)
		(fill yes)
		(layer "In4.Cu")
		(net "GND")
	)
	(gr_poly
		(pts
			(xy 402.871178 -196.977) (xy 402.88105 -196.976529) (xy 402.899333 -196.969071) (xy 402.906738 -196.962522)
			(xy 402.906992 -196.962268) (xy 410.045154 -189.824106) (xy 410.052555 -189.817267) (xy 410.071153 -189.809552)
			(xy 410.081222 -189.80912) (xy 422.101518 -189.80912) (xy 422.111396 -189.808661) (xy 422.129696 -189.80122)
			(xy 422.137078 -189.794642) (xy 422.137332 -189.794388) (xy 427.141894 -184.789826) (xy 427.142402 -184.789318)
			(xy 427.148985 -184.781938) (xy 427.156433 -184.763638) (xy 427.15688 -184.753758) (xy 427.15688 -154.72537)
			(xy 427.157308 -154.715302) (xy 427.165028 -154.696703) (xy 427.171866 -154.689302) (xy 427.295564 -154.565604)
			(xy 427.302415 -154.558207) (xy 427.310156 -154.539609) (xy 427.31055 -154.529536) (xy 427.31055 -140.438886)
			(xy 427.310123 -140.428818) (xy 427.302399 -140.410222) (xy 427.295564 -140.402818) (xy 419.259512 -132.366766)
			(xy 419.252117 -132.35991) (xy 419.233519 -132.352161) (xy 419.223444 -132.35178) (xy 408.930856 -132.35178)
			(xy 408.920789 -132.352211) (xy 408.902194 -132.359934) (xy 408.894788 -132.366766) (xy 407.327354 -133.9342)
			(xy 408.346656 -133.9342) (xy 408.347192 -133.905462) (xy 408.355813 -133.848635) (xy 408.372861 -133.793745)
			(xy 408.39795 -133.742033) (xy 408.430511 -133.69467) (xy 408.44978 -133.673342) (xy 408.456384 -133.66623)
			(xy 408.463496 -133.648704) (xy 408.463496 -133.559296) (xy 408.456384 -133.54177) (xy 408.44978 -133.534658)
			(xy 408.430516 -133.513325) (xy 408.397947 -133.465965) (xy 408.372853 -133.414255) (xy 408.355801 -133.359366)
			(xy 408.347177 -133.302539) (xy 408.346656 -133.2738) (xy 408.347178 -133.24655) (xy 408.354933 -133.192606)
			(xy 408.370287 -133.140314) (xy 408.392925 -133.090739) (xy 408.422388 -133.04489) (xy 408.458076 -133.003701)
			(xy 408.499262 -132.96801) (xy 408.545107 -132.938542) (xy 408.59468 -132.915899) (xy 408.646971 -132.900541)
			(xy 408.700914 -132.89278) (xy 408.728164 -132.892292) (xy 408.75701 -132.892836) (xy 408.814046 -132.901511)
			(xy 408.869122 -132.918685) (xy 408.92098 -132.943964) (xy 408.968436 -132.976772) (xy 408.989784 -132.996178)
			(xy 408.996896 -133.002782) (xy 409.01493 -133.009894) (xy 409.104084 -133.009894) (xy 409.122118 -133.002782)
			(xy 409.12923 -132.996178) (xy 409.150581 -132.976775) (xy 409.198042 -132.943978) (xy 409.2499 -132.9187)
			(xy 409.304973 -132.901518) (xy 409.362005 -132.892825) (xy 409.39085 -132.892292) (xy 409.418102 -132.892802)
			(xy 409.472051 -132.900552) (xy 409.524348 -132.915902) (xy 409.573928 -132.938538) (xy 409.619781 -132.968001)
			(xy 409.660974 -133.00369) (xy 409.696669 -133.044879) (xy 409.726138 -133.090728) (xy 409.748781 -133.140305)
			(xy 409.764137 -133.1926) (xy 409.771895 -133.246548) (xy 409.772358 -133.2738) (xy 409.771819 -133.302538)
			(xy 409.763198 -133.359364) (xy 409.74615 -133.414254) (xy 409.721063 -133.465966) (xy 409.688502 -133.51333)
			(xy 409.669234 -133.534658) (xy 409.66263 -133.54177) (xy 409.655518 -133.559296) (xy 409.655518 -133.648704)
			(xy 409.66263 -133.66623) (xy 409.669234 -133.673342) (xy 409.6885 -133.694673) (xy 409.721068 -133.742034)
			(xy 409.746162 -133.793744) (xy 409.763214 -133.848634) (xy 409.771837 -133.905461) (xy 409.772358 -133.9342)
			(xy 409.771945 -133.961455) (xy 409.764186 -134.01541) (xy 409.748828 -134.067712) (xy 409.726182 -134.117296)
			(xy 409.696709 -134.163151) (xy 409.66101 -134.204345) (xy 409.619811 -134.240039) (xy 409.573952 -134.269506)
			(xy 409.524365 -134.292145) (xy 409.472062 -134.307497) (xy 409.418105 -134.315248) (xy 409.39085 -134.315708)
			(xy 409.362004 -134.315156) (xy 409.304969 -134.306482) (xy 409.249893 -134.28931) (xy 409.198035 -134.264033)
			(xy 409.150579 -134.231228) (xy 409.12923 -134.211822) (xy 409.122118 -134.205218) (xy 409.104084 -134.198106)
			(xy 409.01493 -134.198106) (xy 408.996896 -134.205218) (xy 408.989784 -134.211822) (xy 408.968427 -134.231218)
			(xy 408.920968 -134.264017) (xy 408.869111 -134.289296) (xy 408.81404 -134.306479) (xy 408.757009 -134.315174)
			(xy 408.728164 -134.315708) (xy 408.700912 -134.315256) (xy 408.646963 -134.307494) (xy 408.594668 -134.292135)
			(xy 408.54509 -134.269489) (xy 408.49924 -134.240019) (xy 408.45805 -134.204324) (xy 408.422359 -134.163131)
			(xy 408.392893 -134.117278) (xy 408.370253 -134.067699) (xy 408.354898 -134.015402) (xy 408.347142 -133.961452)
			(xy 408.346656 -133.9342) (xy 407.327354 -133.9342) (xy 406.8826 -134.378954) (xy 406.852628 -134.378954)
			(xy 394.51661 -134.378954) (xy 394.506894 -134.379382) (xy 394.488854 -134.386599) (xy 394.474787 -134.400003)
			(xy 394.470382 -134.408672) (xy 394.425678 -134.506462) (xy 394.429996 -134.535672) (xy 394.439902 -134.547102)
			(xy 394.457452 -134.568017) (xy 394.487014 -134.61392) (xy 394.509727 -134.66357) (xy 394.525128 -134.715951)
			(xy 394.532901 -134.769993) (xy 394.533374 -134.797292) (xy 394.532888 -134.824543) (xy 394.525132 -134.878491)
			(xy 394.509777 -134.930786) (xy 394.509495 -134.931404) (xy 407.260042 -134.931404) (xy 407.264113 -134.875782)
			(xy 407.276239 -134.821345) (xy 407.296162 -134.769254) (xy 407.323458 -134.720619) (xy 407.357544 -134.676476)
			(xy 407.397693 -134.637767) (xy 407.443051 -134.605316) (xy 407.492651 -134.579815) (xy 407.545435 -134.561808)
			(xy 407.600278 -134.551678) (xy 407.656012 -134.549641) (xy 407.711449 -134.555741) (xy 407.765406 -134.569847)
			(xy 407.816735 -134.591659) (xy 407.864341 -134.620713) (xy 407.907209 -134.656388) (xy 407.944426 -134.697925)
			(xy 407.975199 -134.744438) (xy 407.998871 -134.794935) (xy 408.014939 -134.848342) (xy 408.023059 -134.903518)
			(xy 408.023568 -134.931404) (xy 408.023059 -134.95929) (xy 408.014939 -135.014466) (xy 407.998871 -135.067873)
			(xy 407.992236 -135.082026) (xy 409.362908 -135.082026) (xy 409.366979 -135.026404) (xy 409.379105 -134.971967)
			(xy 409.399028 -134.919876) (xy 409.426324 -134.871241) (xy 409.46041 -134.827098) (xy 409.500559 -134.788389)
			(xy 409.545917 -134.755938) (xy 409.595517 -134.730437) (xy 409.648301 -134.71243) (xy 409.703144 -134.7023)
			(xy 409.758878 -134.700263) (xy 409.814315 -134.706363) (xy 409.868272 -134.720469) (xy 409.919601 -134.742281)
			(xy 409.967207 -134.771335) (xy 410.010075 -134.80701) (xy 410.047292 -134.848547) (xy 410.078065 -134.89506)
			(xy 410.101737 -134.945557) (xy 410.117805 -134.998964) (xy 410.125925 -135.05414) (xy 410.126434 -135.082026)
			(xy 410.125925 -135.109912) (xy 410.117805 -135.165088) (xy 410.101737 -135.218495) (xy 410.078065 -135.268992)
			(xy 410.047292 -135.315505) (xy 410.010075 -135.357042) (xy 409.967207 -135.392717) (xy 409.919601 -135.421771)
			(xy 409.868272 -135.443583) (xy 409.814315 -135.457689) (xy 409.758878 -135.463789) (xy 409.703144 -135.461752)
			(xy 409.648301 -135.451622) (xy 409.595517 -135.433615) (xy 409.545917 -135.408114) (xy 409.500559 -135.375663)
			(xy 409.46041 -135.336954) (xy 409.426324 -135.292811) (xy 409.399028 -135.244176) (xy 409.379105 -135.192085)
			(xy 409.366979 -135.137648) (xy 409.362908 -135.082026) (xy 407.992236 -135.082026) (xy 407.975199 -135.11837)
			(xy 407.944426 -135.164883) (xy 407.907209 -135.20642) (xy 407.864341 -135.242095) (xy 407.816735 -135.271149)
			(xy 407.765406 -135.292961) (xy 407.711449 -135.307067) (xy 407.656012 -135.313167) (xy 407.600278 -135.31113)
			(xy 407.545435 -135.301) (xy 407.492651 -135.282993) (xy 407.443051 -135.257492) (xy 407.397693 -135.225041)
			(xy 407.357544 -135.186332) (xy 407.323458 -135.142189) (xy 407.296162 -135.093554) (xy 407.276239 -135.041463)
			(xy 407.264113 -134.987026) (xy 407.260042 -134.931404) (xy 394.509495 -134.931404) (xy 394.487135 -134.980363)
			(xy 394.457669 -135.026213) (xy 394.421978 -135.067404) (xy 394.380787 -135.103095) (xy 394.334937 -135.132561)
			(xy 394.28536 -135.155203) (xy 394.233065 -135.170558) (xy 394.179117 -135.178314) (xy 394.124615 -135.178314)
			(xy 394.070667 -135.170558) (xy 394.018372 -135.155203) (xy 393.968795 -135.132561) (xy 393.922945 -135.103095)
			(xy 393.881754 -135.067404) (xy 393.846063 -135.026213) (xy 393.816597 -134.980363) (xy 393.793955 -134.930786)
			(xy 393.7786 -134.878491) (xy 393.770844 -134.824543) (xy 393.770358 -134.797292) (xy 393.770824 -134.769993)
			(xy 393.778606 -134.715952) (xy 393.79401 -134.663571) (xy 393.81672 -134.613921) (xy 393.846275 -134.568013)
			(xy 393.86383 -134.547102) (xy 393.873736 -134.535672) (xy 393.878054 -134.506462) (xy 393.83335 -134.408672)
			(xy 393.828934 -134.400003) (xy 393.814882 -134.38657) (xy 393.796842 -134.37933) (xy 393.787122 -134.378954)
			(xy 391.018776 -134.378954) (xy 391.008792 -134.379497) (xy 390.990371 -134.387223) (xy 390.982962 -134.39394)
			(xy 390.431782 -134.944866) (xy 390.424937 -134.952264) (xy 390.417214 -134.970863) (xy 390.416796 -134.980934)
			(xy 390.416796 -135.66013) (xy 398.415254 -135.66013) (xy 398.419325 -135.604508) (xy 398.431451 -135.550071)
			(xy 398.451374 -135.49798) (xy 398.47867 -135.449345) (xy 398.512756 -135.405202) (xy 398.552905 -135.366493)
			(xy 398.598263 -135.334042) (xy 398.647863 -135.308541) (xy 398.700647 -135.290534) (xy 398.75549 -135.280404)
			(xy 398.811224 -135.278367) (xy 398.866661 -135.284467) (xy 398.920618 -135.298573) (xy 398.971947 -135.320385)
			(xy 399.019553 -135.349439) (xy 399.062421 -135.385114) (xy 399.099638 -135.426651) (xy 399.130411 -135.473164)
			(xy 399.154083 -135.523661) (xy 399.170151 -135.577068) (xy 399.178271 -135.632244) (xy 399.17878 -135.66013)
			(xy 399.178271 -135.688016) (xy 399.170151 -135.743192) (xy 399.154083 -135.796599) (xy 399.130411 -135.847096)
			(xy 399.099638 -135.893609) (xy 399.062421 -135.935146) (xy 399.019553 -135.970821) (xy 398.971947 -135.999875)
			(xy 398.920618 -136.021687) (xy 398.866661 -136.035793) (xy 398.811224 -136.041893) (xy 398.75549 -136.039856)
			(xy 398.700647 -136.029726) (xy 398.647863 -136.011719) (xy 398.598263 -135.986218) (xy 398.552905 -135.953767)
			(xy 398.512756 -135.915058) (xy 398.47867 -135.870915) (xy 398.451374 -135.82228) (xy 398.431451 -135.770189)
			(xy 398.419325 -135.715752) (xy 398.415254 -135.66013) (xy 390.416796 -135.66013) (xy 390.416796 -136.231376)
			(xy 405.077928 -136.231376) (xy 405.081999 -136.175754) (xy 405.094125 -136.121317) (xy 405.114048 -136.069226)
			(xy 405.141344 -136.020591) (xy 405.17543 -135.976448) (xy 405.215579 -135.937739) (xy 405.260937 -135.905288)
			(xy 405.310537 -135.879787) (xy 405.363321 -135.86178) (xy 405.418164 -135.85165) (xy 405.473898 -135.849613)
			(xy 405.529335 -135.855713) (xy 405.583292 -135.869819) (xy 405.634621 -135.891631) (xy 405.682227 -135.920685)
			(xy 405.725095 -135.95636) (xy 405.762312 -135.997897) (xy 405.793085 -136.04441) (xy 405.816757 -136.094907)
			(xy 405.832825 -136.148314) (xy 405.840945 -136.20349) (xy 405.841454 -136.231376) (xy 407.285696 -136.231376)
			(xy 407.289767 -136.175754) (xy 407.301893 -136.121317) (xy 407.321816 -136.069226) (xy 407.349112 -136.020591)
			(xy 407.383198 -135.976448) (xy 407.423347 -135.937739) (xy 407.468705 -135.905288) (xy 407.518305 -135.879787)
			(xy 407.571089 -135.86178) (xy 407.625932 -135.85165) (xy 407.681666 -135.849613) (xy 407.737103 -135.855713)
			(xy 407.79106 -135.869819) (xy 407.842389 -135.891631) (xy 407.889995 -135.920685) (xy 407.932863 -135.95636)
			(xy 407.97008 -135.997897) (xy 408.000853 -136.04441) (xy 408.024525 -136.094907) (xy 408.040593 -136.148314)
			(xy 408.048713 -136.20349) (xy 408.049222 -136.231376) (xy 408.048713 -136.259262) (xy 408.040593 -136.314438)
			(xy 408.024525 -136.367845) (xy 408.000853 -136.418342) (xy 407.97008 -136.464855) (xy 407.932863 -136.506392)
			(xy 407.889995 -136.542067) (xy 407.842389 -136.571121) (xy 407.79106 -136.592933) (xy 407.737103 -136.607039)
			(xy 407.681666 -136.613139) (xy 407.625932 -136.611102) (xy 407.571089 -136.600972) (xy 407.518305 -136.582965)
			(xy 407.468705 -136.557464) (xy 407.423347 -136.525013) (xy 407.383198 -136.486304) (xy 407.349112 -136.442161)
			(xy 407.321816 -136.393526) (xy 407.301893 -136.341435) (xy 407.289767 -136.286998) (xy 407.285696 -136.231376)
			(xy 405.841454 -136.231376) (xy 405.840945 -136.259262) (xy 405.832825 -136.314438) (xy 405.816757 -136.367845)
			(xy 405.793085 -136.418342) (xy 405.762312 -136.464855) (xy 405.725095 -136.506392) (xy 405.682227 -136.542067)
			(xy 405.634621 -136.571121) (xy 405.583292 -136.592933) (xy 405.529335 -136.607039) (xy 405.473898 -136.613139)
			(xy 405.418164 -136.611102) (xy 405.363321 -136.600972) (xy 405.310537 -136.582965) (xy 405.260937 -136.557464)
			(xy 405.215579 -136.525013) (xy 405.17543 -136.486304) (xy 405.141344 -136.442161) (xy 405.114048 -136.393526)
			(xy 405.094125 -136.341435) (xy 405.081999 -136.286998) (xy 405.077928 -136.231376) (xy 390.416796 -136.231376)
			(xy 390.416796 -138.077702) (xy 390.700004 -138.077702) (xy 390.704075 -138.02208) (xy 390.716201 -137.967643)
			(xy 390.736124 -137.915552) (xy 390.76342 -137.866917) (xy 390.797506 -137.822774) (xy 390.837655 -137.784065)
			(xy 390.883013 -137.751614) (xy 390.932613 -137.726113) (xy 390.985397 -137.708106) (xy 391.04024 -137.697976)
			(xy 391.095974 -137.695939) (xy 391.151411 -137.702039) (xy 391.205368 -137.716145) (xy 391.256697 -137.737957)
			(xy 391.304303 -137.767011) (xy 391.347171 -137.802686) (xy 391.384388 -137.844223) (xy 391.415161 -137.890736)
			(xy 391.438833 -137.941233) (xy 391.454901 -137.99464) (xy 391.463021 -138.049816) (xy 391.46353 -138.077702)
			(xy 391.463021 -138.105588) (xy 391.454901 -138.160764) (xy 391.438833 -138.214171) (xy 391.415161 -138.264668)
			(xy 391.384388 -138.311181) (xy 391.347171 -138.352718) (xy 391.304303 -138.388393) (xy 391.256697 -138.417447)
			(xy 391.205368 -138.439259) (xy 391.151411 -138.453365) (xy 391.095974 -138.459465) (xy 391.04024 -138.457428)
			(xy 390.985397 -138.447298) (xy 390.932613 -138.429291) (xy 390.883013 -138.40379) (xy 390.837655 -138.371339)
			(xy 390.797506 -138.33263) (xy 390.76342 -138.288487) (xy 390.736124 -138.239852) (xy 390.716201 -138.187761)
			(xy 390.704075 -138.133324) (xy 390.700004 -138.077702) (xy 390.416796 -138.077702) (xy 390.416796 -141.416786)
			(xy 390.416237 -141.445349) (xy 390.407305 -141.501773) (xy 390.389659 -141.556106) (xy 390.363733 -141.607011)
			(xy 390.330165 -141.653235) (xy 390.31037 -141.673834) (xy 390.012682 -141.971522) (xy 390.700004 -141.971522)
			(xy 390.704075 -141.9159) (xy 390.716201 -141.861463) (xy 390.736124 -141.809372) (xy 390.76342 -141.760737)
			(xy 390.797506 -141.716594) (xy 390.837655 -141.677885) (xy 390.883013 -141.645434) (xy 390.932613 -141.619933)
			(xy 390.985397 -141.601926) (xy 391.04024 -141.591796) (xy 391.095974 -141.589759) (xy 391.151411 -141.595859)
			(xy 391.205368 -141.609965) (xy 391.256697 -141.631777) (xy 391.304303 -141.660831) (xy 391.347171 -141.696506)
			(xy 391.384388 -141.738043) (xy 391.415161 -141.784556) (xy 391.438833 -141.835053) (xy 391.454901 -141.88846)
			(xy 391.463021 -141.943636) (xy 391.46353 -141.971522) (xy 391.463021 -141.999408) (xy 391.454901 -142.054584)
			(xy 391.438833 -142.107991) (xy 391.415161 -142.158488) (xy 391.384388 -142.205001) (xy 391.347171 -142.246538)
			(xy 391.304303 -142.282213) (xy 391.256697 -142.311267) (xy 391.205368 -142.333079) (xy 391.151411 -142.347185)
			(xy 391.095974 -142.353285) (xy 391.04024 -142.351248) (xy 390.985397 -142.341118) (xy 390.932613 -142.323111)
			(xy 390.883013 -142.29761) (xy 390.837655 -142.265159) (xy 390.797506 -142.22645) (xy 390.76342 -142.182307)
			(xy 390.736124 -142.133672) (xy 390.716201 -142.081581) (xy 390.704075 -142.027144) (xy 390.700004 -141.971522)
			(xy 390.012682 -141.971522) (xy 389.983726 -142.000478) (xy 389.963122 -142.020265) (xy 389.916892 -142.053817)
			(xy 389.865987 -142.079734) (xy 389.811658 -142.097378) (xy 389.755239 -142.106316) (xy 389.726678 -142.106904)
			(xy 388.809992 -142.106904) (xy 388.799923 -142.107329) (xy 388.781321 -142.115046) (xy 388.773924 -142.12189)
			(xy 388.413498 -142.482316) (xy 388.410196 -142.48892) (xy 388.395754 -142.514407) (xy 388.36027 -142.561016)
			(xy 388.318082 -142.601658) (xy 388.270181 -142.635378) (xy 388.217691 -142.661384) (xy 388.161844 -142.679066)
			(xy 388.103952 -142.688009) (xy 388.074662 -142.688564) (xy 388.047412 -142.688098) (xy 387.993468 -142.680336)
			(xy 387.941177 -142.664977) (xy 387.891604 -142.642331) (xy 387.845759 -142.612862) (xy 387.804575 -142.577167)
			(xy 387.768889 -142.535975) (xy 387.739429 -142.490124) (xy 387.716795 -142.440546) (xy 387.701446 -142.388252)
			(xy 387.693696 -142.334306) (xy 387.693154 -142.307056) (xy 387.69369 -142.277766) (xy 387.702643 -142.219875)
			(xy 387.720333 -142.164031) (xy 387.746343 -142.111543) (xy 387.780065 -142.063644) (xy 387.820707 -142.021456)
			(xy 387.867314 -141.98597) (xy 387.892798 -141.971522) (xy 387.896052 -141.969762) (xy 387.90205 -141.96543)
			(xy 387.904736 -141.962886) (xy 388.38124 -141.486382) (xy 388.401842 -141.46659) (xy 388.448069 -141.433028)
			(xy 388.498974 -141.407103) (xy 388.553304 -141.38945) (xy 388.609725 -141.380506) (xy 388.638288 -141.379956)
			(xy 388.857744 -141.379956) (xy 388.868583 -141.379458) (xy 388.888329 -141.37051) (xy 388.895844 -141.362684)
			(xy 388.953502 -141.297406) (xy 388.960106 -141.276578) (xy 388.958582 -141.26591) (xy 388.957263 -141.254271)
			(xy 388.955867 -141.230887) (xy 388.955788 -141.219174) (xy 388.956255 -141.191603) (xy 388.96416 -141.137032)
			(xy 388.971536 -141.110462) (xy 388.973568 -141.10335) (xy 388.973568 -134.558786) (xy 388.973754 -134.543404)
			(xy 388.976421 -134.512754) (xy 388.978902 -134.497572) (xy 388.98068 -134.486396) (xy 388.975092 -134.46506)
			(xy 388.917434 -134.396988) (xy 388.909895 -134.388893) (xy 388.889873 -134.379546) (xy 388.878826 -134.378954)
			(xy 375.089166 -134.378954) (xy 375.079585 -134.379375) (xy 375.061759 -134.386409) (xy 375.047725 -134.399458)
			(xy 375.043192 -134.40791) (xy 374.997472 -134.50443) (xy 375.001028 -134.533386) (xy 375.010426 -134.544816)
			(xy 375.026685 -134.565363) (xy 375.054017 -134.610066) (xy 375.074981 -134.658087) (xy 375.089184 -134.708522)
			(xy 375.096357 -134.760426) (xy 375.096786 -134.786624) (xy 375.0963 -134.813875) (xy 375.088544 -134.867823)
			(xy 375.073189 -134.920118) (xy 375.050547 -134.969695) (xy 375.021081 -135.015545) (xy 374.98539 -135.056736)
			(xy 374.944199 -135.092427) (xy 374.898349 -135.121893) (xy 374.848772 -135.144535) (xy 374.796477 -135.15989)
			(xy 374.742529 -135.167646) (xy 374.688027 -135.167646) (xy 374.634079 -135.15989) (xy 374.581784 -135.144535)
			(xy 374.532207 -135.121893) (xy 374.486357 -135.092427) (xy 374.445166 -135.056736) (xy 374.409475 -135.015545)
			(xy 374.380009 -134.969695) (xy 374.357367 -134.920118) (xy 374.342012 -134.867823) (xy 374.334256 -134.813875)
			(xy 374.33377 -134.786624) (xy 374.333516 -134.786624) (xy 374.333963 -134.760415) (xy 374.341166 -134.708495)
			(xy 374.355411 -134.658049) (xy 374.376431 -134.61003) (xy 374.403828 -134.565343) (xy 374.42013 -134.544816)
			(xy 374.429528 -134.533132) (xy 374.433084 -134.504176) (xy 374.387364 -134.40791) (xy 374.382893 -134.399404)
			(xy 374.368868 -134.386287) (xy 374.350992 -134.379274) (xy 374.34139 -134.378954) (xy 372.695216 -134.378954)
			(xy 372.68563 -134.379366) (xy 372.66779 -134.386389) (xy 372.653741 -134.399436) (xy 372.649242 -134.40791)
			(xy 372.603522 -134.50443) (xy 372.607078 -134.533386) (xy 372.616476 -134.544816) (xy 372.632737 -134.565363)
			(xy 372.660072 -134.610065) (xy 372.681039 -134.658085) (xy 372.695243 -134.708521) (xy 372.702418 -134.760425)
			(xy 372.702836 -134.786624) (xy 372.70235 -134.813875) (xy 372.694594 -134.867823) (xy 372.679239 -134.920118)
			(xy 372.656597 -134.969695) (xy 372.627131 -135.015545) (xy 372.59144 -135.056736) (xy 372.550249 -135.092427)
			(xy 372.504399 -135.121893) (xy 372.454822 -135.144535) (xy 372.402527 -135.15989) (xy 372.348579 -135.167646)
			(xy 372.294077 -135.167646) (xy 372.240129 -135.15989) (xy 372.187834 -135.144535) (xy 372.138257 -135.121893)
			(xy 372.092407 -135.092427) (xy 372.051216 -135.056736) (xy 372.015525 -135.015545) (xy 371.986059 -134.969695)
			(xy 371.963417 -134.920118) (xy 371.948062 -134.867823) (xy 371.940306 -134.813875) (xy 371.93982 -134.786624)
			(xy 371.939566 -134.786624) (xy 371.940013 -134.760416) (xy 371.947217 -134.708495) (xy 371.961463 -134.658051)
			(xy 371.982485 -134.610034) (xy 372.009885 -134.565348) (xy 372.02618 -134.544816) (xy 372.035578 -134.533132)
			(xy 372.039134 -134.504176) (xy 371.993414 -134.40791) (xy 371.98894 -134.399409) (xy 371.974913 -134.386307)
			(xy 371.957039 -134.379311) (xy 371.94744 -134.378954) (xy 367.215928 -134.378954) (xy 367.205865 -134.379392)
			(xy 367.187285 -134.387131) (xy 367.17986 -134.39394) (xy 364.546388 -137.027412) (xy 373.67032 -137.027412)
			(xy 373.674391 -136.97179) (xy 373.686517 -136.917353) (xy 373.70644 -136.865262) (xy 373.733736 -136.816627)
			(xy 373.767822 -136.772484) (xy 373.807971 -136.733775) (xy 373.853329 -136.701324) (xy 373.902929 -136.675823)
			(xy 373.955713 -136.657816) (xy 374.010556 -136.647686) (xy 374.06629 -136.645649) (xy 374.121727 -136.651749)
			(xy 374.175684 -136.665855) (xy 374.227013 -136.687667) (xy 374.274619 -136.716721) (xy 374.317487 -136.752396)
			(xy 374.354704 -136.793933) (xy 374.385477 -136.840446) (xy 374.409149 -136.890943) (xy 374.425217 -136.94435)
			(xy 374.433337 -136.999526) (xy 374.433846 -137.027412) (xy 374.433337 -137.055298) (xy 374.425217 -137.110474)
			(xy 374.409149 -137.163881) (xy 374.385477 -137.214378) (xy 374.354704 -137.260891) (xy 374.317487 -137.302428)
			(xy 374.274619 -137.338103) (xy 374.227013 -137.367157) (xy 374.175684 -137.388969) (xy 374.121727 -137.403075)
			(xy 374.06629 -137.409175) (xy 374.010556 -137.407138) (xy 373.955713 -137.397008) (xy 373.902929 -137.379001)
			(xy 373.853329 -137.3535) (xy 373.807971 -137.321049) (xy 373.767822 -137.28234) (xy 373.733736 -137.238197)
			(xy 373.70644 -137.189562) (xy 373.686517 -137.137471) (xy 373.674391 -137.083034) (xy 373.67032 -137.027412)
			(xy 364.546388 -137.027412) (xy 362.782612 -138.791188) (xy 362.775215 -138.798038) (xy 362.756617 -138.805778)
			(xy 362.746544 -138.806174) (xy 362.106464 -138.806174) (xy 362.093256 -138.809984) (xy 362.08716 -138.81354)
			(xy 362.081055 -138.817047) (xy 362.067526 -138.820923) (xy 362.06049 -138.82116) (xy 347.731842 -138.82116)
			(xy 347.721778 -138.821595) (xy 347.703194 -138.829331) (xy 347.695774 -138.836146) (xy 344.15603 -142.37589)
			(xy 365.645444 -142.37589) (xy 365.649515 -142.320268) (xy 365.661641 -142.265831) (xy 365.681564 -142.21374)
			(xy 365.70886 -142.165105) (xy 365.742946 -142.120962) (xy 365.783095 -142.082253) (xy 365.828453 -142.049802)
			(xy 365.878053 -142.024301) (xy 365.930837 -142.006294) (xy 365.98568 -141.996164) (xy 366.041414 -141.994127)
			(xy 366.096851 -142.000227) (xy 366.150808 -142.014333) (xy 366.202137 -142.036145) (xy 366.249743 -142.065199)
			(xy 366.292611 -142.100874) (xy 366.329828 -142.142411) (xy 366.344483 -142.164562) (xy 370.257832 -142.164562)
			(xy 370.257832 -139.576556) (xy 370.258386 -139.548576) (xy 370.267151 -139.493307) (xy 370.28446 -139.440092)
			(xy 370.309884 -139.390241) (xy 370.342798 -139.344984) (xy 370.362226 -139.324842) (xy 371.417342 -138.269726)
			(xy 371.421152 -138.261598) (xy 371.433085 -138.237405) (xy 371.462722 -138.192332) (xy 371.498412 -138.151883)
			(xy 371.539441 -138.116861) (xy 371.584993 -138.087966) (xy 371.63416 -138.065773) (xy 371.685961 -138.050724)
			(xy 371.739366 -138.04312) (xy 371.766338 -138.04265) (xy 371.799271 -138.043374) (xy 371.86415 -138.054745)
			(xy 371.89537 -138.065256) (xy 371.903752 -138.068304) (xy 373.830596 -138.068304) (xy 373.840606 -138.067888)
			(xy 373.859069 -138.060139) (xy 373.86641 -138.053318) (xy 376.888756 -135.030972) (xy 376.908887 -135.011543)
			(xy 376.954154 -134.978667) (xy 377.004013 -134.953288) (xy 377.057232 -134.936032) (xy 377.112496 -134.927325)
			(xy 377.14047 -134.926832) (xy 385.12242 -134.926832) (xy 385.150386 -134.927398) (xy 385.205632 -134.936129)
			(xy 385.258835 -134.95339) (xy 385.308685 -134.978754) (xy 385.353957 -135.0116) (xy 385.374134 -135.030972)
			(xy 385.69773 -135.354568) (xy 385.717125 -135.374738) (xy 385.750021 -135.419999) (xy 385.775441 -135.469844)
			(xy 385.79276 -135.523049) (xy 385.801552 -135.578306) (xy 385.802124 -135.606282) (xy 385.802124 -136.32942)
			(xy 385.801631 -136.357402) (xy 385.792852 -136.412675) (xy 385.77553 -136.465892) (xy 385.750092 -136.515741)
			(xy 385.717164 -136.560994) (xy 385.69773 -136.581134) (xy 385.605274 -136.67359) (xy 385.601464 -136.681718)
			(xy 385.589526 -136.705909) (xy 385.559888 -136.75098) (xy 385.5242 -136.791429) (xy 385.483171 -136.82645)
			(xy 385.43762 -136.855345) (xy 385.388454 -136.877539) (xy 385.336653 -136.892589) (xy 385.283249 -136.900195)
			(xy 385.256278 -136.900666) (xy 385.229023 -136.900265) (xy 385.175067 -136.892504) (xy 385.122766 -136.877143)
			(xy 385.073183 -136.854495) (xy 385.027327 -136.825021) (xy 384.986134 -136.789321) (xy 384.950441 -136.748121)
			(xy 384.920974 -136.702261) (xy 384.898334 -136.652674) (xy 384.882982 -136.60037) (xy 384.87523 -136.546413)
			(xy 384.87477 -136.519158) (xy 384.875284 -136.490671) (xy 384.883762 -136.434331) (xy 384.900524 -136.379878)
			(xy 384.925196 -136.328523) (xy 384.957231 -136.281408) (xy 384.995915 -136.23958) (xy 385.04039 -136.20397)
			(xy 385.064762 -136.189212) (xy 385.072202 -136.184401) (xy 385.083504 -136.170773) (xy 385.089523 -136.154122)
			(xy 385.089908 -136.14527) (xy 385.089908 -135.774684) (xy 385.089464 -135.764713) (xy 385.081868 -135.746277)
			(xy 385.075176 -135.73887) (xy 384.989832 -135.653526) (xy 384.982427 -135.646804) (xy 384.964003 -135.639082)
			(xy 384.954018 -135.63854) (xy 377.308872 -135.63854) (xy 377.298868 -135.639006) (xy 377.280405 -135.646722)
			(xy 377.273058 -135.653526) (xy 375.826459 -137.100125) (xy 378.717621 -137.100125) (xy 378.717624 -137.045631)
			(xy 378.725382 -136.991692) (xy 378.740737 -136.939406) (xy 378.763377 -136.889837) (xy 378.79284 -136.843995)
			(xy 378.828528 -136.802812) (xy 378.869713 -136.767127) (xy 378.915557 -136.737666) (xy 378.965126 -136.715029)
			(xy 379.017413 -136.699677) (xy 379.071353 -136.691922) (xy 379.125847 -136.691922) (xy 379.179787 -136.699677)
			(xy 379.232074 -136.715029) (xy 379.281643 -136.737666) (xy 379.327487 -136.767127) (xy 379.368672 -136.802812)
			(xy 379.40436 -136.843995) (xy 379.433823 -136.889837) (xy 379.456463 -136.939406) (xy 379.471818 -136.991692)
			(xy 379.479576 -137.045631) (xy 379.480064 -137.072878) (xy 379.47975 -137.094988) (xy 379.474658 -137.138913)
			(xy 379.469904 -137.160508) (xy 379.466602 -137.17397) (xy 379.47473 -137.200386) (xy 379.560836 -137.278872)
			(xy 379.58776 -137.28446) (xy 379.600968 -137.280142) (xy 379.630296 -137.271031) (xy 379.690914 -137.261202)
			(xy 379.721618 -137.260584) (xy 379.748869 -137.261061) (xy 379.802817 -137.26882) (xy 379.855111 -137.284177)
			(xy 379.904688 -137.306819) (xy 379.950538 -137.336287) (xy 379.991728 -137.371979) (xy 380.027419 -137.41317)
			(xy 380.056885 -137.459021) (xy 380.079527 -137.508598) (xy 380.094882 -137.560893) (xy 380.10264 -137.614841)
			(xy 380.103126 -137.642092) (xy 380.103028 -137.652912) (xy 380.101757 -137.674515) (xy 380.100586 -137.685272)
			(xy 380.099316 -137.697718) (xy 380.108206 -137.720832) (xy 380.189486 -137.79246) (xy 380.213616 -137.798302)
			(xy 380.225808 -137.795254) (xy 380.24819 -137.79013) (xy 380.293781 -137.784658) (xy 380.31674 -137.784332)
			(xy 380.343987 -137.784821) (xy 380.397926 -137.792582) (xy 380.450211 -137.807939) (xy 380.499779 -137.830581)
			(xy 380.54562 -137.860047) (xy 380.586802 -137.895736) (xy 380.622485 -137.936922) (xy 380.651944 -137.982768)
			(xy 380.674579 -138.032339) (xy 380.68993 -138.084626) (xy 380.697683 -138.138566) (xy 380.697681 -138.19306)
			(xy 380.689924 -138.247) (xy 380.67457 -138.299286) (xy 380.651932 -138.348856) (xy 380.622469 -138.394699)
			(xy 380.586783 -138.435883) (xy 380.545599 -138.471569) (xy 380.499756 -138.501032) (xy 380.450186 -138.52367)
			(xy 380.3979 -138.539024) (xy 380.34396 -138.546781) (xy 380.289466 -138.546783) (xy 380.235526 -138.53903)
			(xy 380.183239 -138.523679) (xy 380.133668 -138.501044) (xy 380.087822 -138.471585) (xy 380.046636 -138.435902)
			(xy 380.010947 -138.39472) (xy 379.981481 -138.348879) (xy 379.958839 -138.299311) (xy 379.943482 -138.247026)
			(xy 379.935721 -138.193087) (xy 379.935232 -138.16584) (xy 379.935333 -138.15502) (xy 379.936601 -138.133417)
			(xy 379.937772 -138.12266) (xy 379.939042 -138.110214) (xy 379.930152 -138.0871) (xy 379.848872 -138.015472)
			(xy 379.824742 -138.00963) (xy 379.81255 -138.012678) (xy 379.790166 -138.017793) (xy 379.744577 -138.023271)
			(xy 379.721618 -138.0236) (xy 379.694365 -138.023128) (xy 379.640414 -138.015373) (xy 379.588116 -138.000019)
			(xy 379.538535 -137.977378) (xy 379.492682 -137.947911) (xy 379.451489 -137.912218) (xy 379.415795 -137.871026)
			(xy 379.386327 -137.825173) (xy 379.363684 -137.775593) (xy 379.348329 -137.723296) (xy 379.340573 -137.669345)
			(xy 379.34011 -137.642092) (xy 379.34042 -137.619982) (xy 379.345515 -137.576057) (xy 379.35027 -137.554462)
			(xy 379.353572 -137.541) (xy 379.345444 -137.514584) (xy 379.259338 -137.436098) (xy 379.232414 -137.43051)
			(xy 379.219206 -137.434828) (xy 379.189879 -137.443945) (xy 379.129261 -137.45377) (xy 379.098556 -137.454386)
			(xy 379.071309 -137.453875) (xy 379.01737 -137.446113) (xy 378.965085 -137.430755) (xy 378.915518 -137.408113)
			(xy 378.869677 -137.378647) (xy 378.828496 -137.342957) (xy 378.792814 -137.30177) (xy 378.763356 -137.255924)
			(xy 378.740722 -137.206353) (xy 378.725372 -137.154065) (xy 378.717621 -137.100125) (xy 375.826459 -137.100125)
			(xy 374.729131 -138.197453) (xy 375.096236 -138.197453) (xy 375.096236 -138.142947) (xy 375.103993 -138.088995)
			(xy 375.119348 -138.036696) (xy 375.14199 -137.987115) (xy 375.171458 -137.941261) (xy 375.207151 -137.900066)
			(xy 375.248343 -137.864371) (xy 375.294196 -137.834901) (xy 375.343776 -137.812256) (xy 375.396073 -137.796897)
			(xy 375.450025 -137.789137) (xy 375.477278 -137.78865) (xy 375.504916 -137.78913) (xy 375.559612 -137.797126)
			(xy 375.612583 -137.812924) (xy 375.662724 -137.836194) (xy 375.708985 -137.866451) (xy 375.7504 -137.903061)
			(xy 375.786104 -137.94526) (xy 375.815351 -137.992166) (xy 375.837529 -138.042799) (xy 375.845324 -138.06932)
			(xy 375.848626 -138.081766) (xy 375.865898 -138.100054) (xy 375.970546 -138.134852) (xy 375.995184 -138.130534)
			(xy 376.005344 -138.12266) (xy 376.016336 -138.114309) (xy 376.039348 -138.099056) (xy 376.051318 -138.09218)
			(xy 376.059954 -138.087354) (xy 376.071892 -138.072622) (xy 376.098816 -137.988294) (xy 376.097546 -137.969498)
			(xy 376.093482 -137.960608) (xy 376.08218 -137.935237) (xy 376.066223 -137.88204) (xy 376.058166 -137.827088)
			(xy 376.057668 -137.799318) (xy 376.058195 -137.772068) (xy 376.065948 -137.718123) (xy 376.0813 -137.665831)
			(xy 376.103937 -137.616255) (xy 376.133399 -137.570406) (xy 376.169087 -137.529216) (xy 376.210272 -137.493525)
			(xy 376.256118 -137.464057) (xy 376.305691 -137.441415) (xy 376.357982 -137.426057) (xy 376.411926 -137.418298)
			(xy 376.439176 -137.41781) (xy 376.463206 -137.418166) (xy 376.510884 -137.424213) (xy 376.557425 -137.436202)
			(xy 376.579892 -137.444734) (xy 376.588528 -137.448036) (xy 376.60707 -137.448544) (xy 376.688096 -137.41908)
			(xy 376.702066 -137.407142) (xy 376.706638 -137.39876) (xy 376.721075 -137.373331) (xy 376.756523 -137.326828)
			(xy 376.798656 -137.286283) (xy 376.846485 -137.252645) (xy 376.898888 -137.226704) (xy 376.954638 -137.209068)
			(xy 377.012427 -137.20015) (xy 377.041664 -137.199624) (xy 377.068921 -137.20002) (xy 377.12288 -137.207774)
			(xy 377.175187 -137.223128) (xy 377.224776 -137.245771) (xy 377.270637 -137.27524) (xy 377.311838 -137.310937)
			(xy 377.347538 -137.352134) (xy 377.377012 -137.397993) (xy 377.399659 -137.447579) (xy 377.415018 -137.499885)
			(xy 377.422777 -137.553843) (xy 377.422777 -137.608357) (xy 377.415018 -137.662315) (xy 377.399659 -137.714621)
			(xy 377.377012 -137.764207) (xy 377.347538 -137.810066) (xy 377.314594 -137.848083) (xy 377.700412 -137.848083)
			(xy 377.708165 -137.794125) (xy 377.723517 -137.74182) (xy 377.746157 -137.692232) (xy 377.775624 -137.646371)
			(xy 377.811317 -137.605171) (xy 377.852511 -137.569469) (xy 377.898366 -137.539993) (xy 377.947949 -137.517344)
			(xy 378.000251 -137.501981) (xy 378.054207 -137.494218) (xy 378.108719 -137.494212) (xy 378.162676 -137.501965)
			(xy 378.214981 -137.517317) (xy 378.264569 -137.539958) (xy 378.31043 -137.569424) (xy 378.35163 -137.605118)
			(xy 378.387332 -137.646312) (xy 378.416807 -137.692167) (xy 378.439457 -137.74175) (xy 378.45482 -137.794052)
			(xy 378.462582 -137.848008) (xy 378.463048 -137.875264) (xy 378.463048 -137.884662) (xy 378.46254 -137.895584)
			(xy 378.471176 -137.91565) (xy 378.543058 -137.982452) (xy 378.563632 -137.98931) (xy 378.574554 -137.988294)
			(xy 378.612908 -137.986262) (xy 378.640161 -137.986764) (xy 378.694111 -137.994522) (xy 378.746408 -138.009879)
			(xy 378.795987 -138.032523) (xy 378.841839 -138.061992) (xy 378.88303 -138.097686) (xy 378.918722 -138.13888)
			(xy 378.948188 -138.184734) (xy 378.970829 -138.234314) (xy 378.986183 -138.286612) (xy 378.993938 -138.340563)
			(xy 378.993936 -138.395068) (xy 378.986176 -138.449018) (xy 378.970818 -138.501315) (xy 378.948174 -138.550893)
			(xy 378.918704 -138.596745) (xy 378.883008 -138.637935) (xy 378.841814 -138.673627) (xy 378.79596 -138.703092)
			(xy 378.746379 -138.725732) (xy 378.694081 -138.741084) (xy 378.64013 -138.748838) (xy 378.585625 -138.748835)
			(xy 378.531675 -138.741075) (xy 378.479378 -138.725716) (xy 378.4298 -138.70307) (xy 378.383949 -138.673599)
			(xy 378.342759 -138.637903) (xy 378.307069 -138.596708) (xy 378.277605 -138.550854) (xy 378.254966 -138.501272)
			(xy 378.239614 -138.448974) (xy 378.231861 -138.395023) (xy 378.2314 -138.36777) (xy 378.2314 -138.358372)
			(xy 378.231908 -138.34745) (xy 378.223272 -138.327384) (xy 378.15139 -138.260582) (xy 378.130816 -138.253724)
			(xy 378.119894 -138.25474) (xy 378.08154 -138.256772) (xy 378.054284 -138.256388) (xy 378.000327 -138.248636)
			(xy 377.948021 -138.233283) (xy 377.898434 -138.210644) (xy 377.852573 -138.181177) (xy 377.811372 -138.145484)
			(xy 377.77567 -138.104291) (xy 377.746194 -138.058436) (xy 377.723544 -138.008852) (xy 377.708181 -137.95655)
			(xy 377.700418 -137.902594) (xy 377.700412 -137.848083) (xy 377.314594 -137.848083) (xy 377.311838 -137.851263)
			(xy 377.270637 -137.88696) (xy 377.224776 -137.916429) (xy 377.175187 -137.939072) (xy 377.12288 -137.954426)
			(xy 377.068921 -137.96218) (xy 377.041664 -137.96264) (xy 377.017634 -137.962275) (xy 376.969956 -137.956232)
			(xy 376.923416 -137.944246) (xy 376.900948 -137.935716) (xy 376.892312 -137.932414) (xy 376.87377 -137.931906)
			(xy 376.792744 -137.96137) (xy 376.778774 -137.973308) (xy 376.774202 -137.98169) (xy 376.761122 -138.004831)
			(xy 376.729486 -138.047549) (xy 376.692218 -138.085453) (xy 376.650041 -138.117807) (xy 376.627136 -138.131296)
			(xy 376.6185 -138.136122) (xy 376.606562 -138.150854) (xy 376.579638 -138.235182) (xy 376.580908 -138.253978)
			(xy 376.584972 -138.262868) (xy 376.596264 -138.288243) (xy 376.612225 -138.341439) (xy 376.620286 -138.396389)
			(xy 376.620786 -138.424158) (xy 376.620306 -138.451411) (xy 376.612554 -138.505362) (xy 376.597202 -138.557661)
			(xy 376.574563 -138.607243) (xy 376.545097 -138.653097) (xy 376.509405 -138.694291) (xy 376.468213 -138.729985)
			(xy 376.42236 -138.759453) (xy 376.37278 -138.782095) (xy 376.320482 -138.797449) (xy 376.266531 -138.805204)
			(xy 376.239278 -138.805666) (xy 376.211639 -138.805214) (xy 376.156943 -138.797212) (xy 376.103971 -138.781409)
			(xy 376.053831 -138.758135) (xy 376.007571 -138.727875) (xy 375.966156 -138.691261) (xy 375.930452 -138.64906)
			(xy 375.901206 -138.602152) (xy 375.879027 -138.551518) (xy 375.871232 -138.524996) (xy 375.86793 -138.51255)
			(xy 375.850658 -138.494262) (xy 375.74601 -138.459464) (xy 375.721372 -138.463782) (xy 375.711212 -138.471656)
			(xy 375.691054 -138.486766) (xy 375.647534 -138.512142) (xy 375.60105 -138.531561) (xy 375.552411 -138.544683)
			(xy 375.502467 -138.551281) (xy 375.477278 -138.551666) (xy 375.450025 -138.551263) (xy 375.396073 -138.543503)
			(xy 375.343776 -138.528144) (xy 375.294196 -138.505499) (xy 375.248343 -138.476029) (xy 375.207151 -138.440334)
			(xy 375.171458 -138.399139) (xy 375.14199 -138.353285) (xy 375.119348 -138.303704) (xy 375.103993 -138.251405)
			(xy 375.096236 -138.197453) (xy 374.729131 -138.197453) (xy 374.250712 -138.675872) (xy 374.242517 -138.683978)
			(xy 374.225233 -138.699232) (xy 374.216168 -138.706352) (xy 374.208189 -138.713245) (xy 374.198062 -138.731703)
			(xy 374.196211 -138.752675) (xy 374.202947 -138.772621) (xy 374.217134 -138.788177) (xy 374.236377 -138.796716)
			(xy 374.246902 -138.797284) (xy 374.274094 -138.797837) (xy 374.327905 -138.805744) (xy 374.380047 -138.821212)
			(xy 374.429464 -138.843928) (xy 374.475154 -138.873432) (xy 374.516192 -138.909124) (xy 374.551745 -138.950283)
			(xy 374.581094 -138.996073) (xy 374.603642 -139.045567) (xy 374.618933 -139.097761) (xy 374.622542 -139.122912)
			(xy 375.06732 -139.122912) (xy 375.071391 -139.06729) (xy 375.083517 -139.012853) (xy 375.10344 -138.960762)
			(xy 375.130736 -138.912127) (xy 375.164822 -138.867984) (xy 375.204971 -138.829275) (xy 375.250329 -138.796824)
			(xy 375.299929 -138.771323) (xy 375.352713 -138.753316) (xy 375.407556 -138.743186) (xy 375.46329 -138.741149)
			(xy 375.518727 -138.747249) (xy 375.572684 -138.761355) (xy 375.624013 -138.783167) (xy 375.671619 -138.812221)
			(xy 375.714487 -138.847896) (xy 375.751704 -138.889433) (xy 375.782477 -138.935946) (xy 375.806149 -138.986443)
			(xy 375.822217 -139.03985) (xy 375.830337 -139.095026) (xy 375.830846 -139.122912) (xy 375.830337 -139.150798)
			(xy 375.822217 -139.205974) (xy 375.806149 -139.259381) (xy 375.782477 -139.309878) (xy 375.751704 -139.356391)
			(xy 375.714487 -139.397928) (xy 375.671619 -139.433603) (xy 375.624013 -139.462657) (xy 375.572684 -139.484469)
			(xy 375.518727 -139.498575) (xy 375.46329 -139.504675) (xy 375.407556 -139.502638) (xy 375.352713 -139.492508)
			(xy 375.299929 -139.474501) (xy 375.250329 -139.449) (xy 375.204971 -139.416549) (xy 375.164822 -139.37784)
			(xy 375.130736 -139.333697) (xy 375.10344 -139.285062) (xy 375.083517 -139.232971) (xy 375.071391 -139.178534)
			(xy 375.06732 -139.122912) (xy 374.622542 -139.122912) (xy 374.626658 -139.151598) (xy 374.62714 -139.178792)
			(xy 374.626654 -139.206043) (xy 374.618898 -139.259991) (xy 374.603543 -139.312286) (xy 374.580901 -139.361863)
			(xy 374.551435 -139.407713) (xy 374.515744 -139.448904) (xy 374.474553 -139.484595) (xy 374.428703 -139.514061)
			(xy 374.379126 -139.536703) (xy 374.326831 -139.552058) (xy 374.272883 -139.559814) (xy 374.218381 -139.559814)
			(xy 374.164433 -139.552058) (xy 374.112138 -139.536703) (xy 374.062561 -139.514061) (xy 374.016711 -139.484595)
			(xy 373.97552 -139.448904) (xy 373.939829 -139.407713) (xy 373.910363 -139.361863) (xy 373.887721 -139.312286)
			(xy 373.872366 -139.259991) (xy 373.86461 -139.206043) (xy 373.864124 -139.178792) (xy 373.864527 -139.1535)
			(xy 373.871207 -139.10336) (xy 373.884462 -139.054545) (xy 373.904058 -139.007911) (xy 373.929651 -138.964281)
			(xy 373.944896 -138.944096) (xy 373.953786 -138.932666) (xy 373.956834 -138.903964) (xy 373.910352 -138.808714)
			(xy 373.905876 -138.800296) (xy 373.891902 -138.787342) (xy 373.874159 -138.780397) (xy 373.864632 -138.780012)
			(xy 371.93474 -138.780012) (xy 371.924735 -138.780469) (xy 371.906273 -138.788192) (xy 371.898926 -138.794998)
			(xy 370.98478 -139.709144) (xy 370.978118 -139.716569) (xy 370.970531 -139.734995) (xy 370.970048 -139.744958)
			(xy 370.970048 -140.015214) (xy 373.57126 -140.015214) (xy 373.575331 -139.959592) (xy 373.587457 -139.905155)
			(xy 373.60738 -139.853064) (xy 373.634676 -139.804429) (xy 373.668762 -139.760286) (xy 373.708911 -139.721577)
			(xy 373.754269 -139.689126) (xy 373.803869 -139.663625) (xy 373.856653 -139.645618) (xy 373.911496 -139.635488)
			(xy 373.96723 -139.633451) (xy 374.022667 -139.639551) (xy 374.076624 -139.653657) (xy 374.127953 -139.675469)
			(xy 374.175559 -139.704523) (xy 374.218427 -139.740198) (xy 374.255644 -139.781735) (xy 374.286417 -139.828248)
			(xy 374.310089 -139.878745) (xy 374.326157 -139.932152) (xy 374.334277 -139.987328) (xy 374.334786 -140.015214)
			(xy 374.334277 -140.0431) (xy 374.326157 -140.098276) (xy 374.310089 -140.151683) (xy 374.286417 -140.20218)
			(xy 374.255644 -140.248693) (xy 374.218427 -140.29023) (xy 374.175559 -140.325905) (xy 374.127953 -140.354959)
			(xy 374.076624 -140.376771) (xy 374.022667 -140.390877) (xy 373.96723 -140.396977) (xy 373.911496 -140.39494)
			(xy 373.856653 -140.38481) (xy 373.803869 -140.366803) (xy 373.754269 -140.341302) (xy 373.708911 -140.308851)
			(xy 373.668762 -140.270142) (xy 373.634676 -140.225999) (xy 373.60738 -140.177364) (xy 373.587457 -140.125273)
			(xy 373.575331 -140.070836) (xy 373.57126 -140.015214) (xy 370.970048 -140.015214) (xy 370.970048 -140.975334)
			(xy 371.09273 -140.975334) (xy 371.093216 -140.948083) (xy 371.100972 -140.894135) (xy 371.116327 -140.84184)
			(xy 371.138969 -140.792263) (xy 371.168435 -140.746413) (xy 371.204126 -140.705222) (xy 371.245317 -140.669531)
			(xy 371.291167 -140.640065) (xy 371.340744 -140.617423) (xy 371.393039 -140.602068) (xy 371.446987 -140.594312)
			(xy 371.501489 -140.594312) (xy 371.555437 -140.602068) (xy 371.607732 -140.617423) (xy 371.657309 -140.640065)
			(xy 371.703159 -140.669531) (xy 371.74435 -140.705222) (xy 371.780041 -140.746413) (xy 371.809507 -140.792263)
			(xy 371.832149 -140.84184) (xy 371.847504 -140.894135) (xy 371.85526 -140.948083) (xy 371.855746 -140.975334)
			(xy 371.855239 -141.004699) (xy 371.846308 -141.062744) (xy 371.837966 -141.090904) (xy 371.834337 -141.103868)
			(xy 371.833141 -141.130748) (xy 371.839019 -141.157005) (xy 371.851561 -141.18081) (xy 371.869893 -141.200504)
			(xy 371.89274 -141.214717) (xy 371.918509 -141.222459) (xy 371.931946 -141.223238) (xy 371.958688 -141.224443)
			(xy 372.011468 -141.233379) (xy 372.062478 -141.24961) (xy 372.110717 -141.272817) (xy 372.155236 -141.302542)
			(xy 372.195159 -141.338202) (xy 372.229702 -141.379096) (xy 372.258186 -141.424419) (xy 372.28005 -141.473281)
			(xy 372.294866 -141.52472) (xy 372.30234 -141.577727) (xy 372.302786 -141.604492) (xy 372.3023 -141.631743)
			(xy 372.294544 -141.685691) (xy 372.279189 -141.737986) (xy 372.256547 -141.787563) (xy 372.227081 -141.833413)
			(xy 372.19139 -141.874604) (xy 372.150199 -141.910295) (xy 372.104349 -141.939761) (xy 372.054772 -141.962403)
			(xy 372.002477 -141.977758) (xy 371.948529 -141.985514) (xy 371.894027 -141.985514) (xy 371.840079 -141.977758)
			(xy 371.787784 -141.962403) (xy 371.738207 -141.939761) (xy 371.692357 -141.910295) (xy 371.651166 -141.874604)
			(xy 371.615475 -141.833413) (xy 371.586009 -141.787563) (xy 371.563367 -141.737986) (xy 371.548012 -141.685691)
			(xy 371.540256 -141.631743) (xy 371.53977 -141.604492) (xy 371.540286 -141.575128) (xy 371.549211 -141.517082)
			(xy 371.55755 -141.488922) (xy 371.561249 -141.475977) (xy 371.562429 -141.449089) (xy 371.556537 -141.422828)
			(xy 371.543983 -141.399022) (xy 371.52564 -141.379326) (xy 371.502786 -141.365112) (xy 371.477011 -141.357369)
			(xy 371.46357 -141.356588) (xy 371.436825 -141.355433) (xy 371.384046 -141.346486) (xy 371.333036 -141.330246)
			(xy 371.284799 -141.307032) (xy 371.240282 -141.277301) (xy 371.200361 -141.241636) (xy 371.165819 -141.200739)
			(xy 371.137336 -141.155413) (xy 371.115471 -141.106549) (xy 371.100655 -141.055108) (xy 371.093178 -141.0021)
			(xy 371.09273 -140.975334) (xy 370.970048 -140.975334) (xy 370.970048 -141.99616) (xy 370.970532 -142.006126)
			(xy 370.978102 -142.024562) (xy 370.98478 -142.031974) (xy 371.070124 -142.117318) (xy 371.077505 -142.12407)
			(xy 371.095947 -142.131773) (xy 371.105938 -142.132304) (xy 371.783864 -142.132304) (xy 371.792246 -142.129256)
			(xy 371.823458 -142.118717) (xy 371.888342 -142.107359) (xy 371.921278 -142.10665) (xy 371.948529 -142.107196)
			(xy 372.002476 -142.114949) (xy 372.054771 -142.130302) (xy 372.104348 -142.15294) (xy 372.150199 -142.182405)
			(xy 372.19139 -142.218094) (xy 372.227082 -142.259283) (xy 372.256549 -142.305132) (xy 372.279191 -142.354708)
			(xy 372.294546 -142.407002) (xy 372.302303 -142.460949) (xy 372.302303 -142.515451) (xy 372.295745 -142.561056)
			(xy 373.69877 -142.561056) (xy 373.699236 -142.534988) (xy 373.706348 -142.483339) (xy 373.72042 -142.433137)
			(xy 373.74119 -142.385316) (xy 373.768273 -142.340766) (xy 373.801165 -142.300314) (xy 373.839253 -142.264712)
			(xy 373.881831 -142.234623) (xy 373.904764 -142.22222) (xy 373.915178 -142.216886) (xy 373.928894 -142.199106)
			(xy 373.949722 -142.099284) (xy 373.944388 -142.077186) (xy 373.937276 -142.068296) (xy 373.921311 -142.047845)
			(xy 373.894452 -142.003457) (xy 373.87386 -141.955836) (xy 373.859917 -141.905863) (xy 373.852878 -141.854461)
			(xy 373.85244 -141.82852) (xy 373.852894 -141.800916) (xy 373.860837 -141.746283) (xy 373.876574 -141.693366)
			(xy 373.899777 -141.643271) (xy 373.929959 -141.597044) (xy 373.966492 -141.555653) (xy 374.008611 -141.519962)
			(xy 374.031764 -141.504924) (xy 374.042686 -141.498066) (xy 374.055386 -141.475968) (xy 374.05818 -141.365732)
			(xy 374.04675 -141.342872) (xy 374.036082 -141.335506) (xy 374.014869 -141.320146) (xy 373.976466 -141.284535)
			(xy 373.943296 -141.244005) (xy 373.91598 -141.199319) (xy 373.895034 -141.151317) (xy 373.88085 -141.100901)
			(xy 373.873696 -141.049019) (xy 373.873268 -141.022832) (xy 373.873754 -140.995581) (xy 373.88151 -140.941633)
			(xy 373.896865 -140.889338) (xy 373.919507 -140.839761) (xy 373.948973 -140.793911) (xy 373.984664 -140.75272)
			(xy 374.025855 -140.717029) (xy 374.071705 -140.687563) (xy 374.121282 -140.664921) (xy 374.173577 -140.649566)
			(xy 374.227525 -140.64181) (xy 374.282027 -140.64181) (xy 374.335975 -140.649566) (xy 374.38827 -140.664921)
			(xy 374.437847 -140.687563) (xy 374.483697 -140.717029) (xy 374.524888 -140.75272) (xy 374.560579 -140.793911)
			(xy 374.590045 -140.839761) (xy 374.612687 -140.889338) (xy 374.628042 -140.941633) (xy 374.635798 -140.995581)
			(xy 374.636284 -141.022832) (xy 374.635828 -141.050436) (xy 374.62789 -141.105071) (xy 374.612156 -141.15799)
			(xy 374.588955 -141.208086) (xy 374.558771 -141.254313) (xy 374.522237 -141.295703) (xy 374.480115 -141.331392)
			(xy 374.45696 -141.346428) (xy 374.446038 -141.353286) (xy 374.433338 -141.375384) (xy 374.430544 -141.48562)
			(xy 374.441974 -141.50848) (xy 374.452642 -141.515846) (xy 374.473838 -141.531228) (xy 374.51224 -141.566837)
			(xy 374.545411 -141.607363) (xy 374.572728 -141.652045) (xy 374.593677 -141.700043) (xy 374.607865 -141.750456)
			(xy 374.615025 -141.802335) (xy 374.615456 -141.82852) (xy 374.61501 -141.854589) (xy 374.6079 -141.906241)
			(xy 374.593828 -141.956445) (xy 374.573056 -142.004267) (xy 374.54597 -142.048819) (xy 374.513074 -142.089271)
			(xy 374.474981 -142.12487) (xy 374.432398 -142.154956) (xy 374.409462 -142.167356) (xy 374.399048 -142.17269)
			(xy 374.385332 -142.19047) (xy 374.364504 -142.290292) (xy 374.369838 -142.31239) (xy 374.37695 -142.32128)
			(xy 374.392908 -142.341737) (xy 374.419767 -142.386124) (xy 374.44036 -142.433743) (xy 374.454305 -142.483714)
			(xy 374.461346 -142.535116) (xy 374.461786 -142.561056) (xy 374.4613 -142.588307) (xy 374.453544 -142.642255)
			(xy 374.438189 -142.69455) (xy 374.415547 -142.744127) (xy 374.386081 -142.789977) (xy 374.35039 -142.831168)
			(xy 374.309199 -142.866859) (xy 374.263349 -142.896325) (xy 374.213772 -142.918967) (xy 374.161477 -142.934322)
			(xy 374.107529 -142.942078) (xy 374.053027 -142.942078) (xy 373.999079 -142.934322) (xy 373.946784 -142.918967)
			(xy 373.897207 -142.896325) (xy 373.851357 -142.866859) (xy 373.810166 -142.831168) (xy 373.774475 -142.789977)
			(xy 373.745009 -142.744127) (xy 373.722367 -142.69455) (xy 373.707012 -142.642255) (xy 373.699256 -142.588307)
			(xy 373.69877 -142.561056) (xy 372.295745 -142.561056) (xy 372.294546 -142.569398) (xy 372.279191 -142.621692)
			(xy 372.256549 -142.671268) (xy 372.227082 -142.717117) (xy 372.19139 -142.758306) (xy 372.150199 -142.793995)
			(xy 372.104348 -142.82346) (xy 372.054771 -142.846098) (xy 372.002476 -142.861451) (xy 371.948529 -142.869204)
			(xy 371.921278 -142.869666) (xy 371.888345 -142.868938) (xy 371.823466 -142.857569) (xy 371.792246 -142.84706)
			(xy 371.783864 -142.844012) (xy 370.937536 -142.844012) (xy 370.909569 -142.843461) (xy 370.854323 -142.834724)
			(xy 370.801121 -142.81746) (xy 370.751271 -142.792092) (xy 370.705999 -142.759244) (xy 370.685822 -142.739872)
			(xy 370.362226 -142.416276) (xy 370.342845 -142.396094) (xy 370.309948 -142.350836) (xy 370.284527 -142.300993)
			(xy 370.267205 -142.247792) (xy 370.258407 -142.192537) (xy 370.257832 -142.164562) (xy 366.344483 -142.164562)
			(xy 366.360601 -142.188924) (xy 366.384273 -142.239421) (xy 366.400341 -142.292828) (xy 366.408461 -142.348004)
			(xy 366.40897 -142.37589) (xy 366.408461 -142.403776) (xy 366.400341 -142.458952) (xy 366.384273 -142.512359)
			(xy 366.360601 -142.562856) (xy 366.329828 -142.609369) (xy 366.292611 -142.650906) (xy 366.249743 -142.686581)
			(xy 366.202137 -142.715635) (xy 366.150808 -142.737447) (xy 366.096851 -142.751553) (xy 366.041414 -142.757653)
			(xy 365.98568 -142.755616) (xy 365.930837 -142.745486) (xy 365.878053 -142.727479) (xy 365.828453 -142.701978)
			(xy 365.783095 -142.669527) (xy 365.742946 -142.630818) (xy 365.70886 -142.586675) (xy 365.681564 -142.53804)
			(xy 365.661641 -142.485949) (xy 365.649515 -142.431512) (xy 365.645444 -142.37589) (xy 344.15603 -142.37589)
			(xy 343.027762 -143.504158) (xy 373.57126 -143.504158) (xy 373.575331 -143.448536) (xy 373.587457 -143.394099)
			(xy 373.60738 -143.342008) (xy 373.634676 -143.293373) (xy 373.668762 -143.24923) (xy 373.708911 -143.210521)
			(xy 373.754269 -143.17807) (xy 373.803869 -143.152569) (xy 373.856653 -143.134562) (xy 373.911496 -143.124432)
			(xy 373.96723 -143.122395) (xy 374.022667 -143.128495) (xy 374.076624 -143.142601) (xy 374.127953 -143.164413)
			(xy 374.175559 -143.193467) (xy 374.218427 -143.229142) (xy 374.255644 -143.270679) (xy 374.286417 -143.317192)
			(xy 374.310089 -143.367689) (xy 374.326157 -143.421096) (xy 374.334277 -143.476272) (xy 374.334786 -143.504158)
			(xy 374.334277 -143.532044) (xy 374.326157 -143.58722) (xy 374.310089 -143.640627) (xy 374.286417 -143.691124)
			(xy 374.255644 -143.737637) (xy 374.218427 -143.779174) (xy 374.175559 -143.814849) (xy 374.127953 -143.843903)
			(xy 374.076624 -143.865715) (xy 374.022667 -143.879821) (xy 373.96723 -143.885921) (xy 373.911496 -143.883884)
			(xy 373.856653 -143.873754) (xy 373.803869 -143.855747) (xy 373.754269 -143.830246) (xy 373.708911 -143.797795)
			(xy 373.668762 -143.759086) (xy 373.634676 -143.714943) (xy 373.60738 -143.666308) (xy 373.587457 -143.614217)
			(xy 373.575331 -143.55978) (xy 373.57126 -143.504158) (xy 343.027762 -143.504158) (xy 342.011762 -144.520158)
			(xy 371.53926 -144.520158) (xy 371.543331 -144.464536) (xy 371.555457 -144.410099) (xy 371.57538 -144.358008)
			(xy 371.602676 -144.309373) (xy 371.636762 -144.26523) (xy 371.676911 -144.226521) (xy 371.722269 -144.19407)
			(xy 371.771869 -144.168569) (xy 371.824653 -144.150562) (xy 371.879496 -144.140432) (xy 371.93523 -144.138395)
			(xy 371.990667 -144.144495) (xy 372.044624 -144.158601) (xy 372.095953 -144.180413) (xy 372.143559 -144.209467)
			(xy 372.186427 -144.245142) (xy 372.223644 -144.286679) (xy 372.254417 -144.333192) (xy 372.278089 -144.383689)
			(xy 372.294157 -144.437096) (xy 372.302277 -144.492272) (xy 372.302786 -144.520158) (xy 372.302277 -144.548044)
			(xy 372.294157 -144.60322) (xy 372.278089 -144.656627) (xy 372.254417 -144.707124) (xy 372.223644 -144.753637)
			(xy 372.186427 -144.795174) (xy 372.143559 -144.830849) (xy 372.095953 -144.859903) (xy 372.044624 -144.881715)
			(xy 371.990667 -144.895821) (xy 371.93523 -144.901921) (xy 371.879496 -144.899884) (xy 371.824653 -144.889754)
			(xy 371.771869 -144.871747) (xy 371.722269 -144.846246) (xy 371.676911 -144.813795) (xy 371.636762 -144.775086)
			(xy 371.602676 -144.730943) (xy 371.57538 -144.682308) (xy 371.555457 -144.630217) (xy 371.543331 -144.57578)
			(xy 371.53926 -144.520158) (xy 342.011762 -144.520158) (xy 341.004652 -145.527268) (xy 340.997968 -145.534678)
			(xy 340.990382 -145.553114) (xy 340.98992 -145.563082) (xy 340.98992 -147.904962) (xy 344.785959 -147.904962)
			(xy 344.789955 -147.743437) (xy 344.801934 -147.582308) (xy 344.821868 -147.421968) (xy 344.849706 -147.26281)
			(xy 344.885381 -147.105224) (xy 344.928806 -146.949595) (xy 344.979874 -146.796304) (xy 345.038461 -146.645725)
			(xy 345.104422 -146.498229) (xy 345.177597 -146.354175) (xy 345.257807 -146.213915) (xy 345.344854 -146.077795)
			(xy 345.438527 -145.946145) (xy 345.538596 -145.819289) (xy 345.644816 -145.697537) (xy 345.756927 -145.581187)
			(xy 345.874654 -145.470524) (xy 345.997711 -145.365818) (xy 346.125794 -145.267326) (xy 346.258592 -145.175289)
			(xy 346.395779 -145.089931) (xy 346.53702 -145.011463) (xy 346.681968 -144.940075) (xy 346.830269 -144.875943)
			(xy 346.981561 -144.819223) (xy 347.135472 -144.770055) (xy 347.291626 -144.728558) (xy 347.449642 -144.694835)
			(xy 347.609132 -144.668967) (xy 347.769706 -144.651018) (xy 347.930971 -144.641033) (xy 348.092533 -144.639034)
			(xy 348.253995 -144.645028) (xy 348.414964 -144.659) (xy 348.575045 -144.680915) (xy 348.733847 -144.710719)
			(xy 348.89098 -144.748341) (xy 349.04606 -144.793687) (xy 349.198708 -144.846647) (xy 349.34855 -144.907092)
			(xy 349.49522 -144.974872) (xy 349.638358 -145.049823) (xy 349.777614 -145.131761) (xy 349.912648 -145.220486)
			(xy 350.043129 -145.31578) (xy 350.168737 -145.41741) (xy 350.289166 -145.525128) (xy 350.300333 -145.536158)
			(xy 371.53926 -145.536158) (xy 371.543331 -145.480536) (xy 371.555457 -145.426099) (xy 371.57538 -145.374008)
			(xy 371.602676 -145.325373) (xy 371.636762 -145.28123) (xy 371.676911 -145.242521) (xy 371.722269 -145.21007)
			(xy 371.771869 -145.184569) (xy 371.824653 -145.166562) (xy 371.879496 -145.156432) (xy 371.93523 -145.154395)
			(xy 371.990667 -145.160495) (xy 372.044624 -145.174601) (xy 372.095953 -145.196413) (xy 372.143559 -145.225467)
			(xy 372.186427 -145.261142) (xy 372.223644 -145.302679) (xy 372.254417 -145.349192) (xy 372.278089 -145.399689)
			(xy 372.294157 -145.453096) (xy 372.302277 -145.508272) (xy 372.302786 -145.536158) (xy 372.302277 -145.564044)
			(xy 372.294157 -145.61922) (xy 372.278089 -145.672627) (xy 372.254417 -145.723124) (xy 372.223644 -145.769637)
			(xy 372.186427 -145.811174) (xy 372.143559 -145.846849) (xy 372.095953 -145.875903) (xy 372.044624 -145.897715)
			(xy 371.990667 -145.911821) (xy 371.93523 -145.917921) (xy 371.879496 -145.915884) (xy 371.824653 -145.905754)
			(xy 371.771869 -145.887747) (xy 371.722269 -145.862246) (xy 371.676911 -145.829795) (xy 371.636762 -145.791086)
			(xy 371.602676 -145.746943) (xy 371.57538 -145.698308) (xy 371.555457 -145.646217) (xy 371.543331 -145.59178)
			(xy 371.53926 -145.536158) (xy 350.300333 -145.536158) (xy 350.40412 -145.638669) (xy 350.513319 -145.757756)
			(xy 350.616495 -145.882098) (xy 350.713396 -146.01139) (xy 350.803783 -146.145317) (xy 350.887438 -146.283549)
			(xy 350.964153 -146.425749) (xy 350.997569 -146.49577) (xy 365.860074 -146.49577) (xy 365.864145 -146.440148)
			(xy 365.876271 -146.385711) (xy 365.896194 -146.33362) (xy 365.92349 -146.284985) (xy 365.957576 -146.240842)
			(xy 365.997725 -146.202133) (xy 366.043083 -146.169682) (xy 366.092683 -146.144181) (xy 366.145467 -146.126174)
			(xy 366.20031 -146.116044) (xy 366.256044 -146.114007) (xy 366.311481 -146.120107) (xy 366.365438 -146.134213)
			(xy 366.416767 -146.156025) (xy 366.464373 -146.185079) (xy 366.507241 -146.220754) (xy 366.544458 -146.262291)
			(xy 366.575231 -146.308804) (xy 366.598903 -146.359301) (xy 366.614971 -146.412708) (xy 366.623091 -146.467884)
			(xy 366.6236 -146.49577) (xy 366.623091 -146.523656) (xy 366.618896 -146.552158) (xy 371.53926 -146.552158)
			(xy 371.543331 -146.496536) (xy 371.555457 -146.442099) (xy 371.57538 -146.390008) (xy 371.602676 -146.341373)
			(xy 371.636762 -146.29723) (xy 371.676911 -146.258521) (xy 371.722269 -146.22607) (xy 371.771869 -146.200569)
			(xy 371.824653 -146.182562) (xy 371.879496 -146.172432) (xy 371.93523 -146.170395) (xy 371.990667 -146.176495)
			(xy 372.044624 -146.190601) (xy 372.095953 -146.212413) (xy 372.143559 -146.241467) (xy 372.186427 -146.277142)
			(xy 372.223644 -146.318679) (xy 372.254417 -146.365192) (xy 372.278089 -146.415689) (xy 372.294157 -146.469096)
			(xy 372.302277 -146.524272) (xy 372.302786 -146.552158) (xy 372.302277 -146.580044) (xy 372.294157 -146.63522)
			(xy 372.278089 -146.688627) (xy 372.254417 -146.739124) (xy 372.223644 -146.785637) (xy 372.186427 -146.827174)
			(xy 372.143559 -146.862849) (xy 372.095953 -146.891903) (xy 372.044624 -146.913715) (xy 371.990667 -146.927821)
			(xy 371.93523 -146.933921) (xy 371.879496 -146.931884) (xy 371.824653 -146.921754) (xy 371.771869 -146.903747)
			(xy 371.722269 -146.878246) (xy 371.676911 -146.845795) (xy 371.636762 -146.807086) (xy 371.602676 -146.762943)
			(xy 371.57538 -146.714308) (xy 371.555457 -146.662217) (xy 371.543331 -146.60778) (xy 371.53926 -146.552158)
			(xy 366.618896 -146.552158) (xy 366.614971 -146.578832) (xy 366.598903 -146.632239) (xy 366.575231 -146.682736)
			(xy 366.544458 -146.729249) (xy 366.507241 -146.770786) (xy 366.464373 -146.806461) (xy 366.416767 -146.835515)
			(xy 366.365438 -146.857327) (xy 366.311481 -146.871433) (xy 366.256044 -146.877533) (xy 366.20031 -146.875496)
			(xy 366.145467 -146.865366) (xy 366.092683 -146.847359) (xy 366.043083 -146.821858) (xy 365.997725 -146.789407)
			(xy 365.957576 -146.750698) (xy 365.92349 -146.706555) (xy 365.896194 -146.65792) (xy 365.876271 -146.605829)
			(xy 365.864145 -146.551392) (xy 365.860074 -146.49577) (xy 350.997569 -146.49577) (xy 351.033743 -146.571569)
			(xy 351.096036 -146.720652) (xy 351.15088 -146.872633) (xy 351.198141 -147.027141) (xy 351.237703 -147.183797)
			(xy 351.269469 -147.342217) (xy 351.293362 -147.502015) (xy 351.299928 -147.568158) (xy 371.53926 -147.568158)
			(xy 371.543331 -147.512536) (xy 371.555457 -147.458099) (xy 371.57538 -147.406008) (xy 371.602676 -147.357373)
			(xy 371.636762 -147.31323) (xy 371.676911 -147.274521) (xy 371.722269 -147.24207) (xy 371.771869 -147.216569)
			(xy 371.824653 -147.198562) (xy 371.879496 -147.188432) (xy 371.93523 -147.186395) (xy 371.990667 -147.192495)
			(xy 372.044624 -147.206601) (xy 372.095953 -147.228413) (xy 372.143559 -147.257467) (xy 372.186427 -147.293142)
			(xy 372.223644 -147.334679) (xy 372.254417 -147.381192) (xy 372.278089 -147.431689) (xy 372.294157 -147.485096)
			(xy 372.302277 -147.540272) (xy 372.302786 -147.568158) (xy 372.302277 -147.596044) (xy 372.294157 -147.65122)
			(xy 372.278089 -147.704627) (xy 372.254417 -147.755124) (xy 372.223644 -147.801637) (xy 372.186427 -147.843174)
			(xy 372.143559 -147.878849) (xy 372.095953 -147.907903) (xy 372.044624 -147.929715) (xy 371.990667 -147.943821)
			(xy 371.93523 -147.949921) (xy 371.879496 -147.947884) (xy 371.824653 -147.937754) (xy 371.771869 -147.919747)
			(xy 371.722269 -147.894246) (xy 371.676911 -147.861795) (xy 371.636762 -147.823086) (xy 371.602676 -147.778943)
			(xy 371.57538 -147.730308) (xy 371.555457 -147.678217) (xy 371.543331 -147.62378) (xy 371.53926 -147.568158)
			(xy 351.299928 -147.568158) (xy 351.309324 -147.662799) (xy 351.317314 -147.824175) (xy 351.317814 -147.904962)
			(xy 351.317314 -147.985749) (xy 351.309324 -148.147125) (xy 351.293362 -148.307909) (xy 351.269469 -148.467707)
			(xy 351.237703 -148.626127) (xy 351.198141 -148.782783) (xy 351.15088 -148.937291) (xy 351.096036 -149.089272)
			(xy 351.033743 -149.238355) (xy 350.964153 -149.384175) (xy 350.887438 -149.526375) (xy 350.803783 -149.664607)
			(xy 350.713396 -149.798534) (xy 350.616495 -149.927826) (xy 350.513319 -150.052168) (xy 350.40412 -150.171255)
			(xy 350.289166 -150.284796) (xy 350.168737 -150.392514) (xy 350.043129 -150.494144) (xy 349.912648 -150.589438)
			(xy 349.777614 -150.678163) (xy 349.638358 -150.760101) (xy 349.49522 -150.835052) (xy 349.34855 -150.902832)
			(xy 349.198708 -150.963277) (xy 349.04606 -151.016237) (xy 348.89098 -151.061583) (xy 348.733847 -151.099205)
			(xy 348.575045 -151.129009) (xy 348.414964 -151.150924) (xy 348.253995 -151.164896) (xy 348.092533 -151.17089)
			(xy 347.930971 -151.168891) (xy 347.769706 -151.158906) (xy 347.609132 -151.140957) (xy 347.449642 -151.115089)
			(xy 347.291626 -151.081366) (xy 347.135472 -151.039869) (xy 346.981561 -150.990701) (xy 346.830269 -150.933981)
			(xy 346.681968 -150.869849) (xy 346.53702 -150.798461) (xy 346.395779 -150.719993) (xy 346.258592 -150.634635)
			(xy 346.125794 -150.542598) (xy 345.997711 -150.444106) (xy 345.874654 -150.3394) (xy 345.756927 -150.228737)
			(xy 345.644816 -150.112387) (xy 345.538596 -149.990635) (xy 345.438527 -149.863779) (xy 345.344854 -149.732129)
			(xy 345.257807 -149.596009) (xy 345.177597 -149.455749) (xy 345.104422 -149.311695) (xy 345.038461 -149.164199)
			(xy 344.979874 -149.01362) (xy 344.928806 -148.860329) (xy 344.885381 -148.7047) (xy 344.849706 -148.547114)
			(xy 344.821868 -148.387956) (xy 344.801934 -148.227616) (xy 344.789955 -148.066487) (xy 344.785959 -147.904962)
			(xy 340.98992 -147.904962) (xy 340.98992 -152.754768) (xy 358.696256 -152.754768) (xy 358.696256 -152.670072)
			(xy 358.704307 -152.585758) (xy 358.720336 -152.502592) (xy 358.744197 -152.421325) (xy 358.775676 -152.342695)
			(xy 358.814487 -152.267414) (xy 358.860277 -152.196162) (xy 358.912633 -152.129586) (xy 358.971081 -152.068288)
			(xy 359.035091 -152.012823) (xy 359.104083 -151.963694) (xy 359.177433 -151.921345) (xy 359.254476 -151.886161)
			(xy 359.334515 -151.858459) (xy 359.416824 -151.838491) (xy 359.500659 -151.826438) (xy 359.58526 -151.822408)
			(xy 359.669861 -151.826438) (xy 359.753696 -151.838491) (xy 359.836005 -151.858459) (xy 359.916044 -151.886161)
			(xy 359.993087 -151.921345) (xy 360.066437 -151.963694) (xy 360.135429 -152.012823) (xy 360.199439 -152.068288)
			(xy 360.257887 -152.129586) (xy 360.310243 -152.196162) (xy 360.356033 -152.267414) (xy 360.394844 -152.342695)
			(xy 360.426323 -152.421325) (xy 360.450184 -152.502592) (xy 360.466213 -152.585758) (xy 360.474264 -152.670072)
			(xy 360.474768 -152.71242) (xy 360.474264 -152.754768) (xy 361.196378 -152.754768) (xy 361.196378 -152.670072)
			(xy 361.204429 -152.585758) (xy 361.220458 -152.502592) (xy 361.244319 -152.421325) (xy 361.275798 -152.342695)
			(xy 361.314609 -152.267414) (xy 361.360399 -152.196162) (xy 361.412755 -152.129586) (xy 361.471203 -152.068288)
			(xy 361.535213 -152.012823) (xy 361.604205 -151.963694) (xy 361.677555 -151.921345) (xy 361.754598 -151.886161)
			(xy 361.834637 -151.858459) (xy 361.916946 -151.838491) (xy 362.000781 -151.826438) (xy 362.085382 -151.822408)
			(xy 362.169983 -151.826438) (xy 362.253818 -151.838491) (xy 362.336127 -151.858459) (xy 362.416166 -151.886161)
			(xy 362.493209 -151.921345) (xy 362.566559 -151.963694) (xy 362.635551 -152.012823) (xy 362.699561 -152.068288)
			(xy 362.758009 -152.129586) (xy 362.810365 -152.196162) (xy 362.856155 -152.267414) (xy 362.894966 -152.342695)
			(xy 362.926445 -152.421325) (xy 362.950306 -152.502592) (xy 362.966335 -152.585758) (xy 362.974386 -152.670072)
			(xy 362.97489 -152.71242) (xy 362.974386 -152.754768) (xy 362.966335 -152.839082) (xy 362.950306 -152.922248)
			(xy 362.926445 -153.003515) (xy 362.894966 -153.082145) (xy 362.856155 -153.157426) (xy 362.810365 -153.228678)
			(xy 362.758009 -153.295254) (xy 362.699561 -153.356552) (xy 362.635551 -153.412017) (xy 362.566559 -153.461146)
			(xy 362.493209 -153.503495) (xy 362.416166 -153.538679) (xy 362.336127 -153.566381) (xy 362.253818 -153.586349)
			(xy 362.169983 -153.598402) (xy 362.085382 -153.602433) (xy 362.000781 -153.598402) (xy 361.916946 -153.586349)
			(xy 361.834637 -153.566381) (xy 361.754598 -153.538679) (xy 361.677555 -153.503495) (xy 361.604205 -153.461146)
			(xy 361.535213 -153.412017) (xy 361.471203 -153.356552) (xy 361.412755 -153.295254) (xy 361.360399 -153.228678)
			(xy 361.314609 -153.157426) (xy 361.275798 -153.082145) (xy 361.244319 -153.003515) (xy 361.220458 -152.922248)
			(xy 361.204429 -152.839082) (xy 361.196378 -152.754768) (xy 360.474264 -152.754768) (xy 360.466213 -152.839082)
			(xy 360.450184 -152.922248) (xy 360.426323 -153.003515) (xy 360.394844 -153.082145) (xy 360.356033 -153.157426)
			(xy 360.310243 -153.228678) (xy 360.257887 -153.295254) (xy 360.199439 -153.356552) (xy 360.135429 -153.412017)
			(xy 360.066437 -153.461146) (xy 359.993087 -153.503495) (xy 359.916044 -153.538679) (xy 359.836005 -153.566381)
			(xy 359.753696 -153.586349) (xy 359.669861 -153.598402) (xy 359.58526 -153.602433) (xy 359.500659 -153.598402)
			(xy 359.416824 -153.586349) (xy 359.334515 -153.566381) (xy 359.254476 -153.538679) (xy 359.177433 -153.503495)
			(xy 359.104083 -153.461146) (xy 359.035091 -153.412017) (xy 358.971081 -153.356552) (xy 358.912633 -153.295254)
			(xy 358.860277 -153.228678) (xy 358.814487 -153.157426) (xy 358.775676 -153.082145) (xy 358.744197 -153.003515)
			(xy 358.720336 -152.922248) (xy 358.704307 -152.839082) (xy 358.696256 -152.754768) (xy 340.98992 -152.754768)
			(xy 340.98992 -156.799534) (xy 347.421454 -156.799534) (xy 347.42194 -156.772283) (xy 347.429696 -156.718335)
			(xy 347.445051 -156.66604) (xy 347.467693 -156.616463) (xy 347.497159 -156.570613) (xy 347.53285 -156.529422)
			(xy 347.574041 -156.493731) (xy 347.619891 -156.464265) (xy 347.669468 -156.441623) (xy 347.721763 -156.426268)
			(xy 347.775711 -156.418512) (xy 347.830213 -156.418512) (xy 347.884161 -156.426268) (xy 347.936456 -156.441623)
			(xy 347.986033 -156.464265) (xy 348.031883 -156.493731) (xy 348.073074 -156.529422) (xy 348.108765 -156.570613)
			(xy 348.138231 -156.616463) (xy 348.160873 -156.66604) (xy 348.165539 -156.681932) (xy 349.311722 -156.681932)
			(xy 349.312208 -156.654681) (xy 349.319964 -156.600733) (xy 349.335319 -156.548438) (xy 349.357961 -156.498861)
			(xy 349.387427 -156.453011) (xy 349.423118 -156.41182) (xy 349.464309 -156.376129) (xy 349.510159 -156.346663)
			(xy 349.559736 -156.324021) (xy 349.612031 -156.308666) (xy 349.665979 -156.30091) (xy 349.720481 -156.30091)
			(xy 349.774429 -156.308666) (xy 349.826724 -156.324021) (xy 349.876301 -156.346663) (xy 349.922151 -156.376129)
			(xy 349.963342 -156.41182) (xy 349.999033 -156.453011) (xy 350.028499 -156.498861) (xy 350.051141 -156.548438)
			(xy 350.066496 -156.600733) (xy 350.074252 -156.654681) (xy 350.074738 -156.681932) (xy 350.074171 -156.711027)
			(xy 350.065334 -156.768541) (xy 350.047854 -156.824042) (xy 350.022138 -156.876241) (xy 349.988784 -156.923922)
			(xy 349.969074 -156.94533) (xy 349.962216 -156.952696) (xy 349.955104 -156.970476) (xy 349.955612 -157.061154)
			(xy 349.962724 -157.079188) (xy 349.969836 -157.0863) (xy 349.989942 -157.107813) (xy 350.024011 -157.155835)
			(xy 350.050299 -157.20852) (xy 350.068182 -157.264619) (xy 350.077236 -157.322798) (xy 350.077786 -157.352238)
			(xy 350.077691 -157.357572) (xy 350.649538 -157.357572) (xy 350.653609 -157.30195) (xy 350.665735 -157.247513)
			(xy 350.685658 -157.195422) (xy 350.712954 -157.146787) (xy 350.74704 -157.102644) (xy 350.787189 -157.063935)
			(xy 350.832547 -157.031484) (xy 350.882147 -157.005983) (xy 350.934931 -156.987976) (xy 350.989774 -156.977846)
			(xy 351.045508 -156.975809) (xy 351.100945 -156.981909) (xy 351.154902 -156.996015) (xy 351.206231 -157.017827)
			(xy 351.253837 -157.046881) (xy 351.296705 -157.082556) (xy 351.333922 -157.124093) (xy 351.364695 -157.170606)
			(xy 351.388367 -157.221103) (xy 351.404435 -157.27451) (xy 351.412555 -157.329686) (xy 351.413064 -157.357572)
			(xy 351.412555 -157.385458) (xy 351.404435 -157.440634) (xy 351.396108 -157.46831) (xy 365.557825 -157.46831)
			(xy 365.561553 -157.415059) (xy 365.572669 -157.362848) (xy 365.590955 -157.312696) (xy 365.616054 -157.265584)
			(xy 365.647476 -157.22243) (xy 365.684607 -157.184079) (xy 365.70539 -157.167326) (xy 365.714134 -157.159747)
			(xy 365.724328 -157.139001) (xy 365.724948 -157.127448) (xy 365.724948 -157.047184) (xy 365.724405 -157.035612)
			(xy 365.714193 -157.01484) (xy 365.70539 -157.007306) (xy 365.684622 -156.990534) (xy 365.647489 -156.952185)
			(xy 365.616065 -156.909033) (xy 365.590963 -156.861922) (xy 365.572675 -156.811771) (xy 365.561556 -156.75956)
			(xy 365.557825 -156.70631) (xy 365.561553 -156.653059) (xy 365.572669 -156.600848) (xy 365.590955 -156.550696)
			(xy 365.616054 -156.503584) (xy 365.647476 -156.46043) (xy 365.684607 -156.422079) (xy 365.70539 -156.405326)
			(xy 365.714134 -156.397747) (xy 365.724328 -156.377001) (xy 365.724948 -156.365448) (xy 365.724948 -156.285184)
			(xy 365.724405 -156.273612) (xy 365.714193 -156.25284) (xy 365.70539 -156.245306) (xy 365.684622 -156.228534)
			(xy 365.647489 -156.190185) (xy 365.616065 -156.147033) (xy 365.590963 -156.099922) (xy 365.572675 -156.049771)
			(xy 365.561556 -155.99756) (xy 365.557825 -155.94431) (xy 365.561553 -155.891059) (xy 365.572669 -155.838848)
			(xy 365.590955 -155.788696) (xy 365.616054 -155.741584) (xy 365.647476 -155.69843) (xy 365.684607 -155.660079)
			(xy 365.70539 -155.643326) (xy 365.714134 -155.635747) (xy 365.724328 -155.615001) (xy 365.724948 -155.603448)
			(xy 365.724948 -155.523184) (xy 365.724405 -155.511612) (xy 365.714193 -155.49084) (xy 365.70539 -155.483306)
			(xy 365.684622 -155.466534) (xy 365.647489 -155.428185) (xy 365.616065 -155.385033) (xy 365.590963 -155.337922)
			(xy 365.572675 -155.287771) (xy 365.561556 -155.23556) (xy 365.557825 -155.18231) (xy 365.561553 -155.129059)
			(xy 365.572669 -155.076848) (xy 365.590955 -155.026696) (xy 365.616054 -154.979584) (xy 365.647476 -154.93643)
			(xy 365.684607 -154.898079) (xy 365.70539 -154.881326) (xy 365.714134 -154.873747) (xy 365.724328 -154.853001)
			(xy 365.724948 -154.841448) (xy 365.724948 -154.761184) (xy 365.724405 -154.749612) (xy 365.714193 -154.72884)
			(xy 365.70539 -154.721306) (xy 365.682907 -154.703114) (xy 365.643173 -154.661094) (xy 365.610234 -154.613559)
			(xy 365.584845 -154.561598) (xy 365.567589 -154.506401) (xy 365.558859 -154.449232) (xy 365.558324 -154.420316)
			(xy 365.55877 -154.393062) (xy 365.566526 -154.339109) (xy 365.581882 -154.286809) (xy 365.604525 -154.237227)
			(xy 365.633994 -154.191372) (xy 365.669689 -154.150178) (xy 365.710885 -154.114484) (xy 365.756741 -154.085017)
			(xy 365.806324 -154.062376) (xy 365.858625 -154.047023) (xy 365.912578 -154.039269) (xy 365.939832 -154.038808)
			(xy 365.968747 -154.039372) (xy 366.025916 -154.048091) (xy 366.081115 -154.06534) (xy 366.133077 -154.090723)
			(xy 366.180612 -154.123658) (xy 366.222631 -154.163392) (xy 366.240822 -154.185874) (xy 366.248366 -154.194654)
			(xy 366.269139 -154.204824) (xy 366.2807 -154.205432) (xy 366.360964 -154.205432) (xy 366.372533 -154.204865)
			(xy 366.393305 -154.19467) (xy 366.400842 -154.185874) (xy 366.417595 -154.165091) (xy 366.455949 -154.127961)
			(xy 366.499103 -154.096539) (xy 366.546217 -154.07144) (xy 366.596369 -154.053154) (xy 366.64858 -154.042037)
			(xy 366.701832 -154.038307) (xy 366.755084 -154.042037) (xy 366.807295 -154.053154) (xy 366.857447 -154.07144)
			(xy 366.904561 -154.096539) (xy 366.947715 -154.127961) (xy 366.986069 -154.165091) (xy 367.002822 -154.185874)
			(xy 367.010366 -154.194654) (xy 367.031139 -154.204824) (xy 367.0427 -154.205432) (xy 367.122964 -154.205432)
			(xy 367.134533 -154.204865) (xy 367.155305 -154.19467) (xy 367.162842 -154.185874) (xy 367.179595 -154.165091)
			(xy 367.217949 -154.127961) (xy 367.261103 -154.096539) (xy 367.308217 -154.07144) (xy 367.358369 -154.053154)
			(xy 367.41058 -154.042037) (xy 367.463832 -154.038307) (xy 367.517084 -154.042037) (xy 367.569295 -154.053154)
			(xy 367.619447 -154.07144) (xy 367.666561 -154.096539) (xy 367.709715 -154.127961) (xy 367.748069 -154.165091)
			(xy 367.764822 -154.185874) (xy 367.772366 -154.194654) (xy 367.793139 -154.204824) (xy 367.8047 -154.205432)
			(xy 367.884964 -154.205432) (xy 367.896533 -154.204865) (xy 367.917305 -154.19467) (xy 367.924842 -154.185874)
			(xy 367.941595 -154.165091) (xy 367.979949 -154.127961) (xy 368.023103 -154.096539) (xy 368.070217 -154.07144)
			(xy 368.120369 -154.053154) (xy 368.17258 -154.042037) (xy 368.225832 -154.038307) (xy 368.279084 -154.042037)
			(xy 368.331295 -154.053154) (xy 368.381447 -154.07144) (xy 368.428561 -154.096539) (xy 368.471715 -154.127961)
			(xy 368.510069 -154.165091) (xy 368.526822 -154.185874) (xy 368.534366 -154.194654) (xy 368.555139 -154.204824)
			(xy 368.5667 -154.205432) (xy 368.646964 -154.205432) (xy 368.658533 -154.204865) (xy 368.679305 -154.19467)
			(xy 368.686842 -154.185874) (xy 368.703595 -154.165091) (xy 368.741949 -154.127961) (xy 368.785103 -154.096539)
			(xy 368.832217 -154.07144) (xy 368.882369 -154.053154) (xy 368.93458 -154.042037) (xy 368.987832 -154.038307)
			(xy 369.041084 -154.042037) (xy 369.093295 -154.053154) (xy 369.143447 -154.07144) (xy 369.190561 -154.096539)
			(xy 369.233715 -154.127961) (xy 369.272069 -154.165091) (xy 369.288822 -154.185874) (xy 369.296366 -154.194654)
			(xy 369.317139 -154.204824) (xy 369.3287 -154.205432) (xy 369.408964 -154.205432) (xy 369.420533 -154.204865)
			(xy 369.441305 -154.19467) (xy 369.448842 -154.185874) (xy 369.465595 -154.165091) (xy 369.503949 -154.127961)
			(xy 369.547103 -154.096539) (xy 369.594217 -154.07144) (xy 369.644369 -154.053154) (xy 369.69658 -154.042037)
			(xy 369.749832 -154.038307) (xy 369.803084 -154.042037) (xy 369.855295 -154.053154) (xy 369.905447 -154.07144)
			(xy 369.952561 -154.096539) (xy 369.995715 -154.127961) (xy 370.034069 -154.165091) (xy 370.050822 -154.185874)
			(xy 370.058366 -154.194654) (xy 370.079139 -154.204824) (xy 370.0907 -154.205432) (xy 370.170964 -154.205432)
			(xy 370.182533 -154.204865) (xy 370.203305 -154.19467) (xy 370.210842 -154.185874) (xy 370.227595 -154.165091)
			(xy 370.265949 -154.127961) (xy 370.309103 -154.096539) (xy 370.356217 -154.07144) (xy 370.406369 -154.053154)
			(xy 370.45858 -154.042037) (xy 370.511832 -154.038307) (xy 370.565084 -154.042037) (xy 370.617295 -154.053154)
			(xy 370.667447 -154.07144) (xy 370.714561 -154.096539) (xy 370.757715 -154.127961) (xy 370.796069 -154.165091)
			(xy 370.812822 -154.185874) (xy 370.820366 -154.194654) (xy 370.841139 -154.204824) (xy 370.8527 -154.205432)
			(xy 370.932964 -154.205432) (xy 370.944533 -154.204865) (xy 370.965305 -154.19467) (xy 370.972842 -154.185874)
			(xy 370.989595 -154.165091) (xy 371.027949 -154.127961) (xy 371.071103 -154.096539) (xy 371.118217 -154.07144)
			(xy 371.168369 -154.053154) (xy 371.22058 -154.042037) (xy 371.273832 -154.038307) (xy 371.327084 -154.042037)
			(xy 371.379295 -154.053154) (xy 371.429447 -154.07144) (xy 371.476561 -154.096539) (xy 371.519715 -154.127961)
			(xy 371.558069 -154.165091) (xy 371.574822 -154.185874) (xy 371.582366 -154.194654) (xy 371.603139 -154.204824)
			(xy 371.6147 -154.205432) (xy 371.694964 -154.205432) (xy 371.706533 -154.204865) (xy 371.727305 -154.19467)
			(xy 371.734842 -154.185874) (xy 371.751595 -154.165091) (xy 371.789949 -154.127961) (xy 371.833103 -154.096539)
			(xy 371.880217 -154.07144) (xy 371.930369 -154.053154) (xy 371.98258 -154.042037) (xy 372.035832 -154.038307)
			(xy 372.089084 -154.042037) (xy 372.141295 -154.053154) (xy 372.191447 -154.07144) (xy 372.238561 -154.096539)
			(xy 372.281715 -154.127961) (xy 372.320069 -154.165091) (xy 372.336822 -154.185874) (xy 372.344366 -154.194654)
			(xy 372.365139 -154.204824) (xy 372.3767 -154.205432) (xy 372.456964 -154.205432) (xy 372.468533 -154.204865)
			(xy 372.489305 -154.19467) (xy 372.496842 -154.185874) (xy 372.515003 -154.163365) (xy 372.55703 -154.123633)
			(xy 372.604571 -154.090697) (xy 372.656538 -154.065314) (xy 372.711741 -154.048063) (xy 372.768914 -154.03934)
			(xy 372.797832 -154.038808) (xy 372.825085 -154.039248) (xy 372.879035 -154.047009) (xy 372.931332 -154.062369)
			(xy 372.98091 -154.085015) (xy 373.026761 -154.114487) (xy 373.067951 -154.150183) (xy 373.103642 -154.191378)
			(xy 373.133108 -154.237232) (xy 373.155747 -154.286813) (xy 373.171101 -154.339112) (xy 373.178855 -154.393063)
			(xy 373.17934 -154.420316) (xy 373.178784 -154.449232) (xy 373.170066 -154.506402) (xy 373.152817 -154.561601)
			(xy 373.127432 -154.613564) (xy 373.094494 -154.661098) (xy 373.054758 -154.703116) (xy 373.032274 -154.721306)
			(xy 373.023509 -154.728865) (xy 373.013328 -154.749626) (xy 373.012716 -154.761184) (xy 373.012716 -154.841448)
			(xy 373.013311 -154.853013) (xy 373.023488 -154.873784) (xy 373.032274 -154.881326) (xy 373.053071 -154.898062)
			(xy 373.090199 -154.936418) (xy 373.121617 -154.979576) (xy 373.146714 -155.026691) (xy 373.164998 -155.076845)
			(xy 373.176112 -155.129058) (xy 373.17984 -155.18231) (xy 373.17611 -155.235562) (xy 373.164992 -155.287774)
			(xy 373.146706 -155.337927) (xy 373.121607 -155.385041) (xy 373.090186 -155.428197) (xy 373.053057 -155.466552)
			(xy 373.032274 -155.483306) (xy 373.023509 -155.490865) (xy 373.013328 -155.511626) (xy 373.012716 -155.523184)
			(xy 373.012716 -155.603448) (xy 373.013311 -155.615013) (xy 373.023488 -155.635784) (xy 373.032274 -155.643326)
			(xy 373.053071 -155.660062) (xy 373.090199 -155.698418) (xy 373.121617 -155.741576) (xy 373.146714 -155.788691)
			(xy 373.164998 -155.838845) (xy 373.176112 -155.891058) (xy 373.17984 -155.94431) (xy 373.17611 -155.997562)
			(xy 373.164992 -156.049774) (xy 373.146706 -156.099927) (xy 373.121607 -156.147041) (xy 373.090186 -156.190197)
			(xy 373.053057 -156.228552) (xy 373.032274 -156.245306) (xy 373.023509 -156.252865) (xy 373.013328 -156.273626)
			(xy 373.012716 -156.285184) (xy 373.012716 -156.365448) (xy 373.013311 -156.377013) (xy 373.023488 -156.397784)
			(xy 373.032274 -156.405326) (xy 373.053071 -156.422062) (xy 373.090199 -156.460418) (xy 373.121617 -156.503576)
			(xy 373.146714 -156.550691) (xy 373.164998 -156.600845) (xy 373.176112 -156.653058) (xy 373.17984 -156.70631)
			(xy 373.17611 -156.759562) (xy 373.164992 -156.811774) (xy 373.146706 -156.861927) (xy 373.121607 -156.909041)
			(xy 373.090186 -156.952197) (xy 373.053057 -156.990552) (xy 373.032274 -157.007306) (xy 373.023509 -157.014865)
			(xy 373.013328 -157.035626) (xy 373.012716 -157.047184) (xy 373.012716 -157.127448) (xy 373.013311 -157.139013)
			(xy 373.023488 -157.159784) (xy 373.032274 -157.167326) (xy 373.053071 -157.184062) (xy 373.090199 -157.222418)
			(xy 373.121617 -157.265576) (xy 373.146714 -157.312691) (xy 373.164998 -157.362845) (xy 373.176112 -157.415058)
			(xy 373.17984 -157.46831) (xy 373.17611 -157.521562) (xy 373.164992 -157.573774) (xy 373.146706 -157.623927)
			(xy 373.121607 -157.671041) (xy 373.090186 -157.714197) (xy 373.053057 -157.752552) (xy 373.032274 -157.769306)
			(xy 373.023509 -157.776865) (xy 373.013328 -157.797626) (xy 373.012716 -157.809184) (xy 373.012716 -157.889448)
			(xy 373.013311 -157.901013) (xy 373.023488 -157.921784) (xy 373.032274 -157.929326) (xy 373.054765 -157.947509)
			(xy 373.0945 -157.98953) (xy 373.127439 -158.037066) (xy 373.152827 -158.089029) (xy 373.170081 -158.144228)
			(xy 373.178807 -158.201399) (xy 373.17934 -158.230316) (xy 373.178837 -158.257566) (xy 373.171079 -158.311512)
			(xy 373.155724 -158.363804) (xy 373.133083 -158.413379) (xy 373.103618 -158.459228) (xy 373.067929 -158.500417)
			(xy 373.026741 -158.536109) (xy 372.980893 -158.565575) (xy 372.931319 -158.588218) (xy 372.879027 -158.603576)
			(xy 372.825082 -158.611336) (xy 372.797832 -158.611824) (xy 372.768915 -158.611312) (xy 372.711742 -158.602585)
			(xy 372.656542 -158.585328) (xy 372.604579 -158.559936) (xy 372.557046 -158.52699) (xy 372.515031 -158.487245)
			(xy 372.496842 -158.464758) (xy 372.489265 -158.456013) (xy 372.468517 -158.445822) (xy 372.456964 -158.4452)
			(xy 372.3767 -158.4452) (xy 372.365132 -158.44577) (xy 372.344361 -158.455965) (xy 372.336822 -158.464758)
			(xy 372.320069 -158.485541) (xy 372.281715 -158.522671) (xy 372.238561 -158.554093) (xy 372.191447 -158.579192)
			(xy 372.141295 -158.597478) (xy 372.089084 -158.608595) (xy 372.035832 -158.612325) (xy 371.98258 -158.608595)
			(xy 371.930369 -158.597478) (xy 371.880217 -158.579192) (xy 371.833103 -158.554093) (xy 371.789949 -158.522671)
			(xy 371.751595 -158.485541) (xy 371.734842 -158.464758) (xy 371.727265 -158.456013) (xy 371.706517 -158.445822)
			(xy 371.694964 -158.4452) (xy 371.6147 -158.4452) (xy 371.603132 -158.44577) (xy 371.582361 -158.455965)
			(xy 371.574822 -158.464758) (xy 371.556608 -158.487222) (xy 371.514594 -158.526961) (xy 371.467065 -158.559903)
			(xy 371.415108 -158.585295) (xy 371.359914 -158.602555) (xy 371.302747 -158.611287) (xy 371.273832 -158.611824)
			(xy 371.246985 -158.611383) (xy 371.19382 -158.603872) (xy 371.142233 -158.588978) (xy 371.093246 -158.566998)
			(xy 371.047824 -158.538364) (xy 371.006867 -158.503644) (xy 370.971184 -158.463523) (xy 370.941481 -158.418794)
			(xy 370.918343 -158.370342) (xy 370.90985 -158.34487) (xy 370.90477 -158.328868) (xy 370.8781 -158.309056)
			(xy 370.430298 -158.309056) (xy 370.422678 -158.311596) (xy 370.394291 -158.320136) (xy 370.335731 -158.329324)
			(xy 370.306092 -158.329884) (xy 370.276456 -158.329298) (xy 370.217897 -158.320116) (xy 370.189506 -158.311596)
			(xy 370.181886 -158.309056) (xy 369.795298 -158.309056) (xy 369.787678 -158.311596) (xy 369.759291 -158.320136)
			(xy 369.700731 -158.329324) (xy 369.671092 -158.329884) (xy 369.641456 -158.329298) (xy 369.582897 -158.320116)
			(xy 369.554506 -158.311596) (xy 369.546886 -158.309056) (xy 369.160298 -158.309056) (xy 369.152678 -158.311596)
			(xy 369.124291 -158.320136) (xy 369.065731 -158.329324) (xy 369.036092 -158.329884) (xy 369.006456 -158.329298)
			(xy 368.947897 -158.320116) (xy 368.919506 -158.311596) (xy 368.911886 -158.309056) (xy 368.525298 -158.309056)
			(xy 368.517678 -158.311596) (xy 368.489291 -158.320136) (xy 368.430731 -158.329324) (xy 368.401092 -158.329884)
			(xy 368.371456 -158.329298) (xy 368.312897 -158.320116) (xy 368.284506 -158.311596) (xy 368.276886 -158.309056)
			(xy 367.859564 -158.309056) (xy 367.832894 -158.328868) (xy 367.827814 -158.34487) (xy 367.81935 -158.370349)
			(xy 367.79619 -158.418787) (xy 367.766471 -158.463501) (xy 367.730779 -158.50361) (xy 367.689819 -158.538322)
			(xy 367.6444 -158.566952) (xy 367.595417 -158.588935) (xy 367.543837 -158.603838) (xy 367.490677 -158.611365)
			(xy 367.463832 -158.611824) (xy 367.434915 -158.611312) (xy 367.377742 -158.602585) (xy 367.322542 -158.585328)
			(xy 367.270579 -158.559936) (xy 367.223046 -158.52699) (xy 367.181031 -158.487245) (xy 367.162842 -158.464758)
			(xy 367.155265 -158.456013) (xy 367.134517 -158.445822) (xy 367.122964 -158.4452) (xy 367.0427 -158.4452)
			(xy 367.031132 -158.44577) (xy 367.010361 -158.455965) (xy 367.002822 -158.464758) (xy 366.986069 -158.485541)
			(xy 366.947715 -158.522671) (xy 366.904561 -158.554093) (xy 366.857447 -158.579192) (xy 366.807295 -158.597478)
			(xy 366.755084 -158.608595) (xy 366.701832 -158.612325) (xy 366.64858 -158.608595) (xy 366.596369 -158.597478)
			(xy 366.546217 -158.579192) (xy 366.499103 -158.554093) (xy 366.455949 -158.522671) (xy 366.417595 -158.485541)
			(xy 366.400842 -158.464758) (xy 366.393265 -158.456013) (xy 366.372517 -158.445822) (xy 366.360964 -158.4452)
			(xy 366.2807 -158.4452) (xy 366.269132 -158.44577) (xy 366.248361 -158.455965) (xy 366.240822 -158.464758)
			(xy 366.222608 -158.487222) (xy 366.180594 -158.526961) (xy 366.133065 -158.559903) (xy 366.081108 -158.585295)
			(xy 366.025914 -158.602555) (xy 365.968747 -158.611287) (xy 365.939832 -158.611824) (xy 365.912581 -158.611315)
			(xy 365.858632 -158.603563) (xy 365.806336 -158.588212) (xy 365.756757 -158.565574) (xy 365.710905 -158.536111)
			(xy 365.669712 -158.500422) (xy 365.634018 -158.459234) (xy 365.604549 -158.413385) (xy 365.581905 -158.363809)
			(xy 365.566547 -158.311515) (xy 365.558788 -158.257567) (xy 365.558324 -158.230316) (xy 365.558845 -158.201399)
			(xy 365.567572 -158.144228) (xy 365.584829 -158.089028) (xy 365.61022 -158.037067) (xy 365.643164 -157.989533)
			(xy 365.682904 -157.947516) (xy 365.70539 -157.929326) (xy 365.714134 -157.921747) (xy 365.724328 -157.901001)
			(xy 365.724948 -157.889448) (xy 365.724948 -157.809184) (xy 365.724405 -157.797612) (xy 365.714193 -157.77684)
			(xy 365.70539 -157.769306) (xy 365.684622 -157.752534) (xy 365.647489 -157.714185) (xy 365.616065 -157.671033)
			(xy 365.590963 -157.623922) (xy 365.572675 -157.573771) (xy 365.561556 -157.52156) (xy 365.557825 -157.46831)
			(xy 351.396108 -157.46831) (xy 351.388367 -157.494041) (xy 351.364695 -157.544538) (xy 351.333922 -157.591051)
			(xy 351.296705 -157.632588) (xy 351.253837 -157.668263) (xy 351.206231 -157.697317) (xy 351.154902 -157.719129)
			(xy 351.100945 -157.733235) (xy 351.045508 -157.739335) (xy 350.989774 -157.737298) (xy 350.934931 -157.727168)
			(xy 350.882147 -157.709161) (xy 350.832547 -157.68366) (xy 350.787189 -157.651209) (xy 350.74704 -157.6125)
			(xy 350.712954 -157.568357) (xy 350.685658 -157.519722) (xy 350.665735 -157.467631) (xy 350.653609 -157.413194)
			(xy 350.649538 -157.357572) (xy 350.077691 -157.357572) (xy 350.0773 -157.379489) (xy 350.069544 -157.433437)
			(xy 350.054189 -157.485732) (xy 350.031547 -157.535309) (xy 350.002081 -157.581159) (xy 349.96639 -157.62235)
			(xy 349.925199 -157.658041) (xy 349.879349 -157.687507) (xy 349.829772 -157.710149) (xy 349.777477 -157.725504)
			(xy 349.723529 -157.73326) (xy 349.669027 -157.73326) (xy 349.615079 -157.725504) (xy 349.562784 -157.710149)
			(xy 349.513207 -157.687507) (xy 349.467357 -157.658041) (xy 349.426166 -157.62235) (xy 349.390475 -157.581159)
			(xy 349.361009 -157.535309) (xy 349.338367 -157.485732) (xy 349.323012 -157.433437) (xy 349.315256 -157.379489)
			(xy 349.31477 -157.352238) (xy 349.315343 -157.323144) (xy 349.324183 -157.265631) (xy 349.341663 -157.210131)
			(xy 349.367376 -157.157932) (xy 349.400726 -157.110249) (xy 349.420434 -157.08884) (xy 349.427292 -157.081474)
			(xy 349.434404 -157.063694) (xy 349.433896 -156.973016) (xy 349.426784 -156.954982) (xy 349.419672 -156.94787)
			(xy 349.399553 -156.926369) (xy 349.365486 -156.878344) (xy 349.3392 -156.825655) (xy 349.32132 -156.769554)
			(xy 349.31227 -156.711373) (xy 349.311722 -156.681932) (xy 348.165539 -156.681932) (xy 348.176228 -156.718335)
			(xy 348.183984 -156.772283) (xy 348.18447 -156.799534) (xy 348.183812 -156.831097) (xy 348.173425 -156.893362)
			(xy 348.152938 -156.953071) (xy 348.138496 -156.981144) (xy 348.13367 -156.990034) (xy 348.131638 -157.009592)
			(xy 348.157292 -157.09773) (xy 348.169738 -157.113224) (xy 348.178628 -157.118304) (xy 348.185994 -157.122368)
			(xy 348.195646 -157.12821) (xy 348.217744 -157.130242) (xy 348.312232 -157.096714) (xy 348.328234 -157.08122)
			(xy 348.332298 -157.070806) (xy 348.342982 -157.044024) (xy 348.371271 -156.993781) (xy 348.406801 -156.948371)
			(xy 348.448765 -156.908828) (xy 348.496204 -156.876054) (xy 348.548037 -156.850798) (xy 348.603082 -156.833634)
			(xy 348.660084 -156.824954) (xy 348.688914 -156.824426) (xy 348.716167 -156.824845) (xy 348.770118 -156.832604)
			(xy 348.822416 -156.847961) (xy 348.871996 -156.870605) (xy 348.917848 -156.900075) (xy 348.959041 -156.935769)
			(xy 348.994734 -156.976963) (xy 349.024201 -157.022817) (xy 349.046844 -157.072397) (xy 349.062199 -157.124696)
			(xy 349.069956 -157.178647) (xy 349.069956 -157.233153) (xy 349.062199 -157.287104) (xy 349.046844 -157.339403)
			(xy 349.024201 -157.388983) (xy 348.994734 -157.434837) (xy 348.959041 -157.476031) (xy 348.917848 -157.511725)
			(xy 348.871996 -157.541195) (xy 348.822416 -157.563839) (xy 348.770118 -157.579196) (xy 348.716167 -157.586955)
			(xy 348.688914 -157.587442) (xy 348.663679 -157.587033) (xy 348.613646 -157.580418) (xy 348.564926 -157.567248)
			(xy 348.518373 -157.547755) (xy 348.496382 -157.535372) (xy 348.48673 -157.52953) (xy 348.464632 -157.527498)
			(xy 348.370144 -157.561026) (xy 348.354142 -157.57652) (xy 348.350078 -157.586934) (xy 348.339352 -157.613697)
			(xy 348.311066 -157.663936) (xy 348.275539 -157.709344) (xy 348.233582 -157.748886) (xy 348.186149 -157.781661)
			(xy 348.134323 -157.806921) (xy 348.079285 -157.824092) (xy 348.022289 -157.832781) (xy 347.993462 -157.833314)
			(xy 347.96621 -157.832858) (xy 347.912262 -157.825096) (xy 347.859967 -157.809736) (xy 347.81039 -157.787091)
			(xy 347.76454 -157.757622) (xy 347.72335 -157.721927) (xy 347.687659 -157.680735) (xy 347.658193 -157.634882)
			(xy 347.635552 -157.585303) (xy 347.620197 -157.533007) (xy 347.61244 -157.479058) (xy 347.611954 -157.451806)
			(xy 347.612586 -157.420242) (xy 347.622984 -157.357976) (xy 347.643481 -157.298267) (xy 347.657928 -157.270196)
			(xy 347.662754 -157.261306) (xy 347.664786 -157.241748) (xy 347.639132 -157.15361) (xy 347.626686 -157.138116)
			(xy 347.617796 -157.133036) (xy 347.592682 -157.118509) (xy 347.5468 -157.083002) (xy 347.506825 -157.040954)
			(xy 347.473682 -156.993337) (xy 347.448133 -156.941249) (xy 347.430769 -156.885891) (xy 347.421991 -156.828542)
			(xy 347.421454 -156.799534) (xy 340.98992 -156.799534) (xy 340.98992 -159.073596) (xy 343.63533 -159.073596)
			(xy 343.635782 -159.046021) (xy 343.643736 -158.991447) (xy 343.659463 -158.938586) (xy 343.682636 -158.88854)
			(xy 343.712771 -158.842351) (xy 343.749241 -158.800981) (xy 343.76995 -158.782766) (xy 343.778087 -158.775181)
			(xy 343.787429 -158.755016) (xy 343.787984 -158.743904) (xy 343.787984 -158.666688) (xy 343.787444 -158.655575)
			(xy 343.778086 -158.635416) (xy 343.76995 -158.627826) (xy 343.749238 -158.609616) (xy 343.71277 -158.568246)
			(xy 343.68264 -158.522056) (xy 343.659474 -158.472008) (xy 343.643757 -158.419146) (xy 343.635816 -158.364572)
			(xy 343.635817 -158.309423) (xy 343.643759 -158.254849) (xy 343.659476 -158.201987) (xy 343.682642 -158.15194)
			(xy 343.712773 -158.10575) (xy 343.749242 -158.06438) (xy 343.76995 -158.046166) (xy 343.778087 -158.038581)
			(xy 343.787429 -158.018416) (xy 343.787984 -158.007304) (xy 343.787984 -157.930088) (xy 343.787444 -157.918975)
			(xy 343.778086 -157.898816) (xy 343.76995 -157.891226) (xy 343.749238 -157.873016) (xy 343.71277 -157.831646)
			(xy 343.682639 -157.785455) (xy 343.659474 -157.735407) (xy 343.643757 -157.682545) (xy 343.635816 -157.627971)
			(xy 343.63533 -157.600396) (xy 343.635752 -157.573141) (xy 343.64351 -157.519187) (xy 343.658869 -157.466886)
			(xy 343.681514 -157.417303) (xy 343.710986 -157.371448) (xy 343.746685 -157.330255) (xy 343.787882 -157.294561)
			(xy 343.83374 -157.265094) (xy 343.883325 -157.242454) (xy 343.935628 -157.227101) (xy 343.989583 -157.219349)
			(xy 344.016838 -157.218888) (xy 344.044694 -157.219386) (xy 344.09981 -157.227514) (xy 344.153161 -157.243564)
			(xy 344.203613 -157.267195) (xy 344.250097 -157.297905) (xy 344.291626 -157.335043) (xy 344.327319 -157.37782)
			(xy 344.356418 -157.425329) (xy 344.378306 -157.476562) (xy 344.3859 -157.503368) (xy 344.388186 -157.512258)
			(xy 344.398854 -157.527498) (xy 344.470736 -157.57525) (xy 344.48877 -157.579314) (xy 344.497914 -157.578044)
			(xy 344.510931 -157.576375) (xy 344.537115 -157.574595) (xy 344.550238 -157.574488) (xy 344.564387 -157.574577)
			(xy 344.59261 -157.576615) (xy 344.606626 -157.578552) (xy 344.616786 -157.580076) (xy 344.636344 -157.57525)
			(xy 344.710766 -157.51937) (xy 344.720926 -157.501844) (xy 344.722196 -157.491684) (xy 344.726294 -157.464532)
			(xy 344.741264 -157.411701) (xy 344.763653 -157.361562) (xy 344.792999 -157.31515) (xy 344.828695 -157.273425)
			(xy 344.870004 -157.237248) (xy 344.916072 -157.207366) (xy 344.965949 -157.184398) (xy 345.018603 -157.168817)
			(xy 345.072947 -157.160945) (xy 345.100402 -157.160468) (xy 345.127652 -157.160976) (xy 345.181598 -157.168732)
			(xy 345.233891 -157.184086) (xy 345.283466 -157.206726) (xy 345.329316 -157.23619) (xy 345.370505 -157.271879)
			(xy 345.406197 -157.313067) (xy 345.435664 -157.358914) (xy 345.458306 -157.408489) (xy 345.473663 -157.460781)
			(xy 345.481423 -157.514726) (xy 345.48191 -157.541976) (xy 345.481424 -157.56955) (xy 345.473475 -157.624122)
			(xy 345.457754 -157.676981) (xy 345.434588 -157.727027) (xy 345.404459 -157.773217) (xy 345.367995 -157.814589)
			(xy 345.34729 -157.832806) (xy 345.339172 -157.840409) (xy 345.329818 -157.86056) (xy 345.329256 -157.871668)
			(xy 345.329256 -157.948884) (xy 345.329799 -157.959997) (xy 345.339153 -157.980157) (xy 345.34729 -157.987746)
			(xy 345.367976 -158.005984) (xy 345.404449 -158.047347) (xy 345.434584 -158.093531) (xy 345.457755 -158.143574)
			(xy 345.473476 -158.196432) (xy 345.481422 -158.251003) (xy 345.481456 -158.252922) (xy 350.070418 -158.252922)
			(xy 350.074489 -158.1973) (xy 350.086615 -158.142863) (xy 350.106538 -158.090772) (xy 350.133834 -158.042137)
			(xy 350.16792 -157.997994) (xy 350.208069 -157.959285) (xy 350.253427 -157.926834) (xy 350.303027 -157.901333)
			(xy 350.355811 -157.883326) (xy 350.410654 -157.873196) (xy 350.466388 -157.871159) (xy 350.521825 -157.877259)
			(xy 350.575782 -157.891365) (xy 350.627111 -157.913177) (xy 350.674717 -157.942231) (xy 350.717585 -157.977906)
			(xy 350.754802 -158.019443) (xy 350.785575 -158.065956) (xy 350.809247 -158.116453) (xy 350.825315 -158.16986)
			(xy 350.833435 -158.225036) (xy 350.833944 -158.252922) (xy 350.833435 -158.280808) (xy 350.825315 -158.335984)
			(xy 350.809247 -158.389391) (xy 350.785575 -158.439888) (xy 350.754802 -158.486401) (xy 350.717585 -158.527938)
			(xy 350.674717 -158.563613) (xy 350.627111 -158.592667) (xy 350.575782 -158.614479) (xy 350.521825 -158.628585)
			(xy 350.466388 -158.634685) (xy 350.410654 -158.632648) (xy 350.355811 -158.622518) (xy 350.303027 -158.604511)
			(xy 350.253427 -158.57901) (xy 350.208069 -158.546559) (xy 350.16792 -158.50785) (xy 350.133834 -158.463707)
			(xy 350.106538 -158.415072) (xy 350.086615 -158.362981) (xy 350.074489 -158.308544) (xy 350.070418 -158.252922)
			(xy 345.481456 -158.252922) (xy 345.48191 -158.278576) (xy 345.481422 -158.305828) (xy 345.473669 -158.359778)
			(xy 345.458316 -158.412075) (xy 345.435676 -158.461655) (xy 345.406211 -158.507508) (xy 345.37052 -158.548701)
			(xy 345.329329 -158.584395) (xy 345.283478 -158.613864) (xy 345.2339 -158.636507) (xy 345.181604 -158.651863)
			(xy 345.127654 -158.659621) (xy 345.100402 -158.660084) (xy 345.066112 -158.65856) (xy 345.055952 -158.657544)
			(xy 345.036648 -158.66364) (xy 344.966036 -158.722822) (xy 344.956638 -158.740856) (xy 344.955622 -158.751016)
			(xy 344.952637 -158.779185) (xy 344.939468 -158.834276) (xy 344.918293 -158.886813) (xy 344.88958 -158.935639)
			(xy 344.85396 -158.979681) (xy 344.812216 -159.017968) (xy 344.765268 -159.049658) (xy 344.714148 -159.074055)
			(xy 344.659981 -159.090621) (xy 344.60396 -159.098991) (xy 344.575638 -159.099504) (xy 344.557619 -159.099288)
			(xy 344.521744 -159.09585) (xy 344.50401 -159.092646) (xy 344.494612 -159.090868) (xy 344.475562 -159.094678)
			(xy 344.400378 -159.14243) (xy 344.388948 -159.158178) (xy 344.386662 -159.167576) (xy 344.379304 -159.194632)
			(xy 344.357669 -159.246359) (xy 344.328699 -159.294365) (xy 344.293018 -159.337616) (xy 344.251394 -159.375182)
			(xy 344.204722 -159.406254) (xy 344.154006 -159.430165) (xy 344.100338 -159.446399) (xy 344.044873 -159.454607)
			(xy 344.016838 -159.455104) (xy 343.989586 -159.454609) (xy 343.935636 -159.446857) (xy 343.883338 -159.431506)
			(xy 343.833758 -159.408868) (xy 343.787905 -159.379403) (xy 343.746711 -159.343713) (xy 343.711017 -159.302523)
			(xy 343.681549 -159.256672) (xy 343.658906 -159.207094) (xy 343.64355 -159.154797) (xy 343.635793 -159.100848)
			(xy 343.63533 -159.073596) (xy 340.98992 -159.073596) (xy 340.98992 -159.158686) (xy 340.989413 -159.168736)
			(xy 340.98169 -159.187294) (xy 340.974934 -159.194754) (xy 339.536532 -160.633156) (xy 345.303348 -160.633156)
			(xy 345.303835 -160.605582) (xy 345.311781 -160.551009) (xy 345.327501 -160.498149) (xy 345.350667 -160.448103)
			(xy 345.380796 -160.401913) (xy 345.417262 -160.360542) (xy 345.437968 -160.342326) (xy 345.446081 -160.334719)
			(xy 345.455436 -160.314571) (xy 345.456002 -160.303464) (xy 345.456002 -160.226248) (xy 345.455423 -160.21514)
			(xy 345.446092 -160.194981) (xy 345.437968 -160.187386) (xy 345.41724 -160.169193) (xy 345.380773 -160.127819)
			(xy 345.350644 -160.081626) (xy 345.327481 -160.031574) (xy 345.311768 -159.978709) (xy 345.303832 -159.924132)
			(xy 345.303348 -159.896556) (xy 345.30389 -159.867333) (xy 345.312784 -159.809567) (xy 345.330389 -159.753835)
			(xy 345.356291 -159.701441) (xy 345.389885 -159.653614) (xy 345.430382 -159.611472) (xy 345.476836 -159.576003)
			(xy 345.50223 -159.56153) (xy 345.512644 -159.555942) (xy 345.526106 -159.536892) (xy 345.543124 -159.43453)
			(xy 345.53652 -159.412178) (xy 345.528392 -159.403542) (xy 345.509985 -159.382768) (xy 345.478854 -159.336819)
			(xy 345.454881 -159.286762) (xy 345.438595 -159.233703) (xy 345.430355 -159.178817) (xy 345.42984 -159.151066)
			(xy 345.430325 -159.124451) (xy 345.437904 -159.071763) (xy 345.452904 -159.020689) (xy 345.475018 -158.97227)
			(xy 345.503797 -158.92749) (xy 345.538656 -158.887261) (xy 345.578884 -158.852402) (xy 345.623663 -158.823622)
			(xy 345.672082 -158.801506) (xy 345.723155 -158.786506) (xy 345.775843 -158.778925) (xy 345.802458 -158.778448)
			(xy 345.82888 -158.778884) (xy 345.881196 -158.786341) (xy 345.931935 -158.801112) (xy 345.980079 -158.8229)
			(xy 346.024663 -158.851269) (xy 346.045028 -158.86811) (xy 346.051886 -158.874206) (xy 346.068904 -158.880302)
			(xy 346.153232 -158.880302) (xy 346.17025 -158.874206) (xy 346.177108 -158.86811) (xy 346.197474 -158.851271)
			(xy 346.24206 -158.822906) (xy 346.290204 -158.801119) (xy 346.340941 -158.786348) (xy 346.393256 -158.778888)
			(xy 346.4461 -158.778888) (xy 346.498415 -158.786348) (xy 346.549152 -158.801119) (xy 346.597296 -158.822906)
			(xy 346.641882 -158.851271) (xy 346.662248 -158.86811) (xy 346.669106 -158.874206) (xy 346.686124 -158.880302)
			(xy 346.770452 -158.880302) (xy 346.78747 -158.874206) (xy 346.794328 -158.86811) (xy 346.814684 -158.85126)
			(xy 346.859277 -158.822907) (xy 346.907424 -158.80113) (xy 346.958162 -158.786365) (xy 347.010476 -158.778907)
			(xy 347.036898 -158.778448) (xy 347.064782 -158.779011) (xy 347.119928 -158.787323) (xy 347.173219 -158.803761)
			(xy 347.223465 -158.827958) (xy 347.269543 -158.859373) (xy 347.310424 -158.897305) (xy 347.345196 -158.940907)
			(xy 347.37308 -158.989204) (xy 347.393455 -159.041117) (xy 347.405864 -159.095487) (xy 347.410032 -159.1511)
			(xy 347.405864 -159.206713) (xy 347.393455 -159.261083) (xy 347.37308 -159.312996) (xy 347.345196 -159.361293)
			(xy 347.310424 -159.404895) (xy 347.269543 -159.442827) (xy 347.223465 -159.474242) (xy 347.173219 -159.498439)
			(xy 347.119928 -159.514877) (xy 347.064782 -159.523189) (xy 347.036898 -159.523684) (xy 347.010477 -159.523208)
			(xy 346.958163 -159.515759) (xy 346.907426 -159.500997) (xy 346.859281 -159.479218) (xy 346.814695 -159.450858)
			(xy 346.794328 -159.434022) (xy 346.78747 -159.427926) (xy 346.770452 -159.42183) (xy 346.686124 -159.42183)
			(xy 346.669106 -159.427926) (xy 346.662248 -159.434022) (xy 346.641882 -159.450861) (xy 346.597296 -159.479226)
			(xy 346.549152 -159.501013) (xy 346.498415 -159.515784) (xy 346.4461 -159.523244) (xy 346.393256 -159.523244)
			(xy 346.340941 -159.515784) (xy 346.290204 -159.501013) (xy 346.24206 -159.479226) (xy 346.197474 -159.450861)
			(xy 346.177108 -159.434022) (xy 346.17025 -159.427926) (xy 346.153232 -159.42183) (xy 346.068904 -159.42183)
			(xy 346.051886 -159.427926) (xy 346.045028 -159.434022) (xy 346.031089 -159.445692) (xy 346.001317 -159.466557)
			(xy 345.985592 -159.475678) (xy 345.975178 -159.48152) (xy 345.96197 -159.50057) (xy 345.946476 -159.603186)
			(xy 345.953588 -159.625538) (xy 345.961716 -159.63392) (xy 345.981283 -159.655303) (xy 346.01435 -159.702903)
			(xy 346.039827 -159.754962) (xy 346.057126 -159.810278) (xy 346.06585 -159.867576) (xy 346.066364 -159.896556)
			(xy 346.065881 -159.92413) (xy 346.057933 -159.978703) (xy 346.042213 -160.031563) (xy 346.019046 -160.081609)
			(xy 345.988916 -160.127799) (xy 345.986992 -160.129982) (xy 351.02927 -160.129982) (xy 351.029757 -160.102071)
			(xy 351.037894 -160.046845) (xy 351.053991 -159.993394) (xy 351.077705 -159.94286) (xy 351.108529 -159.89632)
			(xy 351.126806 -159.87522) (xy 351.133156 -159.868108) (xy 351.13976 -159.850836) (xy 351.13976 -159.763714)
			(xy 351.133156 -159.746442) (xy 351.126806 -159.73933) (xy 351.108522 -159.718236) (xy 351.077695 -159.671696)
			(xy 351.053981 -159.62116) (xy 351.037886 -159.567707) (xy 351.029754 -159.51248) (xy 351.02927 -159.484568)
			(xy 351.029756 -159.457317) (xy 351.037512 -159.403369) (xy 351.052867 -159.351074) (xy 351.075509 -159.301497)
			(xy 351.104975 -159.255647) (xy 351.140666 -159.214456) (xy 351.181857 -159.178765) (xy 351.227707 -159.149299)
			(xy 351.277284 -159.126657) (xy 351.329579 -159.111302) (xy 351.383527 -159.103546) (xy 351.438029 -159.103546)
			(xy 351.491977 -159.111302) (xy 351.544272 -159.126657) (xy 351.593849 -159.149299) (xy 351.639699 -159.178765)
			(xy 351.68089 -159.214456) (xy 351.716581 -159.255647) (xy 351.746047 -159.301497) (xy 351.768689 -159.351074)
			(xy 351.784044 -159.403369) (xy 351.7918 -159.457317) (xy 351.792286 -159.484568) (xy 351.791815 -159.512479)
			(xy 351.783672 -159.567705) (xy 351.767571 -159.621156) (xy 351.743854 -159.67169) (xy 351.713027 -159.71823)
			(xy 351.69475 -159.73933) (xy 351.6884 -159.746442) (xy 351.681796 -159.763714) (xy 351.681796 -159.850836)
			(xy 351.6884 -159.868108) (xy 351.69475 -159.87522) (xy 351.71302 -159.896326) (xy 351.743847 -159.942864)
			(xy 351.767563 -159.993397) (xy 351.783661 -160.046846) (xy 351.791799 -160.102071) (xy 351.792286 -160.129982)
			(xy 351.7918 -160.157233) (xy 351.784044 -160.211181) (xy 351.768689 -160.263476) (xy 351.746047 -160.313053)
			(xy 351.716581 -160.358903) (xy 351.68089 -160.400094) (xy 351.639699 -160.435785) (xy 351.593849 -160.465251)
			(xy 351.544272 -160.487893) (xy 351.491977 -160.503248) (xy 351.438029 -160.511004) (xy 351.383527 -160.511004)
			(xy 351.329579 -160.503248) (xy 351.277284 -160.487893) (xy 351.227707 -160.465251) (xy 351.181857 -160.435785)
			(xy 351.140666 -160.400094) (xy 351.104975 -160.358903) (xy 351.075509 -160.313053) (xy 351.052867 -160.263476)
			(xy 351.037512 -160.211181) (xy 351.029756 -160.157233) (xy 351.02927 -160.129982) (xy 345.986992 -160.129982)
			(xy 345.95245 -160.16917) (xy 345.931744 -160.187386) (xy 345.923628 -160.19499) (xy 345.914275 -160.215141)
			(xy 345.91371 -160.226248) (xy 345.91371 -160.303464) (xy 345.914279 -160.314574) (xy 345.923616 -160.334733)
			(xy 345.931744 -160.342326) (xy 345.95248 -160.36051) (xy 345.988946 -160.401886) (xy 346.019074 -160.448082)
			(xy 346.042235 -160.498135) (xy 346.057947 -160.551002) (xy 346.065881 -160.60558) (xy 346.066364 -160.633156)
			(xy 346.065878 -160.660407) (xy 346.058122 -160.714355) (xy 346.042767 -160.76665) (xy 346.020125 -160.816227)
			(xy 345.990659 -160.862077) (xy 345.954968 -160.903268) (xy 345.913777 -160.938959) (xy 345.867927 -160.968425)
			(xy 345.81835 -160.991067) (xy 345.766055 -161.006422) (xy 345.712107 -161.014178) (xy 345.657605 -161.014178)
			(xy 345.603657 -161.006422) (xy 345.551362 -160.991067) (xy 345.501785 -160.968425) (xy 345.455935 -160.938959)
			(xy 345.414744 -160.903268) (xy 345.379053 -160.862077) (xy 345.349587 -160.816227) (xy 345.326945 -160.76665)
			(xy 345.31159 -160.714355) (xy 345.303834 -160.660407) (xy 345.303348 -160.633156) (xy 339.536532 -160.633156)
			(xy 338.503006 -161.666682) (xy 338.496172 -161.674085) (xy 338.488466 -161.692683) (xy 338.48802 -161.70275)
			(xy 338.48802 -164.53358) (xy 366.362996 -164.53358) (xy 366.363451 -164.506209) (xy 366.371272 -164.45203)
			(xy 366.386764 -164.399527) (xy 366.409608 -164.34978) (xy 366.439334 -164.303814) (xy 366.456976 -164.282882)
			(xy 366.463072 -164.27577) (xy 366.469422 -164.258752) (xy 366.469422 -164.173408) (xy 366.463072 -164.15639)
			(xy 366.456976 -164.149278) (xy 366.439356 -164.12833) (xy 366.409642 -164.082361) (xy 366.386803 -164.032618)
			(xy 366.371307 -163.980121) (xy 366.363473 -163.925948) (xy 366.362996 -163.89858) (xy 366.363459 -163.871328)
			(xy 366.371219 -163.817379) (xy 366.386576 -163.765084) (xy 366.40922 -163.715506) (xy 366.438689 -163.669656)
			(xy 366.474383 -163.628466) (xy 366.515575 -163.592775) (xy 366.561427 -163.563309) (xy 366.611006 -163.540668)
			(xy 366.663303 -163.525313) (xy 366.717252 -163.517557) (xy 366.744504 -163.517072) (xy 366.771875 -163.517518)
			(xy 366.826056 -163.525338) (xy 366.87856 -163.540831) (xy 366.928306 -163.563677) (xy 366.974272 -163.593408)
			(xy 366.995202 -163.611052) (xy 367.002314 -163.617148) (xy 367.019332 -163.623498) (xy 367.104676 -163.623498)
			(xy 367.121694 -163.617148) (xy 367.128806 -163.611052) (xy 367.149732 -163.593405) (xy 367.195705 -163.563692)
			(xy 367.245454 -163.540857) (xy 367.297957 -163.525368) (xy 367.352134 -163.517544) (xy 367.379504 -163.517072)
			(xy 367.408516 -163.517609) (xy 367.465873 -163.526378) (xy 367.521242 -163.543729) (xy 367.573346 -163.569262)
			(xy 367.620984 -163.602388) (xy 367.642394 -163.621974) (xy 367.649506 -163.628832) (xy 367.667286 -163.635944)
			(xy 367.757202 -163.635944) (xy 367.774982 -163.628832) (xy 367.782094 -163.621974) (xy 367.803503 -163.602389)
			(xy 367.851147 -163.569273) (xy 367.903252 -163.543745) (xy 367.958618 -163.526392) (xy 368.015973 -163.517613)
			(xy 368.044984 -163.517072) (xy 368.072355 -163.51753) (xy 368.126535 -163.525347) (xy 368.179039 -163.540837)
			(xy 368.228786 -163.563681) (xy 368.274751 -163.593409) (xy 368.295682 -163.611052) (xy 368.302794 -163.617148)
			(xy 368.319812 -163.623498) (xy 368.405156 -163.623498) (xy 368.422174 -163.617148) (xy 368.429286 -163.611052)
			(xy 368.450219 -163.593411) (xy 368.496187 -163.563687) (xy 368.545933 -163.540841) (xy 368.598435 -163.525345)
			(xy 368.652613 -163.517516) (xy 368.707355 -163.517516) (xy 368.761533 -163.525345) (xy 368.814035 -163.540841)
			(xy 368.863781 -163.563687) (xy 368.909749 -163.593411) (xy 368.930682 -163.611052) (xy 368.937794 -163.617148)
			(xy 368.954812 -163.623498) (xy 369.040156 -163.623498) (xy 369.057174 -163.617148) (xy 369.064286 -163.611052)
			(xy 369.085219 -163.593411) (xy 369.131187 -163.563687) (xy 369.180933 -163.540841) (xy 369.233435 -163.525345)
			(xy 369.287613 -163.517516) (xy 369.342355 -163.517516) (xy 369.396533 -163.525345) (xy 369.449035 -163.540841)
			(xy 369.498781 -163.563687) (xy 369.544749 -163.593411) (xy 369.565682 -163.611052) (xy 369.572794 -163.617148)
			(xy 369.589812 -163.623498) (xy 369.675156 -163.623498) (xy 369.692174 -163.617148) (xy 369.699286 -163.611052)
			(xy 369.720219 -163.593414) (xy 369.766191 -163.5637) (xy 369.815938 -163.540863) (xy 369.868439 -163.525372)
			(xy 369.922615 -163.517545) (xy 369.949984 -163.517072) (xy 369.977558 -163.517558) (xy 370.032129 -163.525508)
			(xy 370.084988 -163.54123) (xy 370.135034 -163.564396) (xy 370.181224 -163.594524) (xy 370.222597 -163.630987)
			(xy 370.240814 -163.651692) (xy 370.248416 -163.659811) (xy 370.268568 -163.669165) (xy 370.279676 -163.669726)
			(xy 370.356892 -163.669726) (xy 370.368007 -163.669193) (xy 370.388167 -163.659832) (xy 370.395754 -163.651692)
			(xy 370.413984 -163.630998) (xy 370.455349 -163.594527) (xy 370.501535 -163.564393) (xy 370.551579 -163.541224)
			(xy 370.604438 -163.525504) (xy 370.65901 -163.51756) (xy 370.686584 -163.517072) (xy 370.713834 -163.517593)
			(xy 370.767779 -163.525347) (xy 370.820072 -163.540699) (xy 370.869648 -163.563337) (xy 370.915497 -163.592799)
			(xy 370.956687 -163.628487) (xy 370.992379 -163.669674) (xy 371.021846 -163.71552) (xy 371.044488 -163.765094)
			(xy 371.059845 -163.817385) (xy 371.067604 -163.87133) (xy 371.068092 -163.89858) (xy 371.067616 -163.92595)
			(xy 371.059801 -163.980129) (xy 371.044314 -164.032632) (xy 371.021475 -164.082379) (xy 370.991752 -164.128346)
			(xy 370.974112 -164.149278) (xy 370.968016 -164.15639) (xy 370.961666 -164.173408) (xy 370.961666 -164.258752)
			(xy 370.968016 -164.27577) (xy 370.974112 -164.282882) (xy 370.991758 -164.303808) (xy 371.021468 -164.349783)
			(xy 371.044303 -164.399532) (xy 371.059792 -164.452034) (xy 371.067619 -164.50621) (xy 371.068092 -164.53358)
			(xy 371.067581 -164.561585) (xy 371.059415 -164.616996) (xy 371.04324 -164.670619) (xy 371.019404 -164.721303)
			(xy 370.988418 -164.76796) (xy 370.970048 -164.789104) (xy 370.963444 -164.79647) (xy 370.95684 -164.813996)
			(xy 370.958364 -164.903404) (xy 370.96573 -164.920676) (xy 370.972588 -164.927788) (xy 370.992762 -164.949287)
			(xy 371.026905 -164.997347) (xy 371.053251 -165.050087) (xy 371.071172 -165.106251) (xy 371.080242 -165.164503)
			(xy 371.080792 -165.19398) (xy 371.080326 -165.221233) (xy 371.072571 -165.275185) (xy 371.057217 -165.327484)
			(xy 371.034576 -165.377065) (xy 371.005108 -165.422919) (xy 370.969415 -165.464112) (xy 370.928222 -165.499806)
			(xy 370.882368 -165.529274) (xy 370.832787 -165.551916) (xy 370.780489 -165.567271) (xy 370.726537 -165.575026)
			(xy 370.699284 -165.575488) (xy 370.671711 -165.574969) (xy 370.617141 -165.567028) (xy 370.564282 -165.551314)
			(xy 370.514235 -165.528154) (xy 370.468044 -165.49803) (xy 370.426671 -165.461571) (xy 370.408454 -165.440868)
			(xy 370.400871 -165.432728) (xy 370.380705 -165.423387) (xy 370.369592 -165.422834) (xy 370.292376 -165.422834)
			(xy 370.281261 -165.423362) (xy 370.261102 -165.432727) (xy 370.253514 -165.440868) (xy 370.235292 -165.461569)
			(xy 370.193926 -165.498042) (xy 370.147739 -165.528176) (xy 370.097693 -165.551344) (xy 370.044832 -165.567062)
			(xy 369.990258 -165.575002) (xy 369.962684 -165.575488) (xy 369.935313 -165.575034) (xy 369.881134 -165.567214)
			(xy 369.82863 -165.551722) (xy 369.778884 -165.528878) (xy 369.732917 -165.49915) (xy 369.711986 -165.481508)
			(xy 369.704874 -165.475412) (xy 369.687856 -165.469062) (xy 369.602512 -165.469062) (xy 369.585494 -165.475412)
			(xy 369.578382 -165.481508) (xy 369.557449 -165.499149) (xy 369.511481 -165.528873) (xy 369.461735 -165.551719)
			(xy 369.409233 -165.567215) (xy 369.355055 -165.575044) (xy 369.300313 -165.575044) (xy 369.246135 -165.567215)
			(xy 369.193633 -165.551719) (xy 369.143887 -165.528873) (xy 369.097919 -165.499149) (xy 369.076986 -165.481508)
			(xy 369.069874 -165.475412) (xy 369.052856 -165.469062) (xy 368.967512 -165.469062) (xy 368.950494 -165.475412)
			(xy 368.943382 -165.481508) (xy 368.922449 -165.499149) (xy 368.876481 -165.528873) (xy 368.826735 -165.551719)
			(xy 368.774233 -165.567215) (xy 368.720055 -165.575044) (xy 368.665313 -165.575044) (xy 368.611135 -165.567215)
			(xy 368.558633 -165.551719) (xy 368.508887 -165.528873) (xy 368.462919 -165.499149) (xy 368.441986 -165.481508)
			(xy 368.434874 -165.475412) (xy 368.417856 -165.469062) (xy 368.332512 -165.469062) (xy 368.315494 -165.475412)
			(xy 368.308382 -165.481508) (xy 368.287431 -165.499123) (xy 368.241463 -165.528838) (xy 368.19172 -165.551679)
			(xy 368.139224 -165.567176) (xy 368.085052 -165.57501) (xy 368.057684 -165.575488) (xy 368.028671 -165.57497)
			(xy 367.971313 -165.566198) (xy 367.915943 -165.548843) (xy 367.86384 -165.523305) (xy 367.816203 -165.490174)
			(xy 367.794794 -165.470586) (xy 367.787682 -165.463728) (xy 367.769902 -165.456616) (xy 367.679986 -165.456616)
			(xy 367.662206 -165.463728) (xy 367.655094 -165.470586) (xy 367.633699 -165.490187) (xy 367.58605 -165.523298)
			(xy 367.533941 -165.548822) (xy 367.478572 -165.566172) (xy 367.421216 -165.574948) (xy 367.392204 -165.575488)
			(xy 367.364834 -165.575023) (xy 367.310654 -165.567205) (xy 367.258151 -165.551716) (xy 367.208404 -165.528874)
			(xy 367.162438 -165.499149) (xy 367.141506 -165.481508) (xy 367.134394 -165.475412) (xy 367.117376 -165.469062)
			(xy 367.032032 -165.469062) (xy 367.015014 -165.475412) (xy 367.007902 -165.481508) (xy 366.986981 -165.499161)
			(xy 366.941005 -165.52887) (xy 366.891255 -165.551704) (xy 366.838752 -165.567191) (xy 366.784574 -165.575016)
			(xy 366.757204 -165.575488) (xy 366.72995 -165.575041) (xy 366.675998 -165.567284) (xy 366.623698 -165.551927)
			(xy 366.574117 -165.529284) (xy 366.528263 -165.499814) (xy 366.48707 -165.464119) (xy 366.451376 -165.422924)
			(xy 366.421908 -165.377069) (xy 366.399267 -165.327487) (xy 366.383913 -165.275187) (xy 366.376158 -165.221234)
			(xy 366.375696 -165.19398) (xy 366.376186 -165.165974) (xy 366.384357 -165.110563) (xy 366.400537 -165.05694)
			(xy 366.424378 -165.006256) (xy 366.455368 -164.959599) (xy 366.47374 -164.938456) (xy 366.480344 -164.93109)
			(xy 366.486948 -164.913564) (xy 366.485424 -164.824156) (xy 366.478058 -164.806884) (xy 366.4712 -164.799772)
			(xy 366.451022 -164.778276) (xy 366.416876 -164.730217) (xy 366.390529 -164.677477) (xy 366.372609 -164.621311)
			(xy 366.363543 -164.563057) (xy 366.362996 -164.53358) (xy 338.48802 -164.53358) (xy 338.48802 -165.156134)
			(xy 355.727254 -165.156134) (xy 355.72774 -165.128883) (xy 355.735496 -165.074935) (xy 355.750851 -165.02264)
			(xy 355.773493 -164.973063) (xy 355.802959 -164.927213) (xy 355.83865 -164.886022) (xy 355.879841 -164.850331)
			(xy 355.925691 -164.820865) (xy 355.975268 -164.798223) (xy 356.027563 -164.782868) (xy 356.081511 -164.775112)
			(xy 356.136013 -164.775112) (xy 356.189961 -164.782868) (xy 356.242256 -164.798223) (xy 356.291833 -164.820865)
			(xy 356.337683 -164.850331) (xy 356.378874 -164.886022) (xy 356.414565 -164.927213) (xy 356.444031 -164.973063)
			(xy 356.466673 -165.02264) (xy 356.482028 -165.074935) (xy 356.489784 -165.128883) (xy 356.49027 -165.156134)
			(xy 356.489612 -165.187697) (xy 356.479225 -165.249962) (xy 356.458738 -165.309671) (xy 356.444296 -165.337744)
			(xy 356.43947 -165.346634) (xy 356.437438 -165.366192) (xy 356.463092 -165.45433) (xy 356.475538 -165.469824)
			(xy 356.484428 -165.474904) (xy 356.491794 -165.478968) (xy 356.501446 -165.48481) (xy 356.523544 -165.486842)
			(xy 356.618032 -165.453314) (xy 356.634034 -165.43782) (xy 356.638098 -165.427406) (xy 356.648782 -165.400624)
			(xy 356.677071 -165.350381) (xy 356.712601 -165.304971) (xy 356.754565 -165.265428) (xy 356.802004 -165.232654)
			(xy 356.853837 -165.207398) (xy 356.908882 -165.190234) (xy 356.965884 -165.181554) (xy 356.994714 -165.181026)
			(xy 357.021967 -165.181445) (xy 357.075918 -165.189204) (xy 357.128216 -165.204561) (xy 357.177796 -165.227205)
			(xy 357.223648 -165.256675) (xy 357.264841 -165.292369) (xy 357.300534 -165.333563) (xy 357.330001 -165.379417)
			(xy 357.352644 -165.428997) (xy 357.367999 -165.481296) (xy 357.375756 -165.535247) (xy 357.375756 -165.589753)
			(xy 357.367999 -165.643704) (xy 357.358645 -165.675564) (xy 357.617522 -165.675564) (xy 357.617982 -165.648088)
			(xy 357.625879 -165.593707) (xy 357.641505 -165.541025) (xy 357.664536 -165.491132) (xy 357.694494 -165.445065)
			(xy 357.712264 -165.424104) (xy 357.71836 -165.416992) (xy 357.72471 -165.399974) (xy 357.72471 -165.314122)
			(xy 357.71836 -165.297104) (xy 357.712264 -165.289992) (xy 357.69451 -165.269022) (xy 357.664585 -165.222942)
			(xy 357.64157 -165.17305) (xy 357.625942 -165.120375) (xy 357.618023 -165.066004) (xy 357.617522 -165.038532)
			(xy 357.618008 -165.011281) (xy 357.625764 -164.957333) (xy 357.641119 -164.905038) (xy 357.663761 -164.855461)
			(xy 357.693227 -164.809611) (xy 357.728918 -164.76842) (xy 357.770109 -164.732729) (xy 357.815959 -164.703263)
			(xy 357.865536 -164.680621) (xy 357.917831 -164.665266) (xy 357.971779 -164.65751) (xy 358.026281 -164.65751)
			(xy 358.080229 -164.665266) (xy 358.132524 -164.680621) (xy 358.182101 -164.703263) (xy 358.227951 -164.732729)
			(xy 358.269142 -164.76842) (xy 358.304833 -164.809611) (xy 358.334299 -164.855461) (xy 358.356941 -164.905038)
			(xy 358.372296 -164.957333) (xy 358.380052 -165.011281) (xy 358.380538 -165.038532) (xy 358.380062 -165.066007)
			(xy 358.372166 -165.120387) (xy 358.356543 -165.173069) (xy 358.333517 -165.222961) (xy 358.303564 -165.26903)
			(xy 358.285796 -165.289992) (xy 358.2797 -165.297104) (xy 358.27335 -165.314122) (xy 358.27335 -165.399974)
			(xy 358.2797 -165.416992) (xy 358.285796 -165.424104) (xy 358.303542 -165.445081) (xy 358.33347 -165.491158)
			(xy 358.356486 -165.541049) (xy 358.372116 -165.593723) (xy 358.380037 -165.648093) (xy 358.380538 -165.675564)
			(xy 358.380052 -165.702815) (xy 358.372296 -165.756763) (xy 358.356941 -165.809058) (xy 358.334299 -165.858635)
			(xy 358.330831 -165.864032) (xy 358.955338 -165.864032) (xy 358.959409 -165.80841) (xy 358.971535 -165.753973)
			(xy 358.991458 -165.701882) (xy 359.018754 -165.653247) (xy 359.05284 -165.609104) (xy 359.092989 -165.570395)
			(xy 359.138347 -165.537944) (xy 359.187947 -165.512443) (xy 359.240731 -165.494436) (xy 359.295574 -165.484306)
			(xy 359.351308 -165.482269) (xy 359.406745 -165.488369) (xy 359.460702 -165.502475) (xy 359.512031 -165.524287)
			(xy 359.559637 -165.553341) (xy 359.602505 -165.589016) (xy 359.639722 -165.630553) (xy 359.670495 -165.677066)
			(xy 359.694167 -165.727563) (xy 359.710235 -165.78097) (xy 359.718355 -165.836146) (xy 359.718864 -165.864032)
			(xy 359.718355 -165.891918) (xy 359.710235 -165.947094) (xy 359.694167 -166.000501) (xy 359.670495 -166.050998)
			(xy 359.639722 -166.097511) (xy 359.602505 -166.139048) (xy 359.559637 -166.174723) (xy 359.512031 -166.203777)
			(xy 359.460702 -166.225589) (xy 359.406745 -166.239695) (xy 359.351308 -166.245795) (xy 359.295574 -166.243758)
			(xy 359.240731 -166.233628) (xy 359.187947 -166.215621) (xy 359.138347 -166.19012) (xy 359.092989 -166.157669)
			(xy 359.05284 -166.11896) (xy 359.018754 -166.074817) (xy 358.991458 -166.026182) (xy 358.971535 -165.974091)
			(xy 358.959409 -165.919654) (xy 358.955338 -165.864032) (xy 358.330831 -165.864032) (xy 358.304833 -165.904485)
			(xy 358.269142 -165.945676) (xy 358.227951 -165.981367) (xy 358.182101 -166.010833) (xy 358.132524 -166.033475)
			(xy 358.080229 -166.04883) (xy 358.026281 -166.056586) (xy 357.971779 -166.056586) (xy 357.917831 -166.04883)
			(xy 357.865536 -166.033475) (xy 357.815959 -166.010833) (xy 357.770109 -165.981367) (xy 357.728918 -165.945676)
			(xy 357.693227 -165.904485) (xy 357.663761 -165.858635) (xy 357.641119 -165.809058) (xy 357.625764 -165.756763)
			(xy 357.618008 -165.702815) (xy 357.617522 -165.675564) (xy 357.358645 -165.675564) (xy 357.352644 -165.696003)
			(xy 357.330001 -165.745583) (xy 357.300534 -165.791437) (xy 357.264841 -165.832631) (xy 357.223648 -165.868325)
			(xy 357.177796 -165.897795) (xy 357.128216 -165.920439) (xy 357.075918 -165.935796) (xy 357.021967 -165.943555)
			(xy 356.994714 -165.944042) (xy 356.969479 -165.943633) (xy 356.919446 -165.937018) (xy 356.870726 -165.923848)
			(xy 356.824173 -165.904355) (xy 356.802182 -165.891972) (xy 356.79253 -165.88613) (xy 356.770432 -165.884098)
			(xy 356.675944 -165.917626) (xy 356.659942 -165.93312) (xy 356.655878 -165.943534) (xy 356.645152 -165.970297)
			(xy 356.616866 -166.020536) (xy 356.581339 -166.065944) (xy 356.539382 -166.105486) (xy 356.491949 -166.138261)
			(xy 356.440123 -166.163521) (xy 356.385085 -166.180692) (xy 356.328089 -166.189381) (xy 356.299262 -166.189914)
			(xy 356.27201 -166.189458) (xy 356.218062 -166.181696) (xy 356.165767 -166.166336) (xy 356.11619 -166.143691)
			(xy 356.07034 -166.114222) (xy 356.02915 -166.078527) (xy 355.993459 -166.037335) (xy 355.963993 -165.991482)
			(xy 355.941352 -165.941903) (xy 355.925997 -165.889607) (xy 355.91824 -165.835658) (xy 355.917754 -165.808406)
			(xy 355.918386 -165.776842) (xy 355.928784 -165.714576) (xy 355.949281 -165.654867) (xy 355.963728 -165.626796)
			(xy 355.968554 -165.617906) (xy 355.970586 -165.598348) (xy 355.944932 -165.51021) (xy 355.932486 -165.494716)
			(xy 355.923596 -165.489636) (xy 355.898482 -165.475109) (xy 355.8526 -165.439602) (xy 355.812625 -165.397554)
			(xy 355.779482 -165.349937) (xy 355.753933 -165.297849) (xy 355.736569 -165.242491) (xy 355.727791 -165.185142)
			(xy 355.727254 -165.156134) (xy 338.48802 -165.156134) (xy 338.48802 -167.430196) (xy 351.94113 -167.430196)
			(xy 351.941582 -167.402621) (xy 351.949536 -167.348047) (xy 351.965263 -167.295186) (xy 351.988436 -167.24514)
			(xy 352.018571 -167.198951) (xy 352.055041 -167.157581) (xy 352.07575 -167.139366) (xy 352.083887 -167.131781)
			(xy 352.093229 -167.111616) (xy 352.093784 -167.100504) (xy 352.093784 -167.023288) (xy 352.093244 -167.012175)
			(xy 352.083886 -166.992016) (xy 352.07575 -166.984426) (xy 352.055038 -166.966216) (xy 352.01857 -166.924846)
			(xy 351.98844 -166.878656) (xy 351.965274 -166.828608) (xy 351.949557 -166.775746) (xy 351.941616 -166.721172)
			(xy 351.941617 -166.666023) (xy 351.949559 -166.611449) (xy 351.965276 -166.558587) (xy 351.988442 -166.50854)
			(xy 352.018573 -166.46235) (xy 352.055042 -166.42098) (xy 352.07575 -166.402766) (xy 352.083887 -166.395181)
			(xy 352.093229 -166.375016) (xy 352.093784 -166.363904) (xy 352.093784 -166.286688) (xy 352.093244 -166.275575)
			(xy 352.083886 -166.255416) (xy 352.07575 -166.247826) (xy 352.055038 -166.229616) (xy 352.01857 -166.188246)
			(xy 351.988439 -166.142055) (xy 351.965274 -166.092007) (xy 351.949557 -166.039145) (xy 351.941616 -165.984571)
			(xy 351.94113 -165.956996) (xy 351.941552 -165.929741) (xy 351.94931 -165.875787) (xy 351.964669 -165.823486)
			(xy 351.987314 -165.773903) (xy 352.016786 -165.728048) (xy 352.052485 -165.686855) (xy 352.093682 -165.651161)
			(xy 352.13954 -165.621694) (xy 352.189125 -165.599054) (xy 352.241428 -165.583701) (xy 352.295383 -165.575949)
			(xy 352.322638 -165.575488) (xy 352.350494 -165.575986) (xy 352.40561 -165.584114) (xy 352.458961 -165.600164)
			(xy 352.509413 -165.623795) (xy 352.555897 -165.654505) (xy 352.597426 -165.691643) (xy 352.633119 -165.73442)
			(xy 352.662218 -165.781929) (xy 352.684106 -165.833162) (xy 352.6917 -165.859968) (xy 352.693986 -165.868858)
			(xy 352.704654 -165.884098) (xy 352.776536 -165.93185) (xy 352.79457 -165.935914) (xy 352.803714 -165.934644)
			(xy 352.816731 -165.932975) (xy 352.842915 -165.931195) (xy 352.856038 -165.931088) (xy 352.870187 -165.931177)
			(xy 352.89841 -165.933215) (xy 352.912426 -165.935152) (xy 352.922586 -165.936676) (xy 352.942144 -165.93185)
			(xy 353.016566 -165.87597) (xy 353.026726 -165.858444) (xy 353.027996 -165.848284) (xy 353.032094 -165.821132)
			(xy 353.047064 -165.768301) (xy 353.069453 -165.718162) (xy 353.098799 -165.67175) (xy 353.134495 -165.630025)
			(xy 353.175804 -165.593848) (xy 353.221872 -165.563966) (xy 353.271749 -165.540998) (xy 353.324403 -165.525417)
			(xy 353.378747 -165.517545) (xy 353.406202 -165.517068) (xy 353.433452 -165.517576) (xy 353.487398 -165.525332)
			(xy 353.539691 -165.540686) (xy 353.589266 -165.563326) (xy 353.635116 -165.59279) (xy 353.676305 -165.628479)
			(xy 353.711997 -165.669667) (xy 353.741464 -165.715514) (xy 353.764106 -165.765089) (xy 353.779463 -165.817381)
			(xy 353.787223 -165.871326) (xy 353.78771 -165.898576) (xy 353.787224 -165.92615) (xy 353.779275 -165.980722)
			(xy 353.763554 -166.033581) (xy 353.740388 -166.083627) (xy 353.710259 -166.129817) (xy 353.673795 -166.171189)
			(xy 353.65309 -166.189406) (xy 353.644972 -166.197009) (xy 353.635618 -166.21716) (xy 353.635056 -166.228268)
			(xy 353.635056 -166.305484) (xy 353.635599 -166.316597) (xy 353.644953 -166.336757) (xy 353.65309 -166.344346)
			(xy 353.673776 -166.362584) (xy 353.710249 -166.403947) (xy 353.740384 -166.450131) (xy 353.763555 -166.500174)
			(xy 353.779276 -166.553032) (xy 353.787222 -166.607603) (xy 353.787256 -166.609522) (xy 358.376218 -166.609522)
			(xy 358.380289 -166.5539) (xy 358.392415 -166.499463) (xy 358.412338 -166.447372) (xy 358.439634 -166.398737)
			(xy 358.47372 -166.354594) (xy 358.513869 -166.315885) (xy 358.559227 -166.283434) (xy 358.608827 -166.257933)
			(xy 358.661611 -166.239926) (xy 358.716454 -166.229796) (xy 358.772188 -166.227759) (xy 358.827625 -166.233859)
			(xy 358.881582 -166.247965) (xy 358.932911 -166.269777) (xy 358.980517 -166.298831) (xy 359.023385 -166.334506)
			(xy 359.060602 -166.376043) (xy 359.091375 -166.422556) (xy 359.115047 -166.473053) (xy 359.131115 -166.52646)
			(xy 359.139235 -166.581636) (xy 359.139744 -166.609522) (xy 359.139235 -166.637408) (xy 359.131115 -166.692584)
			(xy 359.115047 -166.745991) (xy 359.091375 -166.796488) (xy 359.060602 -166.843001) (xy 359.023385 -166.884538)
			(xy 358.980517 -166.920213) (xy 358.932911 -166.949267) (xy 358.881582 -166.971079) (xy 358.827625 -166.985185)
			(xy 358.772188 -166.991285) (xy 358.716454 -166.989248) (xy 358.661611 -166.979118) (xy 358.608827 -166.961111)
			(xy 358.559227 -166.93561) (xy 358.513869 -166.903159) (xy 358.47372 -166.86445) (xy 358.439634 -166.820307)
			(xy 358.412338 -166.771672) (xy 358.392415 -166.719581) (xy 358.380289 -166.665144) (xy 358.376218 -166.609522)
			(xy 353.787256 -166.609522) (xy 353.78771 -166.635176) (xy 353.787222 -166.662428) (xy 353.779469 -166.716378)
			(xy 353.764116 -166.768675) (xy 353.741476 -166.818255) (xy 353.712011 -166.864108) (xy 353.67632 -166.905301)
			(xy 353.635129 -166.940995) (xy 353.589278 -166.970464) (xy 353.5397 -166.993107) (xy 353.487404 -167.008463)
			(xy 353.433454 -167.016221) (xy 353.406202 -167.016684) (xy 353.371912 -167.01516) (xy 353.361752 -167.014144)
			(xy 353.342448 -167.02024) (xy 353.271836 -167.079422) (xy 353.262438 -167.097456) (xy 353.261422 -167.107616)
			(xy 353.258437 -167.135785) (xy 353.245268 -167.190876) (xy 353.224093 -167.243413) (xy 353.19538 -167.292239)
			(xy 353.15976 -167.336281) (xy 353.118016 -167.374568) (xy 353.071068 -167.406258) (xy 353.019948 -167.430655)
			(xy 352.965781 -167.447221) (xy 352.90976 -167.455591) (xy 352.881438 -167.456104) (xy 352.863419 -167.455888)
			(xy 352.827544 -167.45245) (xy 352.80981 -167.449246) (xy 352.800412 -167.447468) (xy 352.781362 -167.451278)
			(xy 352.706178 -167.49903) (xy 352.694748 -167.514778) (xy 352.692462 -167.524176) (xy 352.685104 -167.551232)
			(xy 352.663469 -167.602959) (xy 352.634499 -167.650965) (xy 352.598818 -167.694216) (xy 352.557194 -167.731782)
			(xy 352.510522 -167.762854) (xy 352.459806 -167.786765) (xy 352.406138 -167.802999) (xy 352.350673 -167.811207)
			(xy 352.322638 -167.811704) (xy 352.295386 -167.811209) (xy 352.241436 -167.803457) (xy 352.189138 -167.788106)
			(xy 352.139558 -167.765468) (xy 352.093705 -167.736003) (xy 352.052511 -167.700313) (xy 352.016817 -167.659123)
			(xy 351.987349 -167.613272) (xy 351.964706 -167.563694) (xy 351.94935 -167.511397) (xy 351.941593 -167.457448)
			(xy 351.94113 -167.430196) (xy 338.48802 -167.430196) (xy 338.48802 -168.921938) (xy 338.488451 -168.932005)
			(xy 338.496177 -168.950597) (xy 338.503006 -168.958006) (xy 338.527136 -168.982136) (xy 353.609148 -168.982136)
			(xy 353.609622 -168.954562) (xy 353.61757 -168.899988) (xy 353.633293 -168.847128) (xy 353.656461 -168.797081)
			(xy 353.686593 -168.750892) (xy 353.723061 -168.709521) (xy 353.743768 -168.691306) (xy 353.75189 -168.683707)
			(xy 353.76124 -168.663552) (xy 353.761802 -168.652444) (xy 353.761802 -168.575228) (xy 353.761234 -168.564118)
			(xy 353.751895 -168.54396) (xy 353.743768 -168.536366) (xy 353.723031 -168.518183) (xy 353.686564 -168.476808)
			(xy 353.656436 -168.430612) (xy 353.633275 -168.380558) (xy 353.617564 -168.327691) (xy 353.60963 -168.273112)
			(xy 353.609148 -168.245536) (xy 353.609734 -168.216611) (xy 353.618463 -168.159423) (xy 353.635726 -168.104209)
			(xy 353.661127 -168.052234) (xy 353.694085 -168.00469) (xy 353.733843 -167.962667) (xy 353.77949 -167.927129)
			(xy 353.804474 -167.912542) (xy 353.814634 -167.906954) (xy 353.827842 -167.888158) (xy 353.84486 -167.786812)
			(xy 353.838256 -167.764968) (xy 353.830636 -167.756078) (xy 353.81284 -167.73549) (xy 353.782818 -167.690102)
			(xy 353.759725 -167.640827) (xy 353.744052 -167.588714) (xy 353.736134 -167.534875) (xy 353.73564 -167.507666)
			(xy 353.736125 -167.481051) (xy 353.743704 -167.428363) (xy 353.758704 -167.377289) (xy 353.780818 -167.32887)
			(xy 353.809597 -167.28409) (xy 353.844456 -167.243861) (xy 353.884684 -167.209002) (xy 353.929463 -167.180222)
			(xy 353.977882 -167.158106) (xy 354.028955 -167.143106) (xy 354.081643 -167.135525) (xy 354.108258 -167.135048)
			(xy 354.13468 -167.135484) (xy 354.186996 -167.142941) (xy 354.237735 -167.157712) (xy 354.285879 -167.1795)
			(xy 354.330463 -167.207869) (xy 354.350828 -167.22471) (xy 354.357686 -167.230806) (xy 354.374704 -167.236902)
			(xy 354.459032 -167.236902) (xy 354.47605 -167.230806) (xy 354.482908 -167.22471) (xy 354.503274 -167.207871)
			(xy 354.54786 -167.179506) (xy 354.596004 -167.157719) (xy 354.646741 -167.142948) (xy 354.699056 -167.135488)
			(xy 354.7519 -167.135488) (xy 354.804215 -167.142948) (xy 354.854952 -167.157719) (xy 354.903096 -167.179506)
			(xy 354.947682 -167.207871) (xy 354.968048 -167.22471) (xy 354.974906 -167.230806) (xy 354.991924 -167.236902)
			(xy 355.076252 -167.236902) (xy 355.09327 -167.230806) (xy 355.100128 -167.22471) (xy 355.120484 -167.20786)
			(xy 355.165077 -167.179507) (xy 355.213224 -167.15773) (xy 355.263962 -167.142965) (xy 355.316276 -167.135507)
			(xy 355.342698 -167.135048) (xy 355.370582 -167.135611) (xy 355.425728 -167.143923) (xy 355.479019 -167.160361)
			(xy 355.529265 -167.184558) (xy 355.575343 -167.215973) (xy 355.616224 -167.253905) (xy 355.650996 -167.297507)
			(xy 355.67888 -167.345804) (xy 355.699255 -167.397717) (xy 355.711664 -167.452087) (xy 355.715832 -167.5077)
			(xy 355.711664 -167.563313) (xy 355.699255 -167.617683) (xy 355.67888 -167.669596) (xy 355.650996 -167.717893)
			(xy 355.616224 -167.761495) (xy 355.575343 -167.799427) (xy 355.529265 -167.830842) (xy 355.479019 -167.855039)
			(xy 355.425728 -167.871477) (xy 355.370582 -167.879789) (xy 355.342698 -167.880284) (xy 355.316277 -167.879808)
			(xy 355.263963 -167.872359) (xy 355.213226 -167.857597) (xy 355.165081 -167.835818) (xy 355.120495 -167.807458)
			(xy 355.100128 -167.790622) (xy 355.09327 -167.784526) (xy 355.076252 -167.77843) (xy 354.991924 -167.77843)
			(xy 354.974906 -167.784526) (xy 354.968048 -167.790622) (xy 354.947682 -167.807461) (xy 354.903096 -167.835826)
			(xy 354.854952 -167.857613) (xy 354.804215 -167.872384) (xy 354.7519 -167.879844) (xy 354.699056 -167.879844)
			(xy 354.646741 -167.872384) (xy 354.596004 -167.857613) (xy 354.54786 -167.835826) (xy 354.503274 -167.807461)
			(xy 354.482908 -167.790622) (xy 354.47605 -167.784526) (xy 354.459032 -167.77843) (xy 354.374704 -167.77843)
			(xy 354.357686 -167.784526) (xy 354.350828 -167.790622) (xy 354.337682 -167.801642) (xy 354.309697 -167.821485)
			(xy 354.294948 -167.830246) (xy 354.284788 -167.836088) (xy 354.271834 -167.854884) (xy 354.256594 -167.956484)
			(xy 354.263198 -167.978328) (xy 354.271072 -167.986964) (xy 354.289974 -168.008207) (xy 354.321908 -168.055254)
			(xy 354.346498 -168.106522) (xy 354.363199 -168.160875) (xy 354.371641 -168.217106) (xy 354.372164 -168.245536)
			(xy 354.371667 -168.27311) (xy 354.363722 -168.327682) (xy 354.348005 -168.380541) (xy 354.32484 -168.430588)
			(xy 354.294713 -168.476778) (xy 354.286072 -168.486582) (xy 359.33507 -168.486582) (xy 359.335557 -168.458671)
			(xy 359.343694 -168.403445) (xy 359.359791 -168.349994) (xy 359.383505 -168.29946) (xy 359.414329 -168.25292)
			(xy 359.432606 -168.23182) (xy 359.438956 -168.224708) (xy 359.44556 -168.207436) (xy 359.44556 -168.120314)
			(xy 359.438956 -168.103042) (xy 359.432606 -168.09593) (xy 359.414322 -168.074836) (xy 359.383495 -168.028296)
			(xy 359.359781 -167.97776) (xy 359.343686 -167.924307) (xy 359.335554 -167.86908) (xy 359.33507 -167.841168)
			(xy 359.335556 -167.813917) (xy 359.343312 -167.759969) (xy 359.358667 -167.707674) (xy 359.381309 -167.658097)
			(xy 359.410775 -167.612247) (xy 359.446466 -167.571056) (xy 359.487657 -167.535365) (xy 359.533507 -167.505899)
			(xy 359.583084 -167.483257) (xy 359.635379 -167.467902) (xy 359.689327 -167.460146) (xy 359.743829 -167.460146)
			(xy 359.797777 -167.467902) (xy 359.850072 -167.483257) (xy 359.899649 -167.505899) (xy 359.945499 -167.535365)
			(xy 359.98669 -167.571056) (xy 360.022381 -167.612247) (xy 360.051847 -167.658097) (xy 360.074489 -167.707674)
			(xy 360.089844 -167.759969) (xy 360.0976 -167.813917) (xy 360.098086 -167.841168) (xy 360.097615 -167.869079)
			(xy 360.089472 -167.924305) (xy 360.073371 -167.977756) (xy 360.049654 -168.02829) (xy 360.018827 -168.07483)
			(xy 360.00055 -168.09593) (xy 359.9942 -168.103042) (xy 359.987596 -168.120314) (xy 359.987596 -168.207436)
			(xy 359.9942 -168.224708) (xy 360.00055 -168.23182) (xy 360.01882 -168.252926) (xy 360.049647 -168.299464)
			(xy 360.073363 -168.349997) (xy 360.089461 -168.403446) (xy 360.097599 -168.458671) (xy 360.098086 -168.486582)
			(xy 360.0976 -168.513833) (xy 360.089844 -168.567781) (xy 360.074489 -168.620076) (xy 360.051847 -168.669653)
			(xy 360.022381 -168.715503) (xy 359.98669 -168.756694) (xy 359.945499 -168.792385) (xy 359.899649 -168.821851)
			(xy 359.850072 -168.844493) (xy 359.797777 -168.859848) (xy 359.743829 -168.867604) (xy 359.689327 -168.867604)
			(xy 359.635379 -168.859848) (xy 359.583084 -168.844493) (xy 359.533507 -168.821851) (xy 359.487657 -168.792385)
			(xy 359.446466 -168.756694) (xy 359.410775 -168.715503) (xy 359.381309 -168.669653) (xy 359.358667 -168.620076)
			(xy 359.343312 -168.567781) (xy 359.335556 -168.513833) (xy 359.33507 -168.486582) (xy 354.286072 -168.486582)
			(xy 354.258249 -168.51815) (xy 354.237544 -168.536366) (xy 354.229437 -168.543978) (xy 354.220078 -168.564123)
			(xy 354.21951 -168.575228) (xy 354.21951 -168.652444) (xy 354.22009 -168.663552) (xy 354.22942 -168.683711)
			(xy 354.237544 -168.691306) (xy 354.25827 -168.709501) (xy 354.294737 -168.750874) (xy 354.324866 -168.797068)
			(xy 354.348029 -168.847119) (xy 354.363743 -168.899984) (xy 354.37168 -168.954561) (xy 354.372164 -168.982136)
			(xy 354.371678 -169.009387) (xy 354.363922 -169.063335) (xy 354.348567 -169.11563) (xy 354.325925 -169.165207)
			(xy 354.296459 -169.211057) (xy 354.260768 -169.252248) (xy 354.219577 -169.287939) (xy 354.173727 -169.317405)
			(xy 354.12415 -169.340047) (xy 354.071855 -169.355402) (xy 354.017907 -169.363158) (xy 353.963405 -169.363158)
			(xy 353.909457 -169.355402) (xy 353.857162 -169.340047) (xy 353.807585 -169.317405) (xy 353.761735 -169.287939)
			(xy 353.720544 -169.252248) (xy 353.684853 -169.211057) (xy 353.655387 -169.165207) (xy 353.632745 -169.11563)
			(xy 353.61739 -169.063335) (xy 353.609634 -169.009387) (xy 353.609148 -168.982136) (xy 338.527136 -168.982136)
			(xy 341.561166 -172.016166) (xy 341.568566 -172.023006) (xy 341.587165 -172.030721) (xy 341.597234 -172.031152)
			(xy 350.977708 -172.031152) (xy 350.987694 -172.031692) (xy 351.006119 -172.039414) (xy 351.013522 -172.046138)
			(xy 351.973896 -173.006512) (xy 351.980741 -173.013911) (xy 351.988471 -173.032509) (xy 351.988882 -173.04258)
			(xy 351.988882 -173.431454) (xy 364.007654 -173.431454) (xy 364.00814 -173.404203) (xy 364.015896 -173.350255)
			(xy 364.031251 -173.29796) (xy 364.053893 -173.248383) (xy 364.083359 -173.202533) (xy 364.11905 -173.161342)
			(xy 364.160241 -173.125651) (xy 364.206091 -173.096185) (xy 364.255668 -173.073543) (xy 364.307963 -173.058188)
			(xy 364.361911 -173.050432) (xy 364.416413 -173.050432) (xy 364.470361 -173.058188) (xy 364.522656 -173.073543)
			(xy 364.572233 -173.096185) (xy 364.618083 -173.125651) (xy 364.659274 -173.161342) (xy 364.694965 -173.202533)
			(xy 364.724431 -173.248383) (xy 364.747073 -173.29796) (xy 364.751739 -173.313852) (xy 365.897922 -173.313852)
			(xy 365.898408 -173.286601) (xy 365.906164 -173.232653) (xy 365.921519 -173.180358) (xy 365.944161 -173.130781)
			(xy 365.973627 -173.084931) (xy 366.009318 -173.04374) (xy 366.050509 -173.008049) (xy 366.096359 -172.978583)
			(xy 366.145936 -172.955941) (xy 366.198231 -172.940586) (xy 366.252179 -172.93283) (xy 366.306681 -172.93283)
			(xy 366.360629 -172.940586) (xy 366.412924 -172.955941) (xy 366.462501 -172.978583) (xy 366.508351 -173.008049)
			(xy 366.549542 -173.04374) (xy 366.585233 -173.084931) (xy 366.614699 -173.130781) (xy 366.62395 -173.151038)
			(xy 373.622824 -173.151038) (xy 373.622824 -148.211032) (xy 373.62342 -148.186048) (xy 373.633169 -148.13704)
			(xy 373.652282 -148.09087) (xy 373.680023 -148.04931) (xy 373.697246 -148.0312) (xy 374.012968 -147.715478)
			(xy 374.019663 -147.707998) (xy 374.027252 -147.689438) (xy 374.0277 -147.67941) (xy 374.0277 -145.62201)
			(xy 374.028157 -145.598087) (xy 374.035691 -145.550839) (xy 374.05053 -145.505352) (xy 374.072305 -145.462748)
			(xy 374.100482 -145.424079) (xy 374.117108 -145.406872) (xy 374.396508 -145.127472) (xy 374.413732 -145.11087)
			(xy 374.452414 -145.082726) (xy 374.495016 -145.060968) (xy 374.540492 -145.04613) (xy 374.587729 -145.038574)
			(xy 374.611646 -145.038064) (xy 380.318264 -145.038064) (xy 380.328311 -145.037712) (xy 380.346908 -145.030111)
			(xy 380.354332 -145.023332) (xy 380.600712 -144.776952) (xy 380.607411 -144.769475) (xy 380.614999 -144.750913)
			(xy 380.615444 -144.740884) (xy 380.615444 -138.808714) (xy 380.615649 -138.802627) (xy 380.61861 -138.790817)
			(xy 380.621286 -138.785346) (xy 380.687834 -138.65606) (xy 380.690827 -138.650694) (xy 380.698914 -138.641449)
			(xy 380.703836 -138.637772) (xy 380.744476 -138.60907) (xy 380.764019 -138.594587) (xy 380.797737 -138.559541)
			(xy 380.82417 -138.518718) (xy 380.842351 -138.473611) (xy 380.851616 -138.425869) (xy 380.852172 -138.401552)
			(xy 380.852172 -138.401044) (xy 380.85203 -138.386307) (xy 380.848715 -138.357022) (xy 380.845568 -138.342624)
			(xy 380.845314 -138.34237) (xy 380.830328 -138.278362) (xy 380.829087 -138.272121) (xy 380.829343 -138.259402)
			(xy 380.830836 -138.253216) (xy 380.866142 -138.126724) (xy 380.868068 -138.120471) (xy 380.87463 -138.109155)
			(xy 380.879096 -138.104372) (xy 381.02286 -137.960354) (xy 381.04006 -137.943735) (xy 381.078745 -137.915611)
			(xy 381.121357 -137.893891) (xy 381.166844 -137.879112) (xy 381.214084 -137.871638) (xy 381.237998 -137.8712)
			(xy 383.718816 -137.8712) (xy 383.742724 -137.871697) (xy 383.78995 -137.879189) (xy 383.835423 -137.893972)
			(xy 383.878027 -137.915681) (xy 383.916714 -137.943783) (xy 383.933954 -137.960354) (xy 384.33883 -138.36523)
			(xy 384.355432 -138.382446) (xy 384.383559 -138.421126) (xy 384.405282 -138.463734) (xy 384.420065 -138.509218)
			(xy 384.427543 -138.556455) (xy 384.427984 -138.580368) (xy 384.427984 -139.186158) (xy 384.74726 -139.186158)
			(xy 384.751331 -139.130536) (xy 384.763457 -139.076099) (xy 384.78338 -139.024008) (xy 384.810676 -138.975373)
			(xy 384.844762 -138.93123) (xy 384.884911 -138.892521) (xy 384.930269 -138.86007) (xy 384.979869 -138.834569)
			(xy 385.032653 -138.816562) (xy 385.087496 -138.806432) (xy 385.14323 -138.804395) (xy 385.198667 -138.810495)
			(xy 385.252624 -138.824601) (xy 385.303953 -138.846413) (xy 385.351559 -138.875467) (xy 385.394427 -138.911142)
			(xy 385.431644 -138.952679) (xy 385.462417 -138.999192) (xy 385.486089 -139.049689) (xy 385.502157 -139.103096)
			(xy 385.510277 -139.158272) (xy 385.510786 -139.186158) (xy 385.510277 -139.214044) (xy 385.502157 -139.26922)
			(xy 385.486089 -139.322627) (xy 385.462417 -139.373124) (xy 385.431644 -139.419637) (xy 385.394427 -139.461174)
			(xy 385.351559 -139.496849) (xy 385.303953 -139.525903) (xy 385.252624 -139.547715) (xy 385.198667 -139.561821)
			(xy 385.14323 -139.567921) (xy 385.087496 -139.565884) (xy 385.032653 -139.555754) (xy 384.979869 -139.537747)
			(xy 384.930269 -139.512246) (xy 384.884911 -139.479795) (xy 384.844762 -139.441086) (xy 384.810676 -139.396943)
			(xy 384.78338 -139.348308) (xy 384.763457 -139.296217) (xy 384.751331 -139.24178) (xy 384.74726 -139.186158)
			(xy 384.427984 -139.186158) (xy 384.427984 -140.202158) (xy 384.767326 -140.202158) (xy 384.771397 -140.146536)
			(xy 384.783523 -140.092099) (xy 384.803446 -140.040008) (xy 384.830742 -139.991373) (xy 384.864828 -139.94723)
			(xy 384.904977 -139.908521) (xy 384.950335 -139.87607) (xy 384.999935 -139.850569) (xy 385.052719 -139.832562)
			(xy 385.107562 -139.822432) (xy 385.163296 -139.820395) (xy 385.218733 -139.826495) (xy 385.27269 -139.840601)
			(xy 385.324019 -139.862413) (xy 385.371625 -139.891467) (xy 385.414493 -139.927142) (xy 385.45171 -139.968679)
			(xy 385.482483 -140.015192) (xy 385.506155 -140.065689) (xy 385.522223 -140.119096) (xy 385.530343 -140.174272)
			(xy 385.530852 -140.202158) (xy 385.530343 -140.230044) (xy 385.522223 -140.28522) (xy 385.506155 -140.338627)
			(xy 385.482483 -140.389124) (xy 385.45171 -140.435637) (xy 385.414493 -140.477174) (xy 385.371625 -140.512849)
			(xy 385.324019 -140.541903) (xy 385.27269 -140.563715) (xy 385.218733 -140.577821) (xy 385.163296 -140.583921)
			(xy 385.107562 -140.581884) (xy 385.052719 -140.571754) (xy 384.999935 -140.553747) (xy 384.950335 -140.528246)
			(xy 384.904977 -140.495795) (xy 384.864828 -140.457086) (xy 384.830742 -140.412943) (xy 384.803446 -140.364308)
			(xy 384.783523 -140.312217) (xy 384.771397 -140.25778) (xy 384.767326 -140.202158) (xy 384.427984 -140.202158)
			(xy 384.427984 -141.309852) (xy 385.56006 -141.309852) (xy 385.564131 -141.25423) (xy 385.576257 -141.199793)
			(xy 385.59618 -141.147702) (xy 385.623476 -141.099067) (xy 385.657562 -141.054924) (xy 385.697711 -141.016215)
			(xy 385.743069 -140.983764) (xy 385.792669 -140.958263) (xy 385.845453 -140.940256) (xy 385.900296 -140.930126)
			(xy 385.95603 -140.928089) (xy 386.011467 -140.934189) (xy 386.065424 -140.948295) (xy 386.116753 -140.970107)
			(xy 386.164359 -140.999161) (xy 386.207227 -141.034836) (xy 386.244444 -141.076373) (xy 386.275217 -141.122886)
			(xy 386.298889 -141.173383) (xy 386.314957 -141.22679) (xy 386.323077 -141.281966) (xy 386.323586 -141.309852)
			(xy 386.323077 -141.337738) (xy 386.314957 -141.392914) (xy 386.298889 -141.446321) (xy 386.275217 -141.496818)
			(xy 386.244444 -141.543331) (xy 386.207227 -141.584868) (xy 386.164359 -141.620543) (xy 386.116753 -141.649597)
			(xy 386.065424 -141.671409) (xy 386.011467 -141.685515) (xy 385.95603 -141.691615) (xy 385.900296 -141.689578)
			(xy 385.845453 -141.679448) (xy 385.792669 -141.661441) (xy 385.743069 -141.63594) (xy 385.697711 -141.603489)
			(xy 385.657562 -141.56478) (xy 385.623476 -141.520637) (xy 385.59618 -141.472002) (xy 385.576257 -141.419911)
			(xy 385.564131 -141.365474) (xy 385.56006 -141.309852) (xy 384.427984 -141.309852) (xy 384.427984 -142.742158)
			(xy 385.5245 -142.742158) (xy 385.528571 -142.686536) (xy 385.540697 -142.632099) (xy 385.56062 -142.580008)
			(xy 385.587916 -142.531373) (xy 385.622002 -142.48723) (xy 385.662151 -142.448521) (xy 385.707509 -142.41607)
			(xy 385.757109 -142.390569) (xy 385.809893 -142.372562) (xy 385.864736 -142.362432) (xy 385.92047 -142.360395)
			(xy 385.975907 -142.366495) (xy 386.029864 -142.380601) (xy 386.081193 -142.402413) (xy 386.128799 -142.431467)
			(xy 386.171667 -142.467142) (xy 386.208884 -142.508679) (xy 386.239657 -142.555192) (xy 386.263329 -142.605689)
			(xy 386.279397 -142.659096) (xy 386.287517 -142.714272) (xy 386.288026 -142.742158) (xy 386.287517 -142.770044)
			(xy 386.279397 -142.82522) (xy 386.263329 -142.878627) (xy 386.239657 -142.929124) (xy 386.208884 -142.975637)
			(xy 386.19687 -142.989046) (xy 388.931912 -142.989046) (xy 388.932398 -142.961795) (xy 388.940154 -142.907847)
			(xy 388.955509 -142.855552) (xy 388.978151 -142.805975) (xy 389.007617 -142.760125) (xy 389.043308 -142.718934)
			(xy 389.084499 -142.683243) (xy 389.130349 -142.653777) (xy 389.179926 -142.631135) (xy 389.232221 -142.61578)
			(xy 389.286169 -142.608024) (xy 389.340671 -142.608024) (xy 389.394619 -142.61578) (xy 389.446914 -142.631135)
			(xy 389.496491 -142.653777) (xy 389.542341 -142.683243) (xy 389.583532 -142.718934) (xy 389.611358 -142.751048)
			(xy 392.299444 -142.751048) (xy 392.300022 -142.723812) (xy 392.307764 -142.669892) (xy 392.323098 -142.617622)
			(xy 392.345711 -142.568065) (xy 392.375144 -142.522229) (xy 392.410799 -142.481047) (xy 392.451949 -142.445354)
			(xy 392.497758 -142.415879) (xy 392.547294 -142.39322) (xy 392.59955 -142.377839) (xy 392.653462 -142.370047)
			(xy 392.680698 -142.36954) (xy 392.711243 -142.370181) (xy 392.771547 -142.379949) (xy 392.829524 -142.399204)
			(xy 392.88369 -142.427454) (xy 392.908536 -142.445232) (xy 392.915216 -142.449877) (xy 392.930632 -142.455054)
			(xy 392.938762 -142.455392) (xy 393.744704 -142.455392) (xy 393.754774 -142.454971) (xy 393.773372 -142.447247)
			(xy 393.780772 -142.440406) (xy 393.886944 -142.334234) (xy 393.893655 -142.326766) (xy 393.901235 -142.308197)
			(xy 393.901676 -142.298166) (xy 393.901676 -138.236706) (xy 393.901284 -138.226663) (xy 393.893711 -138.208067)
			(xy 393.886944 -138.200638) (xy 393.539472 -137.853166) (xy 393.53208 -137.846316) (xy 393.513474 -137.838603)
			(xy 393.503404 -137.83818) (xy 392.721846 -137.83818) (xy 392.694611 -137.837669) (xy 392.640695 -137.829923)
			(xy 392.58843 -137.814582) (xy 392.53888 -137.791958) (xy 392.493055 -137.762513) (xy 392.451887 -137.726846)
			(xy 392.416214 -137.685682) (xy 392.386764 -137.63986) (xy 392.364134 -137.590314) (xy 392.348787 -137.53805)
			(xy 392.341035 -137.484135) (xy 392.341035 -137.429665) (xy 392.348787 -137.37575) (xy 392.364134 -137.323486)
			(xy 392.386764 -137.27394) (xy 392.416214 -137.228118) (xy 392.451887 -137.186954) (xy 392.493055 -137.151287)
			(xy 392.53888 -137.121842) (xy 392.58843 -137.099218) (xy 392.640695 -137.083877) (xy 392.694611 -137.076131)
			(xy 392.721846 -137.075672) (xy 393.682474 -137.075672) (xy 393.712446 -137.076205) (xy 393.77166 -137.085525)
			(xy 393.828685 -137.104002) (xy 393.882113 -137.13118) (xy 393.930626 -137.166388) (xy 393.952222 -137.187178)
			(xy 394.552932 -137.787888) (xy 394.573736 -137.809484) (xy 394.608993 -137.857985) (xy 394.636223 -137.911406)
			(xy 394.654757 -137.968432) (xy 394.661523 -138.011154) (xy 399.242786 -138.011154) (xy 399.246857 -137.955532)
			(xy 399.258983 -137.901095) (xy 399.278906 -137.849004) (xy 399.306202 -137.800369) (xy 399.340288 -137.756226)
			(xy 399.380437 -137.717517) (xy 399.425795 -137.685066) (xy 399.475395 -137.659565) (xy 399.528179 -137.641558)
			(xy 399.583022 -137.631428) (xy 399.638756 -137.629391) (xy 399.694193 -137.635491) (xy 399.74815 -137.649597)
			(xy 399.799479 -137.671409) (xy 399.847085 -137.700463) (xy 399.889953 -137.736138) (xy 399.92717 -137.777675)
			(xy 399.957943 -137.824188) (xy 399.981615 -137.874685) (xy 399.982095 -137.87628) (xy 410.808168 -137.87628)
			(xy 410.812239 -137.820658) (xy 410.824365 -137.766221) (xy 410.844288 -137.71413) (xy 410.871584 -137.665495)
			(xy 410.90567 -137.621352) (xy 410.945819 -137.582643) (xy 410.991177 -137.550192) (xy 411.040777 -137.524691)
			(xy 411.093561 -137.506684) (xy 411.148404 -137.496554) (xy 411.204138 -137.494517) (xy 411.259575 -137.500617)
			(xy 411.313532 -137.514723) (xy 411.364861 -137.536535) (xy 411.412467 -137.565589) (xy 411.455335 -137.601264)
			(xy 411.492552 -137.642801) (xy 411.523325 -137.689314) (xy 411.546997 -137.739811) (xy 411.563065 -137.793218)
			(xy 411.571185 -137.848394) (xy 411.571694 -137.87628) (xy 411.571185 -137.904166) (xy 411.563065 -137.959342)
			(xy 411.546997 -138.012749) (xy 411.523325 -138.063246) (xy 411.492552 -138.109759) (xy 411.455335 -138.151296)
			(xy 411.412467 -138.186971) (xy 411.364861 -138.216025) (xy 411.313532 -138.237837) (xy 411.259575 -138.251943)
			(xy 411.204138 -138.258043) (xy 411.148404 -138.256006) (xy 411.093561 -138.245876) (xy 411.040777 -138.227869)
			(xy 410.991177 -138.202368) (xy 410.945819 -138.169917) (xy 410.90567 -138.131208) (xy 410.871584 -138.087065)
			(xy 410.844288 -138.03843) (xy 410.824365 -137.986339) (xy 410.812239 -137.931902) (xy 410.808168 -137.87628)
			(xy 399.982095 -137.87628) (xy 399.997683 -137.928092) (xy 400.005803 -137.983268) (xy 400.006312 -138.011154)
			(xy 400.005803 -138.03904) (xy 399.997683 -138.094216) (xy 399.981615 -138.147623) (xy 399.957943 -138.19812)
			(xy 399.92717 -138.244633) (xy 399.889953 -138.28617) (xy 399.847085 -138.321845) (xy 399.799479 -138.350899)
			(xy 399.74815 -138.372711) (xy 399.694193 -138.386817) (xy 399.638756 -138.392917) (xy 399.583022 -138.39088)
			(xy 399.528179 -138.38075) (xy 399.475395 -138.362743) (xy 399.425795 -138.337242) (xy 399.380437 -138.304791)
			(xy 399.340288 -138.266082) (xy 399.306202 -138.221939) (xy 399.278906 -138.173304) (xy 399.258983 -138.121213)
			(xy 399.246857 -138.066776) (xy 399.242786 -138.011154) (xy 394.661523 -138.011154) (xy 394.664136 -138.027655)
			(xy 394.664692 -138.057636) (xy 394.664692 -138.936984) (xy 399.28368 -138.936984) (xy 399.287751 -138.881362)
			(xy 399.299877 -138.826925) (xy 399.3198 -138.774834) (xy 399.347096 -138.726199) (xy 399.381182 -138.682056)
			(xy 399.421331 -138.643347) (xy 399.466689 -138.610896) (xy 399.516289 -138.585395) (xy 399.569073 -138.567388)
			(xy 399.623916 -138.557258) (xy 399.67965 -138.555221) (xy 399.735087 -138.561321) (xy 399.789044 -138.575427)
			(xy 399.840373 -138.597239) (xy 399.887979 -138.626293) (xy 399.930847 -138.661968) (xy 399.968064 -138.703505)
			(xy 399.998837 -138.750018) (xy 400.022509 -138.800515) (xy 400.038577 -138.853922) (xy 400.046697 -138.909098)
			(xy 400.047206 -138.936984) (xy 400.046697 -138.96487) (xy 400.038577 -139.020046) (xy 400.022509 -139.073453)
			(xy 399.998837 -139.12395) (xy 399.968064 -139.170463) (xy 399.930847 -139.212) (xy 399.887979 -139.247675)
			(xy 399.840373 -139.276729) (xy 399.789044 -139.298541) (xy 399.735087 -139.312647) (xy 399.67965 -139.318747)
			(xy 399.623916 -139.31671) (xy 399.569073 -139.30658) (xy 399.516289 -139.288573) (xy 399.466689 -139.263072)
			(xy 399.421331 -139.230621) (xy 399.381182 -139.191912) (xy 399.347096 -139.147769) (xy 399.3198 -139.099134)
			(xy 399.299877 -139.047043) (xy 399.287751 -138.992606) (xy 399.28368 -138.936984) (xy 394.664692 -138.936984)
			(xy 394.664692 -139.47267) (xy 410.103318 -139.47267) (xy 410.107389 -139.417048) (xy 410.119515 -139.362611)
			(xy 410.139438 -139.31052) (xy 410.166734 -139.261885) (xy 410.20082 -139.217742) (xy 410.240969 -139.179033)
			(xy 410.286327 -139.146582) (xy 410.335927 -139.121081) (xy 410.388711 -139.103074) (xy 410.443554 -139.092944)
			(xy 410.499288 -139.090907) (xy 410.554725 -139.097007) (xy 410.608682 -139.111113) (xy 410.660011 -139.132925)
			(xy 410.707617 -139.161979) (xy 410.750485 -139.197654) (xy 410.787702 -139.239191) (xy 410.818475 -139.285704)
			(xy 410.842147 -139.336201) (xy 410.858215 -139.389608) (xy 410.866335 -139.444784) (xy 410.866844 -139.47267)
			(xy 410.866335 -139.500556) (xy 410.858215 -139.555732) (xy 410.842147 -139.609139) (xy 410.818475 -139.659636)
			(xy 410.787702 -139.706149) (xy 410.750485 -139.747686) (xy 410.707617 -139.783361) (xy 410.660011 -139.812415)
			(xy 410.608682 -139.834227) (xy 410.554725 -139.848333) (xy 410.499288 -139.854433) (xy 410.443554 -139.852396)
			(xy 410.388711 -139.842266) (xy 410.335927 -139.824259) (xy 410.286327 -139.798758) (xy 410.240969 -139.766307)
			(xy 410.20082 -139.727598) (xy 410.166734 -139.683455) (xy 410.139438 -139.63482) (xy 410.119515 -139.582729)
			(xy 410.107389 -139.528292) (xy 410.103318 -139.47267) (xy 394.664692 -139.47267) (xy 394.664692 -141.316456)
			(xy 410.132274 -141.316456) (xy 410.136345 -141.260834) (xy 410.148471 -141.206397) (xy 410.168394 -141.154306)
			(xy 410.19569 -141.105671) (xy 410.229776 -141.061528) (xy 410.269925 -141.022819) (xy 410.315283 -140.990368)
			(xy 410.364883 -140.964867) (xy 410.417667 -140.94686) (xy 410.47251 -140.93673) (xy 410.528244 -140.934693)
			(xy 410.583681 -140.940793) (xy 410.637638 -140.954899) (xy 410.688967 -140.976711) (xy 410.736573 -141.005765)
			(xy 410.779441 -141.04144) (xy 410.816658 -141.082977) (xy 410.847431 -141.12949) (xy 410.871103 -141.179987)
			(xy 410.887171 -141.233394) (xy 410.895291 -141.28857) (xy 410.8958 -141.316456) (xy 410.895291 -141.344342)
			(xy 410.887171 -141.399518) (xy 410.871103 -141.452925) (xy 410.847431 -141.503422) (xy 410.816658 -141.549935)
			(xy 410.779441 -141.591472) (xy 410.736573 -141.627147) (xy 410.688967 -141.656201) (xy 410.637638 -141.678013)
			(xy 410.583681 -141.692119) (xy 410.528244 -141.698219) (xy 410.47251 -141.696182) (xy 410.417667 -141.686052)
			(xy 410.364883 -141.668045) (xy 410.315283 -141.642544) (xy 410.269925 -141.610093) (xy 410.229776 -141.571384)
			(xy 410.19569 -141.527241) (xy 410.168394 -141.478606) (xy 410.148471 -141.426515) (xy 410.136345 -141.372078)
			(xy 410.132274 -141.316456) (xy 394.664692 -141.316456) (xy 394.664692 -142.477236) (xy 394.66411 -142.507214)
			(xy 394.656011 -142.558262) (xy 415.08502 -142.558262) (xy 415.089091 -142.50264) (xy 415.101217 -142.448203)
			(xy 415.12114 -142.396112) (xy 415.148436 -142.347477) (xy 415.182522 -142.303334) (xy 415.222671 -142.264625)
			(xy 415.268029 -142.232174) (xy 415.317629 -142.206673) (xy 415.370413 -142.188666) (xy 415.425256 -142.178536)
			(xy 415.48099 -142.176499) (xy 415.536427 -142.182599) (xy 415.590384 -142.196705) (xy 415.641713 -142.218517)
			(xy 415.689319 -142.247571) (xy 415.732187 -142.283246) (xy 415.769404 -142.324783) (xy 415.800177 -142.371296)
			(xy 415.823849 -142.421793) (xy 415.839917 -142.4752) (xy 415.848037 -142.530376) (xy 415.848546 -142.558262)
			(xy 415.848037 -142.586148) (xy 415.839917 -142.641324) (xy 415.823849 -142.694731) (xy 415.800177 -142.745228)
			(xy 415.769404 -142.791741) (xy 415.732187 -142.833278) (xy 415.689319 -142.868953) (xy 415.641713 -142.898007)
			(xy 415.590384 -142.919819) (xy 415.536427 -142.933925) (xy 415.48099 -142.940025) (xy 415.425256 -142.937988)
			(xy 415.370413 -142.927858) (xy 415.317629 -142.909851) (xy 415.268029 -142.88435) (xy 415.222671 -142.851899)
			(xy 415.182522 -142.81319) (xy 415.148436 -142.769047) (xy 415.12114 -142.720412) (xy 415.101217 -142.668321)
			(xy 415.089091 -142.613884) (xy 415.08502 -142.558262) (xy 394.656011 -142.558262) (xy 394.654715 -142.566428)
			(xy 394.636177 -142.623446) (xy 394.608953 -142.676864) (xy 394.573712 -142.725369) (xy 394.552932 -142.746984)
			(xy 394.193522 -143.106394) (xy 394.171918 -143.127171) (xy 394.123394 -143.162354) (xy 394.069966 -143.189518)
			(xy 394.012948 -143.207995) (xy 393.953743 -143.217331) (xy 393.923774 -143.2179) (xy 392.766296 -143.2179)
			(xy 392.736323 -143.217394) (xy 392.677107 -143.208069) (xy 392.620082 -143.189586) (xy 392.566654 -143.162402)
			(xy 392.518143 -143.127187) (xy 392.496548 -143.106394) (xy 392.41095 -143.020796) (xy 392.390216 -142.999152)
			(xy 392.355026 -142.95064) (xy 392.327853 -142.897222) (xy 392.309365 -142.840213) (xy 392.300019 -142.781014)
			(xy 392.299444 -142.751048) (xy 389.611358 -142.751048) (xy 389.619223 -142.760125) (xy 389.648689 -142.805975)
			(xy 389.671331 -142.855552) (xy 389.686686 -142.907847) (xy 389.694442 -142.961795) (xy 389.694928 -142.989046)
			(xy 389.69442 -143.008096) (xy 389.694231 -143.021559) (xy 389.699969 -143.047851) (xy 389.71237 -143.071735)
			(xy 389.730574 -143.091555) (xy 389.75332 -143.105937) (xy 389.779032 -143.113884) (xy 389.792464 -143.114776)
			(xy 389.819095 -143.116143) (xy 389.871619 -143.125347) (xy 389.922349 -143.141777) (xy 389.970296 -143.165112)
			(xy 390.014525 -143.194899) (xy 390.054174 -143.230556) (xy 390.08847 -143.271388) (xy 390.116745 -143.316598)
			(xy 390.138446 -143.365307) (xy 390.153152 -143.416563) (xy 390.160575 -143.469368) (xy 390.161018 -143.49603)
			(xy 390.160532 -143.523281) (xy 390.152776 -143.577229) (xy 390.137421 -143.629524) (xy 390.114779 -143.679101)
			(xy 390.085313 -143.724951) (xy 390.049622 -143.766142) (xy 390.008431 -143.801833) (xy 389.962581 -143.831299)
			(xy 389.913004 -143.853941) (xy 389.860709 -143.869296) (xy 389.806761 -143.877052) (xy 389.752259 -143.877052)
			(xy 389.698311 -143.869296) (xy 389.646016 -143.853941) (xy 389.596439 -143.831299) (xy 389.550589 -143.801833)
			(xy 389.509398 -143.766142) (xy 389.473707 -143.724951) (xy 389.444241 -143.679101) (xy 389.421599 -143.629524)
			(xy 389.406244 -143.577229) (xy 389.398488 -143.523281) (xy 389.398002 -143.49603) (xy 389.39851 -143.47698)
			(xy 389.398788 -143.463515) (xy 389.39304 -143.43721) (xy 389.380624 -143.413318) (xy 389.362401 -143.393496)
			(xy 389.339635 -143.379119) (xy 389.313906 -143.371183) (xy 389.300466 -143.3703) (xy 389.273829 -143.36902)
			(xy 389.221302 -143.359806) (xy 389.170569 -143.343366) (xy 389.122621 -143.32002) (xy 389.078391 -143.290224)
			(xy 389.038743 -143.254559) (xy 389.004448 -143.213719) (xy 388.976175 -143.1685) (xy 388.954476 -143.119785)
			(xy 388.939773 -143.068522) (xy 388.932353 -143.015711) (xy 388.931912 -142.989046) (xy 386.19687 -142.989046)
			(xy 386.171667 -143.017174) (xy 386.128799 -143.052849) (xy 386.081193 -143.081903) (xy 386.029864 -143.103715)
			(xy 385.975907 -143.117821) (xy 385.92047 -143.123921) (xy 385.864736 -143.121884) (xy 385.809893 -143.111754)
			(xy 385.757109 -143.093747) (xy 385.707509 -143.068246) (xy 385.662151 -143.035795) (xy 385.622002 -142.997086)
			(xy 385.587916 -142.952943) (xy 385.56062 -142.904308) (xy 385.540697 -142.852217) (xy 385.528571 -142.79778)
			(xy 385.5245 -142.742158) (xy 384.427984 -142.742158) (xy 384.427984 -144.596358) (xy 384.428238 -144.596358)
			(xy 384.428066 -144.60893) (xy 384.425902 -144.63398) (xy 384.42392 -144.646396) (xy 384.422142 -144.657572)
			(xy 384.427984 -144.678908) (xy 384.485642 -144.746726) (xy 384.493176 -144.754825) (xy 384.513204 -144.764165)
			(xy 384.52425 -144.76476) (xy 385.224782 -144.76476) (xy 385.249764 -144.765398) (xy 385.298771 -144.775133)
			(xy 385.344941 -144.794232) (xy 385.386503 -144.821964) (xy 385.404614 -144.839182) (xy 386.262372 -145.69694)
			(xy 386.269838 -145.703653) (xy 386.288409 -145.711232) (xy 386.29844 -145.711672) (xy 394.448538 -145.711672)
			(xy 394.473533 -145.712332) (xy 394.522555 -145.722127) (xy 394.568726 -145.741293) (xy 394.610273 -145.769095)
			(xy 394.62837 -145.786348) (xy 394.64361 -145.801588) (xy 399.016726 -145.801588) (xy 399.020797 -145.745966)
			(xy 399.032923 -145.691529) (xy 399.052846 -145.639438) (xy 399.080142 -145.590803) (xy 399.114228 -145.54666)
			(xy 399.154377 -145.507951) (xy 399.199735 -145.4755) (xy 399.249335 -145.449999) (xy 399.302119 -145.431992)
			(xy 399.356962 -145.421862) (xy 399.412696 -145.419825) (xy 399.468133 -145.425925) (xy 399.52209 -145.440031)
			(xy 399.573419 -145.461843) (xy 399.621025 -145.490897) (xy 399.663893 -145.526572) (xy 399.70111 -145.568109)
			(xy 399.731883 -145.614622) (xy 399.755555 -145.665119) (xy 399.771623 -145.718526) (xy 399.779743 -145.773702)
			(xy 399.780252 -145.801588) (xy 399.779743 -145.829474) (xy 399.771623 -145.88465) (xy 399.755555 -145.938057)
			(xy 399.731883 -145.988554) (xy 399.70111 -146.035067) (xy 399.663893 -146.076604) (xy 399.621025 -146.112279)
			(xy 399.573419 -146.141333) (xy 399.52209 -146.163145) (xy 399.468133 -146.177251) (xy 399.412696 -146.183351)
			(xy 399.356962 -146.181314) (xy 399.302119 -146.171184) (xy 399.249335 -146.153177) (xy 399.199735 -146.127676)
			(xy 399.154377 -146.095225) (xy 399.114228 -146.056516) (xy 399.080142 -146.012373) (xy 399.052846 -145.963738)
			(xy 399.032923 -145.911647) (xy 399.020797 -145.85721) (xy 399.016726 -145.801588) (xy 394.64361 -145.801588)
			(xy 395.63294 -146.790918) (xy 395.650188 -146.809022) (xy 395.678002 -146.850562) (xy 395.697178 -146.896731)
			(xy 395.706979 -146.945754) (xy 395.707616 -146.97075) (xy 395.707616 -147.419822) (xy 396.174466 -147.419822)
			(xy 396.178537 -147.3642) (xy 396.190663 -147.309763) (xy 396.210586 -147.257672) (xy 396.237882 -147.209037)
			(xy 396.271968 -147.164894) (xy 396.312117 -147.126185) (xy 396.357475 -147.093734) (xy 396.407075 -147.068233)
			(xy 396.459859 -147.050226) (xy 396.514702 -147.040096) (xy 396.570436 -147.038059) (xy 396.625873 -147.044159)
			(xy 396.644322 -147.048982) (xy 399.016726 -147.048982) (xy 399.020797 -146.99336) (xy 399.032923 -146.938923)
			(xy 399.052846 -146.886832) (xy 399.080142 -146.838197) (xy 399.114228 -146.794054) (xy 399.154377 -146.755345)
			(xy 399.199735 -146.722894) (xy 399.249335 -146.697393) (xy 399.302119 -146.679386) (xy 399.356962 -146.669256)
			(xy 399.412696 -146.667219) (xy 399.468133 -146.673319) (xy 399.52209 -146.687425) (xy 399.573419 -146.709237)
			(xy 399.621025 -146.738291) (xy 399.663893 -146.773966) (xy 399.70111 -146.815503) (xy 399.731883 -146.862016)
			(xy 399.755555 -146.912513) (xy 399.771623 -146.96592) (xy 399.779743 -147.021096) (xy 399.780252 -147.048982)
			(xy 399.779743 -147.076868) (xy 399.771623 -147.132044) (xy 399.755555 -147.185451) (xy 399.731883 -147.235948)
			(xy 399.70111 -147.282461) (xy 399.663893 -147.323998) (xy 399.621025 -147.359673) (xy 399.573419 -147.388727)
			(xy 399.52209 -147.410539) (xy 399.468133 -147.424645) (xy 399.412696 -147.430745) (xy 399.356962 -147.428708)
			(xy 399.302119 -147.418578) (xy 399.249335 -147.400571) (xy 399.199735 -147.37507) (xy 399.154377 -147.342619)
			(xy 399.114228 -147.30391) (xy 399.080142 -147.259767) (xy 399.052846 -147.211132) (xy 399.032923 -147.159041)
			(xy 399.020797 -147.104604) (xy 399.016726 -147.048982) (xy 396.644322 -147.048982) (xy 396.67983 -147.058265)
			(xy 396.731159 -147.080077) (xy 396.778765 -147.109131) (xy 396.821633 -147.144806) (xy 396.85885 -147.186343)
			(xy 396.889623 -147.232856) (xy 396.913295 -147.283353) (xy 396.929363 -147.33676) (xy 396.937483 -147.391936)
			(xy 396.937992 -147.419822) (xy 396.937483 -147.447708) (xy 396.929363 -147.502884) (xy 396.913295 -147.556291)
			(xy 396.889623 -147.606788) (xy 396.85885 -147.653301) (xy 396.821633 -147.694838) (xy 396.778765 -147.730513)
			(xy 396.731159 -147.759567) (xy 396.67983 -147.781379) (xy 396.625873 -147.795485) (xy 396.570436 -147.801585)
			(xy 396.514702 -147.799548) (xy 396.459859 -147.789418) (xy 396.407075 -147.771411) (xy 396.357475 -147.74591)
			(xy 396.312117 -147.713459) (xy 396.271968 -147.67475) (xy 396.237882 -147.630607) (xy 396.210586 -147.581972)
			(xy 396.190663 -147.529881) (xy 396.178537 -147.475444) (xy 396.174466 -147.419822) (xy 395.707616 -147.419822)
			(xy 395.707616 -148.435151) (xy 396.37106 -148.435151) (xy 396.37106 -148.380649) (xy 396.378816 -148.326702)
			(xy 396.39417 -148.274408) (xy 396.416809 -148.22483) (xy 396.446274 -148.17898) (xy 396.481963 -148.137788)
			(xy 396.523151 -148.102095) (xy 396.568999 -148.072627) (xy 396.618574 -148.049982) (xy 396.670867 -148.034623)
			(xy 396.724813 -148.026862) (xy 396.752064 -148.026374) (xy 396.779321 -148.026858) (xy 396.833275 -148.034645)
			(xy 396.885571 -148.050035) (xy 396.935143 -148.072716) (xy 396.958312 -148.08708) (xy 396.97025 -148.094446)
			(xy 396.997174 -148.095716) (xy 397.100298 -148.04136) (xy 397.114522 -148.018246) (xy 397.11503 -148.004276)
			(xy 397.116244 -147.977504) (xy 397.125109 -147.924654) (xy 397.141284 -147.873565) (xy 397.16445 -147.825243)
			(xy 397.194152 -147.78064) (xy 397.229805 -147.740632) (xy 397.270707 -147.706009) (xy 397.316052 -147.677452)
			(xy 397.364948 -147.655523) (xy 397.416432 -147.640653) (xy 397.46949 -147.633136) (xy 397.496284 -147.632674)
			(xy 397.523534 -147.633193) (xy 397.57748 -147.640947) (xy 397.629773 -147.656299) (xy 397.679348 -147.678937)
			(xy 397.725198 -147.7084) (xy 397.766388 -147.744088) (xy 397.80208 -147.785275) (xy 397.831547 -147.831122)
			(xy 397.854189 -147.880696) (xy 397.869546 -147.932987) (xy 397.877304 -147.986932) (xy 397.877792 -148.014182)
			(xy 398.003776 -148.014182) (xy 398.004262 -147.986931) (xy 398.012018 -147.932983) (xy 398.027373 -147.880688)
			(xy 398.050015 -147.831111) (xy 398.079481 -147.785261) (xy 398.115172 -147.74407) (xy 398.156363 -147.708379)
			(xy 398.202213 -147.678913) (xy 398.25179 -147.656271) (xy 398.304085 -147.640916) (xy 398.358033 -147.63316)
			(xy 398.412535 -147.63316) (xy 398.466483 -147.640916) (xy 398.518778 -147.656271) (xy 398.568355 -147.678913)
			(xy 398.614205 -147.708379) (xy 398.655396 -147.74407) (xy 398.691087 -147.785261) (xy 398.720553 -147.831111)
			(xy 398.743195 -147.880688) (xy 398.75855 -147.932983) (xy 398.759269 -147.937982) (xy 399.016726 -147.937982)
			(xy 399.020797 -147.88236) (xy 399.032923 -147.827923) (xy 399.052846 -147.775832) (xy 399.080142 -147.727197)
			(xy 399.114228 -147.683054) (xy 399.154377 -147.644345) (xy 399.199735 -147.611894) (xy 399.249335 -147.586393)
			(xy 399.302119 -147.568386) (xy 399.356962 -147.558256) (xy 399.412696 -147.556219) (xy 399.468133 -147.562319)
			(xy 399.52209 -147.576425) (xy 399.573419 -147.598237) (xy 399.621025 -147.627291) (xy 399.663893 -147.662966)
			(xy 399.70111 -147.704503) (xy 399.731883 -147.751016) (xy 399.755555 -147.801513) (xy 399.771623 -147.85492)
			(xy 399.779743 -147.910096) (xy 399.780252 -147.937982) (xy 399.779743 -147.965868) (xy 399.771623 -148.021044)
			(xy 399.755555 -148.074451) (xy 399.731883 -148.124948) (xy 399.70111 -148.171461) (xy 399.663893 -148.212998)
			(xy 399.621025 -148.248673) (xy 399.573419 -148.277727) (xy 399.52209 -148.299539) (xy 399.468133 -148.313645)
			(xy 399.412696 -148.319745) (xy 399.356962 -148.317708) (xy 399.302119 -148.307578) (xy 399.249335 -148.289571)
			(xy 399.199735 -148.26407) (xy 399.154377 -148.231619) (xy 399.114228 -148.19291) (xy 399.080142 -148.148767)
			(xy 399.052846 -148.100132) (xy 399.032923 -148.048041) (xy 399.020797 -147.993604) (xy 399.016726 -147.937982)
			(xy 398.759269 -147.937982) (xy 398.766306 -147.986931) (xy 398.766792 -148.014182) (xy 398.766326 -148.041728)
			(xy 398.75841 -148.096247) (xy 398.742727 -148.149059) (xy 398.719603 -148.199062) (xy 398.68952 -148.245215)
			(xy 398.653105 -148.286555) (xy 398.632426 -148.304758) (xy 398.621425 -148.314681) (xy 398.605327 -148.339543)
			(xy 398.59703 -148.367976) (xy 398.597231 -148.397594) (xy 398.605912 -148.425912) (xy 398.622345 -148.450554)
			(xy 398.645152 -148.469452) (xy 398.658588 -148.4757) (xy 398.684099 -148.487036) (xy 398.731775 -148.516077)
			(xy 398.774711 -148.551755) (xy 398.811989 -148.593309) (xy 398.842815 -148.639851) (xy 398.86653 -148.690388)
			(xy 398.882628 -148.743841) (xy 398.890765 -148.79907) (xy 398.891252 -148.826982) (xy 399.016726 -148.826982)
			(xy 399.020797 -148.77136) (xy 399.032923 -148.716923) (xy 399.052846 -148.664832) (xy 399.080142 -148.616197)
			(xy 399.114228 -148.572054) (xy 399.154377 -148.533345) (xy 399.199735 -148.500894) (xy 399.249335 -148.475393)
			(xy 399.302119 -148.457386) (xy 399.356962 -148.447256) (xy 399.412696 -148.445219) (xy 399.468133 -148.451319)
			(xy 399.52209 -148.465425) (xy 399.573419 -148.487237) (xy 399.621025 -148.516291) (xy 399.663893 -148.551966)
			(xy 399.70111 -148.593503) (xy 399.731883 -148.640016) (xy 399.755555 -148.690513) (xy 399.771623 -148.74392)
			(xy 399.779743 -148.799096) (xy 399.780252 -148.826982) (xy 399.779743 -148.854868) (xy 399.771623 -148.910044)
			(xy 399.755555 -148.963451) (xy 399.731883 -149.013948) (xy 399.70111 -149.060461) (xy 399.663893 -149.101998)
			(xy 399.621025 -149.137673) (xy 399.573419 -149.166727) (xy 399.52209 -149.188539) (xy 399.468133 -149.202645)
			(xy 399.412696 -149.208745) (xy 399.356962 -149.206708) (xy 399.302119 -149.196578) (xy 399.249335 -149.178571)
			(xy 399.199735 -149.15307) (xy 399.154377 -149.120619) (xy 399.114228 -149.08191) (xy 399.080142 -149.037767)
			(xy 399.052846 -148.989132) (xy 399.032923 -148.937041) (xy 399.020797 -148.882604) (xy 399.016726 -148.826982)
			(xy 398.891252 -148.826982) (xy 398.890766 -148.854233) (xy 398.88301 -148.908181) (xy 398.867655 -148.960476)
			(xy 398.845013 -149.010053) (xy 398.815547 -149.055903) (xy 398.779856 -149.097094) (xy 398.738665 -149.132785)
			(xy 398.692815 -149.162251) (xy 398.643238 -149.184893) (xy 398.590943 -149.200248) (xy 398.536995 -149.208004)
			(xy 398.482493 -149.208004) (xy 398.428545 -149.200248) (xy 398.37625 -149.184893) (xy 398.326673 -149.162251)
			(xy 398.280823 -149.132785) (xy 398.239632 -149.097094) (xy 398.203941 -149.055903) (xy 398.174475 -149.010053)
			(xy 398.151833 -148.960476) (xy 398.136478 -148.908181) (xy 398.128722 -148.854233) (xy 398.128236 -148.826982)
			(xy 398.128737 -148.799437) (xy 398.136644 -148.744919) (xy 398.15232 -148.692108) (xy 398.175437 -148.642104)
			(xy 398.205514 -148.595951) (xy 398.241925 -148.55461) (xy 398.262602 -148.536406) (xy 398.273524 -148.526404)
			(xy 398.289618 -148.501561) (xy 398.297918 -148.473148) (xy 398.297727 -148.443548) (xy 398.289062 -148.415245)
			(xy 398.272649 -148.390611) (xy 398.249865 -148.371715) (xy 398.23644 -148.365464) (xy 398.210921 -148.354143)
			(xy 398.163243 -148.325102) (xy 398.120306 -148.289422) (xy 398.083027 -148.247867) (xy 398.052202 -148.201322)
			(xy 398.028489 -148.150782) (xy 398.012394 -148.097326) (xy 398.004261 -148.042095) (xy 398.003776 -148.014182)
			(xy 397.877792 -148.014182) (xy 397.877326 -148.041728) (xy 397.86941 -148.096247) (xy 397.853727 -148.149059)
			(xy 397.830603 -148.199062) (xy 397.80052 -148.245215) (xy 397.764105 -148.286555) (xy 397.743426 -148.304758)
			(xy 397.733266 -148.313394) (xy 397.724122 -148.338032) (xy 397.74114 -148.449792) (xy 397.757396 -148.47062)
			(xy 397.769588 -148.4757) (xy 397.795099 -148.487036) (xy 397.842775 -148.516077) (xy 397.885711 -148.551755)
			(xy 397.922989 -148.593309) (xy 397.953815 -148.639851) (xy 397.97753 -148.690388) (xy 397.993628 -148.743841)
			(xy 398.001765 -148.79907) (xy 398.002252 -148.826982) (xy 398.001766 -148.854233) (xy 397.99401 -148.908181)
			(xy 397.978655 -148.960476) (xy 397.956013 -149.010053) (xy 397.926547 -149.055903) (xy 397.890856 -149.097094)
			(xy 397.849665 -149.132785) (xy 397.803815 -149.162251) (xy 397.754238 -149.184893) (xy 397.701943 -149.200248)
			(xy 397.647995 -149.208004) (xy 397.593493 -149.208004) (xy 397.539545 -149.200248) (xy 397.48725 -149.184893)
			(xy 397.437673 -149.162251) (xy 397.391823 -149.132785) (xy 397.350632 -149.097094) (xy 397.314941 -149.055903)
			(xy 397.285475 -149.010053) (xy 397.262833 -148.960476) (xy 397.247478 -148.908181) (xy 397.239722 -148.854233)
			(xy 397.239236 -148.826982) (xy 397.239737 -148.799437) (xy 397.247644 -148.744919) (xy 397.26332 -148.692108)
			(xy 397.286437 -148.642104) (xy 397.316514 -148.595951) (xy 397.352925 -148.55461) (xy 397.373602 -148.536406)
			(xy 397.383762 -148.52777) (xy 397.392906 -148.503132) (xy 397.375888 -148.391372) (xy 397.359632 -148.370544)
			(xy 397.34744 -148.365464) (xy 397.332538 -148.35893) (xy 397.303797 -148.343668) (xy 397.290036 -148.334984)
			(xy 397.278098 -148.327618) (xy 397.251174 -148.326348) (xy 397.14805 -148.380704) (xy 397.133826 -148.403818)
			(xy 397.133318 -148.417788) (xy 397.132213 -148.444566) (xy 397.123338 -148.497423) (xy 397.107153 -148.548516)
			(xy 397.083975 -148.596842) (xy 397.054262 -148.641447) (xy 397.018598 -148.681455) (xy 396.977685 -148.716077)
			(xy 396.932329 -148.744631) (xy 396.883423 -148.766557) (xy 396.831929 -148.781421) (xy 396.778862 -148.788931)
			(xy 396.752064 -148.78939) (xy 396.724813 -148.788938) (xy 396.670867 -148.781177) (xy 396.618574 -148.765818)
			(xy 396.568999 -148.743173) (xy 396.523151 -148.713705) (xy 396.481963 -148.678012) (xy 396.446274 -148.63682)
			(xy 396.416809 -148.59097) (xy 396.39417 -148.541392) (xy 396.378816 -148.489098) (xy 396.37106 -148.435151)
			(xy 395.707616 -148.435151) (xy 395.707616 -149.296882) (xy 396.370046 -149.296882) (xy 396.374117 -149.24126)
			(xy 396.386243 -149.186823) (xy 396.406166 -149.134732) (xy 396.433462 -149.086097) (xy 396.467548 -149.041954)
			(xy 396.507697 -149.003245) (xy 396.553055 -148.970794) (xy 396.602655 -148.945293) (xy 396.655439 -148.927286)
			(xy 396.710282 -148.917156) (xy 396.766016 -148.915119) (xy 396.821453 -148.921219) (xy 396.87541 -148.935325)
			(xy 396.926739 -148.957137) (xy 396.974345 -148.986191) (xy 397.017213 -149.021866) (xy 397.05443 -149.063403)
			(xy 397.085203 -149.109916) (xy 397.108875 -149.160413) (xy 397.124943 -149.21382) (xy 397.133063 -149.268996)
			(xy 397.133572 -149.296882) (xy 397.133063 -149.324768) (xy 397.124943 -149.379944) (xy 397.108875 -149.433351)
			(xy 397.085203 -149.483848) (xy 397.05443 -149.530361) (xy 397.017213 -149.571898) (xy 396.974345 -149.607573)
			(xy 396.926739 -149.636627) (xy 396.87541 -149.658439) (xy 396.821453 -149.672545) (xy 396.766016 -149.678645)
			(xy 396.710282 -149.676608) (xy 396.655439 -149.666478) (xy 396.602655 -149.648471) (xy 396.553055 -149.62297)
			(xy 396.507697 -149.590519) (xy 396.467548 -149.55181) (xy 396.433462 -149.507667) (xy 396.406166 -149.459032)
			(xy 396.386243 -149.406941) (xy 396.374117 -149.352504) (xy 396.370046 -149.296882) (xy 395.707616 -149.296882)
			(xy 395.707616 -149.715982) (xy 397.238726 -149.715982) (xy 397.242797 -149.66036) (xy 397.254923 -149.605923)
			(xy 397.274846 -149.553832) (xy 397.302142 -149.505197) (xy 397.336228 -149.461054) (xy 397.376377 -149.422345)
			(xy 397.421735 -149.389894) (xy 397.471335 -149.364393) (xy 397.524119 -149.346386) (xy 397.578962 -149.336256)
			(xy 397.634696 -149.334219) (xy 397.690133 -149.340319) (xy 397.74409 -149.354425) (xy 397.795419 -149.376237)
			(xy 397.843025 -149.405291) (xy 397.885893 -149.440966) (xy 397.92311 -149.482503) (xy 397.953883 -149.529016)
			(xy 397.977555 -149.579513) (xy 397.993623 -149.63292) (xy 398.001743 -149.688096) (xy 398.002252 -149.715982)
			(xy 398.127726 -149.715982) (xy 398.131797 -149.66036) (xy 398.143923 -149.605923) (xy 398.163846 -149.553832)
			(xy 398.191142 -149.505197) (xy 398.225228 -149.461054) (xy 398.265377 -149.422345) (xy 398.310735 -149.389894)
			(xy 398.360335 -149.364393) (xy 398.413119 -149.346386) (xy 398.467962 -149.336256) (xy 398.523696 -149.334219)
			(xy 398.579133 -149.340319) (xy 398.63309 -149.354425) (xy 398.684419 -149.376237) (xy 398.732025 -149.405291)
			(xy 398.774893 -149.440966) (xy 398.81211 -149.482503) (xy 398.842883 -149.529016) (xy 398.866555 -149.579513)
			(xy 398.882623 -149.63292) (xy 398.890743 -149.688096) (xy 398.891252 -149.715982) (xy 399.016726 -149.715982)
			(xy 399.020797 -149.66036) (xy 399.032923 -149.605923) (xy 399.052846 -149.553832) (xy 399.080142 -149.505197)
			(xy 399.114228 -149.461054) (xy 399.154377 -149.422345) (xy 399.199735 -149.389894) (xy 399.249335 -149.364393)
			(xy 399.302119 -149.346386) (xy 399.356962 -149.336256) (xy 399.412696 -149.334219) (xy 399.468133 -149.340319)
			(xy 399.52209 -149.354425) (xy 399.573419 -149.376237) (xy 399.621025 -149.405291) (xy 399.663893 -149.440966)
			(xy 399.70111 -149.482503) (xy 399.731883 -149.529016) (xy 399.755555 -149.579513) (xy 399.771623 -149.63292)
			(xy 399.779743 -149.688096) (xy 399.780252 -149.715982) (xy 399.779743 -149.743868) (xy 399.771623 -149.799044)
			(xy 399.755555 -149.852451) (xy 399.731883 -149.902948) (xy 399.70111 -149.949461) (xy 399.663893 -149.990998)
			(xy 399.621025 -150.026673) (xy 399.573419 -150.055727) (xy 399.52209 -150.077539) (xy 399.468133 -150.091645)
			(xy 399.412696 -150.097745) (xy 399.356962 -150.095708) (xy 399.302119 -150.085578) (xy 399.249335 -150.067571)
			(xy 399.199735 -150.04207) (xy 399.154377 -150.009619) (xy 399.114228 -149.97091) (xy 399.080142 -149.926767)
			(xy 399.052846 -149.878132) (xy 399.032923 -149.826041) (xy 399.020797 -149.771604) (xy 399.016726 -149.715982)
			(xy 398.891252 -149.715982) (xy 398.890743 -149.743868) (xy 398.882623 -149.799044) (xy 398.866555 -149.852451)
			(xy 398.842883 -149.902948) (xy 398.81211 -149.949461) (xy 398.774893 -149.990998) (xy 398.732025 -150.026673)
			(xy 398.684419 -150.055727) (xy 398.63309 -150.077539) (xy 398.579133 -150.091645) (xy 398.523696 -150.097745)
			(xy 398.467962 -150.095708) (xy 398.413119 -150.085578) (xy 398.360335 -150.067571) (xy 398.310735 -150.04207)
			(xy 398.265377 -150.009619) (xy 398.225228 -149.97091) (xy 398.191142 -149.926767) (xy 398.163846 -149.878132)
			(xy 398.143923 -149.826041) (xy 398.131797 -149.771604) (xy 398.127726 -149.715982) (xy 398.002252 -149.715982)
			(xy 398.001743 -149.743868) (xy 397.993623 -149.799044) (xy 397.977555 -149.852451) (xy 397.953883 -149.902948)
			(xy 397.92311 -149.949461) (xy 397.885893 -149.990998) (xy 397.843025 -150.026673) (xy 397.795419 -150.055727)
			(xy 397.74409 -150.077539) (xy 397.690133 -150.091645) (xy 397.634696 -150.097745) (xy 397.578962 -150.095708)
			(xy 397.524119 -150.085578) (xy 397.471335 -150.067571) (xy 397.421735 -150.04207) (xy 397.376377 -150.009619)
			(xy 397.336228 -149.97091) (xy 397.302142 -149.926767) (xy 397.274846 -149.878132) (xy 397.254923 -149.826041)
			(xy 397.242797 -149.771604) (xy 397.238726 -149.715982) (xy 395.707616 -149.715982) (xy 395.707616 -150.33498)
			(xy 395.707965 -150.345028) (xy 395.715568 -150.363624) (xy 395.722348 -150.371048) (xy 398.001744 -152.650444)
			(xy 408.315158 -152.650444) (xy 408.319229 -152.594822) (xy 408.331355 -152.540385) (xy 408.351278 -152.488294)
			(xy 408.378574 -152.439659) (xy 408.41266 -152.395516) (xy 408.452809 -152.356807) (xy 408.498167 -152.324356)
			(xy 408.547767 -152.298855) (xy 408.600551 -152.280848) (xy 408.655394 -152.270718) (xy 408.711128 -152.268681)
			(xy 408.766565 -152.274781) (xy 408.820522 -152.288887) (xy 408.871851 -152.310699) (xy 408.919457 -152.339753)
			(xy 408.962325 -152.375428) (xy 408.99872 -152.416048) (xy 419.022302 -152.416048) (xy 419.022302 -152.361552)
			(xy 419.030058 -152.307609) (xy 419.04541 -152.25532) (xy 419.068048 -152.205747) (xy 419.097511 -152.159901)
			(xy 419.133197 -152.118714) (xy 419.174382 -152.083025) (xy 419.220226 -152.05356) (xy 419.269797 -152.030919)
			(xy 419.322086 -152.015563) (xy 419.376028 -152.007804) (xy 419.403276 -152.007316) (xy 419.432193 -152.007846)
			(xy 419.489364 -152.016571) (xy 419.544562 -152.033827) (xy 419.596524 -152.059216) (xy 419.644058 -152.092158)
			(xy 419.686076 -152.131897) (xy 419.704266 -152.154382) (xy 419.711833 -152.163138) (xy 419.732588 -152.173322)
			(xy 419.744144 -152.17394) (xy 419.824408 -152.17394) (xy 419.83598 -152.173395) (xy 419.856752 -152.163185)
			(xy 419.864286 -152.154382) (xy 419.881039 -152.133599) (xy 419.919393 -152.096469) (xy 419.962547 -152.065047)
			(xy 420.009661 -152.039948) (xy 420.059813 -152.021662) (xy 420.112024 -152.010545) (xy 420.165276 -152.006815)
			(xy 420.218528 -152.010545) (xy 420.270739 -152.021662) (xy 420.320891 -152.039948) (xy 420.368005 -152.065047)
			(xy 420.411159 -152.096469) (xy 420.449513 -152.133599) (xy 420.466266 -152.154382) (xy 420.473833 -152.163138)
			(xy 420.494588 -152.173322) (xy 420.506144 -152.17394) (xy 420.586408 -152.17394) (xy 420.59798 -152.173395)
			(xy 420.618752 -152.163185) (xy 420.626286 -152.154382) (xy 420.643039 -152.133599) (xy 420.681393 -152.096469)
			(xy 420.724547 -152.065047) (xy 420.771661 -152.039948) (xy 420.821813 -152.021662) (xy 420.874024 -152.010545)
			(xy 420.927276 -152.006815) (xy 420.980528 -152.010545) (xy 421.032739 -152.021662) (xy 421.082891 -152.039948)
			(xy 421.130005 -152.065047) (xy 421.173159 -152.096469) (xy 421.211513 -152.133599) (xy 421.228266 -152.154382)
			(xy 421.235833 -152.163138) (xy 421.256588 -152.173322) (xy 421.268144 -152.17394) (xy 421.348408 -152.17394)
			(xy 421.35998 -152.173395) (xy 421.380752 -152.163185) (xy 421.388286 -152.154382) (xy 421.40648 -152.131901)
			(xy 421.4485 -152.092167) (xy 421.496034 -152.059228) (xy 421.547995 -152.033839) (xy 421.603192 -152.016582)
			(xy 421.66036 -152.007852) (xy 421.689276 -152.007316) (xy 421.716532 -152.007729) (xy 421.770489 -152.015484)
			(xy 421.822793 -152.030839) (xy 421.872379 -152.053481) (xy 421.918238 -152.082951) (xy 421.959436 -152.118647)
			(xy 421.995135 -152.159843) (xy 422.024607 -152.2057) (xy 422.047253 -152.255285) (xy 422.062611 -152.307588)
			(xy 422.070369 -152.361544) (xy 422.070369 -152.416056) (xy 422.062611 -152.470012) (xy 422.047253 -152.522315)
			(xy 422.024607 -152.5719) (xy 421.995135 -152.617757) (xy 421.959436 -152.658953) (xy 421.918238 -152.694649)
			(xy 421.872379 -152.724119) (xy 421.822793 -152.746761) (xy 421.770489 -152.762116) (xy 421.716532 -152.769871)
			(xy 421.689276 -152.770332) (xy 421.66036 -152.769785) (xy 421.603189 -152.761065) (xy 421.54799 -152.743815)
			(xy 421.496027 -152.718429) (xy 421.448493 -152.685489) (xy 421.406476 -152.64575) (xy 421.388286 -152.623266)
			(xy 421.380732 -152.614497) (xy 421.359967 -152.604319) (xy 421.348408 -152.603708) (xy 421.268144 -152.603708)
			(xy 421.256579 -152.604301) (xy 421.235807 -152.614479) (xy 421.228266 -152.623266) (xy 421.211513 -152.644049)
			(xy 421.173159 -152.681179) (xy 421.130005 -152.712601) (xy 421.082891 -152.7377) (xy 421.032739 -152.755986)
			(xy 420.980528 -152.767103) (xy 420.927276 -152.770833) (xy 420.874024 -152.767103) (xy 420.821813 -152.755986)
			(xy 420.771661 -152.7377) (xy 420.724547 -152.712601) (xy 420.681393 -152.681179) (xy 420.643039 -152.644049)
			(xy 420.626286 -152.623266) (xy 420.618732 -152.614497) (xy 420.597967 -152.604319) (xy 420.586408 -152.603708)
			(xy 420.506144 -152.603708) (xy 420.494579 -152.604301) (xy 420.473807 -152.614479) (xy 420.466266 -152.623266)
			(xy 420.449513 -152.644049) (xy 420.411159 -152.681179) (xy 420.368005 -152.712601) (xy 420.320891 -152.7377)
			(xy 420.270739 -152.755986) (xy 420.218528 -152.767103) (xy 420.165276 -152.770833) (xy 420.112024 -152.767103)
			(xy 420.059813 -152.755986) (xy 420.009661 -152.7377) (xy 419.962547 -152.712601) (xy 419.919393 -152.681179)
			(xy 419.881039 -152.644049) (xy 419.864286 -152.623266) (xy 419.856732 -152.614497) (xy 419.835967 -152.604319)
			(xy 419.824408 -152.603708) (xy 419.744144 -152.603708) (xy 419.732579 -152.604301) (xy 419.711807 -152.614479)
			(xy 419.704266 -152.623266) (xy 419.686086 -152.645759) (xy 419.644065 -152.685495) (xy 419.596528 -152.718434)
			(xy 419.544564 -152.743821) (xy 419.489364 -152.761075) (xy 419.432193 -152.7698) (xy 419.403276 -152.770332)
			(xy 419.376028 -152.769796) (xy 419.322086 -152.762037) (xy 419.269797 -152.746681) (xy 419.220226 -152.72404)
			(xy 419.174382 -152.694575) (xy 419.133197 -152.658886) (xy 419.097511 -152.617699) (xy 419.068048 -152.571853)
			(xy 419.04541 -152.52228) (xy 419.030058 -152.469991) (xy 419.022302 -152.416048) (xy 408.99872 -152.416048)
			(xy 408.999542 -152.416965) (xy 409.030315 -152.463478) (xy 409.053987 -152.513975) (xy 409.070055 -152.567382)
			(xy 409.078175 -152.622558) (xy 409.078684 -152.650444) (xy 409.078175 -152.67833) (xy 409.070055 -152.733506)
			(xy 409.053987 -152.786913) (xy 409.030315 -152.83741) (xy 408.999542 -152.883923) (xy 408.962325 -152.92546)
			(xy 408.919457 -152.961135) (xy 408.871851 -152.990189) (xy 408.820522 -153.012001) (xy 408.766565 -153.026107)
			(xy 408.711128 -153.032207) (xy 408.655394 -153.03017) (xy 408.600551 -153.02004) (xy 408.547767 -153.002033)
			(xy 408.498167 -152.976532) (xy 408.452809 -152.944081) (xy 408.41266 -152.905372) (xy 408.378574 -152.861229)
			(xy 408.351278 -152.812594) (xy 408.331355 -152.760503) (xy 408.319229 -152.706066) (xy 408.315158 -152.650444)
			(xy 398.001744 -152.650444) (xy 398.51711 -153.16581) (xy 411.48203 -153.16581) (xy 411.486101 -153.110188)
			(xy 411.498227 -153.055751) (xy 411.51815 -153.00366) (xy 411.545446 -152.955025) (xy 411.579532 -152.910882)
			(xy 411.619681 -152.872173) (xy 411.665039 -152.839722) (xy 411.714639 -152.814221) (xy 411.767423 -152.796214)
			(xy 411.822266 -152.786084) (xy 411.878 -152.784047) (xy 411.933437 -152.790147) (xy 411.987394 -152.804253)
			(xy 412.038723 -152.826065) (xy 412.086329 -152.855119) (xy 412.129197 -152.890794) (xy 412.166414 -152.932331)
			(xy 412.197187 -152.978844) (xy 412.220859 -153.029341) (xy 412.236927 -153.082748) (xy 412.245047 -153.137924)
			(xy 412.245556 -153.16581) (xy 412.37103 -153.16581) (xy 412.375101 -153.110188) (xy 412.387227 -153.055751)
			(xy 412.40715 -153.00366) (xy 412.434446 -152.955025) (xy 412.468532 -152.910882) (xy 412.508681 -152.872173)
			(xy 412.554039 -152.839722) (xy 412.603639 -152.814221) (xy 412.656423 -152.796214) (xy 412.711266 -152.786084)
			(xy 412.767 -152.784047) (xy 412.822437 -152.790147) (xy 412.876394 -152.804253) (xy 412.927723 -152.826065)
			(xy 412.975329 -152.855119) (xy 413.018197 -152.890794) (xy 413.055414 -152.932331) (xy 413.086187 -152.978844)
			(xy 413.109859 -153.029341) (xy 413.125927 -153.082748) (xy 413.134047 -153.137924) (xy 413.134556 -153.16581)
			(xy 413.26003 -153.16581) (xy 413.264101 -153.110188) (xy 413.276227 -153.055751) (xy 413.29615 -153.00366)
			(xy 413.323446 -152.955025) (xy 413.357532 -152.910882) (xy 413.397681 -152.872173) (xy 413.443039 -152.839722)
			(xy 413.492639 -152.814221) (xy 413.545423 -152.796214) (xy 413.600266 -152.786084) (xy 413.656 -152.784047)
			(xy 413.711437 -152.790147) (xy 413.765394 -152.804253) (xy 413.816723 -152.826065) (xy 413.864329 -152.855119)
			(xy 413.907197 -152.890794) (xy 413.944414 -152.932331) (xy 413.975187 -152.978844) (xy 413.998859 -153.029341)
			(xy 414.014927 -153.082748) (xy 414.023047 -153.137924) (xy 414.023556 -153.16581) (xy 414.14903 -153.16581)
			(xy 414.153101 -153.110188) (xy 414.165227 -153.055751) (xy 414.18515 -153.00366) (xy 414.212446 -152.955025)
			(xy 414.246532 -152.910882) (xy 414.286681 -152.872173) (xy 414.332039 -152.839722) (xy 414.381639 -152.814221)
			(xy 414.434423 -152.796214) (xy 414.489266 -152.786084) (xy 414.545 -152.784047) (xy 414.600437 -152.790147)
			(xy 414.654394 -152.804253) (xy 414.705723 -152.826065) (xy 414.753329 -152.855119) (xy 414.796197 -152.890794)
			(xy 414.833414 -152.932331) (xy 414.864187 -152.978844) (xy 414.887859 -153.029341) (xy 414.903927 -153.082748)
			(xy 414.912047 -153.137924) (xy 414.912556 -153.16581) (xy 414.912047 -153.193696) (xy 414.903927 -153.248872)
			(xy 414.887859 -153.302279) (xy 414.864187 -153.352776) (xy 414.833414 -153.399289) (xy 414.796197 -153.440826)
			(xy 414.753329 -153.476501) (xy 414.705723 -153.505555) (xy 414.654394 -153.527367) (xy 414.600437 -153.541473)
			(xy 414.545 -153.547573) (xy 414.489266 -153.545536) (xy 414.434423 -153.535406) (xy 414.381639 -153.517399)
			(xy 414.332039 -153.491898) (xy 414.286681 -153.459447) (xy 414.246532 -153.420738) (xy 414.212446 -153.376595)
			(xy 414.18515 -153.32796) (xy 414.165227 -153.275869) (xy 414.153101 -153.221432) (xy 414.14903 -153.16581)
			(xy 414.023556 -153.16581) (xy 414.023047 -153.193696) (xy 414.014927 -153.248872) (xy 413.998859 -153.302279)
			(xy 413.975187 -153.352776) (xy 413.944414 -153.399289) (xy 413.907197 -153.440826) (xy 413.864329 -153.476501)
			(xy 413.816723 -153.505555) (xy 413.765394 -153.527367) (xy 413.711437 -153.541473) (xy 413.656 -153.547573)
			(xy 413.600266 -153.545536) (xy 413.545423 -153.535406) (xy 413.492639 -153.517399) (xy 413.443039 -153.491898)
			(xy 413.397681 -153.459447) (xy 413.357532 -153.420738) (xy 413.323446 -153.376595) (xy 413.29615 -153.32796)
			(xy 413.276227 -153.275869) (xy 413.264101 -153.221432) (xy 413.26003 -153.16581) (xy 413.134556 -153.16581)
			(xy 413.134047 -153.193696) (xy 413.125927 -153.248872) (xy 413.109859 -153.302279) (xy 413.086187 -153.352776)
			(xy 413.055414 -153.399289) (xy 413.018197 -153.440826) (xy 412.975329 -153.476501) (xy 412.927723 -153.505555)
			(xy 412.876394 -153.527367) (xy 412.822437 -153.541473) (xy 412.767 -153.547573) (xy 412.711266 -153.545536)
			(xy 412.656423 -153.535406) (xy 412.603639 -153.517399) (xy 412.554039 -153.491898) (xy 412.508681 -153.459447)
			(xy 412.468532 -153.420738) (xy 412.434446 -153.376595) (xy 412.40715 -153.32796) (xy 412.387227 -153.275869)
			(xy 412.375101 -153.221432) (xy 412.37103 -153.16581) (xy 412.245556 -153.16581) (xy 412.245047 -153.193696)
			(xy 412.236927 -153.248872) (xy 412.220859 -153.302279) (xy 412.197187 -153.352776) (xy 412.166414 -153.399289)
			(xy 412.129197 -153.440826) (xy 412.086329 -153.476501) (xy 412.038723 -153.505555) (xy 411.987394 -153.527367)
			(xy 411.933437 -153.541473) (xy 411.878 -153.547573) (xy 411.822266 -153.545536) (xy 411.767423 -153.535406)
			(xy 411.714639 -153.517399) (xy 411.665039 -153.491898) (xy 411.619681 -153.459447) (xy 411.579532 -153.420738)
			(xy 411.545446 -153.376595) (xy 411.51815 -153.32796) (xy 411.498227 -153.275869) (xy 411.486101 -153.221432)
			(xy 411.48203 -153.16581) (xy 398.51711 -153.16581) (xy 400.834098 -155.482798) (xy 410.680916 -155.482798)
			(xy 410.681427 -155.453881) (xy 410.690157 -155.396709) (xy 410.707416 -155.34151) (xy 410.732809 -155.289548)
			(xy 410.765754 -155.242014) (xy 410.805496 -155.199998) (xy 410.827982 -155.181808) (xy 410.83675 -155.174253)
			(xy 410.846927 -155.153488) (xy 410.84754 -155.14193) (xy 410.84754 -155.061666) (xy 410.846953 -155.0501)
			(xy 410.836772 -155.029327) (xy 410.827982 -155.021788) (xy 410.805489 -155.003608) (xy 410.765755 -154.961586)
			(xy 410.732818 -154.914048) (xy 410.707431 -154.862085) (xy 410.690177 -154.806886) (xy 410.68145 -154.749715)
			(xy 410.680916 -154.720798) (xy 410.681355 -154.694076) (xy 410.688826 -154.641156) (xy 410.703609 -154.589796)
			(xy 410.725413 -154.541001) (xy 410.753813 -154.495726) (xy 410.788252 -154.454857) (xy 410.828056 -154.419193)
			(xy 410.872448 -154.389431) (xy 410.896308 -154.37739) (xy 410.909262 -154.37104) (xy 410.924502 -154.347418)
			(xy 410.927296 -154.228038) (xy 410.913072 -154.203654) (xy 410.900372 -154.196542) (xy 410.874888 -154.182125)
			(xy 410.828285 -154.14668) (xy 410.787647 -154.10453) (xy 410.753925 -154.056666) (xy 410.727913 -154.004211)
			(xy 410.710222 -153.948398) (xy 410.701266 -153.890537) (xy 410.700728 -153.861262) (xy 410.701214 -153.834011)
			(xy 410.70897 -153.780063) (xy 410.724325 -153.727768) (xy 410.746967 -153.678191) (xy 410.776433 -153.632341)
			(xy 410.812124 -153.59115) (xy 410.853315 -153.555459) (xy 410.899165 -153.525993) (xy 410.948742 -153.503351)
			(xy 411.001037 -153.487996) (xy 411.054985 -153.48024) (xy 411.109487 -153.48024) (xy 411.163435 -153.487996)
			(xy 411.21573 -153.503351) (xy 411.265307 -153.525993) (xy 411.311157 -153.555459) (xy 411.352348 -153.59115)
			(xy 411.388039 -153.632341) (xy 411.417505 -153.678191) (xy 411.440147 -153.727768) (xy 411.455502 -153.780063)
			(xy 411.463258 -153.834011) (xy 411.463744 -153.861262) (xy 411.463294 -153.887984) (xy 411.455828 -153.940905)
			(xy 411.441048 -153.992265) (xy 411.419247 -154.041061) (xy 411.390848 -154.086337) (xy 411.35641 -154.127206)
			(xy 411.316605 -154.16287) (xy 411.272212 -154.19263) (xy 411.248352 -154.20467) (xy 411.235398 -154.21102)
			(xy 411.220158 -154.234642) (xy 411.217364 -154.354022) (xy 411.231588 -154.378406) (xy 411.244288 -154.385518)
			(xy 411.269789 -154.399908) (xy 411.316393 -154.435355) (xy 411.357033 -154.477509) (xy 411.390754 -154.525378)
			(xy 411.416763 -154.577837) (xy 411.434449 -154.633656) (xy 411.443398 -154.691521) (xy 411.443932 -154.720798)
			(xy 411.443438 -154.749716) (xy 411.434708 -154.80689) (xy 411.417447 -154.86209) (xy 411.39205 -154.914052)
			(xy 411.359101 -154.961585) (xy 411.319354 -155.0036) (xy 411.296866 -155.021788) (xy 411.288108 -155.029354)
			(xy 411.277924 -155.05011) (xy 411.277308 -155.061666) (xy 411.277308 -155.14193) (xy 411.277916 -155.153493)
			(xy 411.288084 -155.174265) (xy 411.296866 -155.181808) (xy 411.319346 -155.200003) (xy 411.359083 -155.242021)
			(xy 411.392024 -155.289555) (xy 411.417413 -155.341515) (xy 411.434669 -155.396713) (xy 411.443398 -155.453882)
			(xy 411.443932 -155.482798) (xy 411.443446 -155.510049) (xy 411.43569 -155.563997) (xy 411.431713 -155.57754)
			(xy 415.148268 -155.57754) (xy 415.148789 -155.548623) (xy 415.157514 -155.491451) (xy 415.17477 -155.436251)
			(xy 415.200161 -155.384288) (xy 415.233105 -155.336755) (xy 415.272847 -155.294739) (xy 415.295334 -155.27655)
			(xy 415.304075 -155.268968) (xy 415.314268 -155.248224) (xy 415.314892 -155.236672) (xy 415.314892 -155.156408)
			(xy 415.314319 -155.14484) (xy 415.304127 -155.124069) (xy 415.295334 -155.11653) (xy 415.272872 -155.098313)
			(xy 415.233134 -155.0563) (xy 415.200191 -155.008771) (xy 415.174799 -154.956814) (xy 415.157538 -154.901621)
			(xy 415.148805 -154.844455) (xy 415.148268 -154.81554) (xy 415.148712 -154.788817) (xy 415.156179 -154.735896)
			(xy 415.170959 -154.684535) (xy 415.192761 -154.635739) (xy 415.22116 -154.590464) (xy 415.2556 -154.549594)
			(xy 415.295406 -154.513931) (xy 415.339799 -154.484172) (xy 415.36366 -154.472132) (xy 415.376614 -154.465782)
			(xy 415.391854 -154.44216) (xy 415.394648 -154.32278) (xy 415.380424 -154.298396) (xy 415.367724 -154.291284)
			(xy 415.342227 -154.276888) (xy 415.295622 -154.241442) (xy 415.254981 -154.19929) (xy 415.22126 -154.151422)
			(xy 415.19525 -154.098963) (xy 415.177563 -154.043145) (xy 415.168614 -153.98528) (xy 415.16808 -153.956004)
			(xy 415.168566 -153.928753) (xy 415.176322 -153.874805) (xy 415.191677 -153.82251) (xy 415.214319 -153.772933)
			(xy 415.243785 -153.727083) (xy 415.279476 -153.685892) (xy 415.320667 -153.650201) (xy 415.366517 -153.620735)
			(xy 415.416094 -153.598093) (xy 415.468389 -153.582738) (xy 415.522337 -153.574982) (xy 415.576839 -153.574982)
			(xy 415.630787 -153.582738) (xy 415.683082 -153.598093) (xy 415.732659 -153.620735) (xy 415.778509 -153.650201)
			(xy 415.8197 -153.685892) (xy 415.855391 -153.727083) (xy 415.884857 -153.772933) (xy 415.907499 -153.82251)
			(xy 415.922854 -153.874805) (xy 415.93061 -153.928753) (xy 415.931096 -153.956004) (xy 415.930652 -153.982726)
			(xy 415.923181 -154.035646) (xy 415.908398 -154.087005) (xy 415.886595 -154.135799) (xy 415.858196 -154.181074)
			(xy 415.823758 -154.221944) (xy 415.783954 -154.257608) (xy 415.739563 -154.28737) (xy 415.715704 -154.299412)
			(xy 415.70275 -154.305762) (xy 415.68751 -154.329384) (xy 415.684716 -154.448764) (xy 415.69894 -154.473148)
			(xy 415.71164 -154.48026) (xy 415.737128 -154.494671) (xy 415.78373 -154.530117) (xy 415.824368 -154.572268)
			(xy 415.858089 -154.620134) (xy 415.8841 -154.672589) (xy 415.901791 -154.728403) (xy 415.910746 -154.786265)
			(xy 415.911284 -154.81554) (xy 415.911053 -154.82755) (xy 419.022278 -154.82755) (xy 419.022278 -154.77305)
			(xy 419.030034 -154.719104) (xy 419.045388 -154.666811) (xy 419.068027 -154.617236) (xy 419.097491 -154.571386)
			(xy 419.13318 -154.530197) (xy 419.174367 -154.494505) (xy 419.220215 -154.465038) (xy 419.269789 -154.442396)
			(xy 419.322081 -154.427039) (xy 419.376026 -154.419279) (xy 419.403276 -154.418792) (xy 419.432194 -154.419293)
			(xy 419.489368 -154.42802) (xy 419.544568 -154.445279) (xy 419.596531 -154.470674) (xy 419.644064 -154.503623)
			(xy 419.686078 -154.543369) (xy 419.704266 -154.565858) (xy 419.711837 -154.57461) (xy 419.732589 -154.584797)
			(xy 419.744144 -154.585416) (xy 419.824408 -154.585416) (xy 419.835976 -154.584844) (xy 419.856746 -154.57465)
			(xy 419.864286 -154.565858) (xy 419.881039 -154.545075) (xy 419.919393 -154.507945) (xy 419.962547 -154.476523)
			(xy 420.009661 -154.451424) (xy 420.059813 -154.433138) (xy 420.112024 -154.422021) (xy 420.165276 -154.418291)
			(xy 420.218528 -154.422021) (xy 420.270739 -154.433138) (xy 420.320891 -154.451424) (xy 420.368005 -154.476523)
			(xy 420.411159 -154.507945) (xy 420.449513 -154.545075) (xy 420.466266 -154.565858) (xy 420.473837 -154.57461)
			(xy 420.494589 -154.584797) (xy 420.506144 -154.585416) (xy 420.586408 -154.585416) (xy 420.597976 -154.584844)
			(xy 420.618746 -154.57465) (xy 420.626286 -154.565858) (xy 420.643039 -154.545075) (xy 420.681393 -154.507945)
			(xy 420.724547 -154.476523) (xy 420.771661 -154.451424) (xy 420.821813 -154.433138) (xy 420.874024 -154.422021)
			(xy 420.927276 -154.418291) (xy 420.980528 -154.422021) (xy 421.032739 -154.433138) (xy 421.082891 -154.451424)
			(xy 421.130005 -154.476523) (xy 421.173159 -154.507945) (xy 421.211513 -154.545075) (xy 421.228266 -154.565858)
			(xy 421.235837 -154.57461) (xy 421.256589 -154.584797) (xy 421.268144 -154.585416) (xy 421.348408 -154.585416)
			(xy 421.359976 -154.584844) (xy 421.380746 -154.57465) (xy 421.388286 -154.565858) (xy 421.406474 -154.543372)
			(xy 421.448496 -154.503639) (xy 421.496032 -154.470702) (xy 421.547993 -154.445314) (xy 421.603191 -154.428058)
			(xy 421.66036 -154.419328) (xy 421.689276 -154.418792) (xy 421.71653 -154.419254) (xy 421.770483 -154.427008)
			(xy 421.822784 -154.442362) (xy 421.872367 -154.465003) (xy 421.918223 -154.49447) (xy 421.959419 -154.530164)
			(xy 421.995115 -154.571357) (xy 422.024586 -154.617212) (xy 422.04723 -154.666793) (xy 422.062587 -154.719093)
			(xy 422.070345 -154.773046) (xy 422.070345 -154.827554) (xy 422.062587 -154.881507) (xy 422.04723 -154.933807)
			(xy 422.024586 -154.983388) (xy 421.995115 -155.029243) (xy 421.959419 -155.070436) (xy 421.918223 -155.10613)
			(xy 421.872367 -155.135597) (xy 421.822784 -155.158238) (xy 421.770483 -155.173592) (xy 421.71653 -155.181346)
			(xy 421.689276 -155.181808) (xy 421.660359 -155.18127) (xy 421.603188 -155.17255) (xy 421.547988 -155.155298)
			(xy 421.496025 -155.12991) (xy 421.448491 -155.096968) (xy 421.406475 -155.057228) (xy 421.388286 -155.034742)
			(xy 421.380736 -155.025968) (xy 421.359968 -155.015794) (xy 421.348408 -155.015184) (xy 421.268144 -155.015184)
			(xy 421.25658 -155.015785) (xy 421.235809 -155.025959) (xy 421.228266 -155.034742) (xy 421.211513 -155.055525)
			(xy 421.173159 -155.092655) (xy 421.130005 -155.124077) (xy 421.082891 -155.149176) (xy 421.032739 -155.167462)
			(xy 420.980528 -155.178579) (xy 420.927276 -155.182309) (xy 420.874024 -155.178579) (xy 420.821813 -155.167462)
			(xy 420.771661 -155.149176) (xy 420.724547 -155.124077) (xy 420.681393 -155.092655) (xy 420.643039 -155.055525)
			(xy 420.626286 -155.034742) (xy 420.618736 -155.025968) (xy 420.597968 -155.015794) (xy 420.586408 -155.015184)
			(xy 420.506144 -155.015184) (xy 420.49458 -155.015785) (xy 420.473809 -155.025959) (xy 420.466266 -155.034742)
			(xy 420.449513 -155.055525) (xy 420.411159 -155.092655) (xy 420.368005 -155.124077) (xy 420.320891 -155.149176)
			(xy 420.270739 -155.167462) (xy 420.218528 -155.178579) (xy 420.165276 -155.182309) (xy 420.112024 -155.178579)
			(xy 420.059813 -155.167462) (xy 420.009661 -155.149176) (xy 419.962547 -155.124077) (xy 419.919393 -155.092655)
			(xy 419.881039 -155.055525) (xy 419.864286 -155.034742) (xy 419.856736 -155.025968) (xy 419.835968 -155.015794)
			(xy 419.824408 -155.015184) (xy 419.744144 -155.015184) (xy 419.73258 -155.015785) (xy 419.711809 -155.025959)
			(xy 419.704266 -155.034742) (xy 419.686105 -155.057251) (xy 419.644078 -155.096982) (xy 419.596536 -155.129917)
			(xy 419.544569 -155.155301) (xy 419.489367 -155.172552) (xy 419.432194 -155.181276) (xy 419.403276 -155.181808)
			(xy 419.376026 -155.181321) (xy 419.322081 -155.173561) (xy 419.269789 -155.158204) (xy 419.220215 -155.135562)
			(xy 419.174367 -155.106095) (xy 419.13318 -155.070403) (xy 419.097491 -155.029214) (xy 419.068027 -154.983364)
			(xy 419.045388 -154.933789) (xy 419.030034 -154.881496) (xy 419.022278 -154.82755) (xy 415.911053 -154.82755)
			(xy 415.910729 -154.844456) (xy 415.902008 -154.901625) (xy 415.884758 -154.956824) (xy 415.859373 -155.008786)
			(xy 415.826436 -155.056321) (xy 415.786701 -155.098339) (xy 415.764218 -155.11653) (xy 415.755433 -155.124069)
			(xy 415.745265 -155.144846) (xy 415.74466 -155.156408) (xy 415.74466 -155.236672) (xy 415.745226 -155.248241)
			(xy 415.755422 -155.269013) (xy 415.764218 -155.27655) (xy 415.786681 -155.294765) (xy 415.826417 -155.33678)
			(xy 415.859358 -155.38431) (xy 415.884749 -155.436267) (xy 415.90201 -155.49146) (xy 415.910745 -155.548625)
			(xy 415.911284 -155.57754) (xy 415.910798 -155.604791) (xy 415.903042 -155.658739) (xy 415.887687 -155.711034)
			(xy 415.865045 -155.760611) (xy 415.835579 -155.806461) (xy 415.799888 -155.847652) (xy 415.758697 -155.883343)
			(xy 415.712847 -155.912809) (xy 415.66327 -155.935451) (xy 415.610975 -155.950806) (xy 415.557027 -155.958562)
			(xy 415.502525 -155.958562) (xy 415.448577 -155.950806) (xy 415.396282 -155.935451) (xy 415.346705 -155.912809)
			(xy 415.300855 -155.883343) (xy 415.259664 -155.847652) (xy 415.223973 -155.806461) (xy 415.194507 -155.760611)
			(xy 415.171865 -155.711034) (xy 415.15651 -155.658739) (xy 415.148754 -155.604791) (xy 415.148268 -155.57754)
			(xy 411.431713 -155.57754) (xy 411.420335 -155.616292) (xy 411.397693 -155.665869) (xy 411.368227 -155.711719)
			(xy 411.332536 -155.75291) (xy 411.291345 -155.788601) (xy 411.245495 -155.818067) (xy 411.195918 -155.840709)
			(xy 411.143623 -155.856064) (xy 411.089675 -155.86382) (xy 411.035173 -155.86382) (xy 410.981225 -155.856064)
			(xy 410.92893 -155.840709) (xy 410.879353 -155.818067) (xy 410.833503 -155.788601) (xy 410.792312 -155.75291)
			(xy 410.756621 -155.711719) (xy 410.727155 -155.665869) (xy 410.704513 -155.616292) (xy 410.689158 -155.563997)
			(xy 410.681402 -155.510049) (xy 410.680916 -155.482798) (xy 400.834098 -155.482798) (xy 401.948142 -156.596842)
			(xy 419.77132 -156.596842) (xy 419.775391 -156.54122) (xy 419.787517 -156.486783) (xy 419.80744 -156.434692)
			(xy 419.834736 -156.386057) (xy 419.868822 -156.341914) (xy 419.908971 -156.303205) (xy 419.954329 -156.270754)
			(xy 420.003929 -156.245253) (xy 420.056713 -156.227246) (xy 420.111556 -156.217116) (xy 420.16729 -156.215079)
			(xy 420.222727 -156.221179) (xy 420.276684 -156.235285) (xy 420.328013 -156.257097) (xy 420.375619 -156.286151)
			(xy 420.418487 -156.321826) (xy 420.455704 -156.363363) (xy 420.486477 -156.409876) (xy 420.510149 -156.460373)
			(xy 420.526217 -156.51378) (xy 420.534337 -156.568956) (xy 420.534846 -156.596842) (xy 420.534337 -156.624728)
			(xy 420.526217 -156.679904) (xy 420.510149 -156.733311) (xy 420.486477 -156.783808) (xy 420.455704 -156.830321)
			(xy 420.418487 -156.871858) (xy 420.375619 -156.907533) (xy 420.328013 -156.936587) (xy 420.276684 -156.958399)
			(xy 420.222727 -156.972505) (xy 420.16729 -156.978605) (xy 420.111556 -156.976568) (xy 420.056713 -156.966438)
			(xy 420.003929 -156.948431) (xy 419.954329 -156.92293) (xy 419.908971 -156.890479) (xy 419.868822 -156.85177)
			(xy 419.834736 -156.807627) (xy 419.80744 -156.758992) (xy 419.787517 -156.706901) (xy 419.775391 -156.652464)
			(xy 419.77132 -156.596842) (xy 401.948142 -156.596842) (xy 402.569934 -157.218634) (xy 417.996114 -157.218634)
			(xy 418.000185 -157.163012) (xy 418.012311 -157.108575) (xy 418.032234 -157.056484) (xy 418.05953 -157.007849)
			(xy 418.093616 -156.963706) (xy 418.133765 -156.924997) (xy 418.179123 -156.892546) (xy 418.228723 -156.867045)
			(xy 418.281507 -156.849038) (xy 418.33635 -156.838908) (xy 418.392084 -156.836871) (xy 418.447521 -156.842971)
			(xy 418.501478 -156.857077) (xy 418.552807 -156.878889) (xy 418.600413 -156.907943) (xy 418.643281 -156.943618)
			(xy 418.680498 -156.985155) (xy 418.711271 -157.031668) (xy 418.734943 -157.082165) (xy 418.751011 -157.135572)
			(xy 418.759131 -157.190748) (xy 418.75964 -157.218634) (xy 418.759131 -157.24652) (xy 418.751011 -157.301696)
			(xy 418.734943 -157.355103) (xy 418.711271 -157.4056) (xy 418.680498 -157.452113) (xy 418.643281 -157.49365)
			(xy 418.600413 -157.529325) (xy 418.552807 -157.558379) (xy 418.501478 -157.580191) (xy 418.447521 -157.594297)
			(xy 418.392084 -157.600397) (xy 418.33635 -157.59836) (xy 418.281507 -157.58823) (xy 418.228723 -157.570223)
			(xy 418.179123 -157.544722) (xy 418.133765 -157.512271) (xy 418.093616 -157.473562) (xy 418.05953 -157.429419)
			(xy 418.032234 -157.380784) (xy 418.012311 -157.328693) (xy 418.000185 -157.274256) (xy 417.996114 -157.218634)
			(xy 402.569934 -157.218634) (xy 404.779226 -159.427926) (xy 414.223454 -159.427926) (xy 414.22394 -159.400675)
			(xy 414.231696 -159.346727) (xy 414.247051 -159.294432) (xy 414.269693 -159.244855) (xy 414.299159 -159.199005)
			(xy 414.33485 -159.157814) (xy 414.376041 -159.122123) (xy 414.421891 -159.092657) (xy 414.471468 -159.070015)
			(xy 414.523763 -159.05466) (xy 414.577711 -159.046904) (xy 414.632213 -159.046904) (xy 414.686161 -159.05466)
			(xy 414.738456 -159.070015) (xy 414.788033 -159.092657) (xy 414.833883 -159.122123) (xy 414.875074 -159.157814)
			(xy 414.910765 -159.199005) (xy 414.940231 -159.244855) (xy 414.962873 -159.294432) (xy 414.978228 -159.346727)
			(xy 414.985984 -159.400675) (xy 414.98647 -159.427926) (xy 414.985809 -159.459489) (xy 414.975423 -159.521754)
			(xy 414.954937 -159.581463) (xy 414.940496 -159.609536) (xy 414.93567 -159.618426) (xy 414.933638 -159.637984)
			(xy 414.959292 -159.726122) (xy 414.971738 -159.741616) (xy 414.980628 -159.746696) (xy 414.987994 -159.75076)
			(xy 414.997646 -159.756602) (xy 415.019744 -159.758634) (xy 415.114232 -159.725106) (xy 415.130234 -159.709612)
			(xy 415.134298 -159.699198) (xy 415.144978 -159.672415) (xy 415.173267 -159.622172) (xy 415.208799 -159.576762)
			(xy 415.250763 -159.537219) (xy 415.298203 -159.504446) (xy 415.350036 -159.479189) (xy 415.405082 -159.462026)
			(xy 415.462084 -159.453346) (xy 415.490914 -159.452818) (xy 415.518166 -159.453253) (xy 415.572116 -159.461011)
			(xy 415.624413 -159.476369) (xy 415.673992 -159.499012) (xy 415.719844 -159.528481) (xy 415.761035 -159.564175)
			(xy 415.796727 -159.605368) (xy 415.826194 -159.65122) (xy 415.848836 -159.7008) (xy 415.864192 -159.753097)
			(xy 415.871948 -159.807048) (xy 415.871948 -159.861552) (xy 415.864192 -159.915503) (xy 415.854839 -159.947356)
			(xy 416.113722 -159.947356) (xy 416.114177 -159.91988) (xy 416.122076 -159.865499) (xy 416.137703 -159.812816)
			(xy 416.160735 -159.762924) (xy 416.190693 -159.716857) (xy 416.208464 -159.695896) (xy 416.21456 -159.688784)
			(xy 416.22091 -159.671766) (xy 416.22091 -159.585914) (xy 416.21456 -159.568896) (xy 416.208464 -159.561784)
			(xy 416.190706 -159.540817) (xy 416.160781 -159.494736) (xy 416.137768 -159.444843) (xy 416.122141 -159.392167)
			(xy 416.114222 -159.337796) (xy 416.113722 -159.310324) (xy 416.114208 -159.283073) (xy 416.121964 -159.229125)
			(xy 416.137319 -159.17683) (xy 416.159961 -159.127253) (xy 416.189427 -159.081403) (xy 416.225118 -159.040212)
			(xy 416.266309 -159.004521) (xy 416.312159 -158.975055) (xy 416.361736 -158.952413) (xy 416.414031 -158.937058)
			(xy 416.467979 -158.929302) (xy 416.522481 -158.929302) (xy 416.576429 -158.937058) (xy 416.628724 -158.952413)
			(xy 416.678301 -158.975055) (xy 416.724151 -159.004521) (xy 416.765342 -159.040212) (xy 416.801033 -159.081403)
			(xy 416.830499 -159.127253) (xy 416.853141 -159.17683) (xy 416.868496 -159.229125) (xy 416.876252 -159.283073)
			(xy 416.876738 -159.310324) (xy 416.876256 -159.337799) (xy 416.868362 -159.392178) (xy 416.85274 -159.44486)
			(xy 416.829715 -159.494753) (xy 416.799763 -159.540822) (xy 416.781996 -159.561784) (xy 416.7759 -159.568896)
			(xy 416.76955 -159.585914) (xy 416.76955 -159.671766) (xy 416.7759 -159.688784) (xy 416.781996 -159.695896)
			(xy 416.799738 -159.716876) (xy 416.829667 -159.762952) (xy 416.852684 -159.812842) (xy 416.868314 -159.865515)
			(xy 416.876236 -159.919885) (xy 416.876738 -159.947356) (xy 416.876252 -159.974607) (xy 416.874619 -159.985964)
			(xy 417.451538 -159.985964) (xy 417.455609 -159.930342) (xy 417.467735 -159.875905) (xy 417.487658 -159.823814)
			(xy 417.514954 -159.775179) (xy 417.54904 -159.731036) (xy 417.589189 -159.692327) (xy 417.634547 -159.659876)
			(xy 417.684147 -159.634375) (xy 417.736931 -159.616368) (xy 417.791774 -159.606238) (xy 417.847508 -159.604201)
			(xy 417.902945 -159.610301) (xy 417.956902 -159.624407) (xy 418.008231 -159.646219) (xy 418.055837 -159.675273)
			(xy 418.098705 -159.710948) (xy 418.135922 -159.752485) (xy 418.166695 -159.798998) (xy 418.190367 -159.849495)
			(xy 418.206435 -159.902902) (xy 418.214555 -159.958078) (xy 418.215064 -159.985964) (xy 418.214555 -160.01385)
			(xy 418.206435 -160.069026) (xy 418.190367 -160.122433) (xy 418.166695 -160.17293) (xy 418.135922 -160.219443)
			(xy 418.098705 -160.26098) (xy 418.055837 -160.296655) (xy 418.008231 -160.325709) (xy 417.956902 -160.347521)
			(xy 417.902945 -160.361627) (xy 417.847508 -160.367727) (xy 417.791774 -160.36569) (xy 417.736931 -160.35556)
			(xy 417.684147 -160.337553) (xy 417.634547 -160.312052) (xy 417.589189 -160.279601) (xy 417.54904 -160.240892)
			(xy 417.514954 -160.196749) (xy 417.487658 -160.148114) (xy 417.467735 -160.096023) (xy 417.455609 -160.041586)
			(xy 417.451538 -159.985964) (xy 416.874619 -159.985964) (xy 416.868496 -160.028555) (xy 416.853141 -160.08085)
			(xy 416.830499 -160.130427) (xy 416.801033 -160.176277) (xy 416.765342 -160.217468) (xy 416.724151 -160.253159)
			(xy 416.678301 -160.282625) (xy 416.628724 -160.305267) (xy 416.576429 -160.320622) (xy 416.522481 -160.328378)
			(xy 416.467979 -160.328378) (xy 416.414031 -160.320622) (xy 416.361736 -160.305267) (xy 416.312159 -160.282625)
			(xy 416.266309 -160.253159) (xy 416.225118 -160.217468) (xy 416.189427 -160.176277) (xy 416.159961 -160.130427)
			(xy 416.137319 -160.08085) (xy 416.121964 -160.028555) (xy 416.114208 -159.974607) (xy 416.113722 -159.947356)
			(xy 415.854839 -159.947356) (xy 415.848836 -159.9678) (xy 415.826194 -160.01738) (xy 415.796727 -160.063232)
			(xy 415.761035 -160.104425) (xy 415.719844 -160.140119) (xy 415.673992 -160.169588) (xy 415.624413 -160.192231)
			(xy 415.572116 -160.207589) (xy 415.518166 -160.215347) (xy 415.490914 -160.215834) (xy 415.465679 -160.215426)
			(xy 415.415646 -160.208811) (xy 415.366925 -160.195641) (xy 415.320373 -160.176147) (xy 415.298382 -160.163764)
			(xy 415.28873 -160.157922) (xy 415.266632 -160.15589) (xy 415.172144 -160.189418) (xy 415.156142 -160.204912)
			(xy 415.152078 -160.215326) (xy 415.141347 -160.242087) (xy 415.113063 -160.292327) (xy 415.077537 -160.337735)
			(xy 415.03558 -160.377277) (xy 414.988148 -160.410052) (xy 414.936322 -160.435313) (xy 414.881285 -160.452484)
			(xy 414.824289 -160.461173) (xy 414.795462 -160.461706) (xy 414.76821 -160.461258) (xy 414.714261 -160.453496)
			(xy 414.661965 -160.438136) (xy 414.612388 -160.41549) (xy 414.566537 -160.38602) (xy 414.525347 -160.350324)
			(xy 414.489656 -160.309131) (xy 414.460191 -160.263277) (xy 414.43755 -160.213697) (xy 414.422196 -160.1614)
			(xy 414.41444 -160.10745) (xy 414.413954 -160.080198) (xy 414.414622 -160.048636) (xy 414.425005 -159.98637)
			(xy 414.445487 -159.926661) (xy 414.459928 -159.898588) (xy 414.464754 -159.889698) (xy 414.466786 -159.87014)
			(xy 414.441132 -159.782002) (xy 414.428686 -159.766508) (xy 414.419796 -159.761428) (xy 414.394678 -159.746907)
			(xy 414.348796 -159.711399) (xy 414.308822 -159.66935) (xy 414.275679 -159.621732) (xy 414.250131 -159.569642)
			(xy 414.232768 -159.514284) (xy 414.223991 -159.456935) (xy 414.223454 -159.427926) (xy 404.779226 -159.427926)
			(xy 407.053288 -161.701988) (xy 410.43733 -161.701988) (xy 410.437846 -161.674415) (xy 410.445787 -161.619844)
			(xy 410.461501 -161.566985) (xy 410.484662 -161.516938) (xy 410.514786 -161.470747) (xy 410.551246 -161.429375)
			(xy 410.57195 -161.411158) (xy 410.580091 -161.403576) (xy 410.589431 -161.383409) (xy 410.589984 -161.372296)
			(xy 410.589984 -161.29508) (xy 410.589448 -161.283966) (xy 410.580088 -161.263807) (xy 410.57195 -161.256218)
			(xy 410.55123 -161.238017) (xy 410.514762 -161.196645) (xy 410.484632 -161.150454) (xy 410.461467 -161.100405)
			(xy 410.44575 -161.047542) (xy 410.43781 -160.992967) (xy 410.437811 -160.937817) (xy 410.445754 -160.883243)
			(xy 410.461472 -160.83038) (xy 410.484639 -160.780332) (xy 410.514772 -160.734142) (xy 410.551241 -160.692772)
			(xy 410.57195 -160.674558) (xy 410.580091 -160.666976) (xy 410.589431 -160.646809) (xy 410.589984 -160.635696)
			(xy 410.589984 -160.55848) (xy 410.589448 -160.547366) (xy 410.580088 -160.527207) (xy 410.57195 -160.519618)
			(xy 410.551234 -160.501412) (xy 410.514767 -160.460041) (xy 410.484636 -160.413849) (xy 410.461472 -160.363801)
			(xy 410.445756 -160.310938) (xy 410.437816 -160.256363) (xy 410.43733 -160.228788) (xy 410.437744 -160.201533)
			(xy 410.445503 -160.147578) (xy 410.460863 -160.095277) (xy 410.48351 -160.045694) (xy 410.512982 -159.99984)
			(xy 410.548681 -159.958646) (xy 410.58988 -159.922952) (xy 410.635738 -159.893486) (xy 410.685324 -159.870845)
			(xy 410.737627 -159.855493) (xy 410.791583 -159.84774) (xy 410.818838 -159.84728) (xy 410.846694 -159.847784)
			(xy 410.901809 -159.855912) (xy 410.955159 -159.871962) (xy 411.005611 -159.895592) (xy 411.052095 -159.926301)
			(xy 411.093624 -159.963438) (xy 411.129317 -160.006215) (xy 411.158417 -160.053723) (xy 411.180305 -160.104955)
			(xy 411.1879 -160.13176) (xy 411.190186 -160.14065) (xy 411.200854 -160.15589) (xy 411.272736 -160.203642)
			(xy 411.29077 -160.207706) (xy 411.299914 -160.206436) (xy 411.312931 -160.204767) (xy 411.339115 -160.202987)
			(xy 411.352238 -160.20288) (xy 411.366387 -160.20297) (xy 411.39461 -160.205007) (xy 411.408626 -160.206944)
			(xy 411.418786 -160.208468) (xy 411.438344 -160.203642) (xy 411.512766 -160.147762) (xy 411.522926 -160.130236)
			(xy 411.524196 -160.120076) (xy 411.528288 -160.092923) (xy 411.543259 -160.040092) (xy 411.565649 -159.989953)
			(xy 411.594995 -159.943541) (xy 411.630692 -159.901816) (xy 411.672002 -159.865639) (xy 411.718071 -159.835758)
			(xy 411.767948 -159.81279) (xy 411.820602 -159.797209) (xy 411.874946 -159.789337) (xy 411.902402 -159.78886)
			(xy 411.929652 -159.789376) (xy 411.983597 -159.797132) (xy 412.035889 -159.812486) (xy 412.085464 -159.835125)
			(xy 412.131313 -159.864588) (xy 412.172502 -159.900276) (xy 412.208194 -159.941463) (xy 412.237661 -159.987309)
			(xy 412.260304 -160.036883) (xy 412.275662 -160.089174) (xy 412.283422 -160.143118) (xy 412.28391 -160.170368)
			(xy 412.283419 -160.197942) (xy 412.275471 -160.252513) (xy 412.259751 -160.305372) (xy 412.236585 -160.355418)
			(xy 412.206458 -160.401609) (xy 412.169995 -160.442981) (xy 412.14929 -160.461198) (xy 412.141175 -160.468804)
			(xy 412.131819 -160.488953) (xy 412.131256 -160.50006) (xy 412.131256 -160.577276) (xy 412.131804 -160.588389)
			(xy 412.141155 -160.608548) (xy 412.14929 -160.616138) (xy 412.170021 -160.634328) (xy 412.20649 -160.675701)
			(xy 412.23662 -160.721895) (xy 412.259782 -160.771947) (xy 412.275494 -160.824814) (xy 412.283428 -160.879392)
			(xy 412.283462 -160.881314) (xy 416.872418 -160.881314) (xy 416.876489 -160.825692) (xy 416.888615 -160.771255)
			(xy 416.908538 -160.719164) (xy 416.935834 -160.670529) (xy 416.96992 -160.626386) (xy 417.010069 -160.587677)
			(xy 417.055427 -160.555226) (xy 417.105027 -160.529725) (xy 417.157811 -160.511718) (xy 417.212654 -160.501588)
			(xy 417.268388 -160.499551) (xy 417.323825 -160.505651) (xy 417.377782 -160.519757) (xy 417.429111 -160.541569)
			(xy 417.476717 -160.570623) (xy 417.519585 -160.606298) (xy 417.556802 -160.647835) (xy 417.587575 -160.694348)
			(xy 417.611247 -160.744845) (xy 417.627315 -160.798252) (xy 417.635435 -160.853428) (xy 417.635944 -160.881314)
			(xy 417.635435 -160.9092) (xy 417.627315 -160.964376) (xy 417.611247 -161.017783) (xy 417.587575 -161.06828)
			(xy 417.556802 -161.114793) (xy 417.519585 -161.15633) (xy 417.476717 -161.192005) (xy 417.429111 -161.221059)
			(xy 417.377782 -161.242871) (xy 417.323825 -161.256977) (xy 417.268388 -161.263077) (xy 417.212654 -161.26104)
			(xy 417.157811 -161.25091) (xy 417.105027 -161.232903) (xy 417.055427 -161.207402) (xy 417.010069 -161.174951)
			(xy 416.96992 -161.136242) (xy 416.935834 -161.092099) (xy 416.908538 -161.043464) (xy 416.888615 -160.991373)
			(xy 416.876489 -160.936936) (xy 416.872418 -160.881314) (xy 412.283462 -160.881314) (xy 412.28391 -160.906968)
			(xy 412.283415 -160.93422) (xy 412.275662 -160.98817) (xy 412.26031 -161.040467) (xy 412.237672 -161.090047)
			(xy 412.208207 -161.1359) (xy 412.172517 -161.177093) (xy 412.131327 -161.212787) (xy 412.085477 -161.242256)
			(xy 412.035899 -161.264899) (xy 411.983603 -161.280255) (xy 411.929654 -161.288013) (xy 411.902402 -161.288476)
			(xy 411.868112 -161.286952) (xy 411.857952 -161.285936) (xy 411.838648 -161.292032) (xy 411.768036 -161.351214)
			(xy 411.758638 -161.369248) (xy 411.757622 -161.379408) (xy 411.75463 -161.407576) (xy 411.741462 -161.462667)
			(xy 411.720289 -161.515204) (xy 411.691577 -161.56403) (xy 411.655957 -161.608072) (xy 411.614214 -161.646359)
			(xy 411.567266 -161.67805) (xy 411.516147 -161.702447) (xy 411.46198 -161.719013) (xy 411.405959 -161.727383)
			(xy 411.377638 -161.727896) (xy 411.359619 -161.72768) (xy 411.323744 -161.724243) (xy 411.30601 -161.721038)
			(xy 411.296612 -161.71926) (xy 411.277562 -161.72307) (xy 411.202378 -161.770822) (xy 411.190948 -161.78657)
			(xy 411.188662 -161.795968) (xy 411.181299 -161.823022) (xy 411.159665 -161.87475) (xy 411.130696 -161.922756)
			(xy 411.095016 -161.966007) (xy 411.053392 -162.003573) (xy 411.006721 -162.034646) (xy 410.956005 -162.058557)
			(xy 410.902338 -162.074791) (xy 410.846873 -162.082999) (xy 410.818838 -162.083496) (xy 410.791586 -162.083009)
			(xy 410.737635 -162.075257) (xy 410.685337 -162.059905) (xy 410.635756 -162.037266) (xy 410.589902 -162.007801)
			(xy 410.548709 -161.97211) (xy 410.513014 -161.930919) (xy 410.483546 -161.885067) (xy 410.460904 -161.835488)
			(xy 410.445548 -161.783191) (xy 410.437793 -161.72924) (xy 410.43733 -161.701988) (xy 407.053288 -161.701988)
			(xy 408.607514 -163.256214) (xy 412.105348 -163.256214) (xy 412.105858 -163.227297) (xy 412.114586 -163.170124)
			(xy 412.131845 -163.114924) (xy 412.157238 -163.062962) (xy 412.190184 -163.015429) (xy 412.229927 -162.973413)
			(xy 412.252414 -162.955224) (xy 412.261163 -162.94765) (xy 412.271353 -162.9269) (xy 412.271972 -162.915346)
			(xy 412.271972 -162.835082) (xy 412.271422 -162.823511) (xy 412.261214 -162.80274) (xy 412.252414 -162.795204)
			(xy 412.229935 -162.777007) (xy 412.190199 -162.734989) (xy 412.157259 -162.687456) (xy 412.13187 -162.635495)
			(xy 412.114613 -162.580299) (xy 412.105883 -162.52313) (xy 412.105348 -162.494214) (xy 412.105894 -162.466154)
			(xy 412.114126 -162.410641) (xy 412.1304 -162.356932) (xy 412.154364 -162.306186) (xy 412.185502 -162.259497)
			(xy 412.223142 -162.217872) (xy 412.266473 -162.182208) (xy 412.29026 -162.167316) (xy 412.299912 -162.161474)
			(xy 412.312104 -162.14344) (xy 412.329122 -162.04565) (xy 412.323534 -162.024568) (xy 412.316422 -162.015678)
			(xy 412.300531 -161.995603) (xy 412.273783 -161.951945) (xy 412.253257 -161.905041) (xy 412.239338 -161.855769)
			(xy 412.232287 -161.805057) (xy 412.23184 -161.779458) (xy 412.232317 -161.752843) (xy 412.239898 -161.700154)
			(xy 412.254898 -161.649081) (xy 412.277014 -161.600662) (xy 412.305794 -161.555882) (xy 412.340653 -161.515653)
			(xy 412.380882 -161.480794) (xy 412.425662 -161.452014) (xy 412.474081 -161.429898) (xy 412.525154 -161.414898)
			(xy 412.577843 -161.407317) (xy 412.604458 -161.40684) (xy 412.63088 -161.407278) (xy 412.683196 -161.414735)
			(xy 412.733934 -161.429505) (xy 412.782078 -161.451293) (xy 412.826663 -161.479661) (xy 412.847028 -161.496502)
			(xy 412.853886 -161.502598) (xy 412.870904 -161.508694) (xy 412.955232 -161.508694) (xy 412.97225 -161.502598)
			(xy 412.979108 -161.496502) (xy 412.999474 -161.479663) (xy 413.04406 -161.451298) (xy 413.092204 -161.429511)
			(xy 413.142941 -161.41474) (xy 413.195256 -161.40728) (xy 413.2481 -161.40728) (xy 413.300415 -161.41474)
			(xy 413.351152 -161.429511) (xy 413.399296 -161.451298) (xy 413.443882 -161.479663) (xy 413.464248 -161.496502)
			(xy 413.471106 -161.502598) (xy 413.488124 -161.508694) (xy 413.572452 -161.508694) (xy 413.58947 -161.502598)
			(xy 413.596328 -161.496502) (xy 413.616683 -161.479651) (xy 413.661276 -161.451298) (xy 413.709423 -161.429521)
			(xy 413.760162 -161.414756) (xy 413.812476 -161.407299) (xy 413.838898 -161.40684) (xy 413.866782 -161.407419)
			(xy 413.921926 -161.415731) (xy 413.975216 -161.432168) (xy 414.025461 -161.456364) (xy 414.071538 -161.487779)
			(xy 414.112419 -161.525711) (xy 414.147189 -161.569311) (xy 414.175073 -161.617607) (xy 414.195447 -161.669519)
			(xy 414.207856 -161.723889) (xy 414.212024 -161.7795) (xy 414.207856 -161.835111) (xy 414.195447 -161.889481)
			(xy 414.175073 -161.941393) (xy 414.147189 -161.989689) (xy 414.112419 -162.033289) (xy 414.071538 -162.071221)
			(xy 414.025461 -162.102636) (xy 413.975216 -162.126832) (xy 413.921926 -162.143269) (xy 413.866782 -162.151581)
			(xy 413.838898 -162.152076) (xy 413.812477 -162.151601) (xy 413.760163 -162.144153) (xy 413.709425 -162.129391)
			(xy 413.661281 -162.107611) (xy 413.616695 -162.079251) (xy 413.596328 -162.062414) (xy 413.58947 -162.056318)
			(xy 413.572452 -162.050222) (xy 413.488124 -162.050222) (xy 413.471106 -162.056318) (xy 413.464248 -162.062414)
			(xy 413.443882 -162.079253) (xy 413.399296 -162.107618) (xy 413.351152 -162.129405) (xy 413.300415 -162.144176)
			(xy 413.2481 -162.151636) (xy 413.195256 -162.151636) (xy 413.142941 -162.144176) (xy 413.092204 -162.129405)
			(xy 413.04406 -162.107618) (xy 412.999474 -162.079253) (xy 412.979108 -162.062414) (xy 412.97225 -162.056318)
			(xy 412.955232 -162.050222) (xy 412.870904 -162.050222) (xy 412.853886 -162.056318) (xy 412.847028 -162.062414)
			(xy 412.836226 -162.071478) (xy 412.813466 -162.088129) (xy 412.801562 -162.095688) (xy 412.79191 -162.10153)
			(xy 412.779972 -162.119818) (xy 412.764732 -162.218116) (xy 412.770574 -162.238944) (xy 412.77794 -162.24758)
			(xy 412.794941 -162.268341) (xy 412.823546 -162.31374) (xy 412.845507 -162.3627) (xy 412.860393 -162.414253)
			(xy 412.867909 -162.467384) (xy 412.868364 -162.494214) (xy 412.867797 -162.523129) (xy 412.85908 -162.580299)
			(xy 412.841833 -162.635497) (xy 412.81645 -162.687459) (xy 412.783514 -162.734994) (xy 412.761405 -162.758374)
			(xy 417.83127 -162.758374) (xy 417.831752 -162.730463) (xy 417.83989 -162.675237) (xy 417.855988 -162.621786)
			(xy 417.879703 -162.571252) (xy 417.910529 -162.524712) (xy 417.928806 -162.503612) (xy 417.935156 -162.4965)
			(xy 417.94176 -162.479228) (xy 417.94176 -162.392106) (xy 417.935156 -162.374834) (xy 417.928806 -162.367722)
			(xy 417.910518 -162.346631) (xy 417.879692 -162.30009) (xy 417.855978 -162.249554) (xy 417.839884 -162.1961)
			(xy 417.831753 -162.140872) (xy 417.83127 -162.11296) (xy 417.831756 -162.085709) (xy 417.839512 -162.031761)
			(xy 417.854867 -161.979466) (xy 417.877509 -161.929889) (xy 417.906975 -161.884039) (xy 417.942666 -161.842848)
			(xy 417.983857 -161.807157) (xy 418.029707 -161.777691) (xy 418.079284 -161.755049) (xy 418.131579 -161.739694)
			(xy 418.185527 -161.731938) (xy 418.240029 -161.731938) (xy 418.293977 -161.739694) (xy 418.346272 -161.755049)
			(xy 418.395849 -161.777691) (xy 418.441699 -161.807157) (xy 418.48289 -161.842848) (xy 418.518581 -161.884039)
			(xy 418.548047 -161.929889) (xy 418.570689 -161.979466) (xy 418.586044 -162.031761) (xy 418.5938 -162.085709)
			(xy 418.594286 -162.11296) (xy 418.59381 -162.140871) (xy 418.585669 -162.196097) (xy 418.569568 -162.249547)
			(xy 418.545852 -162.300082) (xy 418.515027 -162.346621) (xy 418.49675 -162.367722) (xy 418.4904 -162.374834)
			(xy 418.483796 -162.392106) (xy 418.483796 -162.479228) (xy 418.4904 -162.4965) (xy 418.49675 -162.503612)
			(xy 418.515016 -162.524721) (xy 418.545843 -162.571258) (xy 418.56956 -162.62179) (xy 418.58566 -162.675239)
			(xy 418.593798 -162.730464) (xy 418.594286 -162.758374) (xy 418.5938 -162.785625) (xy 418.586044 -162.839573)
			(xy 418.570689 -162.891868) (xy 418.548047 -162.941445) (xy 418.518581 -162.987295) (xy 418.48289 -163.028486)
			(xy 418.441699 -163.064177) (xy 418.395849 -163.093643) (xy 418.346272 -163.116285) (xy 418.293977 -163.13164)
			(xy 418.240029 -163.139396) (xy 418.185527 -163.139396) (xy 418.131579 -163.13164) (xy 418.079284 -163.116285)
			(xy 418.029707 -163.093643) (xy 417.983857 -163.064177) (xy 417.942666 -163.028486) (xy 417.906975 -162.987295)
			(xy 417.877509 -162.941445) (xy 417.854867 -162.891868) (xy 417.839512 -162.839573) (xy 417.831756 -162.785625)
			(xy 417.83127 -162.758374) (xy 412.761405 -162.758374) (xy 412.74378 -162.777013) (xy 412.721298 -162.795204)
			(xy 412.712538 -162.802768) (xy 412.702354 -162.823525) (xy 412.70174 -162.835082) (xy 412.70174 -162.915346)
			(xy 412.702327 -162.926912) (xy 412.712509 -162.947684) (xy 412.721298 -162.955224) (xy 412.743793 -162.973402)
			(xy 412.783527 -163.015424) (xy 412.816465 -163.062962) (xy 412.841851 -163.114926) (xy 412.859105 -163.170126)
			(xy 412.867831 -163.227297) (xy 412.868364 -163.256214) (xy 412.867878 -163.283465) (xy 412.860122 -163.337413)
			(xy 412.844767 -163.389708) (xy 412.822125 -163.439285) (xy 412.792659 -163.485135) (xy 412.756968 -163.526326)
			(xy 412.715777 -163.562017) (xy 412.669927 -163.591483) (xy 412.62035 -163.614125) (xy 412.568055 -163.62948)
			(xy 412.514107 -163.637236) (xy 412.459605 -163.637236) (xy 412.405657 -163.62948) (xy 412.353362 -163.614125)
			(xy 412.303785 -163.591483) (xy 412.257935 -163.562017) (xy 412.216744 -163.526326) (xy 412.181053 -163.485135)
			(xy 412.151587 -163.439285) (xy 412.128945 -163.389708) (xy 412.11359 -163.337413) (xy 412.105834 -163.283465)
			(xy 412.105348 -163.256214) (xy 408.607514 -163.256214) (xy 408.893518 -163.542218) (xy 408.910757 -163.560313)
			(xy 408.938497 -163.601876) (xy 408.9576 -163.648051) (xy 408.967334 -163.697065) (xy 408.96794 -163.72205)
			(xy 408.96794 -164.27577) (xy 408.966416 -164.303964) (xy 408.964892 -164.31768) (xy 408.96172 -164.341521)
			(xy 408.947527 -164.38747) (xy 408.924935 -164.429925) (xy 408.910282 -164.448998) (xy 408.900884 -164.460682)
			(xy 408.882596 -164.481002) (xy 408.551634 -164.811964) (xy 409.069538 -164.811964) (xy 409.073609 -164.756342)
			(xy 409.085735 -164.701905) (xy 409.105658 -164.649814) (xy 409.132954 -164.601179) (xy 409.16704 -164.557036)
			(xy 409.207189 -164.518327) (xy 409.252547 -164.485876) (xy 409.302147 -164.460375) (xy 409.354931 -164.442368)
			(xy 409.409774 -164.432238) (xy 409.465508 -164.430201) (xy 409.520945 -164.436301) (xy 409.574902 -164.450407)
			(xy 409.626231 -164.472219) (xy 409.673837 -164.501273) (xy 409.716705 -164.536948) (xy 409.753922 -164.578485)
			(xy 409.784695 -164.624998) (xy 409.808367 -164.675495) (xy 409.824435 -164.728902) (xy 409.832555 -164.784078)
			(xy 409.833064 -164.811964) (xy 409.832555 -164.83985) (xy 409.824435 -164.895026) (xy 409.808367 -164.948433)
			(xy 409.784695 -164.99893) (xy 409.753922 -165.045443) (xy 409.716705 -165.08698) (xy 409.673837 -165.122655)
			(xy 409.626231 -165.151709) (xy 409.574902 -165.173521) (xy 409.520945 -165.187627) (xy 409.465508 -165.193727)
			(xy 409.409774 -165.19169) (xy 409.354931 -165.18156) (xy 409.302147 -165.163553) (xy 409.252547 -165.138052)
			(xy 409.207189 -165.105601) (xy 409.16704 -165.066892) (xy 409.132954 -165.022749) (xy 409.105658 -164.974114)
			(xy 409.085735 -164.922023) (xy 409.073609 -164.867586) (xy 409.069538 -164.811964) (xy 408.551634 -164.811964)
			(xy 408.477974 -164.885624) (xy 408.474164 -164.8968) (xy 408.465251 -164.921568) (xy 408.441542 -164.968566)
			(xy 408.411595 -165.011857) (xy 408.375978 -165.050617) (xy 408.335369 -165.084111) (xy 408.290539 -165.111701)
			(xy 408.242341 -165.132864) (xy 408.19169 -165.147196) (xy 408.13955 -165.154426) (xy 408.11323 -165.154864)
			(xy 408.085976 -165.154417) (xy 408.032022 -165.146663) (xy 407.979721 -165.131308) (xy 407.930138 -165.108666)
			(xy 407.884283 -165.079197) (xy 407.843089 -165.043501) (xy 407.807395 -165.002306) (xy 407.777927 -164.956449)
			(xy 407.755287 -164.906866) (xy 407.739934 -164.854564) (xy 407.732182 -164.80061) (xy 407.731722 -164.773356)
			(xy 407.732177 -164.74588) (xy 407.740076 -164.691499) (xy 407.755703 -164.638816) (xy 407.778735 -164.588924)
			(xy 407.808693 -164.542857) (xy 407.826464 -164.521896) (xy 407.83256 -164.514784) (xy 407.83891 -164.497766)
			(xy 407.83891 -164.411914) (xy 407.83256 -164.394896) (xy 407.826464 -164.387784) (xy 407.808706 -164.366817)
			(xy 407.778781 -164.320736) (xy 407.755768 -164.270843) (xy 407.740141 -164.218167) (xy 407.732222 -164.163796)
			(xy 407.731722 -164.136324) (xy 407.732274 -164.107895) (xy 407.740715 -164.051668) (xy 407.757412 -163.997317)
			(xy 407.781996 -163.946049) (xy 407.813921 -163.899001) (xy 407.832814 -163.877752) (xy 407.839672 -163.870386)
			(xy 407.846276 -163.852352) (xy 407.844752 -163.771834) (xy 407.844159 -163.762125) (xy 407.836569 -163.74423)
			(xy 407.83002 -163.737036) (xy 394.892276 -150.799292) (xy 394.875019 -150.781197) (xy 394.84721 -150.739652)
			(xy 394.828038 -150.69348) (xy 394.818238 -150.644456) (xy 394.8176 -150.61946) (xy 394.8176 -147.25523)
			(xy 394.817268 -147.24518) (xy 394.809655 -147.226583) (xy 394.802868 -147.219162) (xy 394.200126 -146.61642)
			(xy 394.192665 -146.609701) (xy 394.17409 -146.602127) (xy 394.164058 -146.601688) (xy 386.01396 -146.601688)
			(xy 385.988966 -146.601012) (xy 385.939946 -146.59122) (xy 385.893775 -146.572058) (xy 385.852226 -146.544262)
			(xy 385.834128 -146.527012) (xy 384.97637 -145.669254) (xy 384.96898 -145.662402) (xy 384.950373 -145.654691)
			(xy 384.940302 -145.654268) (xy 384.457956 -145.654268) (xy 384.428746 -145.682462) (xy 384.427984 -145.70329)
			(xy 384.426568 -145.727172) (xy 384.417224 -145.774088) (xy 384.400663 -145.818968) (xy 384.377293 -145.860708)
			(xy 384.347687 -145.898285) (xy 384.330448 -145.914872) (xy 384.26263 -145.977102) (xy 384.254248 -145.995898)
			(xy 384.253994 -146.006312) (xy 384.254326 -146.016574) (xy 384.262038 -146.035579) (xy 384.26898 -146.043142)
			(xy 385.889345 -147.663662) (xy 387.813054 -147.663662) (xy 387.81702 -147.579131) (xy 387.828885 -147.495344)
			(xy 387.848543 -147.413035) (xy 387.875823 -147.332929) (xy 387.910484 -147.25573) (xy 387.952222 -147.182115)
			(xy 388.000669 -147.112732) (xy 388.055401 -147.048191) (xy 388.115937 -146.989059) (xy 388.181743 -146.935855)
			(xy 388.252243 -146.889047) (xy 388.326815 -146.849046) (xy 388.404806 -146.816204) (xy 388.48553 -146.79081)
			(xy 388.568277 -146.773087) (xy 388.652319 -146.763189) (xy 388.73692 -146.761206) (xy 388.821334 -146.767153)
			(xy 388.904821 -146.780978) (xy 388.986646 -146.802561) (xy 389.06609 -146.831711) (xy 389.142456 -146.868172)
			(xy 389.215072 -146.911624) (xy 389.2833 -146.961685) (xy 389.34654 -147.017915) (xy 389.404237 -147.07982)
			(xy 389.455884 -147.146856) (xy 389.501026 -147.218433) (xy 389.539268 -147.293923) (xy 389.570272 -147.372662)
			(xy 389.593767 -147.453959) (xy 389.609546 -147.537098) (xy 389.61747 -147.62135) (xy 389.617966 -147.663662)
			(xy 390.353054 -147.663662) (xy 390.35702 -147.579131) (xy 390.368885 -147.495344) (xy 390.388543 -147.413035)
			(xy 390.415823 -147.332929) (xy 390.450484 -147.25573) (xy 390.492222 -147.182115) (xy 390.540669 -147.112732)
			(xy 390.595401 -147.048191) (xy 390.655937 -146.989059) (xy 390.721743 -146.935855) (xy 390.792243 -146.889047)
			(xy 390.866815 -146.849046) (xy 390.944806 -146.816204) (xy 391.02553 -146.79081) (xy 391.108277 -146.773087)
			(xy 391.192319 -146.763189) (xy 391.27692 -146.761206) (xy 391.361334 -146.767153) (xy 391.444821 -146.780978)
			(xy 391.526646 -146.802561) (xy 391.60609 -146.831711) (xy 391.682456 -146.868172) (xy 391.755072 -146.911624)
			(xy 391.8233 -146.961685) (xy 391.88654 -147.017915) (xy 391.944237 -147.07982) (xy 391.995884 -147.146856)
			(xy 392.041026 -147.218433) (xy 392.079268 -147.293923) (xy 392.110272 -147.372662) (xy 392.133767 -147.453959)
			(xy 392.149546 -147.537098) (xy 392.15747 -147.62135) (xy 392.157966 -147.663662) (xy 392.15747 -147.705974)
			(xy 392.149546 -147.790226) (xy 392.133767 -147.873365) (xy 392.110272 -147.954662) (xy 392.079268 -148.033401)
			(xy 392.041026 -148.108891) (xy 391.995884 -148.180468) (xy 391.944237 -148.247504) (xy 391.88654 -148.309409)
			(xy 391.8233 -148.365639) (xy 391.755072 -148.4157) (xy 391.682456 -148.459152) (xy 391.60609 -148.495613)
			(xy 391.526646 -148.524763) (xy 391.444821 -148.546346) (xy 391.361334 -148.560171) (xy 391.27692 -148.566118)
			(xy 391.192319 -148.564135) (xy 391.108277 -148.554237) (xy 391.02553 -148.536514) (xy 390.944806 -148.51112)
			(xy 390.866815 -148.478278) (xy 390.792243 -148.438277) (xy 390.721743 -148.391469) (xy 390.655937 -148.338265)
			(xy 390.595401 -148.279133) (xy 390.540669 -148.214592) (xy 390.492222 -148.145209) (xy 390.450484 -148.071594)
			(xy 390.415823 -147.994395) (xy 390.388543 -147.914289) (xy 390.368885 -147.83198) (xy 390.35702 -147.748193)
			(xy 390.353054 -147.663662) (xy 389.617966 -147.663662) (xy 389.61747 -147.705974) (xy 389.609546 -147.790226)
			(xy 389.593767 -147.873365) (xy 389.570272 -147.954662) (xy 389.539268 -148.033401) (xy 389.501026 -148.108891)
			(xy 389.455884 -148.180468) (xy 389.404237 -148.247504) (xy 389.34654 -148.309409) (xy 389.2833 -148.365639)
			(xy 389.215072 -148.4157) (xy 389.142456 -148.459152) (xy 389.06609 -148.495613) (xy 388.986646 -148.524763)
			(xy 388.904821 -148.546346) (xy 388.821334 -148.560171) (xy 388.73692 -148.566118) (xy 388.652319 -148.564135)
			(xy 388.568277 -148.554237) (xy 388.48553 -148.536514) (xy 388.404806 -148.51112) (xy 388.326815 -148.478278)
			(xy 388.252243 -148.438277) (xy 388.181743 -148.391469) (xy 388.115937 -148.338265) (xy 388.055401 -148.279133)
			(xy 388.000669 -148.214592) (xy 387.952222 -148.145209) (xy 387.910484 -148.071594) (xy 387.875823 -147.994395)
			(xy 387.848543 -147.914289) (xy 387.828885 -147.83198) (xy 387.81702 -147.748193) (xy 387.813054 -147.663662)
			(xy 385.889345 -147.663662) (xy 386.92455 -148.698966) (xy 386.931977 -148.705772) (xy 386.950556 -148.713512)
			(xy 386.960618 -148.713952) (xy 390.63168 -148.713952) (xy 390.656662 -148.714594) (xy 390.705669 -148.724328)
			(xy 390.751838 -148.743426) (xy 390.7934 -148.771157) (xy 390.811512 -148.788374) (xy 400.059652 -158.036514)
			(xy 400.0769 -158.054617) (xy 400.104714 -158.096159) (xy 400.123889 -158.142328) (xy 400.133691 -158.19135)
			(xy 400.134328 -158.216346) (xy 400.134328 -164.253926) (xy 405.841454 -164.253926) (xy 405.84194 -164.226675)
			(xy 405.849696 -164.172727) (xy 405.865051 -164.120432) (xy 405.887693 -164.070855) (xy 405.917159 -164.025005)
			(xy 405.95285 -163.983814) (xy 405.994041 -163.948123) (xy 406.039891 -163.918657) (xy 406.089468 -163.896015)
			(xy 406.141763 -163.88066) (xy 406.195711 -163.872904) (xy 406.250213 -163.872904) (xy 406.304161 -163.88066)
			(xy 406.356456 -163.896015) (xy 406.406033 -163.918657) (xy 406.451883 -163.948123) (xy 406.493074 -163.983814)
			(xy 406.528765 -164.025005) (xy 406.558231 -164.070855) (xy 406.580873 -164.120432) (xy 406.596228 -164.172727)
			(xy 406.603984 -164.226675) (xy 406.60447 -164.253926) (xy 406.603809 -164.285489) (xy 406.593423 -164.347754)
			(xy 406.572937 -164.407463) (xy 406.558496 -164.435536) (xy 406.55367 -164.444426) (xy 406.551638 -164.463984)
			(xy 406.577292 -164.552122) (xy 406.589738 -164.567616) (xy 406.598628 -164.572696) (xy 406.605994 -164.57676)
			(xy 406.615646 -164.582602) (xy 406.637744 -164.584634) (xy 406.732232 -164.551106) (xy 406.748234 -164.535612)
			(xy 406.752298 -164.525198) (xy 406.762978 -164.498415) (xy 406.791267 -164.448172) (xy 406.826799 -164.402762)
			(xy 406.868763 -164.363219) (xy 406.916203 -164.330446) (xy 406.968036 -164.305189) (xy 407.023082 -164.288026)
			(xy 407.080084 -164.279346) (xy 407.108914 -164.278818) (xy 407.136166 -164.279253) (xy 407.190116 -164.287011)
			(xy 407.242413 -164.302369) (xy 407.291992 -164.325012) (xy 407.337844 -164.354481) (xy 407.379035 -164.390175)
			(xy 407.414727 -164.431368) (xy 407.444194 -164.47722) (xy 407.466836 -164.5268) (xy 407.482192 -164.579097)
			(xy 407.489948 -164.633048) (xy 407.489948 -164.687552) (xy 407.482192 -164.741503) (xy 407.466836 -164.7938)
			(xy 407.444194 -164.84338) (xy 407.414727 -164.889232) (xy 407.379035 -164.930425) (xy 407.337844 -164.966119)
			(xy 407.291992 -164.995588) (xy 407.242413 -165.018231) (xy 407.190116 -165.033589) (xy 407.136166 -165.041347)
			(xy 407.108914 -165.041834) (xy 407.083679 -165.041426) (xy 407.033646 -165.034811) (xy 406.984925 -165.021641)
			(xy 406.938373 -165.002147) (xy 406.916382 -164.989764) (xy 406.90673 -164.983922) (xy 406.884632 -164.98189)
			(xy 406.790144 -165.015418) (xy 406.774142 -165.030912) (xy 406.770078 -165.041326) (xy 406.759347 -165.068087)
			(xy 406.731063 -165.118327) (xy 406.695537 -165.163735) (xy 406.65358 -165.203277) (xy 406.606148 -165.236052)
			(xy 406.554322 -165.261313) (xy 406.499285 -165.278484) (xy 406.442289 -165.287173) (xy 406.413462 -165.287706)
			(xy 406.38621 -165.287258) (xy 406.332261 -165.279496) (xy 406.279965 -165.264136) (xy 406.230388 -165.24149)
			(xy 406.184537 -165.21202) (xy 406.143347 -165.176324) (xy 406.107656 -165.135131) (xy 406.078191 -165.089277)
			(xy 406.05555 -165.039697) (xy 406.040196 -164.9874) (xy 406.03244 -164.93345) (xy 406.031954 -164.906198)
			(xy 406.032622 -164.874636) (xy 406.043005 -164.81237) (xy 406.063487 -164.752661) (xy 406.077928 -164.724588)
			(xy 406.082754 -164.715698) (xy 406.084786 -164.69614) (xy 406.059132 -164.608002) (xy 406.046686 -164.592508)
			(xy 406.037796 -164.587428) (xy 406.012678 -164.572907) (xy 405.966796 -164.537399) (xy 405.926822 -164.49535)
			(xy 405.893679 -164.447732) (xy 405.868131 -164.395642) (xy 405.850768 -164.340284) (xy 405.841991 -164.282935)
			(xy 405.841454 -164.253926) (xy 400.134328 -164.253926) (xy 400.134328 -166.527988) (xy 402.05533 -166.527988)
			(xy 402.055846 -166.500415) (xy 402.063787 -166.445844) (xy 402.079501 -166.392985) (xy 402.102662 -166.342938)
			(xy 402.132786 -166.296747) (xy 402.169246 -166.255375) (xy 402.18995 -166.237158) (xy 402.198091 -166.229576)
			(xy 402.207431 -166.209409) (xy 402.207984 -166.198296) (xy 402.207984 -166.12108) (xy 402.207448 -166.109966)
			(xy 402.198088 -166.089807) (xy 402.18995 -166.082218) (xy 402.16923 -166.064017) (xy 402.132762 -166.022645)
			(xy 402.102632 -165.976454) (xy 402.079467 -165.926405) (xy 402.06375 -165.873542) (xy 402.05581 -165.818967)
			(xy 402.055811 -165.763817) (xy 402.063754 -165.709243) (xy 402.079472 -165.65638) (xy 402.102639 -165.606332)
			(xy 402.132772 -165.560142) (xy 402.169241 -165.518772) (xy 402.18995 -165.500558) (xy 402.198091 -165.492976)
			(xy 402.207431 -165.472809) (xy 402.207984 -165.461696) (xy 402.207984 -165.38448) (xy 402.207448 -165.373366)
			(xy 402.198088 -165.353207) (xy 402.18995 -165.345618) (xy 402.169234 -165.327412) (xy 402.132767 -165.286041)
			(xy 402.102636 -165.239849) (xy 402.079472 -165.189801) (xy 402.063756 -165.136938) (xy 402.055816 -165.082363)
			(xy 402.05533 -165.054788) (xy 402.055744 -165.027533) (xy 402.063503 -164.973578) (xy 402.078863 -164.921277)
			(xy 402.10151 -164.871694) (xy 402.130982 -164.82584) (xy 402.166681 -164.784646) (xy 402.20788 -164.748952)
			(xy 402.253738 -164.719486) (xy 402.303324 -164.696845) (xy 402.355627 -164.681493) (xy 402.409583 -164.67374)
			(xy 402.436838 -164.67328) (xy 402.464694 -164.673784) (xy 402.519809 -164.681912) (xy 402.573159 -164.697962)
			(xy 402.623611 -164.721592) (xy 402.670095 -164.752301) (xy 402.711624 -164.789438) (xy 402.747317 -164.832215)
			(xy 402.776417 -164.879723) (xy 402.798305 -164.930955) (xy 402.8059 -164.95776) (xy 402.808186 -164.96665)
			(xy 402.818854 -164.98189) (xy 402.890736 -165.029642) (xy 402.90877 -165.033706) (xy 402.917914 -165.032436)
			(xy 402.930931 -165.030767) (xy 402.957115 -165.028987) (xy 402.970238 -165.02888) (xy 402.984387 -165.02897)
			(xy 403.01261 -165.031007) (xy 403.026626 -165.032944) (xy 403.036786 -165.034468) (xy 403.056344 -165.029642)
			(xy 403.130766 -164.973762) (xy 403.140926 -164.956236) (xy 403.142196 -164.946076) (xy 403.146288 -164.918923)
			(xy 403.161259 -164.866092) (xy 403.183649 -164.815953) (xy 403.212995 -164.769541) (xy 403.248692 -164.727816)
			(xy 403.290002 -164.691639) (xy 403.336071 -164.661758) (xy 403.385948 -164.63879) (xy 403.438602 -164.623209)
			(xy 403.492946 -164.615337) (xy 403.520402 -164.61486) (xy 403.547652 -164.615376) (xy 403.601597 -164.623132)
			(xy 403.653889 -164.638486) (xy 403.703464 -164.661125) (xy 403.749313 -164.690588) (xy 403.790502 -164.726276)
			(xy 403.826194 -164.767463) (xy 403.855661 -164.813309) (xy 403.878304 -164.862883) (xy 403.893662 -164.915174)
			(xy 403.901422 -164.969118) (xy 403.90191 -164.996368) (xy 403.901419 -165.023942) (xy 403.893471 -165.078513)
			(xy 403.877751 -165.131372) (xy 403.854585 -165.181418) (xy 403.824458 -165.227609) (xy 403.787995 -165.268981)
			(xy 403.76729 -165.287198) (xy 403.759175 -165.294804) (xy 403.749819 -165.314953) (xy 403.749256 -165.32606)
			(xy 403.749256 -165.403276) (xy 403.749804 -165.414389) (xy 403.759155 -165.434548) (xy 403.76729 -165.442138)
			(xy 403.788021 -165.460328) (xy 403.82449 -165.501701) (xy 403.85462 -165.547895) (xy 403.877782 -165.597947)
			(xy 403.893494 -165.650814) (xy 403.901428 -165.705392) (xy 403.901462 -165.707314) (xy 408.490418 -165.707314)
			(xy 408.494489 -165.651692) (xy 408.506615 -165.597255) (xy 408.526538 -165.545164) (xy 408.553834 -165.496529)
			(xy 408.58792 -165.452386) (xy 408.628069 -165.413677) (xy 408.673427 -165.381226) (xy 408.723027 -165.355725)
			(xy 408.775811 -165.337718) (xy 408.830654 -165.327588) (xy 408.886388 -165.325551) (xy 408.941825 -165.331651)
			(xy 408.995782 -165.345757) (xy 409.047111 -165.367569) (xy 409.094717 -165.396623) (xy 409.137585 -165.432298)
			(xy 409.174802 -165.473835) (xy 409.205575 -165.520348) (xy 409.229247 -165.570845) (xy 409.245315 -165.624252)
			(xy 409.253435 -165.679428) (xy 409.253944 -165.707314) (xy 409.253435 -165.7352) (xy 409.245315 -165.790376)
			(xy 409.229247 -165.843783) (xy 409.205575 -165.89428) (xy 409.174802 -165.940793) (xy 409.137585 -165.98233)
			(xy 409.094717 -166.018005) (xy 409.047111 -166.047059) (xy 408.995782 -166.068871) (xy 408.941825 -166.082977)
			(xy 408.886388 -166.089077) (xy 408.830654 -166.08704) (xy 408.775811 -166.07691) (xy 408.723027 -166.058903)
			(xy 408.673427 -166.033402) (xy 408.628069 -166.000951) (xy 408.58792 -165.962242) (xy 408.553834 -165.918099)
			(xy 408.526538 -165.869464) (xy 408.506615 -165.817373) (xy 408.494489 -165.762936) (xy 408.490418 -165.707314)
			(xy 403.901462 -165.707314) (xy 403.90191 -165.732968) (xy 403.901415 -165.76022) (xy 403.893662 -165.81417)
			(xy 403.87831 -165.866467) (xy 403.855672 -165.916047) (xy 403.826207 -165.9619) (xy 403.790517 -166.003093)
			(xy 403.749327 -166.038787) (xy 403.703477 -166.068256) (xy 403.653899 -166.090899) (xy 403.601603 -166.106255)
			(xy 403.547654 -166.114013) (xy 403.520402 -166.114476) (xy 403.486112 -166.112952) (xy 403.475952 -166.111936)
			(xy 403.456648 -166.118032) (xy 403.386036 -166.177214) (xy 403.376638 -166.195248) (xy 403.375622 -166.205408)
			(xy 403.37263 -166.233576) (xy 403.359462 -166.288667) (xy 403.338289 -166.341204) (xy 403.309577 -166.39003)
			(xy 403.273957 -166.434072) (xy 403.232214 -166.472359) (xy 403.185266 -166.50405) (xy 403.134147 -166.528447)
			(xy 403.07998 -166.545013) (xy 403.023959 -166.553383) (xy 402.995638 -166.553896) (xy 402.977619 -166.55368)
			(xy 402.941744 -166.550243) (xy 402.92401 -166.547038) (xy 402.914612 -166.54526) (xy 402.895562 -166.54907)
			(xy 402.820378 -166.596822) (xy 402.808948 -166.61257) (xy 402.806662 -166.621968) (xy 402.799299 -166.649022)
			(xy 402.777665 -166.70075) (xy 402.748696 -166.748756) (xy 402.713016 -166.792007) (xy 402.671392 -166.829573)
			(xy 402.624721 -166.860646) (xy 402.574005 -166.884557) (xy 402.520338 -166.900791) (xy 402.464873 -166.908999)
			(xy 402.436838 -166.909496) (xy 402.409586 -166.909009) (xy 402.355635 -166.901257) (xy 402.303337 -166.885905)
			(xy 402.253756 -166.863266) (xy 402.207902 -166.833801) (xy 402.166709 -166.79811) (xy 402.131014 -166.756919)
			(xy 402.101546 -166.711067) (xy 402.078904 -166.661488) (xy 402.063548 -166.609191) (xy 402.055793 -166.55524)
			(xy 402.05533 -166.527988) (xy 400.134328 -166.527988) (xy 400.134328 -168.082214) (xy 403.723348 -168.082214)
			(xy 403.723858 -168.053297) (xy 403.732586 -167.996124) (xy 403.749845 -167.940924) (xy 403.775238 -167.888962)
			(xy 403.808184 -167.841429) (xy 403.847927 -167.799413) (xy 403.870414 -167.781224) (xy 403.879163 -167.77365)
			(xy 403.889353 -167.7529) (xy 403.889972 -167.741346) (xy 403.889972 -167.661082) (xy 403.889422 -167.649511)
			(xy 403.879214 -167.62874) (xy 403.870414 -167.621204) (xy 403.847935 -167.603007) (xy 403.808199 -167.560989)
			(xy 403.775259 -167.513456) (xy 403.74987 -167.461495) (xy 403.732613 -167.406299) (xy 403.723883 -167.34913)
			(xy 403.723348 -167.320214) (xy 403.723894 -167.292154) (xy 403.732126 -167.236641) (xy 403.7484 -167.182932)
			(xy 403.772364 -167.132186) (xy 403.803502 -167.085497) (xy 403.841142 -167.043872) (xy 403.884473 -167.008208)
			(xy 403.90826 -166.993316) (xy 403.917912 -166.987474) (xy 403.930104 -166.96944) (xy 403.947122 -166.87165)
			(xy 403.941534 -166.850568) (xy 403.934422 -166.841678) (xy 403.918531 -166.821603) (xy 403.891783 -166.777945)
			(xy 403.871257 -166.731041) (xy 403.857338 -166.681769) (xy 403.850287 -166.631057) (xy 403.84984 -166.605458)
			(xy 403.850317 -166.578843) (xy 403.857898 -166.526154) (xy 403.872898 -166.475081) (xy 403.895014 -166.426662)
			(xy 403.923794 -166.381882) (xy 403.958653 -166.341653) (xy 403.998882 -166.306794) (xy 404.043662 -166.278014)
			(xy 404.092081 -166.255898) (xy 404.143154 -166.240898) (xy 404.195843 -166.233317) (xy 404.222458 -166.23284)
			(xy 404.24888 -166.233278) (xy 404.301196 -166.240735) (xy 404.351934 -166.255505) (xy 404.400078 -166.277293)
			(xy 404.444663 -166.305661) (xy 404.465028 -166.322502) (xy 404.471886 -166.328598) (xy 404.488904 -166.334694)
			(xy 404.573232 -166.334694) (xy 404.59025 -166.328598) (xy 404.597108 -166.322502) (xy 404.617474 -166.305663)
			(xy 404.66206 -166.277298) (xy 404.710204 -166.255511) (xy 404.760941 -166.24074) (xy 404.813256 -166.23328)
			(xy 404.8661 -166.23328) (xy 404.918415 -166.24074) (xy 404.969152 -166.255511) (xy 405.017296 -166.277298)
			(xy 405.061882 -166.305663) (xy 405.082248 -166.322502) (xy 405.089106 -166.328598) (xy 405.106124 -166.334694)
			(xy 405.190452 -166.334694) (xy 405.20747 -166.328598) (xy 405.214328 -166.322502) (xy 405.234683 -166.305651)
			(xy 405.279276 -166.277298) (xy 405.327423 -166.255521) (xy 405.378162 -166.240756) (xy 405.430476 -166.233299)
			(xy 405.456898 -166.23284) (xy 405.484782 -166.233419) (xy 405.539926 -166.241731) (xy 405.593216 -166.258168)
			(xy 405.643461 -166.282364) (xy 405.689538 -166.313779) (xy 405.730419 -166.351711) (xy 405.765189 -166.395311)
			(xy 405.793073 -166.443607) (xy 405.813447 -166.495519) (xy 405.825856 -166.549889) (xy 405.830024 -166.6055)
			(xy 405.825856 -166.661111) (xy 405.813447 -166.715481) (xy 405.793073 -166.767393) (xy 405.765189 -166.815689)
			(xy 405.730419 -166.859289) (xy 405.689538 -166.897221) (xy 405.643461 -166.928636) (xy 405.593216 -166.952832)
			(xy 405.539926 -166.969269) (xy 405.484782 -166.977581) (xy 405.456898 -166.978076) (xy 405.430477 -166.977601)
			(xy 405.378163 -166.970153) (xy 405.327425 -166.955391) (xy 405.279281 -166.933611) (xy 405.234695 -166.905251)
			(xy 405.214328 -166.888414) (xy 405.20747 -166.882318) (xy 405.190452 -166.876222) (xy 405.106124 -166.876222)
			(xy 405.089106 -166.882318) (xy 405.082248 -166.888414) (xy 405.061882 -166.905253) (xy 405.017296 -166.933618)
			(xy 404.969152 -166.955405) (xy 404.918415 -166.970176) (xy 404.8661 -166.977636) (xy 404.813256 -166.977636)
			(xy 404.760941 -166.970176) (xy 404.710204 -166.955405) (xy 404.66206 -166.933618) (xy 404.617474 -166.905253)
			(xy 404.597108 -166.888414) (xy 404.59025 -166.882318) (xy 404.573232 -166.876222) (xy 404.488904 -166.876222)
			(xy 404.471886 -166.882318) (xy 404.465028 -166.888414) (xy 404.454226 -166.897478) (xy 404.431466 -166.914129)
			(xy 404.419562 -166.921688) (xy 404.40991 -166.92753) (xy 404.397972 -166.945818) (xy 404.382732 -167.044116)
			(xy 404.388574 -167.064944) (xy 404.39594 -167.07358) (xy 404.412941 -167.094341) (xy 404.441546 -167.13974)
			(xy 404.463507 -167.1887) (xy 404.478393 -167.240253) (xy 404.485909 -167.293384) (xy 404.486364 -167.320214)
			(xy 404.485797 -167.349129) (xy 404.47708 -167.406299) (xy 404.459833 -167.461497) (xy 404.43445 -167.513459)
			(xy 404.401514 -167.560994) (xy 404.379405 -167.584374) (xy 409.44927 -167.584374) (xy 409.449752 -167.556463)
			(xy 409.45789 -167.501237) (xy 409.473988 -167.447786) (xy 409.497703 -167.397252) (xy 409.528529 -167.350712)
			(xy 409.546806 -167.329612) (xy 409.553156 -167.3225) (xy 409.55976 -167.305228) (xy 409.55976 -167.218106)
			(xy 409.553156 -167.200834) (xy 409.546806 -167.193722) (xy 409.528518 -167.172631) (xy 409.497692 -167.12609)
			(xy 409.473978 -167.075554) (xy 409.457884 -167.0221) (xy 409.449753 -166.966872) (xy 409.44927 -166.93896)
			(xy 409.449756 -166.911709) (xy 409.457512 -166.857761) (xy 409.472867 -166.805466) (xy 409.495509 -166.755889)
			(xy 409.524975 -166.710039) (xy 409.560666 -166.668848) (xy 409.601857 -166.633157) (xy 409.647707 -166.603691)
			(xy 409.697284 -166.581049) (xy 409.749579 -166.565694) (xy 409.803527 -166.557938) (xy 409.858029 -166.557938)
			(xy 409.911977 -166.565694) (xy 409.964272 -166.581049) (xy 410.013849 -166.603691) (xy 410.059699 -166.633157)
			(xy 410.10089 -166.668848) (xy 410.136581 -166.710039) (xy 410.166047 -166.755889) (xy 410.188689 -166.805466)
			(xy 410.204044 -166.857761) (xy 410.2118 -166.911709) (xy 410.212286 -166.93896) (xy 410.21181 -166.966871)
			(xy 410.203669 -167.022097) (xy 410.187568 -167.075547) (xy 410.163852 -167.126082) (xy 410.133027 -167.172621)
			(xy 410.11475 -167.193722) (xy 410.1084 -167.200834) (xy 410.101796 -167.218106) (xy 410.101796 -167.305228)
			(xy 410.1084 -167.3225) (xy 410.11475 -167.329612) (xy 410.133016 -167.350721) (xy 410.163843 -167.397258)
			(xy 410.18756 -167.44779) (xy 410.20366 -167.501239) (xy 410.211798 -167.556464) (xy 410.212286 -167.584374)
			(xy 410.2118 -167.611625) (xy 410.204044 -167.665573) (xy 410.188689 -167.717868) (xy 410.166047 -167.767445)
			(xy 410.136581 -167.813295) (xy 410.10089 -167.854486) (xy 410.059699 -167.890177) (xy 410.013849 -167.919643)
			(xy 409.964272 -167.942285) (xy 409.911977 -167.95764) (xy 409.858029 -167.965396) (xy 409.803527 -167.965396)
			(xy 409.749579 -167.95764) (xy 409.697284 -167.942285) (xy 409.647707 -167.919643) (xy 409.601857 -167.890177)
			(xy 409.560666 -167.854486) (xy 409.524975 -167.813295) (xy 409.495509 -167.767445) (xy 409.472867 -167.717868)
			(xy 409.457512 -167.665573) (xy 409.449756 -167.611625) (xy 409.44927 -167.584374) (xy 404.379405 -167.584374)
			(xy 404.36178 -167.603013) (xy 404.339298 -167.621204) (xy 404.330538 -167.628768) (xy 404.320354 -167.649525)
			(xy 404.31974 -167.661082) (xy 404.31974 -167.741346) (xy 404.320327 -167.752912) (xy 404.330509 -167.773684)
			(xy 404.339298 -167.781224) (xy 404.361793 -167.799402) (xy 404.401527 -167.841424) (xy 404.434465 -167.888962)
			(xy 404.459851 -167.940926) (xy 404.477105 -167.996126) (xy 404.485831 -168.053297) (xy 404.486364 -168.082214)
			(xy 404.485878 -168.109465) (xy 404.478122 -168.163413) (xy 404.462767 -168.215708) (xy 404.440125 -168.265285)
			(xy 404.410659 -168.311135) (xy 404.374968 -168.352326) (xy 404.333777 -168.388017) (xy 404.287927 -168.417483)
			(xy 404.23835 -168.440125) (xy 404.186055 -168.45548) (xy 404.132107 -168.463236) (xy 404.077605 -168.463236)
			(xy 404.023657 -168.45548) (xy 403.971362 -168.440125) (xy 403.921785 -168.417483) (xy 403.875935 -168.388017)
			(xy 403.834744 -168.352326) (xy 403.799053 -168.311135) (xy 403.769587 -168.265285) (xy 403.746945 -168.215708)
			(xy 403.73159 -168.163413) (xy 403.723834 -168.109465) (xy 403.723348 -168.082214) (xy 400.134328 -168.082214)
			(xy 400.134328 -171.340018) (xy 400.134707 -171.350062) (xy 400.142289 -171.368659) (xy 400.14906 -171.376086)
			(xy 400.569938 -171.796964) (xy 400.587155 -171.815078) (xy 400.614898 -171.856636) (xy 400.634007 -171.902804)
			(xy 400.643749 -171.951813) (xy 400.64436 -171.976796) (xy 400.64436 -172.867574) (xy 400.643772 -172.892559)
			(xy 400.634021 -172.941568) (xy 400.614907 -172.987737) (xy 400.587162 -173.029297) (xy 400.569938 -173.047406)
			(xy 400.228054 -173.38929) (xy 400.745958 -173.38929) (xy 400.750029 -173.333668) (xy 400.762155 -173.279231)
			(xy 400.782078 -173.22714) (xy 400.809374 -173.178505) (xy 400.84346 -173.134362) (xy 400.883609 -173.095653)
			(xy 400.928967 -173.063202) (xy 400.978567 -173.037701) (xy 401.031351 -173.019694) (xy 401.086194 -173.009564)
			(xy 401.141928 -173.007527) (xy 401.197365 -173.013627) (xy 401.251322 -173.027733) (xy 401.302651 -173.049545)
			(xy 401.350257 -173.078599) (xy 401.393125 -173.114274) (xy 401.430342 -173.155811) (xy 401.461115 -173.202324)
			(xy 401.484787 -173.252821) (xy 401.500855 -173.306228) (xy 401.508975 -173.361404) (xy 401.509484 -173.38929)
			(xy 401.508975 -173.417176) (xy 401.500855 -173.472352) (xy 401.484787 -173.525759) (xy 401.461115 -173.576256)
			(xy 401.430342 -173.622769) (xy 401.393125 -173.664306) (xy 401.350257 -173.699981) (xy 401.302651 -173.729035)
			(xy 401.251322 -173.750847) (xy 401.197365 -173.764953) (xy 401.141928 -173.771053) (xy 401.086194 -173.769016)
			(xy 401.031351 -173.758886) (xy 400.978567 -173.740879) (xy 400.928967 -173.715378) (xy 400.883609 -173.682927)
			(xy 400.84346 -173.644218) (xy 400.809374 -173.600075) (xy 400.782078 -173.55144) (xy 400.762155 -173.499349)
			(xy 400.750029 -173.444912) (xy 400.745958 -173.38929) (xy 400.228054 -173.38929) (xy 400.154394 -173.46295)
			(xy 400.150584 -173.474126) (xy 400.141669 -173.498893) (xy 400.117958 -173.54589) (xy 400.08801 -173.589179)
			(xy 400.052394 -173.627938) (xy 400.011785 -173.661431) (xy 399.966956 -173.689022) (xy 399.918759 -173.710185)
			(xy 399.868109 -173.724519) (xy 399.815969 -173.731751) (xy 399.78965 -173.73219) (xy 399.762398 -173.731698)
			(xy 399.708447 -173.723948) (xy 399.656148 -173.708597) (xy 399.606567 -173.685959) (xy 399.560713 -173.656494)
			(xy 399.519519 -173.620803) (xy 399.483825 -173.579613) (xy 399.454356 -173.533761) (xy 399.431714 -173.484182)
			(xy 399.416359 -173.431885) (xy 399.408604 -173.377934) (xy 399.408142 -173.350682) (xy 399.408607 -173.323206)
			(xy 399.416503 -173.268826) (xy 399.432127 -173.216143) (xy 399.455157 -173.16625) (xy 399.485114 -173.120183)
			(xy 399.502884 -173.099222) (xy 399.50898 -173.09211) (xy 399.51533 -173.075092) (xy 399.51533 -172.98924)
			(xy 399.50898 -172.972222) (xy 399.502884 -172.96511) (xy 399.485141 -172.944131) (xy 399.455214 -172.898053)
			(xy 399.432197 -172.848164) (xy 399.416566 -172.79549) (xy 399.408644 -172.741121) (xy 399.408142 -172.71365)
			(xy 399.408718 -172.684579) (xy 399.417547 -172.627112) (xy 399.434993 -172.57165) (xy 399.460652 -172.519476)
			(xy 399.49393 -172.4718) (xy 399.534057 -172.429725) (xy 399.580102 -172.394225) (xy 399.631001 -172.366123)
			(xy 399.685574 -172.346068) (xy 399.713958 -172.339762) (xy 399.731738 -172.336206) (xy 399.754852 -172.308012)
			(xy 399.754852 -172.261276) (xy 399.754452 -172.251204) (xy 399.746715 -172.232605) (xy 399.739866 -172.225208)
			(xy 399.318988 -171.80433) (xy 399.301704 -171.78626) (xy 399.273899 -171.744706) (xy 399.254734 -171.698527)
			(xy 399.244944 -171.649497) (xy 399.244312 -171.624498) (xy 399.244312 -158.500826) (xy 399.243978 -158.490776)
			(xy 399.236366 -158.472179) (xy 399.22958 -158.464758) (xy 390.383268 -149.618446) (xy 390.375868 -149.611606)
			(xy 390.357269 -149.603885) (xy 390.3472 -149.60346) (xy 386.600192 -149.60346) (xy 386.575209 -149.602832)
			(xy 386.526202 -149.593093) (xy 386.480033 -149.573991) (xy 386.438471 -149.546257) (xy 386.42036 -149.529038)
			(xy 384.503676 -147.612608) (xy 384.473958 -147.606512) (xy 384.45948 -147.612608) (xy 384.450421 -147.616847)
			(xy 384.436243 -147.630928) (xy 384.428518 -147.649356) (xy 384.427984 -147.659344) (xy 384.427984 -150.314914)
			(xy 384.427854 -150.329028) (xy 384.425313 -150.357141) (xy 384.422904 -150.371048) (xy 384.420618 -150.382224)
			(xy 384.426206 -150.404068) (xy 384.48361 -150.473156) (xy 384.491237 -150.481375) (xy 384.511528 -150.49086)
			(xy 384.522726 -150.491444) (xy 388.949946 -150.491444) (xy 388.974941 -150.492107) (xy 389.023962 -150.501902)
			(xy 389.070133 -150.521067) (xy 389.111681 -150.548868) (xy 389.129778 -150.56612) (xy 393.49807 -154.934412)
			(xy 393.515315 -154.952501) (xy 393.543051 -154.994068) (xy 393.562152 -155.040244) (xy 393.571885 -155.089258)
			(xy 393.572492 -155.114244) (xy 393.572492 -173.21911) (xy 394.24737 -173.21911) (xy 394.247869 -173.190192)
			(xy 394.256598 -173.133019) (xy 394.273858 -173.077818) (xy 394.299253 -173.025856) (xy 394.332202 -172.978323)
			(xy 394.371948 -172.936308) (xy 394.394436 -172.91812) (xy 394.40319 -172.910551) (xy 394.413376 -172.889797)
			(xy 394.413994 -172.878242) (xy 394.413994 -172.797978) (xy 394.413381 -172.786416) (xy 394.403217 -172.765644)
			(xy 394.394436 -172.7581) (xy 394.37196 -172.7399) (xy 394.332223 -172.697883) (xy 394.299282 -172.65035)
			(xy 394.273892 -172.598391) (xy 394.256634 -172.543194) (xy 394.247905 -172.486026) (xy 394.24737 -172.45711)
			(xy 394.247888 -172.42986) (xy 394.255642 -172.375915) (xy 394.270995 -172.323622) (xy 394.293633 -172.274046)
			(xy 394.323096 -172.228197) (xy 394.358784 -172.187007) (xy 394.399971 -172.151316) (xy 394.445818 -172.121849)
			(xy 394.495392 -172.099206) (xy 394.547683 -172.083849) (xy 394.601628 -172.07609) (xy 394.628878 -172.075602)
			(xy 394.657633 -172.07612) (xy 394.714492 -172.08474) (xy 394.769411 -172.101804) (xy 394.821143 -172.126924)
			(xy 394.868516 -172.15953) (xy 394.910453 -172.198882) (xy 394.946002 -172.244087) (xy 394.974358 -172.294119)
			(xy 394.994877 -172.347843) (xy 395.001496 -172.37583) (xy 395.003782 -172.386244) (xy 395.015974 -172.402754)
			(xy 395.097508 -172.45203) (xy 395.117828 -172.454824) (xy 395.128242 -172.451776) (xy 395.153392 -172.445244)
			(xy 395.204877 -172.438231) (xy 395.230858 -172.437806) (xy 395.25811 -172.438294) (xy 395.312061 -172.446046)
			(xy 395.364359 -172.461397) (xy 395.41394 -172.484036) (xy 395.459794 -172.513501) (xy 395.500988 -172.549192)
			(xy 395.536682 -172.590383) (xy 395.56615 -172.636235) (xy 395.588793 -172.685814) (xy 395.604148 -172.738111)
			(xy 395.611904 -172.792062) (xy 395.612366 -172.819314) (xy 395.612162 -172.831252) (xy 397.517874 -172.831252)
			(xy 397.51836 -172.804001) (xy 397.526116 -172.750053) (xy 397.541471 -172.697758) (xy 397.564113 -172.648181)
			(xy 397.593579 -172.602331) (xy 397.62927 -172.56114) (xy 397.670461 -172.525449) (xy 397.716311 -172.495983)
			(xy 397.765888 -172.473341) (xy 397.818183 -172.457986) (xy 397.872131 -172.45023) (xy 397.926633 -172.45023)
			(xy 397.980581 -172.457986) (xy 398.032876 -172.473341) (xy 398.082453 -172.495983) (xy 398.128303 -172.525449)
			(xy 398.169494 -172.56114) (xy 398.205185 -172.602331) (xy 398.234651 -172.648181) (xy 398.257293 -172.697758)
			(xy 398.272648 -172.750053) (xy 398.280404 -172.804001) (xy 398.28089 -172.831252) (xy 398.280237 -172.862815)
			(xy 398.269847 -172.925081) (xy 398.249359 -172.98479) (xy 398.234916 -173.012862) (xy 398.23009 -173.021752)
			(xy 398.228058 -173.04131) (xy 398.253712 -173.129448) (xy 398.266158 -173.144942) (xy 398.275048 -173.150022)
			(xy 398.282414 -173.154086) (xy 398.292066 -173.159928) (xy 398.314164 -173.16196) (xy 398.408652 -173.128432)
			(xy 398.424654 -173.112938) (xy 398.428718 -173.102524) (xy 398.439395 -173.075739) (xy 398.467683 -173.025495)
			(xy 398.503214 -172.980083) (xy 398.545179 -172.94054) (xy 398.592619 -172.907766) (xy 398.644454 -172.88251)
			(xy 398.6995 -172.865348) (xy 398.756504 -172.85667) (xy 398.785334 -172.856144) (xy 398.81258 -172.856728)
			(xy 398.866517 -172.864488) (xy 398.918801 -172.879844) (xy 398.968368 -172.902484) (xy 399.014208 -172.931948)
			(xy 399.055389 -172.967635) (xy 399.091073 -173.008819) (xy 399.120532 -173.054662) (xy 399.143168 -173.10423)
			(xy 399.158519 -173.156516) (xy 399.166274 -173.210454) (xy 399.166274 -173.264946) (xy 399.158519 -173.318884)
			(xy 399.143168 -173.37117) (xy 399.120532 -173.420738) (xy 399.091073 -173.466581) (xy 399.055389 -173.507765)
			(xy 399.014208 -173.543452) (xy 398.968368 -173.572916) (xy 398.918801 -173.595556) (xy 398.866517 -173.610912)
			(xy 398.81258 -173.618672) (xy 398.785334 -173.61916) (xy 398.760098 -173.618784) (xy 398.710064 -173.612158)
			(xy 398.661343 -173.598979) (xy 398.614792 -173.579477) (xy 398.592802 -173.56709) (xy 398.58315 -173.561248)
			(xy 398.561052 -173.559216) (xy 398.466564 -173.592744) (xy 398.450562 -173.608238) (xy 398.446498 -173.618652)
			(xy 398.435848 -173.645448) (xy 398.407552 -173.695689) (xy 398.372015 -173.741098) (xy 398.330046 -173.780638)
			(xy 398.282602 -173.813409) (xy 398.230765 -173.838664) (xy 398.175717 -173.855826) (xy 398.118713 -173.864505)
			(xy 398.089882 -173.865032) (xy 398.062631 -173.864539) (xy 398.008685 -173.856781) (xy 397.956392 -173.841424)
			(xy 397.906816 -173.818783) (xy 397.860967 -173.789317) (xy 397.819778 -173.753626) (xy 397.784087 -173.712438)
			(xy 397.75462 -173.666589) (xy 397.731978 -173.617014) (xy 397.716621 -173.564721) (xy 397.708861 -173.510775)
			(xy 397.708374 -173.483524) (xy 397.709022 -173.451961) (xy 397.719415 -173.389695) (xy 397.739905 -173.329986)
			(xy 397.754348 -173.301914) (xy 397.759174 -173.293024) (xy 397.761206 -173.273466) (xy 397.735552 -173.185328)
			(xy 397.723106 -173.169834) (xy 397.714216 -173.164754) (xy 397.689114 -173.150207) (xy 397.643231 -173.114704)
			(xy 397.603256 -173.07266) (xy 397.57011 -173.025046) (xy 397.544559 -172.972961) (xy 397.527193 -172.917606)
			(xy 397.518413 -172.860259) (xy 397.517874 -172.831252) (xy 395.612162 -172.831252) (xy 395.611926 -172.845003)
			(xy 395.60503 -172.895915) (xy 395.591363 -172.945442) (xy 395.571175 -172.992687) (xy 395.544828 -173.036795)
			(xy 395.512801 -173.076968) (xy 395.475673 -173.112481) (xy 395.45514 -173.127924) (xy 395.445742 -173.134782)
			(xy 395.43482 -173.154848) (xy 395.430248 -173.257718) (xy 395.439138 -173.2788) (xy 395.448028 -173.286674)
			(xy 395.4681 -173.304875) (xy 395.503432 -173.345953) (xy 395.532592 -173.39162) (xy 395.554992 -173.440956)
			(xy 395.570182 -173.492966) (xy 395.577854 -173.546603) (xy 395.57833 -173.573694) (xy 395.57785 -173.601268)
			(xy 395.569899 -173.65584) (xy 395.554176 -173.708699) (xy 395.531008 -173.758745) (xy 395.500879 -173.804935)
			(xy 395.464415 -173.846307) (xy 395.44371 -173.864524) (xy 395.435587 -173.872122) (xy 395.426235 -173.892277)
			(xy 395.425676 -173.903386) (xy 395.425676 -173.980602) (xy 395.426203 -173.991717) (xy 395.435568 -174.011877)
			(xy 395.44371 -174.019464) (xy 395.464409 -174.037688) (xy 395.50088 -174.079055) (xy 395.531013 -174.125242)
			(xy 395.554181 -174.175287) (xy 395.5699 -174.228147) (xy 395.577843 -174.28272) (xy 395.577877 -174.28464)
			(xy 400.166838 -174.28464) (xy 400.170909 -174.229018) (xy 400.183035 -174.174581) (xy 400.202958 -174.12249)
			(xy 400.230254 -174.073855) (xy 400.26434 -174.029712) (xy 400.304489 -173.991003) (xy 400.349847 -173.958552)
			(xy 400.399447 -173.933051) (xy 400.452231 -173.915044) (xy 400.507074 -173.904914) (xy 400.562808 -173.902877)
			(xy 400.618245 -173.908977) (xy 400.672202 -173.923083) (xy 400.723531 -173.944895) (xy 400.771137 -173.973949)
			(xy 400.814005 -174.009624) (xy 400.851222 -174.051161) (xy 400.881995 -174.097674) (xy 400.905667 -174.148171)
			(xy 400.921735 -174.201578) (xy 400.929855 -174.256754) (xy 400.930364 -174.28464) (xy 400.929855 -174.312526)
			(xy 400.921735 -174.367702) (xy 400.905667 -174.421109) (xy 400.881995 -174.471606) (xy 400.851222 -174.518119)
			(xy 400.814005 -174.559656) (xy 400.771137 -174.595331) (xy 400.723531 -174.624385) (xy 400.672202 -174.646197)
			(xy 400.618245 -174.660303) (xy 400.562808 -174.666403) (xy 400.507074 -174.664366) (xy 400.452231 -174.654236)
			(xy 400.399447 -174.636229) (xy 400.349847 -174.610728) (xy 400.304489 -174.578277) (xy 400.26434 -174.539568)
			(xy 400.230254 -174.495425) (xy 400.202958 -174.44679) (xy 400.183035 -174.394699) (xy 400.170909 -174.340262)
			(xy 400.166838 -174.28464) (xy 395.577877 -174.28464) (xy 395.57833 -174.310294) (xy 395.577817 -174.337544)
			(xy 395.570062 -174.39149) (xy 395.554708 -174.443783) (xy 395.532069 -174.493358) (xy 395.502606 -174.539208)
			(xy 395.466917 -174.580397) (xy 395.42573 -174.616089) (xy 395.379883 -174.645556) (xy 395.330309 -174.668199)
			(xy 395.278017 -174.683556) (xy 395.224072 -174.691315) (xy 395.196822 -174.691802) (xy 395.162532 -174.690278)
			(xy 395.152372 -174.689262) (xy 395.133068 -174.695358) (xy 395.062456 -174.75454) (xy 395.053058 -174.772574)
			(xy 395.052042 -174.782734) (xy 395.049052 -174.810902) (xy 395.035882 -174.865992) (xy 395.014706 -174.918527)
			(xy 394.985993 -174.967352) (xy 394.950373 -175.011393) (xy 394.90863 -175.04968) (xy 394.861683 -175.08137)
			(xy 394.810564 -175.105768) (xy 394.756399 -175.122335) (xy 394.700379 -175.130708) (xy 394.672058 -175.131222)
			(xy 394.644806 -175.130761) (xy 394.590858 -175.122999) (xy 394.538564 -175.10764) (xy 394.488988 -175.084995)
			(xy 394.443138 -175.055525) (xy 394.401949 -175.019831) (xy 394.366258 -174.978639) (xy 394.336792 -174.932788)
			(xy 394.314151 -174.88321) (xy 394.298795 -174.830914) (xy 394.291037 -174.776966) (xy 394.29055 -174.749714)
			(xy 394.291055 -174.721852) (xy 394.299155 -174.666721) (xy 394.315183 -174.613353) (xy 394.3388 -174.562882)
			(xy 394.369504 -174.516381) (xy 394.406643 -174.474838) (xy 394.42771 -174.456598) (xy 394.436854 -174.448978)
			(xy 394.446506 -174.427896) (xy 394.44295 -174.32401) (xy 394.432028 -174.303436) (xy 394.422376 -174.296324)
			(xy 394.401856 -174.280863) (xy 394.36472 -174.245358) (xy 394.332685 -174.20519) (xy 394.306333 -174.161085)
			(xy 394.286139 -174.113842) (xy 394.272469 -174.064316) (xy 394.26557 -174.013403) (xy 394.26515 -173.987714)
			(xy 394.265721 -173.959177) (xy 394.274209 -173.902738) (xy 394.291013 -173.848194) (xy 394.315757 -173.796762)
			(xy 394.347888 -173.749593) (xy 394.38669 -173.707738) (xy 394.40866 -173.689518) (xy 394.418058 -173.682152)
			(xy 394.427964 -173.660562) (xy 394.425678 -173.555914) (xy 394.414502 -173.535086) (xy 394.40485 -173.527974)
			(xy 394.384266 -173.512553) (xy 394.347079 -173.47702) (xy 394.315 -173.436815) (xy 394.28861 -173.392667)
			(xy 394.268388 -173.345375) (xy 394.254699 -173.295795) (xy 394.247791 -173.244827) (xy 394.24737 -173.21911)
			(xy 393.572492 -173.21911) (xy 393.572492 -176.02327) (xy 393.571893 -176.048254) (xy 393.562143 -176.097262)
			(xy 393.543032 -176.143431) (xy 393.515292 -176.184992) (xy 393.49807 -176.203102) (xy 393.043918 -176.657254)
			(xy 395.399768 -176.657254) (xy 395.4003 -176.628337) (xy 395.409022 -176.571166) (xy 395.426276 -176.515966)
			(xy 395.451665 -176.464004) (xy 395.484608 -176.41647) (xy 395.524349 -176.374454) (xy 395.546834 -176.356264)
			(xy 395.555613 -176.348719) (xy 395.565786 -176.327947) (xy 395.566392 -176.316386) (xy 395.566392 -176.236122)
			(xy 395.565812 -176.224555) (xy 395.555624 -176.203784) (xy 395.546834 -176.196244) (xy 395.524379 -176.17802)
			(xy 395.48464 -176.136008) (xy 395.451697 -176.08848) (xy 395.426303 -176.036525) (xy 395.409041 -175.981333)
			(xy 395.400306 -175.924168) (xy 395.399768 -175.895254) (xy 395.400301 -175.86727) (xy 395.408459 -175.811899)
			(xy 395.424621 -175.758315) (xy 395.448442 -175.707669) (xy 395.479408 -175.661048) (xy 395.516856 -175.619454)
			(xy 395.559981 -175.583779) (xy 395.583664 -175.568864) (xy 395.593316 -175.563022) (xy 395.605508 -175.545242)
			(xy 395.622272 -175.447706) (xy 395.616938 -175.426624) (xy 395.609826 -175.417988) (xy 395.594097 -175.39796)
			(xy 395.567643 -175.354446) (xy 395.547359 -175.307735) (xy 395.533624 -175.258697) (xy 395.526693 -175.208246)
			(xy 395.52626 -175.182784) (xy 395.526742 -175.156168) (xy 395.534319 -175.103479) (xy 395.549317 -175.052405)
			(xy 395.571431 -175.003984) (xy 395.60021 -174.959203) (xy 395.635069 -174.918974) (xy 395.675298 -174.884114)
			(xy 395.720079 -174.855334) (xy 395.768499 -174.833219) (xy 395.819573 -174.81822) (xy 395.872262 -174.810642)
			(xy 395.898878 -174.810166) (xy 395.925299 -174.810644) (xy 395.977613 -174.818091) (xy 396.028351 -174.832851)
			(xy 396.076496 -174.85463) (xy 396.121082 -174.882991) (xy 396.141448 -174.899828) (xy 396.148306 -174.905924)
			(xy 396.165324 -174.91202) (xy 396.249652 -174.91202) (xy 396.26667 -174.905924) (xy 396.273528 -174.899828)
			(xy 396.293894 -174.882989) (xy 396.33848 -174.854624) (xy 396.386624 -174.832837) (xy 396.437361 -174.818066)
			(xy 396.489676 -174.810606) (xy 396.54252 -174.810606) (xy 396.594835 -174.818066) (xy 396.645572 -174.832837)
			(xy 396.693716 -174.854624) (xy 396.738302 -174.882989) (xy 396.758668 -174.899828) (xy 396.765526 -174.905924)
			(xy 396.782544 -174.91202) (xy 396.866872 -174.91202) (xy 396.88389 -174.905924) (xy 396.890748 -174.899828)
			(xy 396.911099 -174.882972) (xy 396.955693 -174.854619) (xy 397.003841 -174.832842) (xy 397.054581 -174.818079)
			(xy 397.106896 -174.810624) (xy 397.133318 -174.810166) (xy 397.161201 -174.81072) (xy 397.216343 -174.819034)
			(xy 397.26963 -174.835473) (xy 397.319873 -174.859671) (xy 397.365947 -174.891086) (xy 397.406825 -174.929017)
			(xy 397.441594 -174.972617) (xy 397.469476 -175.020912) (xy 397.489849 -175.072823) (xy 397.502257 -175.12719)
			(xy 397.506425 -175.1828) (xy 397.502257 -175.23841) (xy 397.489849 -175.292777) (xy 397.469476 -175.344688)
			(xy 397.441594 -175.392983) (xy 397.406825 -175.436583) (xy 397.365947 -175.474514) (xy 397.319873 -175.505929)
			(xy 397.26963 -175.530127) (xy 397.216343 -175.546566) (xy 397.161201 -175.55488) (xy 397.133318 -175.555402)
			(xy 397.106897 -175.554933) (xy 397.054582 -175.547486) (xy 397.003843 -175.532723) (xy 396.955699 -175.510942)
			(xy 396.911113 -175.482579) (xy 396.890748 -175.46574) (xy 396.88389 -175.459644) (xy 396.866872 -175.453548)
			(xy 396.782544 -175.453548) (xy 396.765526 -175.459644) (xy 396.758668 -175.46574) (xy 396.738302 -175.482579)
			(xy 396.693716 -175.510944) (xy 396.645572 -175.532731) (xy 396.594835 -175.547502) (xy 396.54252 -175.554962)
			(xy 396.489676 -175.554962) (xy 396.437361 -175.547502) (xy 396.386624 -175.532731) (xy 396.33848 -175.510944)
			(xy 396.293894 -175.482579) (xy 396.273528 -175.46574) (xy 396.26667 -175.459644) (xy 396.249652 -175.453548)
			(xy 396.165324 -175.453548) (xy 396.148306 -175.459644) (xy 396.141448 -175.46574) (xy 396.130876 -175.474582)
			(xy 396.108628 -175.490856) (xy 396.096998 -175.498252) (xy 396.0876 -175.504348) (xy 396.075662 -175.522382)
			(xy 396.060168 -175.620172) (xy 396.06601 -175.641254) (xy 396.073376 -175.649636) (xy 396.090191 -175.670369)
			(xy 396.118506 -175.715623) (xy 396.140232 -175.764384) (xy 396.154944 -175.815698) (xy 396.162355 -175.868563)
			(xy 396.162784 -175.895254) (xy 396.162239 -175.92417) (xy 396.153516 -175.98134) (xy 396.136264 -176.036539)
			(xy 396.110877 -176.088501) (xy 396.077938 -176.136035) (xy 396.053667 -176.1617) (xy 401.12569 -176.1617)
			(xy 401.126182 -176.133789) (xy 401.134317 -176.078563) (xy 401.150413 -176.025113) (xy 401.174125 -175.974578)
			(xy 401.204949 -175.928038) (xy 401.223226 -175.906938) (xy 401.229576 -175.899826) (xy 401.23618 -175.882554)
			(xy 401.23618 -175.795432) (xy 401.229576 -175.77816) (xy 401.223226 -175.771048) (xy 401.204938 -175.749957)
			(xy 401.174114 -175.703415) (xy 401.150402 -175.652878) (xy 401.134308 -175.599425) (xy 401.126175 -175.544198)
			(xy 401.12569 -175.516286) (xy 401.126176 -175.489035) (xy 401.133932 -175.435087) (xy 401.149287 -175.382792)
			(xy 401.171929 -175.333215) (xy 401.201395 -175.287365) (xy 401.237086 -175.246174) (xy 401.278277 -175.210483)
			(xy 401.324127 -175.181017) (xy 401.373704 -175.158375) (xy 401.425999 -175.14302) (xy 401.479947 -175.135264)
			(xy 401.534449 -175.135264) (xy 401.588397 -175.14302) (xy 401.640692 -175.158375) (xy 401.690269 -175.181017)
			(xy 401.736119 -175.210483) (xy 401.77731 -175.246174) (xy 401.813001 -175.287365) (xy 401.842467 -175.333215)
			(xy 401.865109 -175.382792) (xy 401.880464 -175.435087) (xy 401.88822 -175.489035) (xy 401.888706 -175.516286)
			(xy 401.888206 -175.544197) (xy 401.880074 -175.599422) (xy 401.86398 -175.652873) (xy 401.840269 -175.703408)
			(xy 401.809446 -175.749948) (xy 401.79117 -175.771048) (xy 401.78482 -175.77816) (xy 401.778216 -175.795432)
			(xy 401.778216 -175.882554) (xy 401.78482 -175.899826) (xy 401.79117 -175.906938) (xy 401.809451 -175.928035)
			(xy 401.840276 -175.974575) (xy 401.863989 -176.02511) (xy 401.880085 -176.078562) (xy 401.88822 -176.133789)
			(xy 401.888706 -176.1617) (xy 401.88822 -176.188951) (xy 401.880464 -176.242899) (xy 401.865109 -176.295194)
			(xy 401.842467 -176.344771) (xy 401.813001 -176.390621) (xy 401.77731 -176.431812) (xy 401.736119 -176.467503)
			(xy 401.690269 -176.496969) (xy 401.640692 -176.519611) (xy 401.588397 -176.534966) (xy 401.534449 -176.542722)
			(xy 401.479947 -176.542722) (xy 401.425999 -176.534966) (xy 401.373704 -176.519611) (xy 401.324127 -176.496969)
			(xy 401.278277 -176.467503) (xy 401.237086 -176.431812) (xy 401.201395 -176.390621) (xy 401.171929 -176.344771)
			(xy 401.149287 -176.295194) (xy 401.133932 -176.242899) (xy 401.126176 -176.188951) (xy 401.12569 -176.1617)
			(xy 396.053667 -176.1617) (xy 396.038202 -176.178053) (xy 396.015718 -176.196244) (xy 396.006927 -176.203777)
			(xy 395.996763 -176.224558) (xy 395.99616 -176.236122) (xy 395.99616 -176.316386) (xy 395.996718 -176.327956)
			(xy 396.006919 -176.348728) (xy 396.015718 -176.356264) (xy 396.038188 -176.374471) (xy 396.077923 -176.416488)
			(xy 396.110863 -176.46402) (xy 396.136254 -176.515978) (xy 396.153513 -176.571172) (xy 396.162247 -176.628339)
			(xy 396.162784 -176.657254) (xy 396.162298 -176.684505) (xy 396.154542 -176.738453) (xy 396.139187 -176.790748)
			(xy 396.116545 -176.840325) (xy 396.087079 -176.886175) (xy 396.051388 -176.927366) (xy 396.010197 -176.963057)
			(xy 395.964347 -176.992523) (xy 395.91477 -177.015165) (xy 395.862475 -177.03052) (xy 395.808527 -177.038276)
			(xy 395.754025 -177.038276) (xy 395.700077 -177.03052) (xy 395.647782 -177.015165) (xy 395.598205 -176.992523)
			(xy 395.552355 -176.963057) (xy 395.511164 -176.927366) (xy 395.475473 -176.886175) (xy 395.446007 -176.840325)
			(xy 395.423365 -176.790748) (xy 395.40801 -176.738453) (xy 395.400254 -176.684505) (xy 395.399768 -176.657254)
			(xy 393.043918 -176.657254) (xy 392.244326 -177.456846) (xy 392.237521 -177.464274) (xy 392.22978 -177.482852)
			(xy 392.22934 -177.492914) (xy 392.22934 -178.440334) (xy 392.228734 -178.465318) (xy 392.218989 -178.514326)
			(xy 392.19988 -178.560496) (xy 392.17214 -178.602056) (xy 392.154918 -178.620166) (xy 391.813034 -178.96205)
			(xy 392.330938 -178.96205) (xy 392.335009 -178.906428) (xy 392.347135 -178.851991) (xy 392.367058 -178.7999)
			(xy 392.394354 -178.751265) (xy 392.42844 -178.707122) (xy 392.468589 -178.668413) (xy 392.513947 -178.635962)
			(xy 392.563547 -178.610461) (xy 392.616331 -178.592454) (xy 392.671174 -178.582324) (xy 392.726908 -178.580287)
			(xy 392.782345 -178.586387) (xy 392.836302 -178.600493) (xy 392.887631 -178.622305) (xy 392.935237 -178.651359)
			(xy 392.978105 -178.687034) (xy 393.015322 -178.728571) (xy 393.046095 -178.775084) (xy 393.069767 -178.825581)
			(xy 393.085835 -178.878988) (xy 393.093955 -178.934164) (xy 393.094464 -178.96205) (xy 393.093955 -178.989936)
			(xy 393.085835 -179.045112) (xy 393.069767 -179.098519) (xy 393.046095 -179.149016) (xy 393.015322 -179.195529)
			(xy 392.978105 -179.237066) (xy 392.935237 -179.272741) (xy 392.887631 -179.301795) (xy 392.836302 -179.323607)
			(xy 392.782345 -179.337713) (xy 392.726908 -179.343813) (xy 392.671174 -179.341776) (xy 392.616331 -179.331646)
			(xy 392.563547 -179.313639) (xy 392.513947 -179.288138) (xy 392.468589 -179.255687) (xy 392.42844 -179.216978)
			(xy 392.394354 -179.172835) (xy 392.367058 -179.1242) (xy 392.347135 -179.072109) (xy 392.335009 -179.017672)
			(xy 392.330938 -178.96205) (xy 391.813034 -178.96205) (xy 391.739374 -179.03571) (xy 391.735564 -179.046886)
			(xy 391.726643 -179.071651) (xy 391.702936 -179.11865) (xy 391.67299 -179.161941) (xy 391.637374 -179.200702)
			(xy 391.596766 -179.234196) (xy 391.551937 -179.261786) (xy 391.50374 -179.282949) (xy 391.45309 -179.297282)
			(xy 391.40095 -179.304512) (xy 391.37463 -179.30495) (xy 391.347381 -179.304394) (xy 391.293438 -179.296643)
			(xy 391.241148 -179.281293) (xy 391.191573 -179.258659) (xy 391.145725 -179.2292) (xy 391.104535 -179.193516)
			(xy 391.068844 -179.152333) (xy 391.039376 -179.10649) (xy 391.016732 -179.05692) (xy 391.001373 -179.004632)
			(xy 390.993611 -178.95069) (xy 390.993122 -178.923442) (xy 390.993628 -178.895968) (xy 391.001514 -178.841589)
			(xy 391.017129 -178.788907) (xy 391.04015 -178.739014) (xy 391.070098 -178.692944) (xy 391.087864 -178.671982)
			(xy 391.09396 -178.66487) (xy 391.10031 -178.647852) (xy 391.10031 -178.562) (xy 391.09396 -178.544982)
			(xy 391.087864 -178.53787) (xy 391.070099 -178.516909) (xy 391.040176 -178.470826) (xy 391.017164 -178.420932)
			(xy 391.001538 -178.368255) (xy 390.993621 -178.313882) (xy 390.993122 -178.28641) (xy 390.993678 -178.257339)
			(xy 391.002512 -178.199872) (xy 391.019963 -178.14441) (xy 391.045625 -178.092237) (xy 391.078906 -178.044562)
			(xy 391.119034 -178.002488) (xy 391.165081 -177.966988) (xy 391.21598 -177.938885) (xy 391.270554 -177.918829)
			(xy 391.298938 -177.912522) (xy 391.316718 -177.908966) (xy 391.339832 -177.880772) (xy 391.339832 -177.208434)
			(xy 391.340427 -177.18345) (xy 391.350176 -177.134441) (xy 391.369289 -177.088272) (xy 391.397031 -177.046712)
			(xy 391.414254 -177.028602) (xy 392.667998 -175.774858) (xy 392.674849 -175.767466) (xy 392.682562 -175.748861)
			(xy 392.682984 -175.73879) (xy 392.682984 -155.398724) (xy 392.68255 -155.388656) (xy 392.674836 -155.370057)
			(xy 392.667998 -155.362656) (xy 388.701534 -151.396192) (xy 388.694062 -151.389486) (xy 388.675496 -151.381902)
			(xy 388.665466 -151.38146) (xy 383.584958 -151.38146) (xy 383.559963 -151.380794) (xy 383.510942 -151.371)
			(xy 383.464771 -151.351835) (xy 383.423223 -151.324036) (xy 383.405126 -151.306784) (xy 383.12725 -151.028908)
			(xy 383.119782 -151.022198) (xy 383.101212 -151.014619) (xy 383.091182 -151.014176) (xy 381.449072 -151.014176)
			(xy 381.439069 -151.013706) (xy 381.420606 -151.005993) (xy 381.413258 -150.99919) (xy 381.066548 -150.65248)
			(xy 381.059073 -150.645779) (xy 381.040509 -150.638192) (xy 381.03048 -150.637748) (xy 377.159012 -150.637748)
			(xy 377.148986 -150.63813) (xy 377.13046 -150.645805) (xy 377.116285 -150.65999) (xy 377.108623 -150.678521)
			(xy 377.108212 -150.688548) (xy 377.108212 -155.640532) (xy 378.748036 -155.640532) (xy 378.748512 -155.613162)
			(xy 378.756326 -155.558983) (xy 378.771812 -155.50648) (xy 378.794652 -155.456733) (xy 378.824375 -155.410766)
			(xy 378.842016 -155.389834) (xy 378.848112 -155.382722) (xy 378.854462 -155.365704) (xy 378.854462 -155.28036)
			(xy 378.848112 -155.263342) (xy 378.842016 -155.25623) (xy 378.824407 -155.235272) (xy 378.794682 -155.189308)
			(xy 378.771835 -155.139566) (xy 378.756337 -155.087068) (xy 378.748506 -155.032893) (xy 378.748502 -154.978155)
			(xy 378.756327 -154.923979) (xy 378.771818 -154.871479) (xy 378.794659 -154.821734) (xy 378.824378 -154.775767)
			(xy 378.842016 -154.754834) (xy 378.848112 -154.747722) (xy 378.854462 -154.730704) (xy 378.854462 -154.64536)
			(xy 378.848112 -154.628342) (xy 378.842016 -154.62123) (xy 378.824407 -154.600272) (xy 378.794682 -154.554308)
			(xy 378.771835 -154.504566) (xy 378.756337 -154.452068) (xy 378.748506 -154.397893) (xy 378.748502 -154.343155)
			(xy 378.756327 -154.288979) (xy 378.771818 -154.236479) (xy 378.794659 -154.186734) (xy 378.824378 -154.140767)
			(xy 378.842016 -154.119834) (xy 378.848112 -154.112722) (xy 378.854462 -154.095704) (xy 378.854462 -154.01036)
			(xy 378.848112 -153.993342) (xy 378.842016 -153.98623) (xy 378.82438 -153.965295) (xy 378.794667 -153.919324)
			(xy 378.77183 -153.869577) (xy 378.756339 -153.817076) (xy 378.74851 -153.762901) (xy 378.748036 -153.735532)
			(xy 378.748485 -153.708278) (xy 378.756239 -153.654324) (xy 378.771593 -153.602023) (xy 378.794235 -153.55244)
			(xy 378.823704 -153.506585) (xy 378.859399 -153.465391) (xy 378.900595 -153.429697) (xy 378.946451 -153.400229)
			(xy 378.996035 -153.377589) (xy 379.048336 -153.362236) (xy 379.10229 -153.354484) (xy 379.129544 -153.354024)
			(xy 379.15945 -153.35459) (xy 379.218528 -153.363942) (xy 379.275423 -153.382394) (xy 379.328744 -153.409495)
			(xy 379.377186 -153.444582) (xy 379.398784 -153.465276) (xy 379.405896 -153.472388) (xy 379.423168 -153.479754)
			(xy 379.512576 -153.482548) (xy 379.530356 -153.476198) (xy 379.537722 -153.469594) (xy 379.545539 -153.462796)
			(xy 379.561805 -153.449962) (xy 379.570234 -153.44394) (xy 379.579632 -153.437336) (xy 379.590808 -153.418032)
			(xy 379.599444 -153.317956) (xy 379.591824 -153.297128) (xy 379.583696 -153.289) (xy 379.562873 -153.267422)
			(xy 379.527622 -153.218915) (xy 379.500396 -153.165488) (xy 379.481867 -153.10846) (xy 379.47249 -153.049234)
			(xy 379.471936 -153.019252) (xy 379.472424 -152.991882) (xy 379.480235 -152.937704) (xy 379.495719 -152.885201)
			(xy 379.518556 -152.835453) (xy 379.548276 -152.789486) (xy 379.565916 -152.768554) (xy 379.572012 -152.761442)
			(xy 379.578362 -152.744424) (xy 379.578362 -152.65908) (xy 379.572012 -152.642062) (xy 379.565916 -152.63495)
			(xy 379.548289 -152.614008) (xy 379.518575 -152.568038) (xy 379.495737 -152.518293) (xy 379.480243 -152.465795)
			(xy 379.472411 -152.411621) (xy 379.471936 -152.384252) (xy 379.472333 -152.356998) (xy 379.480097 -152.303044)
			(xy 379.495461 -152.250745) (xy 379.518111 -152.201165) (xy 379.547586 -152.155313) (xy 379.583287 -152.114122)
			(xy 379.624486 -152.078431) (xy 379.670346 -152.048967) (xy 379.719932 -152.026329) (xy 379.772234 -152.010978)
			(xy 379.826189 -152.003227) (xy 379.853444 -152.002744) (xy 379.880814 -152.003232) (xy 379.934992 -152.011043)
			(xy 379.987495 -152.026526) (xy 380.037243 -152.049363) (xy 380.08321 -152.079084) (xy 380.104142 -152.096724)
			(xy 380.111254 -152.10282) (xy 380.128272 -152.10917) (xy 380.213616 -152.10917) (xy 380.230634 -152.10282)
			(xy 380.237746 -152.096724) (xy 380.258679 -152.079083) (xy 380.304647 -152.049359) (xy 380.354393 -152.026513)
			(xy 380.406895 -152.011017) (xy 380.461073 -152.003188) (xy 380.515815 -152.003188) (xy 380.569993 -152.011017)
			(xy 380.622495 -152.026513) (xy 380.672241 -152.049359) (xy 380.718209 -152.079083) (xy 380.739142 -152.096724)
			(xy 380.746254 -152.10282) (xy 380.763272 -152.10917) (xy 380.848616 -152.10917) (xy 380.865634 -152.10282)
			(xy 380.872746 -152.096724) (xy 380.893679 -152.079083) (xy 380.939647 -152.049359) (xy 380.989393 -152.026513)
			(xy 381.041895 -152.011017) (xy 381.096073 -152.003188) (xy 381.150815 -152.003188) (xy 381.204993 -152.011017)
			(xy 381.257495 -152.026513) (xy 381.307241 -152.049359) (xy 381.353209 -152.079083) (xy 381.374142 -152.096724)
			(xy 381.381254 -152.10282) (xy 381.398272 -152.10917) (xy 381.483616 -152.10917) (xy 381.500634 -152.10282)
			(xy 381.507746 -152.096724) (xy 381.528691 -152.0791) (xy 381.57466 -152.049385) (xy 381.624404 -152.026546)
			(xy 381.676902 -152.011052) (xy 381.731076 -152.00322) (xy 381.758444 -152.002744) (xy 381.785694 -152.003237)
			(xy 381.839639 -152.010998) (xy 381.891931 -152.026356) (xy 381.941505 -152.048999) (xy 381.987353 -152.078465)
			(xy 382.028541 -152.114156) (xy 382.064232 -152.155344) (xy 382.093699 -152.201191) (xy 382.116342 -152.250765)
			(xy 382.131701 -152.303057) (xy 382.139463 -152.357002) (xy 382.139952 -152.384252) (xy 382.139469 -152.411622)
			(xy 382.131657 -152.465801) (xy 382.116173 -152.518304) (xy 382.093334 -152.568051) (xy 382.063612 -152.614018)
			(xy 382.045972 -152.63495) (xy 382.039876 -152.642062) (xy 382.033526 -152.65908) (xy 382.033526 -152.744424)
			(xy 382.039876 -152.761442) (xy 382.045972 -152.768554) (xy 382.063599 -152.789496) (xy 382.093313 -152.835466)
			(xy 382.116152 -152.885211) (xy 382.131646 -152.937709) (xy 382.139477 -152.991883) (xy 382.139952 -153.019252)
			(xy 382.139434 -153.048033) (xy 382.13078 -153.104939) (xy 382.113677 -153.159901) (xy 382.088512 -153.21167)
			(xy 382.055856 -153.259071) (xy 382.016451 -153.30103) (xy 381.97119 -153.336593) (xy 381.946404 -153.35123)
			(xy 381.936498 -153.356818) (xy 381.923544 -153.37536) (xy 381.906272 -153.47569) (xy 381.912114 -153.49728)
			(xy 381.919734 -153.50617) (xy 381.937187 -153.527084) (xy 381.96664 -153.572906) (xy 381.989282 -153.622449)
			(xy 382.004654 -153.674706) (xy 382.012443 -153.728617) (xy 382.012952 -153.755852) (xy 382.012469 -153.783222)
			(xy 382.004657 -153.837401) (xy 381.989173 -153.889904) (xy 381.966334 -153.939651) (xy 381.936612 -153.985618)
			(xy 381.918972 -154.00655) (xy 381.912876 -154.013662) (xy 381.906526 -154.03068) (xy 381.906526 -154.116024)
			(xy 381.912876 -154.133042) (xy 381.918972 -154.140154) (xy 381.936566 -154.161125) (xy 381.966293 -154.207086)
			(xy 381.989141 -154.256826) (xy 382.004641 -154.309322) (xy 382.012474 -154.363496) (xy 382.012479 -154.418232)
			(xy 382.004656 -154.472407) (xy 381.989166 -154.524906) (xy 381.966327 -154.574651) (xy 381.936609 -154.620617)
			(xy 381.918972 -154.64155) (xy 381.912876 -154.648662) (xy 381.906526 -154.66568) (xy 381.906526 -154.751024)
			(xy 381.912876 -154.768042) (xy 381.918972 -154.775154) (xy 381.936566 -154.796125) (xy 381.966293 -154.842086)
			(xy 381.989141 -154.891826) (xy 382.004641 -154.944322) (xy 382.012474 -154.998496) (xy 382.012479 -155.053232)
			(xy 382.004656 -155.107407) (xy 381.989166 -155.159906) (xy 381.966327 -155.209651) (xy 381.936609 -155.255617)
			(xy 381.918972 -155.27655) (xy 381.912876 -155.283662) (xy 381.906526 -155.30068) (xy 381.906526 -155.386024)
			(xy 381.912876 -155.403042) (xy 381.918972 -155.410154) (xy 381.936599 -155.431096) (xy 381.966313 -155.477066)
			(xy 381.989152 -155.526811) (xy 382.004646 -155.579309) (xy 382.012477 -155.633483) (xy 382.012952 -155.660852)
			(xy 382.012435 -155.688653) (xy 382.004382 -155.743668) (xy 381.988424 -155.79693) (xy 381.9649 -155.84731)
			(xy 381.934309 -155.89374) (xy 381.897299 -155.935234) (xy 381.8763 -155.95346) (xy 381.86815 -155.961065)
			(xy 381.858649 -155.981196) (xy 381.858012 -155.992322) (xy 381.858012 -156.071824) (xy 381.8763 -156.097732)
			(xy 381.891286 -156.10332) (xy 381.918266 -156.113936) (xy 381.968932 -156.142116) (xy 382.014751 -156.177637)
			(xy 382.054669 -156.21968) (xy 382.087768 -156.267279) (xy 382.113284 -156.319338) (xy 382.130631 -156.374657)
			(xy 382.139409 -156.431964) (xy 382.139952 -156.460952) (xy 382.139469 -156.488322) (xy 382.131657 -156.542501)
			(xy 382.116173 -156.595004) (xy 382.093334 -156.644751) (xy 382.063612 -156.690718) (xy 382.045972 -156.71165)
			(xy 382.039876 -156.718762) (xy 382.033526 -156.73578) (xy 382.033526 -156.821124) (xy 382.039876 -156.838142)
			(xy 382.045972 -156.845254) (xy 382.063599 -156.866196) (xy 382.093313 -156.912166) (xy 382.116152 -156.961911)
			(xy 382.127975 -157.001972) (xy 386.91185 -157.001972) (xy 386.912287 -156.974601) (xy 386.92011 -156.92042)
			(xy 386.935605 -156.867916) (xy 386.958454 -156.818169) (xy 386.988185 -156.772204) (xy 387.00583 -156.751274)
			(xy 387.011926 -156.744162) (xy 387.018276 -156.727144) (xy 387.018276 -156.6418) (xy 387.011926 -156.624782)
			(xy 387.00583 -156.61767) (xy 386.988215 -156.596718) (xy 386.958498 -156.550752) (xy 386.935657 -156.501009)
			(xy 386.920161 -156.448512) (xy 386.912327 -156.39434) (xy 386.91185 -156.366972) (xy 386.912354 -156.339204)
			(xy 386.920393 -156.284252) (xy 386.936312 -156.231046) (xy 386.959775 -156.180709) (xy 386.990286 -156.134304)
			(xy 387.00837 -156.113226) (xy 387.01472 -156.106114) (xy 387.021324 -156.088842) (xy 387.021324 -156.002482)
			(xy 387.01472 -155.98521) (xy 387.00837 -155.978098) (xy 386.990305 -155.957004) (xy 386.959797 -155.910601)
			(xy 386.936331 -155.860268) (xy 386.920405 -155.807066) (xy 386.912353 -155.752119) (xy 386.91185 -155.724352)
			(xy 386.912334 -155.696982) (xy 386.920146 -155.642803) (xy 386.93563 -155.5903) (xy 386.958468 -155.540553)
			(xy 386.98819 -155.494586) (xy 387.00583 -155.473654) (xy 387.011926 -155.466542) (xy 387.018276 -155.449524)
			(xy 387.018276 -155.36418) (xy 387.011926 -155.347162) (xy 387.00583 -155.34005) (xy 386.988206 -155.319106)
			(xy 386.95849 -155.273137) (xy 386.935651 -155.223393) (xy 386.920157 -155.170894) (xy 386.912326 -155.11672)
			(xy 386.91185 -155.089352) (xy 386.912358 -155.060613) (xy 386.920986 -155.003785) (xy 386.938041 -154.948895)
			(xy 386.963136 -154.897183) (xy 386.995703 -154.849821) (xy 387.014974 -154.828494) (xy 387.021578 -154.821382)
			(xy 387.02869 -154.803856) (xy 387.02869 -154.714448) (xy 387.021578 -154.696922) (xy 387.014974 -154.68981)
			(xy 386.995686 -154.668497) (xy 386.963121 -154.621132) (xy 386.938031 -154.569417) (xy 386.920985 -154.514523)
			(xy 386.912368 -154.457692) (xy 386.91185 -154.428952) (xy 386.912334 -154.401582) (xy 386.920146 -154.347403)
			(xy 386.93563 -154.2949) (xy 386.958468 -154.245153) (xy 386.98819 -154.199186) (xy 387.00583 -154.178254)
			(xy 387.011926 -154.171142) (xy 387.018276 -154.154124) (xy 387.018276 -154.06878) (xy 387.011926 -154.051762)
			(xy 387.00583 -154.04465) (xy 386.988206 -154.023706) (xy 386.95849 -153.977737) (xy 386.935651 -153.927993)
			(xy 386.920157 -153.875494) (xy 386.912326 -153.82132) (xy 386.91185 -153.793952) (xy 386.912333 -153.766701)
			(xy 386.920095 -153.712756) (xy 386.935454 -153.660464) (xy 386.958098 -153.610889) (xy 386.987565 -153.565041)
			(xy 387.023257 -153.523852) (xy 387.064446 -153.488162) (xy 387.110294 -153.458695) (xy 387.159869 -153.436052)
			(xy 387.212162 -153.420694) (xy 387.266107 -153.412933) (xy 387.293358 -153.412444) (xy 387.320728 -153.412924)
			(xy 387.374907 -153.420737) (xy 387.42741 -153.436222) (xy 387.477157 -153.459061) (xy 387.523124 -153.488783)
			(xy 387.544056 -153.506424) (xy 387.551168 -153.51252) (xy 387.568186 -153.51887) (xy 387.65353 -153.51887)
			(xy 387.670548 -153.51252) (xy 387.67766 -153.506424) (xy 387.698599 -153.488794) (xy 387.74457 -153.45908)
			(xy 387.794315 -153.436242) (xy 387.846815 -153.420749) (xy 387.900989 -153.412919) (xy 387.928358 -153.412444)
			(xy 387.955606 -153.413017) (xy 388.009548 -153.420767) (xy 388.061838 -153.436114) (xy 388.111412 -153.458747)
			(xy 388.15726 -153.488204) (xy 388.19845 -153.523887) (xy 388.234142 -153.565068) (xy 388.26361 -153.610909)
			(xy 388.286254 -153.660477) (xy 388.301614 -153.712764) (xy 388.309376 -153.766704) (xy 388.309866 -153.793952)
			(xy 388.30938 -153.821322) (xy 388.301568 -153.8755) (xy 388.286084 -153.928003) (xy 388.263247 -153.977751)
			(xy 388.233526 -154.023718) (xy 388.215886 -154.04465) (xy 388.20979 -154.051762) (xy 388.20344 -154.06878)
			(xy 388.20344 -154.154124) (xy 388.20979 -154.171142) (xy 388.215886 -154.178254) (xy 388.233515 -154.199194)
			(xy 388.263229 -154.245165) (xy 388.286067 -154.29491) (xy 388.30156 -154.347409) (xy 388.309391 -154.401583)
			(xy 388.309866 -154.428952) (xy 388.309356 -154.457691) (xy 388.300728 -154.514518) (xy 388.283673 -154.569409)
			(xy 388.258579 -154.62112) (xy 388.226013 -154.668483) (xy 388.206742 -154.68981) (xy 388.200138 -154.696922)
			(xy 388.193026 -154.714448) (xy 388.193026 -154.803856) (xy 388.200138 -154.821382) (xy 388.206742 -154.828494)
			(xy 388.226034 -154.849803) (xy 388.258598 -154.897169) (xy 388.283687 -154.948886) (xy 388.300732 -155.003781)
			(xy 388.309349 -155.060612) (xy 388.309866 -155.089352) (xy 388.30938 -155.116722) (xy 388.301568 -155.1709)
			(xy 388.286084 -155.223403) (xy 388.263247 -155.273151) (xy 388.233526 -155.319118) (xy 388.215886 -155.34005)
			(xy 388.20979 -155.347162) (xy 388.20344 -155.36418) (xy 388.20344 -155.449524) (xy 388.20979 -155.466542)
			(xy 388.215886 -155.473654) (xy 388.233515 -155.494594) (xy 388.263229 -155.540565) (xy 388.286067 -155.59031)
			(xy 388.30156 -155.642809) (xy 388.309391 -155.696983) (xy 388.309866 -155.724352) (xy 388.309372 -155.752121)
			(xy 388.30133 -155.807073) (xy 388.285408 -155.860279) (xy 388.261943 -155.910615) (xy 388.231431 -155.95702)
			(xy 388.213346 -155.978098) (xy 388.206996 -155.98521) (xy 388.200392 -156.002482) (xy 388.200392 -156.088842)
			(xy 388.206996 -156.106114) (xy 388.213346 -156.113226) (xy 388.231425 -156.134308) (xy 388.261931 -156.180715)
			(xy 388.285393 -156.231051) (xy 388.301316 -156.284255) (xy 388.309365 -156.339204) (xy 388.309866 -156.366972)
			(xy 388.309392 -156.394342) (xy 388.301577 -156.448521) (xy 388.28609 -156.501024) (xy 388.26325 -156.550771)
			(xy 388.233527 -156.596738) (xy 388.215886 -156.61767) (xy 388.20979 -156.624782) (xy 388.20344 -156.6418)
			(xy 388.20344 -156.727144) (xy 388.20979 -156.744162) (xy 388.215886 -156.751274) (xy 388.233524 -156.772207)
			(xy 388.263237 -156.818179) (xy 388.286073 -156.867926) (xy 388.301564 -156.920427) (xy 388.309392 -156.974603)
			(xy 388.309866 -157.001972) (xy 388.309419 -157.029226) (xy 388.301664 -157.08318) (xy 388.28631 -157.13548)
			(xy 388.263667 -157.185063) (xy 388.234198 -157.230919) (xy 388.198503 -157.272113) (xy 388.157307 -157.307807)
			(xy 388.111451 -157.337274) (xy 388.061867 -157.359915) (xy 388.009566 -157.375267) (xy 387.955612 -157.38302)
			(xy 387.928358 -157.38348) (xy 387.900989 -157.382985) (xy 387.846811 -157.375175) (xy 387.794308 -157.359693)
			(xy 387.74456 -157.336857) (xy 387.698592 -157.307139) (xy 387.67766 -157.2895) (xy 387.670548 -157.283404)
			(xy 387.65353 -157.277054) (xy 387.568186 -157.277054) (xy 387.551168 -157.283404) (xy 387.544056 -157.2895)
			(xy 387.523114 -157.307126) (xy 387.477144 -157.33684) (xy 387.427399 -157.359678) (xy 387.3749 -157.375173)
			(xy 387.320726 -157.383004) (xy 387.293358 -157.38348) (xy 387.266104 -157.383061) (xy 387.212153 -157.375298)
			(xy 387.159855 -157.359936) (xy 387.110276 -157.337288) (xy 387.064424 -157.307815) (xy 387.023234 -157.272117)
			(xy 386.987543 -157.23092) (xy 386.958078 -157.185063) (xy 386.935439 -157.135479) (xy 386.920087 -157.083179)
			(xy 386.912334 -157.029226) (xy 386.91185 -157.001972) (xy 382.127975 -157.001972) (xy 382.131646 -157.014409)
			(xy 382.139477 -157.068583) (xy 382.139952 -157.095952) (xy 382.1394 -157.123202) (xy 382.131651 -157.177147)
			(xy 382.116303 -157.229441) (xy 382.093669 -157.279018) (xy 382.064211 -157.324869) (xy 382.028526 -157.366061)
			(xy 381.987343 -157.401755) (xy 381.941499 -157.431225) (xy 381.891927 -157.453871) (xy 381.839637 -157.469231)
			(xy 381.785694 -157.476994) (xy 381.758444 -157.47746) (xy 381.731074 -157.476978) (xy 381.676895 -157.469165)
			(xy 381.624392 -157.453681) (xy 381.574645 -157.430842) (xy 381.528678 -157.40112) (xy 381.507746 -157.38348)
			(xy 381.500634 -157.377384) (xy 381.483616 -157.371034) (xy 381.398272 -157.371034) (xy 381.381254 -157.377384)
			(xy 381.374142 -157.38348) (xy 381.353209 -157.401121) (xy 381.307241 -157.430845) (xy 381.257495 -157.453691)
			(xy 381.204993 -157.469187) (xy 381.150815 -157.477016) (xy 381.096073 -157.477016) (xy 381.041895 -157.469187)
			(xy 380.989393 -157.453691) (xy 380.939647 -157.430845) (xy 380.893679 -157.401121) (xy 380.872746 -157.38348)
			(xy 380.865634 -157.377384) (xy 380.848616 -157.371034) (xy 380.763272 -157.371034) (xy 380.746254 -157.377384)
			(xy 380.739142 -157.38348) (xy 380.718209 -157.401121) (xy 380.672241 -157.430845) (xy 380.622495 -157.453691)
			(xy 380.569993 -157.469187) (xy 380.515815 -157.477016) (xy 380.461073 -157.477016) (xy 380.406895 -157.469187)
			(xy 380.354393 -157.453691) (xy 380.304647 -157.430845) (xy 380.258679 -157.401121) (xy 380.237746 -157.38348)
			(xy 380.230634 -157.377384) (xy 380.213616 -157.371034) (xy 380.128272 -157.371034) (xy 380.111254 -157.377384)
			(xy 380.104142 -157.38348) (xy 380.083202 -157.40111) (xy 380.037232 -157.430824) (xy 379.987486 -157.453662)
			(xy 379.934987 -157.469155) (xy 379.880813 -157.476985) (xy 379.853444 -157.47746) (xy 379.82354 -157.476843)
			(xy 379.764464 -157.467504) (xy 379.707569 -157.449064) (xy 379.654247 -157.421974) (xy 379.605804 -157.386898)
			(xy 379.584204 -157.366208) (xy 379.577092 -157.359096) (xy 379.55982 -157.35173) (xy 379.470412 -157.348936)
			(xy 379.452632 -157.355286) (xy 379.445266 -157.36189) (xy 379.424251 -157.37974) (xy 379.378064 -157.409851)
			(xy 379.328024 -157.433002) (xy 379.275173 -157.448711) (xy 379.220612 -157.456652) (xy 379.193044 -157.45714)
			(xy 379.165794 -157.456604) (xy 379.111847 -157.448854) (xy 379.059552 -157.433505) (xy 379.009975 -157.41087)
			(xy 378.964123 -157.381409) (xy 378.92293 -157.345723) (xy 378.887236 -157.304538) (xy 378.857767 -157.258692)
			(xy 378.835122 -157.209119) (xy 378.819762 -157.156827) (xy 378.812002 -157.102882) (xy 378.811536 -157.075632)
			(xy 378.812012 -157.048262) (xy 378.819826 -156.994083) (xy 378.835312 -156.94158) (xy 378.858152 -156.891833)
			(xy 378.887875 -156.845866) (xy 378.905516 -156.824934) (xy 378.911612 -156.817822) (xy 378.917962 -156.800804)
			(xy 378.917962 -156.71546) (xy 378.911612 -156.698442) (xy 378.905516 -156.69133) (xy 378.88788 -156.670395)
			(xy 378.858167 -156.624424) (xy 378.83533 -156.574677) (xy 378.819839 -156.522176) (xy 378.81201 -156.468001)
			(xy 378.811536 -156.440632) (xy 378.812066 -156.411956) (xy 378.820635 -156.355248) (xy 378.837599 -156.300463)
			(xy 378.862576 -156.248836) (xy 378.895002 -156.201531) (xy 378.934147 -156.159616) (xy 378.956316 -156.14142)
			(xy 378.966222 -156.133546) (xy 378.976382 -156.110432) (xy 378.967746 -156.000704) (xy 378.95403 -155.979622)
			(xy 378.942854 -155.973272) (xy 378.917936 -155.958648) (xy 378.872393 -155.923103) (xy 378.832729 -155.881098)
			(xy 378.79985 -155.833593) (xy 378.774509 -155.781675) (xy 378.757285 -155.72653) (xy 378.74857 -155.669418)
			(xy 378.748036 -155.640532) (xy 377.108212 -155.640532) (xy 377.108212 -157.954472) (xy 377.108649 -157.96454)
			(xy 377.116361 -157.983138) (xy 377.123198 -157.99054) (xy 381.827716 -162.695058) (xy 386.317994 -162.695058)
			(xy 386.317994 -162.610362) (xy 386.326045 -162.526048) (xy 386.342074 -162.442882) (xy 386.365935 -162.361615)
			(xy 386.397414 -162.282985) (xy 386.436225 -162.207704) (xy 386.482015 -162.136452) (xy 386.534371 -162.069876)
			(xy 386.592819 -162.008578) (xy 386.656829 -161.953113) (xy 386.725821 -161.903984) (xy 386.799171 -161.861635)
			(xy 386.876214 -161.826451) (xy 386.956253 -161.798749) (xy 387.038562 -161.778781) (xy 387.122397 -161.766728)
			(xy 387.206998 -161.762698) (xy 387.291599 -161.766728) (xy 387.375434 -161.778781) (xy 387.457743 -161.798749)
			(xy 387.537782 -161.826451) (xy 387.614825 -161.861635) (xy 387.688175 -161.903984) (xy 387.757167 -161.953113)
			(xy 387.821177 -162.008578) (xy 387.879625 -162.069876) (xy 387.931981 -162.136452) (xy 387.977771 -162.207704)
			(xy 388.016582 -162.282985) (xy 388.048061 -162.361615) (xy 388.071922 -162.442882) (xy 388.087951 -162.526048)
			(xy 388.096002 -162.610362) (xy 388.096506 -162.65271) (xy 388.096002 -162.695058) (xy 388.087951 -162.779372)
			(xy 388.071922 -162.862538) (xy 388.048061 -162.943805) (xy 388.016582 -163.022435) (xy 387.977771 -163.097716)
			(xy 387.931981 -163.168968) (xy 387.879625 -163.235544) (xy 387.821177 -163.296842) (xy 387.757167 -163.352307)
			(xy 387.688175 -163.401436) (xy 387.614825 -163.443785) (xy 387.537782 -163.478969) (xy 387.457743 -163.506671)
			(xy 387.375434 -163.526639) (xy 387.291599 -163.538692) (xy 387.206998 -163.542723) (xy 387.122397 -163.538692)
			(xy 387.038562 -163.526639) (xy 386.956253 -163.506671) (xy 386.876214 -163.478969) (xy 386.799171 -163.443785)
			(xy 386.725821 -163.401436) (xy 386.656829 -163.352307) (xy 386.592819 -163.296842) (xy 386.534371 -163.235544)
			(xy 386.482015 -163.168968) (xy 386.436225 -163.097716) (xy 386.397414 -163.022435) (xy 386.365935 -162.943805)
			(xy 386.342074 -162.862538) (xy 386.326045 -162.779372) (xy 386.317994 -162.695058) (xy 381.827716 -162.695058)
			(xy 383.823718 -164.69106) (xy 383.84093 -164.709179) (xy 383.868675 -164.750735) (xy 383.887785 -164.796902)
			(xy 383.897528 -164.845909) (xy 383.89814 -164.870892) (xy 383.89814 -165.19518) (xy 386.317994 -165.19518)
			(xy 386.317994 -165.110484) (xy 386.326045 -165.02617) (xy 386.342074 -164.943004) (xy 386.365935 -164.861737)
			(xy 386.397414 -164.783107) (xy 386.436225 -164.707826) (xy 386.482015 -164.636574) (xy 386.534371 -164.569998)
			(xy 386.592819 -164.5087) (xy 386.656829 -164.453235) (xy 386.725821 -164.404106) (xy 386.799171 -164.361757)
			(xy 386.876214 -164.326573) (xy 386.956253 -164.298871) (xy 387.038562 -164.278903) (xy 387.122397 -164.26685)
			(xy 387.206998 -164.26282) (xy 387.291599 -164.26685) (xy 387.375434 -164.278903) (xy 387.457743 -164.298871)
			(xy 387.537782 -164.326573) (xy 387.614825 -164.361757) (xy 387.688175 -164.404106) (xy 387.757167 -164.453235)
			(xy 387.821177 -164.5087) (xy 387.879625 -164.569998) (xy 387.931981 -164.636574) (xy 387.977771 -164.707826)
			(xy 388.016582 -164.783107) (xy 388.048061 -164.861737) (xy 388.071922 -164.943004) (xy 388.087951 -165.02617)
			(xy 388.096002 -165.110484) (xy 388.096506 -165.152832) (xy 388.096002 -165.19518) (xy 388.087951 -165.279494)
			(xy 388.071922 -165.36266) (xy 388.048061 -165.443927) (xy 388.016582 -165.522557) (xy 387.977771 -165.597838)
			(xy 387.931981 -165.66909) (xy 387.879625 -165.735666) (xy 387.821177 -165.796964) (xy 387.757167 -165.852429)
			(xy 387.688175 -165.901558) (xy 387.614825 -165.943907) (xy 387.537782 -165.979091) (xy 387.457743 -166.006793)
			(xy 387.375434 -166.026761) (xy 387.291599 -166.038814) (xy 387.206998 -166.042845) (xy 387.122397 -166.038814)
			(xy 387.038562 -166.026761) (xy 386.956253 -166.006793) (xy 386.876214 -165.979091) (xy 386.799171 -165.943907)
			(xy 386.725821 -165.901558) (xy 386.656829 -165.852429) (xy 386.592819 -165.796964) (xy 386.534371 -165.735666)
			(xy 386.482015 -165.66909) (xy 386.436225 -165.597838) (xy 386.397414 -165.522557) (xy 386.365935 -165.443927)
			(xy 386.342074 -165.36266) (xy 386.326045 -165.279494) (xy 386.317994 -165.19518) (xy 383.89814 -165.19518)
			(xy 383.89814 -178.404012) (xy 389.102854 -178.404012) (xy 389.10334 -178.376761) (xy 389.111096 -178.322813)
			(xy 389.126451 -178.270518) (xy 389.149093 -178.220941) (xy 389.178559 -178.175091) (xy 389.21425 -178.1339)
			(xy 389.255441 -178.098209) (xy 389.301291 -178.068743) (xy 389.350868 -178.046101) (xy 389.403163 -178.030746)
			(xy 389.457111 -178.02299) (xy 389.511613 -178.02299) (xy 389.565561 -178.030746) (xy 389.617856 -178.046101)
			(xy 389.667433 -178.068743) (xy 389.713283 -178.098209) (xy 389.754474 -178.1339) (xy 389.790165 -178.175091)
			(xy 389.819631 -178.220941) (xy 389.842273 -178.270518) (xy 389.857628 -178.322813) (xy 389.865384 -178.376761)
			(xy 389.86587 -178.404012) (xy 389.865203 -178.435575) (xy 389.854819 -178.49784) (xy 389.834336 -178.557549)
			(xy 389.819896 -178.585622) (xy 389.81507 -178.594512) (xy 389.813038 -178.61407) (xy 389.838692 -178.702208)
			(xy 389.851138 -178.717702) (xy 389.860028 -178.722782) (xy 389.867394 -178.726846) (xy 389.877046 -178.732688)
			(xy 389.899144 -178.73472) (xy 389.993632 -178.701192) (xy 390.009634 -178.685698) (xy 390.013698 -178.675284)
			(xy 390.024371 -178.648498) (xy 390.052662 -178.598255) (xy 390.088195 -178.552845) (xy 390.13016 -178.513303)
			(xy 390.177601 -178.480531) (xy 390.229435 -178.455275) (xy 390.284481 -178.438111) (xy 390.341484 -178.429432)
			(xy 390.370314 -178.428904) (xy 390.397565 -178.429367) (xy 390.451513 -178.437125) (xy 390.503808 -178.452482)
			(xy 390.553385 -178.475125) (xy 390.599235 -178.504592) (xy 390.640425 -178.540285) (xy 390.676116 -178.581476)
			(xy 390.705582 -178.627327) (xy 390.728223 -178.676905) (xy 390.743578 -178.7292) (xy 390.751334 -178.783149)
			(xy 390.751334 -178.837651) (xy 390.743578 -178.8916) (xy 390.728223 -178.943895) (xy 390.705582 -178.993473)
			(xy 390.676116 -179.039324) (xy 390.640425 -179.080515) (xy 390.599235 -179.116208) (xy 390.553385 -179.145675)
			(xy 390.503808 -179.168318) (xy 390.451513 -179.183675) (xy 390.397565 -179.191433) (xy 390.370314 -179.19192)
			(xy 390.345079 -179.191514) (xy 390.295045 -179.184898) (xy 390.246325 -179.171728) (xy 390.199773 -179.152234)
			(xy 390.177782 -179.13985) (xy 390.16813 -179.134008) (xy 390.146032 -179.131976) (xy 390.051544 -179.165504)
			(xy 390.035542 -179.180998) (xy 390.031478 -179.191412) (xy 390.02074 -179.21817) (xy 389.992457 -179.26841)
			(xy 389.956933 -179.313819) (xy 389.914977 -179.353362) (xy 389.867546 -179.386137) (xy 389.815721 -179.411399)
			(xy 389.760684 -179.428569) (xy 389.703689 -179.437259) (xy 389.674862 -179.437792) (xy 389.647609 -179.437357)
			(xy 389.593659 -179.429595) (xy 389.541362 -179.414235) (xy 389.491784 -179.391588) (xy 389.445933 -179.362116)
			(xy 389.404742 -179.326419) (xy 389.369051 -179.285224) (xy 389.339586 -179.239369) (xy 389.316946 -179.189787)
			(xy 389.301593 -179.137488) (xy 389.293839 -179.083537) (xy 389.293354 -179.056284) (xy 389.294016 -179.024721)
			(xy 389.304401 -178.962456) (xy 389.324886 -178.902747) (xy 389.339328 -178.874674) (xy 389.344154 -178.865784)
			(xy 389.346186 -178.846226) (xy 389.320532 -178.758088) (xy 389.308086 -178.742594) (xy 389.299196 -178.737514)
			(xy 389.274072 -178.723003) (xy 389.22819 -178.687493) (xy 389.188216 -178.645443) (xy 389.155073 -178.597823)
			(xy 389.129526 -178.545732) (xy 389.112165 -178.490372) (xy 389.10339 -178.433021) (xy 389.102854 -178.404012)
			(xy 383.89814 -178.404012) (xy 383.89814 -178.440334) (xy 383.897534 -178.465318) (xy 383.887789 -178.514326)
			(xy 383.86868 -178.560496) (xy 383.84094 -178.602056) (xy 383.823718 -178.620166) (xy 383.481834 -178.96205)
			(xy 383.999738 -178.96205) (xy 384.003809 -178.906428) (xy 384.015935 -178.851991) (xy 384.035858 -178.7999)
			(xy 384.063154 -178.751265) (xy 384.09724 -178.707122) (xy 384.137389 -178.668413) (xy 384.182747 -178.635962)
			(xy 384.232347 -178.610461) (xy 384.285131 -178.592454) (xy 384.339974 -178.582324) (xy 384.395708 -178.580287)
			(xy 384.451145 -178.586387) (xy 384.505102 -178.600493) (xy 384.556431 -178.622305) (xy 384.604037 -178.651359)
			(xy 384.646905 -178.687034) (xy 384.684122 -178.728571) (xy 384.714895 -178.775084) (xy 384.738567 -178.825581)
			(xy 384.754635 -178.878988) (xy 384.762755 -178.934164) (xy 384.763264 -178.96205) (xy 384.762755 -178.989936)
			(xy 384.754635 -179.045112) (xy 384.738567 -179.098519) (xy 384.714895 -179.149016) (xy 384.684122 -179.195529)
			(xy 384.646905 -179.237066) (xy 384.604037 -179.272741) (xy 384.556431 -179.301795) (xy 384.505102 -179.323607)
			(xy 384.451145 -179.337713) (xy 384.395708 -179.343813) (xy 384.339974 -179.341776) (xy 384.285131 -179.331646)
			(xy 384.232347 -179.313639) (xy 384.182747 -179.288138) (xy 384.137389 -179.255687) (xy 384.09724 -179.216978)
			(xy 384.063154 -179.172835) (xy 384.035858 -179.1242) (xy 384.015935 -179.072109) (xy 384.003809 -179.017672)
			(xy 383.999738 -178.96205) (xy 383.481834 -178.96205) (xy 383.408174 -179.03571) (xy 383.404364 -179.046886)
			(xy 383.395443 -179.071651) (xy 383.371736 -179.11865) (xy 383.34179 -179.161941) (xy 383.306174 -179.200702)
			(xy 383.265566 -179.234196) (xy 383.220737 -179.261786) (xy 383.17254 -179.282949) (xy 383.12189 -179.297282)
			(xy 383.06975 -179.304512) (xy 383.04343 -179.30495) (xy 383.016181 -179.304394) (xy 382.962238 -179.296643)
			(xy 382.909948 -179.281293) (xy 382.860373 -179.258659) (xy 382.814525 -179.2292) (xy 382.773335 -179.193516)
			(xy 382.737644 -179.152333) (xy 382.708176 -179.10649) (xy 382.685532 -179.05692) (xy 382.670173 -179.004632)
			(xy 382.662411 -178.95069) (xy 382.661922 -178.923442) (xy 382.662428 -178.895968) (xy 382.670314 -178.841589)
			(xy 382.685929 -178.788907) (xy 382.70895 -178.739014) (xy 382.738898 -178.692944) (xy 382.756664 -178.671982)
			(xy 382.76276 -178.66487) (xy 382.76911 -178.647852) (xy 382.76911 -178.562) (xy 382.76276 -178.544982)
			(xy 382.756664 -178.53787) (xy 382.738899 -178.516909) (xy 382.708976 -178.470826) (xy 382.685964 -178.420932)
			(xy 382.670338 -178.368255) (xy 382.662421 -178.313882) (xy 382.661922 -178.28641) (xy 382.662478 -178.257339)
			(xy 382.671312 -178.199872) (xy 382.688763 -178.14441) (xy 382.714425 -178.092237) (xy 382.747706 -178.044562)
			(xy 382.787834 -178.002488) (xy 382.833881 -177.966988) (xy 382.88478 -177.938885) (xy 382.939354 -177.918829)
			(xy 382.967738 -177.912522) (xy 382.985518 -177.908966) (xy 383.008632 -177.880772) (xy 383.008632 -165.155372)
			(xy 383.008239 -165.145299) (xy 383.000498 -165.1267) (xy 382.993646 -165.119304) (xy 376.293126 -158.418784)
			(xy 376.275878 -158.400697) (xy 376.248143 -158.359129) (xy 376.229042 -158.312952) (xy 376.21931 -158.263938)
			(xy 376.218704 -158.238952) (xy 376.218704 -151.064976) (xy 376.218232 -151.054967) (xy 376.210565 -151.036476)
			(xy 376.196408 -151.022324) (xy 376.177913 -151.014664) (xy 376.167904 -151.014176) (xy 374.689116 -151.014176)
			(xy 374.674997 -151.013983) (xy 374.646885 -151.011307) (xy 374.632982 -151.008842) (xy 374.621806 -151.006556)
			(xy 374.599962 -151.012144) (xy 374.530874 -151.069548) (xy 374.522589 -151.077147) (xy 374.512975 -151.09744)
			(xy 374.512332 -151.108664) (xy 374.512332 -162.639178) (xy 376.980954 -162.639178) (xy 376.980954 -162.554482)
			(xy 376.989005 -162.470168) (xy 377.005034 -162.387002) (xy 377.028895 -162.305735) (xy 377.060374 -162.227105)
			(xy 377.099185 -162.151824) (xy 377.144975 -162.080572) (xy 377.197331 -162.013996) (xy 377.255779 -161.952698)
			(xy 377.319789 -161.897233) (xy 377.388781 -161.848104) (xy 377.462131 -161.805755) (xy 377.539174 -161.770571)
			(xy 377.619213 -161.742869) (xy 377.701522 -161.722901) (xy 377.785357 -161.710848) (xy 377.869958 -161.706818)
			(xy 377.954559 -161.710848) (xy 378.038394 -161.722901) (xy 378.120703 -161.742869) (xy 378.200742 -161.770571)
			(xy 378.277785 -161.805755) (xy 378.351135 -161.848104) (xy 378.420127 -161.897233) (xy 378.484137 -161.952698)
			(xy 378.542585 -162.013996) (xy 378.594941 -162.080572) (xy 378.640731 -162.151824) (xy 378.679542 -162.227105)
			(xy 378.711021 -162.305735) (xy 378.734882 -162.387002) (xy 378.750911 -162.470168) (xy 378.758962 -162.554482)
			(xy 378.759466 -162.59683) (xy 378.758962 -162.639178) (xy 378.750911 -162.723492) (xy 378.734882 -162.806658)
			(xy 378.711021 -162.887925) (xy 378.679542 -162.966555) (xy 378.640731 -163.041836) (xy 378.594941 -163.113088)
			(xy 378.542585 -163.179664) (xy 378.484137 -163.240962) (xy 378.420127 -163.296427) (xy 378.351135 -163.345556)
			(xy 378.277785 -163.387905) (xy 378.200742 -163.423089) (xy 378.120703 -163.450791) (xy 378.038394 -163.470759)
			(xy 377.954559 -163.482812) (xy 377.869958 -163.486843) (xy 377.785357 -163.482812) (xy 377.701522 -163.470759)
			(xy 377.619213 -163.450791) (xy 377.539174 -163.423089) (xy 377.462131 -163.387905) (xy 377.388781 -163.345556)
			(xy 377.319789 -163.296427) (xy 377.255779 -163.240962) (xy 377.197331 -163.179664) (xy 377.144975 -163.113088)
			(xy 377.099185 -163.041836) (xy 377.060374 -162.966555) (xy 377.028895 -162.887925) (xy 377.005034 -162.806658)
			(xy 376.989005 -162.723492) (xy 376.980954 -162.639178) (xy 374.512332 -162.639178) (xy 374.512332 -165.1393)
			(xy 376.980954 -165.1393) (xy 376.980954 -165.054604) (xy 376.989005 -164.97029) (xy 377.005034 -164.887124)
			(xy 377.028895 -164.805857) (xy 377.060374 -164.727227) (xy 377.099185 -164.651946) (xy 377.144975 -164.580694)
			(xy 377.197331 -164.514118) (xy 377.255779 -164.45282) (xy 377.319789 -164.397355) (xy 377.388781 -164.348226)
			(xy 377.462131 -164.305877) (xy 377.539174 -164.270693) (xy 377.619213 -164.242991) (xy 377.701522 -164.223023)
			(xy 377.785357 -164.21097) (xy 377.869958 -164.20694) (xy 377.954559 -164.21097) (xy 378.038394 -164.223023)
			(xy 378.120703 -164.242991) (xy 378.200742 -164.270693) (xy 378.277785 -164.305877) (xy 378.351135 -164.348226)
			(xy 378.420127 -164.397355) (xy 378.484137 -164.45282) (xy 378.542585 -164.514118) (xy 378.594941 -164.580694)
			(xy 378.640731 -164.651946) (xy 378.679542 -164.727227) (xy 378.711021 -164.805857) (xy 378.734882 -164.887124)
			(xy 378.750911 -164.97029) (xy 378.758962 -165.054604) (xy 378.759466 -165.096952) (xy 378.758962 -165.1393)
			(xy 378.750911 -165.223614) (xy 378.734882 -165.30678) (xy 378.711021 -165.388047) (xy 378.679542 -165.466677)
			(xy 378.640731 -165.541958) (xy 378.594941 -165.61321) (xy 378.542585 -165.679786) (xy 378.484137 -165.741084)
			(xy 378.420127 -165.796549) (xy 378.351135 -165.845678) (xy 378.277785 -165.888027) (xy 378.200742 -165.923211)
			(xy 378.120703 -165.950913) (xy 378.038394 -165.970881) (xy 377.954559 -165.982934) (xy 377.869958 -165.986965)
			(xy 377.785357 -165.982934) (xy 377.701522 -165.970881) (xy 377.619213 -165.950913) (xy 377.539174 -165.923211)
			(xy 377.462131 -165.888027) (xy 377.388781 -165.845678) (xy 377.319789 -165.796549) (xy 377.255779 -165.741084)
			(xy 377.197331 -165.679786) (xy 377.144975 -165.61321) (xy 377.099185 -165.541958) (xy 377.060374 -165.466677)
			(xy 377.028895 -165.388047) (xy 377.005034 -165.30678) (xy 376.989005 -165.223614) (xy 376.980954 -165.1393)
			(xy 374.512332 -165.1393) (xy 374.512332 -172.866558) (xy 374.512771 -172.876626) (xy 374.520481 -172.895224)
			(xy 374.527318 -172.902626) (xy 375.42089 -173.796198) (xy 375.438115 -173.814305) (xy 375.465859 -173.855864)
			(xy 375.484966 -173.902035) (xy 375.494704 -173.951046) (xy 375.495312 -173.97603) (xy 375.495312 -178.404012)
			(xy 380.771654 -178.404012) (xy 380.77214 -178.376761) (xy 380.779896 -178.322813) (xy 380.795251 -178.270518)
			(xy 380.817893 -178.220941) (xy 380.847359 -178.175091) (xy 380.88305 -178.1339) (xy 380.924241 -178.098209)
			(xy 380.970091 -178.068743) (xy 381.019668 -178.046101) (xy 381.071963 -178.030746) (xy 381.125911 -178.02299)
			(xy 381.180413 -178.02299) (xy 381.234361 -178.030746) (xy 381.286656 -178.046101) (xy 381.336233 -178.068743)
			(xy 381.382083 -178.098209) (xy 381.423274 -178.1339) (xy 381.458965 -178.175091) (xy 381.488431 -178.220941)
			(xy 381.511073 -178.270518) (xy 381.526428 -178.322813) (xy 381.534184 -178.376761) (xy 381.53467 -178.404012)
			(xy 381.534003 -178.435575) (xy 381.523619 -178.49784) (xy 381.503136 -178.557549) (xy 381.488696 -178.585622)
			(xy 381.48387 -178.594512) (xy 381.481838 -178.61407) (xy 381.507492 -178.702208) (xy 381.519938 -178.717702)
			(xy 381.528828 -178.722782) (xy 381.536194 -178.726846) (xy 381.545846 -178.732688) (xy 381.567944 -178.73472)
			(xy 381.662432 -178.701192) (xy 381.678434 -178.685698) (xy 381.682498 -178.675284) (xy 381.693171 -178.648498)
			(xy 381.721462 -178.598255) (xy 381.756995 -178.552845) (xy 381.79896 -178.513303) (xy 381.846401 -178.480531)
			(xy 381.898235 -178.455275) (xy 381.953281 -178.438111) (xy 382.010284 -178.429432) (xy 382.039114 -178.428904)
			(xy 382.066365 -178.429367) (xy 382.120313 -178.437125) (xy 382.172608 -178.452482) (xy 382.222185 -178.475125)
			(xy 382.268035 -178.504592) (xy 382.309225 -178.540285) (xy 382.344916 -178.581476) (xy 382.374382 -178.627327)
			(xy 382.397023 -178.676905) (xy 382.412378 -178.7292) (xy 382.420134 -178.783149) (xy 382.420134 -178.837651)
			(xy 382.412378 -178.8916) (xy 382.397023 -178.943895) (xy 382.374382 -178.993473) (xy 382.344916 -179.039324)
			(xy 382.309225 -179.080515) (xy 382.268035 -179.116208) (xy 382.222185 -179.145675) (xy 382.172608 -179.168318)
			(xy 382.120313 -179.183675) (xy 382.066365 -179.191433) (xy 382.039114 -179.19192) (xy 382.013879 -179.191514)
			(xy 381.963845 -179.184898) (xy 381.915125 -179.171728) (xy 381.868573 -179.152234) (xy 381.846582 -179.13985)
			(xy 381.83693 -179.134008) (xy 381.814832 -179.131976) (xy 381.720344 -179.165504) (xy 381.704342 -179.180998)
			(xy 381.700278 -179.191412) (xy 381.68954 -179.21817) (xy 381.661257 -179.26841) (xy 381.625733 -179.313819)
			(xy 381.583777 -179.353362) (xy 381.536346 -179.386137) (xy 381.484521 -179.411399) (xy 381.429484 -179.428569)
			(xy 381.372489 -179.437259) (xy 381.343662 -179.437792) (xy 381.316409 -179.437357) (xy 381.262459 -179.429595)
			(xy 381.210162 -179.414235) (xy 381.160584 -179.391588) (xy 381.114733 -179.362116) (xy 381.073542 -179.326419)
			(xy 381.037851 -179.285224) (xy 381.008386 -179.239369) (xy 380.985746 -179.189787) (xy 380.970393 -179.137488)
			(xy 380.962639 -179.083537) (xy 380.962154 -179.056284) (xy 380.962816 -179.024721) (xy 380.973201 -178.962456)
			(xy 380.993686 -178.902747) (xy 381.008128 -178.874674) (xy 381.012954 -178.865784) (xy 381.014986 -178.846226)
			(xy 380.989332 -178.758088) (xy 380.976886 -178.742594) (xy 380.967996 -178.737514) (xy 380.942872 -178.723003)
			(xy 380.89699 -178.687493) (xy 380.857016 -178.645443) (xy 380.823873 -178.597823) (xy 380.798326 -178.545732)
			(xy 380.780965 -178.490372) (xy 380.77219 -178.433021) (xy 380.771654 -178.404012) (xy 375.495312 -178.404012)
			(xy 375.495312 -178.440334) (xy 375.494714 -178.465318) (xy 375.484968 -178.514328) (xy 375.465857 -178.560498)
			(xy 375.438114 -178.602057) (xy 375.42089 -178.620166) (xy 375.079006 -178.96205) (xy 375.59691 -178.96205)
			(xy 375.600981 -178.906428) (xy 375.613107 -178.851991) (xy 375.63303 -178.7999) (xy 375.660326 -178.751265)
			(xy 375.694412 -178.707122) (xy 375.734561 -178.668413) (xy 375.779919 -178.635962) (xy 375.829519 -178.610461)
			(xy 375.882303 -178.592454) (xy 375.937146 -178.582324) (xy 375.99288 -178.580287) (xy 376.048317 -178.586387)
			(xy 376.102274 -178.600493) (xy 376.153603 -178.622305) (xy 376.201209 -178.651359) (xy 376.244077 -178.687034)
			(xy 376.281294 -178.728571) (xy 376.312067 -178.775084) (xy 376.335739 -178.825581) (xy 376.351807 -178.878988)
			(xy 376.359927 -178.934164) (xy 376.360436 -178.96205) (xy 376.359927 -178.989936) (xy 376.351807 -179.045112)
			(xy 376.335739 -179.098519) (xy 376.312067 -179.149016) (xy 376.281294 -179.195529) (xy 376.244077 -179.237066)
			(xy 376.201209 -179.272741) (xy 376.153603 -179.301795) (xy 376.102274 -179.323607) (xy 376.048317 -179.337713)
			(xy 375.99288 -179.343813) (xy 375.937146 -179.341776) (xy 375.882303 -179.331646) (xy 375.829519 -179.313639)
			(xy 375.779919 -179.288138) (xy 375.734561 -179.255687) (xy 375.694412 -179.216978) (xy 375.660326 -179.172835)
			(xy 375.63303 -179.1242) (xy 375.613107 -179.072109) (xy 375.600981 -179.017672) (xy 375.59691 -178.96205)
			(xy 375.079006 -178.96205) (xy 375.031762 -179.009294) (xy 375.025158 -179.021232) (xy 375.02338 -179.028344)
			(xy 375.016318 -179.055805) (xy 374.995167 -179.108412) (xy 374.966461 -179.157309) (xy 374.930834 -179.201418)
			(xy 374.88907 -179.239767) (xy 374.842089 -179.271512) (xy 374.790928 -179.295953) (xy 374.736712 -179.312552)
			(xy 374.680636 -179.320943) (xy 374.652286 -179.32146) (xy 374.625031 -179.321058) (xy 374.571075 -179.313298)
			(xy 374.518773 -179.297938) (xy 374.469189 -179.27529) (xy 374.423334 -179.245816) (xy 374.38214 -179.210116)
			(xy 374.346447 -179.168916) (xy 374.31698 -179.123056) (xy 374.294341 -179.073469) (xy 374.278989 -179.021164)
			(xy 374.271238 -178.967207) (xy 374.270778 -178.939952) (xy 374.271259 -178.912277) (xy 374.279258 -178.857507)
			(xy 374.295095 -178.804471) (xy 374.318438 -178.754283) (xy 374.348794 -178.707999) (xy 374.36679 -178.686968)
			(xy 374.37314 -178.679602) (xy 374.379744 -178.662076) (xy 374.37822 -178.573938) (xy 374.370854 -178.556412)
			(xy 374.36425 -178.549554) (xy 374.344616 -178.528141) (xy 374.311423 -178.480464) (xy 374.285833 -178.428309)
			(xy 374.268437 -178.372881) (xy 374.259637 -178.315457) (xy 374.259094 -178.28641) (xy 374.259592 -178.257336)
			(xy 374.268429 -178.199863) (xy 374.285883 -178.144397) (xy 374.311551 -178.092221) (xy 374.344839 -178.044544)
			(xy 374.384976 -178.002469) (xy 374.431031 -177.966972) (xy 374.48194 -177.938873) (xy 374.536522 -177.918825)
			(xy 374.56491 -177.912522) (xy 374.58269 -177.908966) (xy 374.605804 -177.880772) (xy 374.605804 -174.26051)
			(xy 374.605399 -174.250438) (xy 374.597667 -174.231839) (xy 374.590818 -174.224442) (xy 373.697246 -173.33087)
			(xy 373.680042 -173.312744) (xy 373.652298 -173.27119) (xy 373.633185 -173.225025) (xy 373.623439 -173.17602)
			(xy 373.622824 -173.151038) (xy 366.62395 -173.151038) (xy 366.637341 -173.180358) (xy 366.652696 -173.232653)
			(xy 366.660452 -173.286601) (xy 366.660938 -173.313852) (xy 366.66048 -173.340646) (xy 366.65298 -173.393706)
			(xy 366.638135 -173.445197) (xy 366.616237 -173.494106) (xy 366.587715 -173.539473) (xy 366.570768 -173.560232)
			(xy 366.564672 -173.567344) (xy 366.558576 -173.584362) (xy 366.5601 -173.670214) (xy 366.566958 -173.686978)
			(xy 366.573308 -173.69409) (xy 366.591915 -173.715263) (xy 366.623297 -173.762086) (xy 366.647447 -173.813016)
			(xy 366.663841 -173.866946) (xy 366.672122 -173.922701) (xy 366.672622 -173.950884) (xy 366.672136 -173.978135)
			(xy 366.670503 -173.989492) (xy 367.235738 -173.989492) (xy 367.239809 -173.93387) (xy 367.251935 -173.879433)
			(xy 367.271858 -173.827342) (xy 367.299154 -173.778707) (xy 367.33324 -173.734564) (xy 367.373389 -173.695855)
			(xy 367.418747 -173.663404) (xy 367.468347 -173.637903) (xy 367.521131 -173.619896) (xy 367.575974 -173.609766)
			(xy 367.631708 -173.607729) (xy 367.687145 -173.613829) (xy 367.741102 -173.627935) (xy 367.792431 -173.649747)
			(xy 367.840037 -173.678801) (xy 367.882905 -173.714476) (xy 367.920122 -173.756013) (xy 367.950895 -173.802526)
			(xy 367.974567 -173.853023) (xy 367.990635 -173.90643) (xy 367.998755 -173.961606) (xy 367.999264 -173.989492)
			(xy 367.998755 -174.017378) (xy 367.990635 -174.072554) (xy 367.974567 -174.125961) (xy 367.950895 -174.176458)
			(xy 367.920122 -174.222971) (xy 367.882905 -174.264508) (xy 367.840037 -174.300183) (xy 367.792431 -174.329237)
			(xy 367.741102 -174.351049) (xy 367.687145 -174.365155) (xy 367.631708 -174.371255) (xy 367.575974 -174.369218)
			(xy 367.521131 -174.359088) (xy 367.468347 -174.341081) (xy 367.418747 -174.31558) (xy 367.373389 -174.283129)
			(xy 367.33324 -174.24442) (xy 367.299154 -174.200277) (xy 367.271858 -174.151642) (xy 367.251935 -174.099551)
			(xy 367.239809 -174.045114) (xy 367.235738 -173.989492) (xy 366.670503 -173.989492) (xy 366.66438 -174.032083)
			(xy 366.649025 -174.084378) (xy 366.626383 -174.133955) (xy 366.596917 -174.179805) (xy 366.561226 -174.220996)
			(xy 366.520035 -174.256687) (xy 366.474185 -174.286153) (xy 366.424608 -174.308795) (xy 366.372313 -174.32415)
			(xy 366.318365 -174.331906) (xy 366.263863 -174.331906) (xy 366.209915 -174.32415) (xy 366.15762 -174.308795)
			(xy 366.108043 -174.286153) (xy 366.062193 -174.256687) (xy 366.021002 -174.220996) (xy 365.985311 -174.179805)
			(xy 365.955845 -174.133955) (xy 365.933203 -174.084378) (xy 365.917848 -174.032083) (xy 365.910092 -173.978135)
			(xy 365.909606 -173.950884) (xy 365.91004 -173.924089) (xy 365.917547 -173.871028) (xy 365.932399 -173.819538)
			(xy 365.954302 -173.770629) (xy 365.982828 -173.725262) (xy 365.999776 -173.704504) (xy 366.005872 -173.697392)
			(xy 366.011968 -173.680374) (xy 366.010444 -173.594522) (xy 366.003586 -173.577758) (xy 365.997236 -173.570646)
			(xy 365.978637 -173.549467) (xy 365.947256 -173.502644) (xy 365.923105 -173.451715) (xy 365.906709 -173.397788)
			(xy 365.898424 -173.342035) (xy 365.897922 -173.313852) (xy 364.751739 -173.313852) (xy 364.762428 -173.350255)
			(xy 364.770184 -173.404203) (xy 364.77067 -173.431454) (xy 364.77002 -173.463017) (xy 364.759629 -173.525283)
			(xy 364.73914 -173.584992) (xy 364.724696 -173.613064) (xy 364.71987 -173.621954) (xy 364.717838 -173.641512)
			(xy 364.743492 -173.72965) (xy 364.755938 -173.745144) (xy 364.764828 -173.750224) (xy 364.772194 -173.754288)
			(xy 364.781846 -173.76013) (xy 364.803944 -173.762162) (xy 364.898432 -173.728634) (xy 364.914434 -173.71314)
			(xy 364.918498 -173.702726) (xy 364.929193 -173.675949) (xy 364.957479 -173.625705) (xy 364.993008 -173.580294)
			(xy 365.034969 -173.54075) (xy 365.082407 -173.507976) (xy 365.134239 -173.482718) (xy 365.189283 -173.465554)
			(xy 365.246285 -173.456874) (xy 365.275114 -173.456346) (xy 365.302361 -173.456925) (xy 365.356301 -173.464682)
			(xy 365.408588 -173.480037) (xy 365.458157 -173.502676) (xy 365.504 -173.532139) (xy 365.545184 -173.567826)
			(xy 365.580869 -173.609011) (xy 365.610331 -173.654855) (xy 365.632968 -173.704425) (xy 365.648321 -173.756713)
			(xy 365.656076 -173.810653) (xy 365.656076 -173.865147) (xy 365.648321 -173.919087) (xy 365.632968 -173.971375)
			(xy 365.610331 -174.020945) (xy 365.580869 -174.066789) (xy 365.545184 -174.107974) (xy 365.504 -174.143661)
			(xy 365.458157 -174.173124) (xy 365.408588 -174.195763) (xy 365.356301 -174.211118) (xy 365.302361 -174.218875)
			(xy 365.275114 -174.219362) (xy 365.249879 -174.21895) (xy 365.199846 -174.212335) (xy 365.151126 -174.199166)
			(xy 365.104573 -174.179674) (xy 365.082582 -174.167292) (xy 365.07293 -174.16145) (xy 365.050832 -174.159418)
			(xy 364.956344 -174.192946) (xy 364.940342 -174.20844) (xy 364.936278 -174.218854) (xy 364.925562 -174.245622)
			(xy 364.897274 -174.29586) (xy 364.861745 -174.341267) (xy 364.819786 -174.380808) (xy 364.772352 -174.413582)
			(xy 364.720525 -174.438842) (xy 364.665486 -174.456012) (xy 364.608489 -174.464701) (xy 364.579662 -174.465234)
			(xy 364.552411 -174.464758) (xy 364.498464 -174.456997) (xy 364.446171 -174.441638) (xy 364.396595 -174.418994)
			(xy 364.350746 -174.389526) (xy 364.309557 -174.353834) (xy 364.273866 -174.312644) (xy 364.2444 -174.266794)
			(xy 364.221758 -174.217218) (xy 364.206401 -174.164924) (xy 364.198642 -174.110977) (xy 364.198154 -174.083726)
			(xy 364.198793 -174.052162) (xy 364.209188 -173.989896) (xy 364.229682 -173.930188) (xy 364.244128 -173.902116)
			(xy 364.248954 -173.893226) (xy 364.250986 -173.873668) (xy 364.225332 -173.78553) (xy 364.212886 -173.770036)
			(xy 364.203996 -173.764956) (xy 364.17889 -173.750415) (xy 364.133008 -173.71491) (xy 364.093034 -173.672865)
			(xy 364.059889 -173.62525) (xy 364.034339 -173.573164) (xy 364.016973 -173.517809) (xy 364.008193 -173.460462)
			(xy 364.007654 -173.431454) (xy 351.988882 -173.431454) (xy 351.988882 -175.705516) (xy 360.22153 -175.705516)
			(xy 360.221996 -175.677941) (xy 360.229947 -175.623368) (xy 360.245671 -175.570508) (xy 360.268841 -175.520462)
			(xy 360.298974 -175.474272) (xy 360.335442 -175.432901) (xy 360.35615 -175.414686) (xy 360.364278 -175.407093)
			(xy 360.373625 -175.386934) (xy 360.374184 -175.375824) (xy 360.374184 -175.298608) (xy 360.373632 -175.287496)
			(xy 360.364283 -175.267337) (xy 360.35615 -175.259746) (xy 360.335458 -175.241514) (xy 360.29899 -175.200147)
			(xy 360.268859 -175.15396) (xy 360.245693 -175.103915) (xy 360.229975 -175.051055) (xy 360.222033 -174.996484)
			(xy 360.222031 -174.941337) (xy 360.229971 -174.886765) (xy 360.245686 -174.833905) (xy 360.268849 -174.783859)
			(xy 360.298978 -174.73767) (xy 360.335443 -174.6963) (xy 360.35615 -174.678086) (xy 360.364278 -174.670493)
			(xy 360.373625 -174.650334) (xy 360.374184 -174.639224) (xy 360.374184 -174.562008) (xy 360.373632 -174.550896)
			(xy 360.364283 -174.530737) (xy 360.35615 -174.523146) (xy 360.335448 -174.504925) (xy 360.298979 -174.463557)
			(xy 360.268847 -174.417369) (xy 360.24568 -174.367323) (xy 360.229961 -174.314463) (xy 360.222018 -174.25989)
			(xy 360.22153 -174.232316) (xy 360.22197 -174.205062) (xy 360.229726 -174.151108) (xy 360.245082 -174.098807)
			(xy 360.267725 -174.049225) (xy 360.297195 -174.00337) (xy 360.332892 -173.962176) (xy 360.374087 -173.926482)
			(xy 360.419944 -173.897015) (xy 360.469528 -173.874374) (xy 360.52183 -173.859021) (xy 360.575784 -173.851269)
			(xy 360.603038 -173.850808) (xy 360.630895 -173.851291) (xy 360.686012 -173.85942) (xy 360.739364 -173.875471)
			(xy 360.789817 -173.899103) (xy 360.836302 -173.929815) (xy 360.877831 -173.966955) (xy 360.913523 -174.009735)
			(xy 360.942621 -174.057246) (xy 360.964507 -174.108481) (xy 360.9721 -174.135288) (xy 360.974386 -174.144178)
			(xy 360.985054 -174.159418) (xy 361.056936 -174.20717) (xy 361.07497 -174.211234) (xy 361.084114 -174.209964)
			(xy 361.097131 -174.208295) (xy 361.123315 -174.206515) (xy 361.136438 -174.206408) (xy 361.150587 -174.206497)
			(xy 361.17881 -174.208534) (xy 361.192826 -174.210472) (xy 361.202986 -174.211996) (xy 361.222544 -174.20717)
			(xy 361.296966 -174.15129) (xy 361.307126 -174.133764) (xy 361.308396 -174.123604) (xy 361.312431 -174.096442)
			(xy 361.327412 -174.04361) (xy 361.349811 -173.993471) (xy 361.379165 -173.947061) (xy 361.414869 -173.905337)
			(xy 361.456184 -173.869162) (xy 361.502258 -173.839283) (xy 361.552139 -173.816316) (xy 361.604797 -173.800736)
			(xy 361.659145 -173.792865) (xy 361.686602 -173.792388) (xy 361.713853 -173.792876) (xy 361.767801 -173.800633)
			(xy 361.820095 -173.815988) (xy 361.869672 -173.838629) (xy 361.915522 -173.868095) (xy 361.956712 -173.903786)
			(xy 361.992404 -173.944976) (xy 362.02187 -173.990826) (xy 362.044512 -174.040403) (xy 362.059867 -174.092697)
			(xy 362.067624 -174.146645) (xy 362.06811 -174.173896) (xy 362.067638 -174.20147) (xy 362.059686 -174.256043)
			(xy 362.043962 -174.308902) (xy 362.020793 -174.358948) (xy 361.990662 -174.405138) (xy 361.954196 -174.44651)
			(xy 361.93349 -174.464726) (xy 361.925363 -174.472321) (xy 361.916014 -174.492478) (xy 361.915456 -174.503588)
			(xy 361.915456 -174.580804) (xy 361.915988 -174.591919) (xy 361.92535 -174.612078) (xy 361.93349 -174.619666)
			(xy 361.954186 -174.637894) (xy 361.990658 -174.679259) (xy 362.020792 -174.725445) (xy 362.043961 -174.77549)
			(xy 362.05968 -174.82835) (xy 362.067623 -174.882922) (xy 362.067657 -174.884842) (xy 366.656618 -174.884842)
			(xy 366.660689 -174.82922) (xy 366.672815 -174.774783) (xy 366.692738 -174.722692) (xy 366.720034 -174.674057)
			(xy 366.75412 -174.629914) (xy 366.794269 -174.591205) (xy 366.839627 -174.558754) (xy 366.889227 -174.533253)
			(xy 366.942011 -174.515246) (xy 366.996854 -174.505116) (xy 367.052588 -174.503079) (xy 367.108025 -174.509179)
			(xy 367.161982 -174.523285) (xy 367.213311 -174.545097) (xy 367.260917 -174.574151) (xy 367.303785 -174.609826)
			(xy 367.341002 -174.651363) (xy 367.371775 -174.697876) (xy 367.395447 -174.748373) (xy 367.411515 -174.80178)
			(xy 367.419635 -174.856956) (xy 367.420144 -174.884842) (xy 367.419635 -174.912728) (xy 367.411515 -174.967904)
			(xy 367.395447 -175.021311) (xy 367.371775 -175.071808) (xy 367.341002 -175.118321) (xy 367.303785 -175.159858)
			(xy 367.260917 -175.195533) (xy 367.213311 -175.224587) (xy 367.161982 -175.246399) (xy 367.108025 -175.260505)
			(xy 367.052588 -175.266605) (xy 366.996854 -175.264568) (xy 366.942011 -175.254438) (xy 366.889227 -175.236431)
			(xy 366.839627 -175.21093) (xy 366.794269 -175.178479) (xy 366.75412 -175.13977) (xy 366.720034 -175.095627)
			(xy 366.692738 -175.046992) (xy 366.672815 -174.994901) (xy 366.660689 -174.940464) (xy 366.656618 -174.884842)
			(xy 362.067657 -174.884842) (xy 362.06811 -174.910496) (xy 362.067641 -174.937749) (xy 362.059885 -174.991699)
			(xy 362.044529 -175.043997) (xy 362.021887 -175.093577) (xy 361.99242 -175.13943) (xy 361.956727 -175.180623)
			(xy 361.915535 -175.216316) (xy 361.869682 -175.245784) (xy 361.820103 -175.268427) (xy 361.767805 -175.283783)
			(xy 361.713855 -175.291541) (xy 361.686602 -175.292004) (xy 361.652312 -175.29048) (xy 361.642152 -175.289464)
			(xy 361.622848 -175.29556) (xy 361.552236 -175.354742) (xy 361.542838 -175.372776) (xy 361.541822 -175.382936)
			(xy 361.538854 -175.411107) (xy 361.525682 -175.466199) (xy 361.504505 -175.518735) (xy 361.475789 -175.567561)
			(xy 361.440167 -175.611602) (xy 361.398421 -175.649889) (xy 361.351472 -175.681579) (xy 361.30035 -175.705976)
			(xy 361.246183 -175.722541) (xy 361.19016 -175.730911) (xy 361.161838 -175.731424) (xy 361.143819 -175.731207)
			(xy 361.107944 -175.72777) (xy 361.09021 -175.724566) (xy 361.080812 -175.722788) (xy 361.061762 -175.726598)
			(xy 360.986578 -175.77435) (xy 360.975148 -175.790098) (xy 360.972862 -175.799496) (xy 360.965518 -175.826556)
			(xy 360.94388 -175.878283) (xy 360.914908 -175.926288) (xy 360.879225 -175.969538) (xy 360.837599 -176.007104)
			(xy 360.790925 -176.038175) (xy 360.740208 -176.062085) (xy 360.686539 -176.078319) (xy 360.631073 -176.086527)
			(xy 360.603038 -176.087024) (xy 360.575787 -176.086509) (xy 360.521839 -176.078758) (xy 360.469543 -176.063408)
			(xy 360.419964 -176.040771) (xy 360.374111 -176.011308) (xy 360.332918 -175.97562) (xy 360.297224 -175.934432)
			(xy 360.267755 -175.888584) (xy 360.245111 -175.839008) (xy 360.229753 -175.786714) (xy 360.221994 -175.732767)
			(xy 360.22153 -175.705516) (xy 351.988882 -175.705516) (xy 351.988882 -176.0601) (xy 351.989305 -176.070171)
			(xy 351.997017 -176.088777) (xy 352.003868 -176.096168) (xy 352.519234 -176.611534) (xy 352.526631 -176.618382)
			(xy 352.54523 -176.626115) (xy 352.555302 -176.62652) (xy 355.572822 -176.62652) (xy 355.58289 -176.626948)
			(xy 355.601487 -176.63467) (xy 355.60889 -176.641506) (xy 356.2223 -177.254916) (xy 361.889548 -177.254916)
			(xy 361.890008 -177.227341) (xy 361.897959 -177.172767) (xy 361.913684 -177.119906) (xy 361.936855 -177.06986)
			(xy 361.96699 -177.023671) (xy 362.00346 -176.982301) (xy 362.024168 -176.964086) (xy 362.032299 -176.956496)
			(xy 362.041644 -176.936334) (xy 362.042202 -176.925224) (xy 362.042202 -176.848008) (xy 362.041645 -176.836897)
			(xy 362.032298 -176.816739) (xy 362.024168 -176.809146) (xy 362.003469 -176.790921) (xy 361.967 -176.749555)
			(xy 361.936867 -176.703367) (xy 361.913699 -176.653322) (xy 361.897979 -176.600462) (xy 361.890036 -176.54589)
			(xy 361.889548 -176.518316) (xy 361.889957 -176.491765) (xy 361.897325 -176.439176) (xy 361.911921 -176.388119)
			(xy 361.933462 -176.339582) (xy 361.961532 -176.294504) (xy 361.995586 -176.253759) (xy 362.034966 -176.218135)
			(xy 362.05668 -176.202848) (xy 362.064808 -176.197006) (xy 362.07573 -176.18075) (xy 362.093764 -176.091088)
			(xy 362.089954 -176.07153) (xy 362.084366 -176.063148) (xy 362.070006 -176.040293) (xy 362.047322 -175.991317)
			(xy 362.031927 -175.939584) (xy 362.024142 -175.886173) (xy 362.02366 -175.859186) (xy 362.024144 -175.83257)
			(xy 362.031721 -175.779881) (xy 362.046719 -175.728807) (xy 362.068832 -175.680386) (xy 362.097611 -175.635605)
			(xy 362.13247 -175.595376) (xy 362.172699 -175.560516) (xy 362.217479 -175.531736) (xy 362.265899 -175.509621)
			(xy 362.316973 -175.494622) (xy 362.369662 -175.487044) (xy 362.396278 -175.486568) (xy 362.422699 -175.487046)
			(xy 362.475013 -175.494492) (xy 362.525751 -175.509253) (xy 362.573896 -175.531032) (xy 362.618482 -175.559393)
			(xy 362.638848 -175.57623) (xy 362.645706 -175.582326) (xy 362.662724 -175.588422) (xy 362.747052 -175.588422)
			(xy 362.76407 -175.582326) (xy 362.770928 -175.57623) (xy 362.791294 -175.559391) (xy 362.83588 -175.531026)
			(xy 362.884024 -175.509239) (xy 362.934761 -175.494468) (xy 362.987076 -175.487008) (xy 363.03992 -175.487008)
			(xy 363.092235 -175.494468) (xy 363.142972 -175.509239) (xy 363.191116 -175.531026) (xy 363.235702 -175.559391)
			(xy 363.256068 -175.57623) (xy 363.262926 -175.582326) (xy 363.279944 -175.588422) (xy 363.364272 -175.588422)
			(xy 363.38129 -175.582326) (xy 363.388148 -175.57623) (xy 363.408499 -175.559374) (xy 363.453093 -175.531021)
			(xy 363.501241 -175.509244) (xy 363.551981 -175.494481) (xy 363.604296 -175.487026) (xy 363.630718 -175.486568)
			(xy 363.658601 -175.487118) (xy 363.713744 -175.495432) (xy 363.767031 -175.511871) (xy 363.817274 -175.536069)
			(xy 363.863349 -175.567484) (xy 363.904227 -175.605416) (xy 363.938995 -175.649016) (xy 363.966878 -175.697311)
			(xy 363.987251 -175.749222) (xy 363.999659 -175.80359) (xy 364.003827 -175.8592) (xy 363.999659 -175.91481)
			(xy 363.987251 -175.969178) (xy 363.966878 -176.021089) (xy 363.938995 -176.069384) (xy 363.904227 -176.112984)
			(xy 363.863349 -176.150916) (xy 363.817274 -176.182331) (xy 363.767031 -176.206529) (xy 363.713744 -176.222968)
			(xy 363.658601 -176.231282) (xy 363.630718 -176.231804) (xy 363.604297 -176.231335) (xy 363.551982 -176.223888)
			(xy 363.501243 -176.209125) (xy 363.453099 -176.187344) (xy 363.408514 -176.158981) (xy 363.388148 -176.142142)
			(xy 363.38129 -176.136046) (xy 363.364272 -176.12995) (xy 363.279944 -176.12995) (xy 363.262926 -176.136046)
			(xy 363.256068 -176.142142) (xy 363.235702 -176.158981) (xy 363.191116 -176.187346) (xy 363.142972 -176.209133)
			(xy 363.092235 -176.223904) (xy 363.03992 -176.231364) (xy 362.987076 -176.231364) (xy 362.934761 -176.223904)
			(xy 362.884024 -176.209133) (xy 362.83588 -176.187346) (xy 362.791294 -176.158981) (xy 362.770928 -176.142142)
			(xy 362.76407 -176.136046) (xy 362.747052 -176.12995) (xy 362.662724 -176.12995) (xy 362.645706 -176.136046)
			(xy 362.638848 -176.142142) (xy 362.61167 -176.163224) (xy 362.603288 -176.169066) (xy 362.59262 -176.18583)
			(xy 362.576618 -176.275746) (xy 362.580682 -176.29505) (xy 362.58627 -176.303432) (xy 362.601926 -176.327311)
			(xy 362.626709 -176.378749) (xy 362.643545 -176.433308) (xy 362.652057 -176.489767) (xy 362.652564 -176.518316)
			(xy 362.652053 -176.545889) (xy 362.644112 -176.60046) (xy 362.628396 -176.65332) (xy 362.605235 -176.703366)
			(xy 362.57511 -176.749557) (xy 362.56423 -176.761902) (xy 367.61547 -176.761902) (xy 367.615969 -176.733991)
			(xy 367.624103 -176.678766) (xy 367.640197 -176.625316) (xy 367.663908 -176.574781) (xy 367.69473 -176.528241)
			(xy 367.713006 -176.50714) (xy 367.719356 -176.500028) (xy 367.72596 -176.482756) (xy 367.72596 -176.395634)
			(xy 367.719356 -176.378362) (xy 367.713006 -176.37125) (xy 367.694731 -176.350148) (xy 367.663903 -176.30361)
			(xy 367.640187 -176.253076) (xy 367.62409 -176.199625) (xy 367.615955 -176.144399) (xy 367.61547 -176.116488)
			(xy 367.615956 -176.089237) (xy 367.623712 -176.035289) (xy 367.639067 -175.982994) (xy 367.661709 -175.933417)
			(xy 367.691175 -175.887567) (xy 367.726866 -175.846376) (xy 367.768057 -175.810685) (xy 367.813907 -175.781219)
			(xy 367.863484 -175.758577) (xy 367.915779 -175.743222) (xy 367.969727 -175.735466) (xy 368.024229 -175.735466)
			(xy 368.078177 -175.743222) (xy 368.130472 -175.758577) (xy 368.180049 -175.781219) (xy 368.225899 -175.810685)
			(xy 368.26709 -175.846376) (xy 368.302781 -175.887567) (xy 368.332247 -175.933417) (xy 368.354889 -175.982994)
			(xy 368.370244 -176.035289) (xy 368.378 -176.089237) (xy 368.378486 -176.116488) (xy 368.377967 -176.144398)
			(xy 368.369836 -176.199621) (xy 368.353746 -176.253071) (xy 368.330039 -176.303606) (xy 368.299223 -176.350148)
			(xy 368.28095 -176.37125) (xy 368.2746 -176.378362) (xy 368.267996 -176.395634) (xy 368.267996 -176.482756)
			(xy 368.2746 -176.500028) (xy 368.28095 -176.50714) (xy 368.299229 -176.528239) (xy 368.330055 -176.574778)
			(xy 368.353769 -176.625313) (xy 368.369865 -176.678764) (xy 368.378 -176.733991) (xy 368.378486 -176.761902)
			(xy 368.378 -176.789153) (xy 368.370244 -176.843101) (xy 368.354889 -176.895396) (xy 368.332247 -176.944973)
			(xy 368.302781 -176.990823) (xy 368.26709 -177.032014) (xy 368.225899 -177.067705) (xy 368.180049 -177.097171)
			(xy 368.130472 -177.119813) (xy 368.078177 -177.135168) (xy 368.024229 -177.142924) (xy 367.969727 -177.142924)
			(xy 367.915779 -177.135168) (xy 367.863484 -177.119813) (xy 367.813907 -177.097171) (xy 367.768057 -177.067705)
			(xy 367.726866 -177.032014) (xy 367.691175 -176.990823) (xy 367.661709 -176.944973) (xy 367.639067 -176.895396)
			(xy 367.623712 -176.843101) (xy 367.615956 -176.789153) (xy 367.61547 -176.761902) (xy 362.56423 -176.761902)
			(xy 362.538648 -176.79093) (xy 362.517944 -176.809146) (xy 362.509801 -176.816725) (xy 362.500463 -176.836895)
			(xy 362.49991 -176.848008) (xy 362.49991 -176.925224) (xy 362.500445 -176.936338) (xy 362.509807 -176.956496)
			(xy 362.517944 -176.964086) (xy 362.53866 -176.982291) (xy 362.575128 -177.023662) (xy 362.605259 -177.069854)
			(xy 362.628423 -177.119903) (xy 362.644139 -177.172766) (xy 362.652079 -177.227341) (xy 362.652564 -177.254916)
			(xy 362.652078 -177.282167) (xy 362.644322 -177.336115) (xy 362.628967 -177.38841) (xy 362.606325 -177.437987)
			(xy 362.576859 -177.483837) (xy 362.541168 -177.525028) (xy 362.499977 -177.560719) (xy 362.454127 -177.590185)
			(xy 362.40455 -177.612827) (xy 362.352255 -177.628182) (xy 362.298307 -177.635938) (xy 362.243805 -177.635938)
			(xy 362.189857 -177.628182) (xy 362.137562 -177.612827) (xy 362.087985 -177.590185) (xy 362.042135 -177.560719)
			(xy 362.000944 -177.525028) (xy 361.965253 -177.483837) (xy 361.935787 -177.437987) (xy 361.913145 -177.38841)
			(xy 361.89779 -177.336115) (xy 361.890034 -177.282167) (xy 361.889548 -177.254916) (xy 356.2223 -177.254916)
			(xy 358.199539 -179.232155) (xy 368.583129 -179.232155) (xy 368.583129 -179.177645) (xy 368.590887 -179.123689)
			(xy 368.606244 -179.071387) (xy 368.628889 -179.021803) (xy 368.65836 -178.975946) (xy 368.694057 -178.93475)
			(xy 368.735254 -178.899054) (xy 368.781112 -178.869584) (xy 368.830696 -178.846941) (xy 368.882999 -178.831585)
			(xy 368.936955 -178.823828) (xy 368.96421 -178.823366) (xy 368.975284 -178.823436) (xy 368.997396 -178.824709)
			(xy 369.008406 -178.825906) (xy 369.018312 -178.827176) (xy 369.037108 -178.822096) (xy 369.109244 -178.766978)
			(xy 369.118896 -178.750468) (xy 369.12042 -178.740562) (xy 369.125354 -178.712096) (xy 369.142666 -178.656979)
			(xy 369.168078 -178.605095) (xy 369.201009 -178.557628) (xy 369.24071 -178.515659) (xy 369.263168 -178.497484)
			(xy 369.271944 -178.489936) (xy 369.282117 -178.469166) (xy 369.282726 -178.457606) (xy 369.282726 -178.377342)
			(xy 369.282157 -178.365773) (xy 369.271964 -178.345001) (xy 369.263168 -178.337464) (xy 369.240661 -178.319301)
			(xy 369.200928 -178.277275) (xy 369.167993 -178.229734) (xy 369.142609 -178.177767) (xy 369.125358 -178.122565)
			(xy 369.116634 -178.065392) (xy 369.116102 -178.036474) (xy 369.116588 -178.009223) (xy 369.124344 -177.955275)
			(xy 369.139699 -177.90298) (xy 369.162341 -177.853403) (xy 369.191807 -177.807553) (xy 369.227498 -177.766362)
			(xy 369.268689 -177.730671) (xy 369.314539 -177.701205) (xy 369.364116 -177.678563) (xy 369.416411 -177.663208)
			(xy 369.470359 -177.655452) (xy 369.524861 -177.655452) (xy 369.578809 -177.663208) (xy 369.631104 -177.678563)
			(xy 369.680681 -177.701205) (xy 369.726531 -177.730671) (xy 369.767722 -177.766362) (xy 369.803413 -177.807553)
			(xy 369.832879 -177.853403) (xy 369.855521 -177.90298) (xy 369.870876 -177.955275) (xy 369.878632 -178.009223)
			(xy 369.879118 -178.036474) (xy 369.878612 -178.065392) (xy 369.869885 -178.122565) (xy 369.852627 -178.177765)
			(xy 369.827233 -178.229728) (xy 369.794286 -178.277261) (xy 369.75454 -178.319276) (xy 369.732052 -178.337464)
			(xy 369.723303 -178.345037) (xy 369.713114 -178.365788) (xy 369.712494 -178.377342) (xy 369.712494 -178.404012)
			(xy 372.368826 -178.404012) (xy 372.369312 -178.376761) (xy 372.377068 -178.322813) (xy 372.392423 -178.270518)
			(xy 372.415065 -178.220941) (xy 372.444531 -178.175091) (xy 372.480222 -178.1339) (xy 372.521413 -178.098209)
			(xy 372.567263 -178.068743) (xy 372.61684 -178.046101) (xy 372.669135 -178.030746) (xy 372.723083 -178.02299)
			(xy 372.777585 -178.02299) (xy 372.831533 -178.030746) (xy 372.883828 -178.046101) (xy 372.933405 -178.068743)
			(xy 372.979255 -178.098209) (xy 373.020446 -178.1339) (xy 373.056137 -178.175091) (xy 373.085603 -178.220941)
			(xy 373.108245 -178.270518) (xy 373.1236 -178.322813) (xy 373.131356 -178.376761) (xy 373.131842 -178.404012)
			(xy 373.131179 -178.435575) (xy 373.120794 -178.49784) (xy 373.100309 -178.557549) (xy 373.085868 -178.585622)
			(xy 373.081042 -178.594512) (xy 373.07901 -178.61407) (xy 373.104664 -178.702208) (xy 373.11711 -178.717702)
			(xy 373.126 -178.722782) (xy 373.133366 -178.726846) (xy 373.143018 -178.732688) (xy 373.165116 -178.73472)
			(xy 373.259604 -178.701192) (xy 373.275606 -178.685698) (xy 373.27967 -178.675284) (xy 373.290366 -178.648508)
			(xy 373.318654 -178.598266) (xy 373.354184 -178.552857) (xy 373.396146 -178.513315) (xy 373.443583 -178.480541)
			(xy 373.495414 -178.455283) (xy 373.550457 -178.438117) (xy 373.607457 -178.429434) (xy 373.636286 -178.428904)
			(xy 373.66354 -178.429342) (xy 373.717495 -178.437098) (xy 373.769796 -178.452453) (xy 373.819379 -178.475095)
			(xy 373.865236 -178.504564) (xy 373.906431 -178.540259) (xy 373.942128 -178.581453) (xy 373.971598 -178.627308)
			(xy 373.994242 -178.676891) (xy 374.009599 -178.729192) (xy 374.017357 -178.783146) (xy 374.017357 -178.837654)
			(xy 374.009599 -178.891608) (xy 373.994242 -178.943909) (xy 373.971598 -178.993492) (xy 373.942128 -179.039347)
			(xy 373.906431 -179.080541) (xy 373.865236 -179.116236) (xy 373.819379 -179.145705) (xy 373.769796 -179.168347)
			(xy 373.717495 -179.183702) (xy 373.66354 -179.191458) (xy 373.636286 -179.19192) (xy 373.611051 -179.191526)
			(xy 373.561017 -179.184907) (xy 373.512296 -179.171733) (xy 373.465745 -179.152235) (xy 373.443754 -179.13985)
			(xy 373.434102 -179.134008) (xy 373.412004 -179.131976) (xy 373.317516 -179.165504) (xy 373.301514 -179.180998)
			(xy 373.29745 -179.191412) (xy 373.286735 -179.21818) (xy 373.25845 -179.268421) (xy 373.222922 -179.31383)
			(xy 373.180963 -179.353373) (xy 373.133528 -179.386147) (xy 373.0817 -179.411407) (xy 373.02666 -179.428575)
			(xy 372.969662 -179.437261) (xy 372.940834 -179.437792) (xy 372.913581 -179.437313) (xy 372.85963 -179.42956)
			(xy 372.807332 -179.414208) (xy 372.75775 -179.391568) (xy 372.711896 -179.362102) (xy 372.670703 -179.32641)
			(xy 372.635009 -179.285218) (xy 372.605541 -179.239365) (xy 372.582899 -179.189785) (xy 372.567544 -179.137488)
			(xy 372.559788 -179.083537) (xy 372.559326 -179.056284) (xy 372.559992 -179.024721) (xy 372.570376 -178.962456)
			(xy 372.590859 -178.902747) (xy 372.6053 -178.874674) (xy 372.610126 -178.865784) (xy 372.612158 -178.846226)
			(xy 372.586504 -178.758088) (xy 372.574058 -178.742594) (xy 372.565168 -178.737514) (xy 372.540061 -178.722975)
			(xy 372.494175 -178.687473) (xy 372.454197 -178.645429) (xy 372.421051 -178.597814) (xy 372.395502 -178.545726)
			(xy 372.378138 -178.490369) (xy 372.369362 -178.43302) (xy 372.368826 -178.404012) (xy 369.712494 -178.404012)
			(xy 369.712494 -178.457606) (xy 369.713063 -178.469174) (xy 369.723259 -178.489945) (xy 369.732052 -178.497484)
			(xy 369.75586 -178.516753) (xy 369.797577 -178.561593) (xy 369.831578 -178.612534) (xy 369.856986 -178.66826)
			(xy 369.865656 -178.697636) (xy 369.867942 -178.70678) (xy 369.879372 -178.72202) (xy 369.953286 -178.768756)
			(xy 369.971828 -178.772566) (xy 369.981226 -178.770788) (xy 369.997726 -178.76805) (xy 370.031049 -178.765125)
			(xy 370.047774 -178.764946) (xy 370.075022 -178.765502) (xy 370.128965 -178.773254) (xy 370.181256 -178.788604)
			(xy 370.23083 -178.811238) (xy 370.276678 -178.840698) (xy 370.317867 -178.876382) (xy 370.353559 -178.917564)
			(xy 370.383027 -178.963407) (xy 370.405671 -179.012977) (xy 370.421031 -179.065264) (xy 370.428793 -179.119206)
			(xy 370.429282 -179.146454) (xy 370.428791 -179.174028) (xy 370.420844 -179.2286) (xy 370.405125 -179.281459)
			(xy 370.38196 -179.331506) (xy 370.351831 -179.377696) (xy 370.315367 -179.419068) (xy 370.294662 -179.437284)
			(xy 370.286549 -179.444891) (xy 370.277193 -179.465039) (xy 370.276628 -179.476146) (xy 370.276628 -179.553362)
			(xy 370.277193 -179.564472) (xy 370.286533 -179.584632) (xy 370.294662 -179.592224) (xy 370.31538 -179.610428)
			(xy 370.351852 -179.651797) (xy 370.381984 -179.697988) (xy 370.405149 -179.748038) (xy 370.420863 -179.800902)
			(xy 370.428799 -179.855479) (xy 370.428833 -179.8574) (xy 375.01779 -179.8574) (xy 375.021861 -179.801778)
			(xy 375.033987 -179.747341) (xy 375.05391 -179.69525) (xy 375.081206 -179.646615) (xy 375.115292 -179.602472)
			(xy 375.155441 -179.563763) (xy 375.200799 -179.531312) (xy 375.250399 -179.505811) (xy 375.303183 -179.487804)
			(xy 375.358026 -179.477674) (xy 375.41376 -179.475637) (xy 375.469197 -179.481737) (xy 375.523154 -179.495843)
			(xy 375.574483 -179.517655) (xy 375.622089 -179.546709) (xy 375.664957 -179.582384) (xy 375.702174 -179.623921)
			(xy 375.732947 -179.670434) (xy 375.756619 -179.720931) (xy 375.772687 -179.774338) (xy 375.780807 -179.829514)
			(xy 375.781316 -179.8574) (xy 375.780807 -179.885286) (xy 375.772687 -179.940462) (xy 375.756619 -179.993869)
			(xy 375.732947 -180.044366) (xy 375.702174 -180.090879) (xy 375.664957 -180.132416) (xy 375.622089 -180.168091)
			(xy 375.574483 -180.197145) (xy 375.523154 -180.218957) (xy 375.469197 -180.233063) (xy 375.41376 -180.239163)
			(xy 375.358026 -180.237126) (xy 375.303183 -180.226996) (xy 375.250399 -180.208989) (xy 375.200799 -180.183488)
			(xy 375.155441 -180.151037) (xy 375.115292 -180.112328) (xy 375.081206 -180.068185) (xy 375.05391 -180.01955)
			(xy 375.033987 -179.967459) (xy 375.021861 -179.913022) (xy 375.01779 -179.8574) (xy 370.428833 -179.8574)
			(xy 370.429282 -179.883054) (xy 370.428802 -179.910307) (xy 370.42105 -179.964259) (xy 370.405699 -180.016558)
			(xy 370.38306 -180.066139) (xy 370.353594 -180.111994) (xy 370.317902 -180.153188) (xy 370.27671 -180.188882)
			(xy 370.230857 -180.21835) (xy 370.181276 -180.240992) (xy 370.128978 -180.256346) (xy 370.075027 -180.2641)
			(xy 370.047774 -180.264562) (xy 370.013484 -180.263038) (xy 370.003324 -180.262022) (xy 369.98402 -180.268118)
			(xy 369.913408 -180.3273) (xy 369.90401 -180.345334) (xy 369.902994 -180.355494) (xy 369.900102 -180.383674)
			(xy 369.88692 -180.438769) (xy 369.865734 -180.491308) (xy 369.837009 -180.540135) (xy 369.801378 -180.584175)
			(xy 369.759624 -180.622461) (xy 369.712666 -180.654149) (xy 369.661538 -180.678543) (xy 369.607363 -180.695105)
			(xy 369.551335 -180.703471) (xy 369.52301 -180.703982) (xy 369.495756 -180.703535) (xy 369.441803 -180.695779)
			(xy 369.389504 -180.680423) (xy 369.339922 -180.65778) (xy 369.294067 -180.62831) (xy 369.252874 -180.592615)
			(xy 369.21718 -180.55142) (xy 369.187713 -180.505564) (xy 369.165071 -180.455981) (xy 369.149718 -180.403681)
			(xy 369.141964 -180.349728) (xy 369.141502 -180.322474) (xy 369.141961 -180.29461) (xy 369.150067 -180.239476)
			(xy 369.166104 -180.186106) (xy 369.189729 -180.135635) (xy 369.220443 -180.089136) (xy 369.25759 -180.047596)
			(xy 369.278662 -180.029358) (xy 369.287806 -180.021738) (xy 369.297458 -180.000656) (xy 369.293902 -179.89677)
			(xy 369.28298 -179.876196) (xy 369.273328 -179.869084) (xy 369.252417 -179.853361) (xy 369.214661 -179.817144)
			(xy 369.182219 -179.7761) (xy 369.155703 -179.730999) (xy 369.135611 -179.682693) (xy 369.128548 -179.657502)
			(xy 369.126262 -179.648612) (xy 369.115594 -179.633372) (xy 369.043712 -179.58562) (xy 369.025678 -179.581556)
			(xy 369.016534 -179.582826) (xy 369.003518 -179.5845) (xy 368.977333 -179.586277) (xy 368.96421 -179.586382)
			(xy 368.936955 -179.585972) (xy 368.882999 -179.578215) (xy 368.830696 -179.562859) (xy 368.781112 -179.540216)
			(xy 368.735254 -179.510746) (xy 368.694057 -179.47505) (xy 368.65836 -179.433854) (xy 368.628889 -179.387997)
			(xy 368.606244 -179.338413) (xy 368.590887 -179.286111) (xy 368.583129 -179.232155) (xy 358.199539 -179.232155)
			(xy 360.146346 -181.178962) (xy 360.153189 -181.186361) (xy 360.160909 -181.20496) (xy 360.161332 -181.21503)
			(xy 360.161332 -182.141876) (xy 370.14785 -182.141876) (xy 370.148351 -182.114302) (xy 370.156294 -182.05973)
			(xy 370.17201 -182.00687) (xy 370.195174 -181.956824) (xy 370.225301 -181.910634) (xy 370.261765 -181.869262)
			(xy 370.28247 -181.851046) (xy 370.290574 -181.843431) (xy 370.299934 -181.823289) (xy 370.300504 -181.812184)
			(xy 370.300504 -181.734968) (xy 370.299968 -181.723854) (xy 370.290607 -181.703696) (xy 370.28247 -181.696106)
			(xy 370.261753 -181.677902) (xy 370.225284 -181.636531) (xy 370.195153 -181.590339) (xy 370.171989 -181.54029)
			(xy 370.156274 -181.487427) (xy 370.148335 -181.432851) (xy 370.14785 -181.405276) (xy 370.148454 -181.37583)
			(xy 370.157513 -181.317638) (xy 370.175399 -181.261528) (xy 370.201686 -181.208827) (xy 370.235752 -181.160788)
			(xy 370.276789 -181.118547) (xy 370.323824 -181.083106) (xy 370.349526 -181.068726) (xy 370.357908 -181.064408)
			(xy 370.3701 -181.050438) (xy 370.399818 -180.968904) (xy 370.399564 -180.950362) (xy 370.396008 -180.941726)
			(xy 370.387638 -180.919707) (xy 370.375885 -180.87409) (xy 370.369955 -180.827357) (xy 370.369592 -180.803804)
			(xy 370.370038 -180.777186) (xy 370.377614 -180.724491) (xy 370.392612 -180.673411) (xy 370.414727 -180.624986)
			(xy 370.443509 -180.580201) (xy 370.478372 -180.539967) (xy 370.518605 -180.505105) (xy 370.563391 -180.476324)
			(xy 370.611817 -180.45421) (xy 370.662897 -180.439213) (xy 370.715592 -180.431637) (xy 370.74221 -180.431186)
			(xy 370.768632 -180.431641) (xy 370.820947 -180.439092) (xy 370.871686 -180.453858) (xy 370.91983 -180.475642)
			(xy 370.964415 -180.504008) (xy 370.98478 -180.520848) (xy 370.991638 -180.526944) (xy 371.008656 -180.53304)
			(xy 371.092984 -180.53304) (xy 371.110002 -180.526944) (xy 371.11686 -180.520848) (xy 371.137226 -180.504009)
			(xy 371.181812 -180.475644) (xy 371.229956 -180.453857) (xy 371.280693 -180.439086) (xy 371.333008 -180.431626)
			(xy 371.385852 -180.431626) (xy 371.438167 -180.439086) (xy 371.488904 -180.453857) (xy 371.537048 -180.475644)
			(xy 371.581634 -180.504009) (xy 371.602 -180.520848) (xy 371.608858 -180.526944) (xy 371.625876 -180.53304)
			(xy 371.710204 -180.53304) (xy 371.727222 -180.526944) (xy 371.73408 -180.520848) (xy 371.754459 -180.504027)
			(xy 371.799044 -180.475668) (xy 371.847186 -180.453884) (xy 371.897919 -180.439113) (xy 371.95023 -180.431649)
			(xy 371.97665 -180.431186) (xy 372.00454 -180.431669) (xy 372.059696 -180.439976) (xy 372.112999 -180.456411)
			(xy 372.163256 -180.480608) (xy 372.209346 -180.512026) (xy 372.250237 -180.549962) (xy 372.285017 -180.59357)
			(xy 372.312909 -180.641874) (xy 372.327118 -180.678074) (xy 376.98553 -180.678074) (xy 376.986036 -180.650501)
			(xy 376.993979 -180.595929) (xy 377.009695 -180.54307) (xy 377.032858 -180.493023) (xy 377.062984 -180.446833)
			(xy 377.099445 -180.40546) (xy 377.12015 -180.387244) (xy 377.128252 -180.379627) (xy 377.137613 -180.359486)
			(xy 377.138184 -180.348382) (xy 377.138184 -180.271166) (xy 377.137656 -180.260051) (xy 377.12829 -180.239893)
			(xy 377.12015 -180.232304) (xy 377.099416 -180.214118) (xy 377.062948 -180.172745) (xy 377.032818 -180.126551)
			(xy 377.009654 -180.0765) (xy 376.993938 -180.023636) (xy 376.985999 -179.969059) (xy 376.986001 -179.913908)
			(xy 376.993945 -179.859331) (xy 377.009666 -179.806468) (xy 377.032834 -179.756419) (xy 377.062969 -179.710229)
			(xy 377.09944 -179.668858) (xy 377.12015 -179.650644) (xy 377.128252 -179.643027) (xy 377.137613 -179.622886)
			(xy 377.138184 -179.611782) (xy 377.138184 -179.534566) (xy 377.137656 -179.523451) (xy 377.12829 -179.503293)
			(xy 377.12015 -179.495704) (xy 377.099428 -179.477505) (xy 377.06296 -179.436133) (xy 377.032831 -179.38994)
			(xy 377.009667 -179.33989) (xy 376.993953 -179.287025) (xy 376.986015 -179.232449) (xy 376.98553 -179.204874)
			(xy 376.985931 -179.177619) (xy 376.993692 -179.123664) (xy 377.009054 -179.071362) (xy 377.031702 -179.021779)
			(xy 377.061176 -178.975924) (xy 377.096876 -178.934731) (xy 377.138076 -178.899038) (xy 377.183936 -178.869571)
			(xy 377.233522 -178.846931) (xy 377.285826 -178.831579) (xy 377.339783 -178.823826) (xy 377.367038 -178.823366)
			(xy 377.394893 -178.82388) (xy 377.450008 -178.832008) (xy 377.503357 -178.848057) (xy 377.553809 -178.871686)
			(xy 377.600292 -178.902394) (xy 377.641821 -178.93953) (xy 377.677514 -178.982305) (xy 377.706615 -179.029811)
			(xy 377.728505 -179.081041) (xy 377.7361 -179.107846) (xy 377.738386 -179.116736) (xy 377.749054 -179.131976)
			(xy 377.820936 -179.179728) (xy 377.83897 -179.183792) (xy 377.848114 -179.182522) (xy 377.861131 -179.180854)
			(xy 377.887315 -179.179073) (xy 377.900438 -179.178966) (xy 377.914587 -179.179056) (xy 377.94281 -179.181093)
			(xy 377.956826 -179.18303) (xy 377.966986 -179.184554) (xy 377.986544 -179.179728) (xy 378.060966 -179.123848)
			(xy 378.071126 -179.106322) (xy 378.072396 -179.096162) (xy 378.076477 -179.069007) (xy 378.09145 -179.016176)
			(xy 378.113841 -178.966037) (xy 378.143189 -178.919625) (xy 378.178888 -178.877901) (xy 378.220198 -178.841724)
			(xy 378.266268 -178.811843) (xy 378.316146 -178.788875) (xy 378.368801 -178.773295) (xy 378.423146 -178.765423)
			(xy 378.450602 -178.764946) (xy 378.477851 -178.765476) (xy 378.531795 -178.773231) (xy 378.584086 -178.788584)
			(xy 378.63366 -178.811222) (xy 378.679508 -178.840685) (xy 378.720697 -178.876371) (xy 378.756389 -178.917556)
			(xy 378.785856 -178.963401) (xy 378.8085 -179.012973) (xy 378.823859 -179.065262) (xy 378.831621 -179.119205)
			(xy 378.83211 -179.146454) (xy 378.831609 -179.174027) (xy 378.823663 -179.228598) (xy 378.807945 -179.281457)
			(xy 378.784782 -179.331503) (xy 378.754655 -179.377694) (xy 378.718194 -179.419067) (xy 378.69749 -179.437284)
			(xy 378.689382 -179.444896) (xy 378.680022 -179.46504) (xy 378.679456 -179.476146) (xy 378.679456 -179.553362)
			(xy 378.680011 -179.564474) (xy 378.689357 -179.584634) (xy 378.69749 -179.592224) (xy 378.718214 -179.610421)
			(xy 378.754684 -179.651793) (xy 378.784814 -179.697985) (xy 378.807978 -179.748036) (xy 378.823692 -179.800901)
			(xy 378.831627 -179.855478) (xy 378.831661 -179.8574) (xy 383.420618 -179.8574) (xy 383.424689 -179.801778)
			(xy 383.436815 -179.747341) (xy 383.456738 -179.69525) (xy 383.484034 -179.646615) (xy 383.51812 -179.602472)
			(xy 383.558269 -179.563763) (xy 383.603627 -179.531312) (xy 383.653227 -179.505811) (xy 383.706011 -179.487804)
			(xy 383.760854 -179.477674) (xy 383.816588 -179.475637) (xy 383.872025 -179.481737) (xy 383.925982 -179.495843)
			(xy 383.977311 -179.517655) (xy 384.024917 -179.546709) (xy 384.067785 -179.582384) (xy 384.105002 -179.623921)
			(xy 384.135775 -179.670434) (xy 384.159447 -179.720931) (xy 384.175515 -179.774338) (xy 384.183635 -179.829514)
			(xy 384.184144 -179.8574) (xy 384.183635 -179.885286) (xy 384.175515 -179.940462) (xy 384.159447 -179.993869)
			(xy 384.135775 -180.044366) (xy 384.105002 -180.090879) (xy 384.067785 -180.132416) (xy 384.024917 -180.168091)
			(xy 383.977311 -180.197145) (xy 383.925982 -180.218957) (xy 383.872025 -180.233063) (xy 383.816588 -180.239163)
			(xy 383.760854 -180.237126) (xy 383.706011 -180.226996) (xy 383.653227 -180.208989) (xy 383.603627 -180.183488)
			(xy 383.558269 -180.151037) (xy 383.51812 -180.112328) (xy 383.484034 -180.068185) (xy 383.456738 -180.01955)
			(xy 383.436815 -179.967459) (xy 383.424689 -179.913022) (xy 383.420618 -179.8574) (xy 378.831661 -179.8574)
			(xy 378.83211 -179.883054) (xy 378.831602 -179.910306) (xy 378.823851 -179.964255) (xy 378.808501 -180.016552)
			(xy 378.785864 -180.066132) (xy 378.756401 -180.111985) (xy 378.720712 -180.153178) (xy 378.679523 -180.188872)
			(xy 378.633674 -180.218341) (xy 378.584097 -180.240984) (xy 378.531802 -180.256341) (xy 378.477854 -180.264098)
			(xy 378.450602 -180.264562) (xy 378.416312 -180.263038) (xy 378.406152 -180.262022) (xy 378.386848 -180.268118)
			(xy 378.316236 -180.3273) (xy 378.306838 -180.345334) (xy 378.305822 -180.355494) (xy 378.302902 -180.383671)
			(xy 378.289722 -180.438763) (xy 378.268538 -180.4913) (xy 378.239816 -180.540125) (xy 378.204187 -180.584165)
			(xy 378.162437 -180.622451) (xy 378.115483 -180.65414) (xy 378.064358 -180.678535) (xy 378.010187 -180.6951)
			(xy 377.954162 -180.703469) (xy 377.925838 -180.703982) (xy 377.907819 -180.703764) (xy 377.871944 -180.700328)
			(xy 377.85421 -180.697124) (xy 377.844812 -180.695346) (xy 377.825762 -180.699156) (xy 377.750578 -180.746908)
			(xy 377.739148 -180.762656) (xy 377.736862 -180.772054) (xy 377.72949 -180.799106) (xy 377.707858 -180.850833)
			(xy 377.67889 -180.898839) (xy 377.643212 -180.942091) (xy 377.601589 -180.979658) (xy 377.554918 -181.010731)
			(xy 377.504204 -181.034642) (xy 377.450537 -181.050876) (xy 377.395072 -181.059085) (xy 377.367038 -181.059582)
			(xy 377.339785 -181.059109) (xy 377.285833 -181.051357) (xy 377.233534 -181.036004) (xy 377.183952 -181.013364)
			(xy 377.138097 -180.983898) (xy 377.096904 -180.948205) (xy 377.061209 -180.907012) (xy 377.031741 -180.861159)
			(xy 377.0091 -180.811578) (xy 376.993746 -180.759279) (xy 376.985992 -180.705327) (xy 376.98553 -180.678074)
			(xy 372.327118 -180.678074) (xy 372.333289 -180.693797) (xy 372.345702 -180.748177) (xy 372.349871 -180.8038)
			(xy 372.345702 -180.859423) (xy 372.333289 -180.913803) (xy 372.312909 -180.965726) (xy 372.285017 -181.01403)
			(xy 372.250237 -181.057638) (xy 372.209346 -181.095574) (xy 372.163256 -181.126992) (xy 372.112999 -181.151189)
			(xy 372.059696 -181.167624) (xy 372.00454 -181.175931) (xy 371.97665 -181.176422) (xy 371.950227 -181.175988)
			(xy 371.897911 -181.168532) (xy 371.847172 -181.153761) (xy 371.799029 -181.131972) (xy 371.754445 -181.103602)
			(xy 371.73408 -181.08676) (xy 371.727222 -181.080664) (xy 371.710204 -181.074568) (xy 371.625876 -181.074568)
			(xy 371.608858 -181.080664) (xy 371.602 -181.08676) (xy 371.581634 -181.103599) (xy 371.537048 -181.131964)
			(xy 371.488904 -181.153751) (xy 371.438167 -181.168522) (xy 371.385852 -181.175982) (xy 371.333008 -181.175982)
			(xy 371.280693 -181.168522) (xy 371.229956 -181.153751) (xy 371.181812 -181.131964) (xy 371.137226 -181.103599)
			(xy 371.11686 -181.08676) (xy 371.110002 -181.080664) (xy 371.092984 -181.074568) (xy 371.008656 -181.074568)
			(xy 370.991638 -181.080664) (xy 370.98478 -181.08676) (xy 370.970662 -181.098517) (xy 370.94051 -181.119513)
			(xy 370.924582 -181.12867) (xy 370.916454 -181.133242) (xy 370.904516 -181.147466) (xy 370.876576 -181.229508)
			(xy 370.877084 -181.24805) (xy 370.880894 -181.25694) (xy 370.89036 -181.280513) (xy 370.903704 -181.329528)
			(xy 370.910443 -181.379877) (xy 370.910866 -181.405276) (xy 370.910396 -181.432851) (xy 370.902446 -181.487424)
			(xy 370.886722 -181.540284) (xy 370.863553 -181.59033) (xy 370.833421 -181.63652) (xy 370.796953 -181.677891)
			(xy 370.776246 -181.696106) (xy 370.768121 -181.703702) (xy 370.758773 -181.723859) (xy 370.758238 -181.73446)
			(xy 375.976642 -181.73446) (xy 375.977123 -181.706549) (xy 375.985262 -181.651323) (xy 376.001361 -181.597873)
			(xy 376.025076 -181.547338) (xy 376.055901 -181.500798) (xy 376.074178 -181.479698) (xy 376.080528 -181.472586)
			(xy 376.087132 -181.455314) (xy 376.087132 -181.368192) (xy 376.080528 -181.35092) (xy 376.074178 -181.343808)
			(xy 376.055879 -181.322726) (xy 376.025055 -181.276182) (xy 376.001344 -181.225643) (xy 375.985253 -181.172188)
			(xy 375.977124 -181.116958) (xy 375.976642 -181.089046) (xy 375.977128 -181.061795) (xy 375.984884 -181.007847)
			(xy 376.000239 -180.955552) (xy 376.022881 -180.905975) (xy 376.052347 -180.860125) (xy 376.088038 -180.818934)
			(xy 376.129229 -180.783243) (xy 376.175079 -180.753777) (xy 376.224656 -180.731135) (xy 376.276951 -180.71578)
			(xy 376.330899 -180.708024) (xy 376.385401 -180.708024) (xy 376.439349 -180.71578) (xy 376.491644 -180.731135)
			(xy 376.541221 -180.753777) (xy 376.587071 -180.783243) (xy 376.628262 -180.818934) (xy 376.663953 -180.860125)
			(xy 376.693419 -180.905975) (xy 376.716061 -180.955552) (xy 376.731416 -181.007847) (xy 376.739172 -181.061795)
			(xy 376.739658 -181.089046) (xy 376.739181 -181.116957) (xy 376.731041 -181.172183) (xy 376.714941 -181.225634)
			(xy 376.691225 -181.276168) (xy 376.660399 -181.322708) (xy 376.642122 -181.343808) (xy 376.635772 -181.35092)
			(xy 376.629168 -181.368192) (xy 376.629168 -181.455314) (xy 376.635772 -181.472586) (xy 376.642122 -181.479698)
			(xy 376.660377 -181.500817) (xy 376.691207 -181.54735) (xy 376.714926 -181.59788) (xy 376.731028 -181.651327)
			(xy 376.739169 -181.70655) (xy 376.739658 -181.73446) (xy 376.739172 -181.761711) (xy 376.731416 -181.815659)
			(xy 376.716061 -181.867954) (xy 376.693419 -181.917531) (xy 376.663953 -181.963381) (xy 376.628262 -182.004572)
			(xy 376.587071 -182.040263) (xy 376.541221 -182.069729) (xy 376.491644 -182.092371) (xy 376.439349 -182.107726)
			(xy 376.385401 -182.115482) (xy 376.330899 -182.115482) (xy 376.276951 -182.107726) (xy 376.224656 -182.092371)
			(xy 376.175079 -182.069729) (xy 376.129229 -182.040263) (xy 376.088038 -182.004572) (xy 376.052347 -181.963381)
			(xy 376.022881 -181.917531) (xy 376.000239 -181.867954) (xy 375.984884 -181.815659) (xy 375.977128 -181.761711)
			(xy 375.976642 -181.73446) (xy 370.758238 -181.73446) (xy 370.758212 -181.734968) (xy 370.758212 -181.812184)
			(xy 370.758769 -181.823295) (xy 370.768115 -181.843454) (xy 370.776246 -181.851046) (xy 370.796943 -181.869272)
			(xy 370.833413 -181.910639) (xy 370.863546 -181.956826) (xy 370.886713 -182.006871) (xy 370.902433 -182.05973)
			(xy 370.910378 -182.114302) (xy 370.910866 -182.141876) (xy 370.91038 -182.169127) (xy 370.902624 -182.223075)
			(xy 370.900363 -182.230776) (xy 378.653548 -182.230776) (xy 378.654049 -182.203203) (xy 378.661992 -182.148631)
			(xy 378.677709 -182.095771) (xy 378.700872 -182.045724) (xy 378.730999 -181.999534) (xy 378.767463 -181.958162)
			(xy 378.788168 -181.939946) (xy 378.796272 -181.932331) (xy 378.805632 -181.912189) (xy 378.806202 -181.901084)
			(xy 378.806202 -181.823868) (xy 378.805667 -181.812754) (xy 378.796305 -181.792596) (xy 378.788168 -181.785006)
			(xy 378.76745 -181.766802) (xy 378.730982 -181.725431) (xy 378.700851 -181.679239) (xy 378.677687 -181.62919)
			(xy 378.661972 -181.576327) (xy 378.654033 -181.521751) (xy 378.653548 -181.494176) (xy 378.654063 -181.465222)
			(xy 378.662824 -181.40798) (xy 378.680128 -181.352717) (xy 378.705578 -181.3007) (xy 378.738589 -181.253122)
			(xy 378.778405 -181.211074) (xy 378.824113 -181.175519) (xy 378.849128 -181.160928) (xy 378.859542 -181.15534)
			(xy 378.87275 -181.136544) (xy 378.889514 -181.035198) (xy 378.883164 -181.0131) (xy 378.87529 -181.004464)
			(xy 378.857463 -180.983825) (xy 378.827355 -180.938354) (xy 378.804192 -180.888983) (xy 378.788467 -180.836764)
			(xy 378.780517 -180.782811) (xy 378.78004 -180.755544) (xy 378.780575 -180.728929) (xy 378.788144 -180.676241)
			(xy 378.803135 -180.625165) (xy 378.825241 -180.576743) (xy 378.854014 -180.531961) (xy 378.888867 -180.491728)
			(xy 378.929092 -180.456866) (xy 378.973868 -180.428083) (xy 379.022285 -180.405965) (xy 379.073356 -180.390962)
			(xy 379.126043 -180.383381) (xy 379.152658 -180.382926) (xy 379.17908 -180.383368) (xy 379.231396 -180.390824)
			(xy 379.282134 -180.405594) (xy 379.330278 -180.427381) (xy 379.374862 -180.455748) (xy 379.395228 -180.472588)
			(xy 379.402086 -180.478684) (xy 379.419104 -180.48478) (xy 379.503432 -180.48478) (xy 379.52045 -180.478684)
			(xy 379.527308 -180.472588) (xy 379.547674 -180.455749) (xy 379.59226 -180.427384) (xy 379.640404 -180.405597)
			(xy 379.691141 -180.390826) (xy 379.743456 -180.383366) (xy 379.7963 -180.383366) (xy 379.848615 -180.390826)
			(xy 379.899352 -180.405597) (xy 379.947496 -180.427384) (xy 379.992082 -180.455749) (xy 380.012448 -180.472588)
			(xy 380.019306 -180.478684) (xy 380.036324 -180.48478) (xy 380.120652 -180.48478) (xy 380.13767 -180.478684)
			(xy 380.144528 -180.472588) (xy 380.164882 -180.455735) (xy 380.209475 -180.427383) (xy 380.257623 -180.405606)
			(xy 380.308362 -180.390842) (xy 380.360676 -180.383385) (xy 380.387098 -180.382926) (xy 380.414988 -180.383333)
			(xy 380.470145 -180.391646) (xy 380.523448 -180.408088) (xy 380.573704 -180.43229) (xy 380.619792 -180.463712)
			(xy 380.660682 -180.501652) (xy 380.695461 -180.545262) (xy 380.723351 -180.59357) (xy 380.74373 -180.645494)
			(xy 380.751166 -180.678074) (xy 385.31673 -180.678074) (xy 385.317236 -180.650501) (xy 385.325179 -180.595929)
			(xy 385.340895 -180.54307) (xy 385.364058 -180.493023) (xy 385.394184 -180.446833) (xy 385.430645 -180.40546)
			(xy 385.45135 -180.387244) (xy 385.459452 -180.379627) (xy 385.468813 -180.359486) (xy 385.469384 -180.348382)
			(xy 385.469384 -180.271166) (xy 385.468856 -180.260051) (xy 385.45949 -180.239893) (xy 385.45135 -180.232304)
			(xy 385.430616 -180.214118) (xy 385.394148 -180.172745) (xy 385.364018 -180.126551) (xy 385.340854 -180.0765)
			(xy 385.325138 -180.023636) (xy 385.317199 -179.969059) (xy 385.317201 -179.913908) (xy 385.325145 -179.859331)
			(xy 385.340866 -179.806468) (xy 385.364034 -179.756419) (xy 385.394169 -179.710229) (xy 385.43064 -179.668858)
			(xy 385.45135 -179.650644) (xy 385.459452 -179.643027) (xy 385.468813 -179.622886) (xy 385.469384 -179.611782)
			(xy 385.469384 -179.534566) (xy 385.468856 -179.523451) (xy 385.45949 -179.503293) (xy 385.45135 -179.495704)
			(xy 385.430628 -179.477505) (xy 385.39416 -179.436133) (xy 385.364031 -179.38994) (xy 385.340867 -179.33989)
			(xy 385.325153 -179.287025) (xy 385.317215 -179.232449) (xy 385.31673 -179.204874) (xy 385.317131 -179.177619)
			(xy 385.324892 -179.123664) (xy 385.340254 -179.071362) (xy 385.362902 -179.021779) (xy 385.392376 -178.975924)
			(xy 385.428076 -178.934731) (xy 385.469276 -178.899038) (xy 385.515136 -178.869571) (xy 385.564722 -178.846931)
			(xy 385.617026 -178.831579) (xy 385.670983 -178.823826) (xy 385.698238 -178.823366) (xy 385.726093 -178.82388)
			(xy 385.781208 -178.832008) (xy 385.834557 -178.848057) (xy 385.885009 -178.871686) (xy 385.931492 -178.902394)
			(xy 385.973021 -178.93953) (xy 386.008714 -178.982305) (xy 386.037815 -179.029811) (xy 386.059705 -179.081041)
			(xy 386.0673 -179.107846) (xy 386.069586 -179.116736) (xy 386.080254 -179.131976) (xy 386.152136 -179.179728)
			(xy 386.17017 -179.183792) (xy 386.179314 -179.182522) (xy 386.192331 -179.180854) (xy 386.218515 -179.179073)
			(xy 386.231638 -179.178966) (xy 386.245787 -179.179056) (xy 386.27401 -179.181093) (xy 386.288026 -179.18303)
			(xy 386.298186 -179.184554) (xy 386.317744 -179.179728) (xy 386.392166 -179.123848) (xy 386.402326 -179.106322)
			(xy 386.403596 -179.096162) (xy 386.407677 -179.069007) (xy 386.42265 -179.016176) (xy 386.445041 -178.966037)
			(xy 386.474389 -178.919625) (xy 386.510088 -178.877901) (xy 386.551398 -178.841724) (xy 386.597468 -178.811843)
			(xy 386.647346 -178.788875) (xy 386.700001 -178.773295) (xy 386.754346 -178.765423) (xy 386.781802 -178.764946)
			(xy 386.809051 -178.765476) (xy 386.862995 -178.773231) (xy 386.915286 -178.788584) (xy 386.96486 -178.811222)
			(xy 387.010708 -178.840685) (xy 387.051897 -178.876371) (xy 387.087589 -178.917556) (xy 387.117056 -178.963401)
			(xy 387.1397 -179.012973) (xy 387.155059 -179.065262) (xy 387.162821 -179.119205) (xy 387.16331 -179.146454)
			(xy 387.162809 -179.174027) (xy 387.154863 -179.228598) (xy 387.139145 -179.281457) (xy 387.115982 -179.331503)
			(xy 387.085855 -179.377694) (xy 387.049394 -179.419067) (xy 387.02869 -179.437284) (xy 387.020582 -179.444896)
			(xy 387.011222 -179.46504) (xy 387.010656 -179.476146) (xy 387.010656 -179.553362) (xy 387.011211 -179.564474)
			(xy 387.020557 -179.584634) (xy 387.02869 -179.592224) (xy 387.049414 -179.610421) (xy 387.085884 -179.651793)
			(xy 387.116014 -179.697985) (xy 387.139178 -179.748036) (xy 387.154892 -179.800901) (xy 387.162827 -179.855478)
			(xy 387.162861 -179.8574) (xy 391.751818 -179.8574) (xy 391.755889 -179.801778) (xy 391.768015 -179.747341)
			(xy 391.787938 -179.69525) (xy 391.815234 -179.646615) (xy 391.84932 -179.602472) (xy 391.889469 -179.563763)
			(xy 391.934827 -179.531312) (xy 391.984427 -179.505811) (xy 392.037211 -179.487804) (xy 392.092054 -179.477674)
			(xy 392.147788 -179.475637) (xy 392.203225 -179.481737) (xy 392.257182 -179.495843) (xy 392.308511 -179.517655)
			(xy 392.356117 -179.546709) (xy 392.398985 -179.582384) (xy 392.436202 -179.623921) (xy 392.466975 -179.670434)
			(xy 392.490647 -179.720931) (xy 392.506715 -179.774338) (xy 392.514835 -179.829514) (xy 392.515344 -179.8574)
			(xy 392.514835 -179.885286) (xy 392.506715 -179.940462) (xy 392.490647 -179.993869) (xy 392.466975 -180.044366)
			(xy 392.436202 -180.090879) (xy 392.398985 -180.132416) (xy 392.356117 -180.168091) (xy 392.308511 -180.197145)
			(xy 392.257182 -180.218957) (xy 392.203225 -180.233063) (xy 392.147788 -180.239163) (xy 392.092054 -180.237126)
			(xy 392.037211 -180.226996) (xy 391.984427 -180.208989) (xy 391.934827 -180.183488) (xy 391.889469 -180.151037)
			(xy 391.84932 -180.112328) (xy 391.815234 -180.068185) (xy 391.787938 -180.01955) (xy 391.768015 -179.967459)
			(xy 391.755889 -179.913022) (xy 391.751818 -179.8574) (xy 387.162861 -179.8574) (xy 387.16331 -179.883054)
			(xy 387.162802 -179.910306) (xy 387.155051 -179.964255) (xy 387.139701 -180.016552) (xy 387.117064 -180.066132)
			(xy 387.087601 -180.111985) (xy 387.051912 -180.153178) (xy 387.010723 -180.188872) (xy 386.964874 -180.218341)
			(xy 386.915297 -180.240984) (xy 386.863002 -180.256341) (xy 386.809054 -180.264098) (xy 386.781802 -180.264562)
			(xy 386.747512 -180.263038) (xy 386.737352 -180.262022) (xy 386.718048 -180.268118) (xy 386.647436 -180.3273)
			(xy 386.638038 -180.345334) (xy 386.637022 -180.355494) (xy 386.634102 -180.383671) (xy 386.620922 -180.438763)
			(xy 386.599738 -180.4913) (xy 386.571016 -180.540125) (xy 386.535387 -180.584165) (xy 386.493637 -180.622451)
			(xy 386.446683 -180.65414) (xy 386.395558 -180.678535) (xy 386.341387 -180.6951) (xy 386.285362 -180.703469)
			(xy 386.257038 -180.703982) (xy 386.239019 -180.703764) (xy 386.203144 -180.700328) (xy 386.18541 -180.697124)
			(xy 386.176012 -180.695346) (xy 386.156962 -180.699156) (xy 386.081778 -180.746908) (xy 386.070348 -180.762656)
			(xy 386.068062 -180.772054) (xy 386.06069 -180.799106) (xy 386.039058 -180.850833) (xy 386.01009 -180.898839)
			(xy 385.974412 -180.942091) (xy 385.932789 -180.979658) (xy 385.886118 -181.010731) (xy 385.835404 -181.034642)
			(xy 385.781737 -181.050876) (xy 385.726272 -181.059085) (xy 385.698238 -181.059582) (xy 385.670985 -181.059109)
			(xy 385.617033 -181.051357) (xy 385.564734 -181.036004) (xy 385.515152 -181.013364) (xy 385.469297 -180.983898)
			(xy 385.428104 -180.948205) (xy 385.392409 -180.907012) (xy 385.362941 -180.861159) (xy 385.3403 -180.811578)
			(xy 385.324946 -180.759279) (xy 385.317192 -180.705327) (xy 385.31673 -180.678074) (xy 380.751166 -180.678074)
			(xy 380.756142 -180.699876) (xy 380.760311 -180.7555) (xy 380.756142 -180.811124) (xy 380.74373 -180.865506)
			(xy 380.723351 -180.91743) (xy 380.695461 -180.965738) (xy 380.660682 -181.009348) (xy 380.619792 -181.047288)
			(xy 380.573704 -181.07871) (xy 380.523448 -181.102912) (xy 380.470145 -181.119354) (xy 380.414988 -181.127667)
			(xy 380.387098 -181.128162) (xy 380.360677 -181.127691) (xy 380.308363 -181.120242) (xy 380.257625 -181.105479)
			(xy 380.20948 -181.083699) (xy 380.164894 -181.055337) (xy 380.144528 -181.0385) (xy 380.13767 -181.032404)
			(xy 380.120652 -181.026308) (xy 380.036324 -181.026308) (xy 380.019306 -181.032404) (xy 380.012448 -181.0385)
			(xy 379.992082 -181.055339) (xy 379.947496 -181.083704) (xy 379.899352 -181.105491) (xy 379.848615 -181.120262)
			(xy 379.7963 -181.127722) (xy 379.743456 -181.127722) (xy 379.691141 -181.120262) (xy 379.640404 -181.105491)
			(xy 379.59226 -181.083704) (xy 379.547674 -181.055339) (xy 379.527308 -181.0385) (xy 379.52045 -181.032404)
			(xy 379.503432 -181.026308) (xy 379.419104 -181.026308) (xy 379.402086 -181.032404) (xy 379.395228 -181.0385)
			(xy 379.382014 -181.04952) (xy 379.353903 -181.069365) (xy 379.339094 -181.078124) (xy 379.328934 -181.08422)
			(xy 379.31598 -181.103016) (xy 379.300486 -181.204616) (xy 379.30709 -181.22646) (xy 379.315218 -181.235096)
			(xy 379.334155 -181.256385) (xy 379.366166 -181.303519) (xy 379.390819 -181.354885) (xy 379.407566 -181.409345)
			(xy 379.416035 -181.465688) (xy 379.416564 -181.494176) (xy 379.416094 -181.521751) (xy 379.408144 -181.576324)
			(xy 379.392421 -181.629184) (xy 379.369252 -181.67923) (xy 379.339119 -181.72542) (xy 379.33115 -181.73446)
			(xy 384.37947 -181.73446) (xy 384.379944 -181.706549) (xy 384.388084 -181.651322) (xy 384.404184 -181.597871)
			(xy 384.427901 -181.547337) (xy 384.458728 -181.500798) (xy 384.477006 -181.479698) (xy 384.483356 -181.472586)
			(xy 384.48996 -181.455314) (xy 384.48996 -181.368192) (xy 384.483356 -181.35092) (xy 384.477006 -181.343808)
			(xy 384.458711 -181.322722) (xy 384.427886 -181.27618) (xy 384.404174 -181.225642) (xy 384.388081 -181.172188)
			(xy 384.379952 -181.116958) (xy 384.37947 -181.089046) (xy 384.379956 -181.061795) (xy 384.387712 -181.007847)
			(xy 384.403067 -180.955552) (xy 384.425709 -180.905975) (xy 384.455175 -180.860125) (xy 384.490866 -180.818934)
			(xy 384.532057 -180.783243) (xy 384.577907 -180.753777) (xy 384.627484 -180.731135) (xy 384.679779 -180.71578)
			(xy 384.733727 -180.708024) (xy 384.788229 -180.708024) (xy 384.842177 -180.71578) (xy 384.894472 -180.731135)
			(xy 384.944049 -180.753777) (xy 384.989899 -180.783243) (xy 385.03109 -180.818934) (xy 385.066781 -180.860125)
			(xy 385.096247 -180.905975) (xy 385.118889 -180.955552) (xy 385.134244 -181.007847) (xy 385.142 -181.061795)
			(xy 385.142486 -181.089046) (xy 385.142002 -181.116957) (xy 385.133862 -181.172182) (xy 385.117764 -181.225632)
			(xy 385.09405 -181.276167) (xy 385.063226 -181.322707) (xy 385.04495 -181.343808) (xy 385.0386 -181.35092)
			(xy 385.031996 -181.368192) (xy 385.031996 -181.455314) (xy 385.0386 -181.472586) (xy 385.04495 -181.479698)
			(xy 385.063209 -181.500813) (xy 385.094038 -181.547348) (xy 385.117756 -181.597879) (xy 385.133857 -181.651326)
			(xy 385.141997 -181.70655) (xy 385.142486 -181.73446) (xy 385.142 -181.761711) (xy 385.134244 -181.815659)
			(xy 385.118889 -181.867954) (xy 385.096247 -181.917531) (xy 385.066781 -181.963381) (xy 385.03109 -182.004572)
			(xy 384.989899 -182.040263) (xy 384.944049 -182.069729) (xy 384.894472 -182.092371) (xy 384.842177 -182.107726)
			(xy 384.788229 -182.115482) (xy 384.733727 -182.115482) (xy 384.679779 -182.107726) (xy 384.627484 -182.092371)
			(xy 384.577907 -182.069729) (xy 384.532057 -182.040263) (xy 384.490866 -182.004572) (xy 384.455175 -181.963381)
			(xy 384.425709 -181.917531) (xy 384.403067 -181.867954) (xy 384.387712 -181.815659) (xy 384.379956 -181.761711)
			(xy 384.37947 -181.73446) (xy 379.33115 -181.73446) (xy 379.302651 -181.766791) (xy 379.281944 -181.785006)
			(xy 379.273819 -181.792602) (xy 379.264471 -181.812759) (xy 379.26391 -181.823868) (xy 379.26391 -181.901084)
			(xy 379.264468 -181.912195) (xy 379.273813 -181.932354) (xy 379.281944 -181.939946) (xy 379.302641 -181.958172)
			(xy 379.339111 -181.999539) (xy 379.369243 -182.045726) (xy 379.392411 -182.095771) (xy 379.408131 -182.14863)
			(xy 379.416076 -182.203202) (xy 379.416564 -182.230776) (xy 386.984748 -182.230776) (xy 386.985249 -182.203203)
			(xy 386.993192 -182.148631) (xy 387.008909 -182.095771) (xy 387.032072 -182.045724) (xy 387.062199 -181.999534)
			(xy 387.098663 -181.958162) (xy 387.119368 -181.939946) (xy 387.127472 -181.932331) (xy 387.136832 -181.912189)
			(xy 387.137402 -181.901084) (xy 387.137402 -181.823868) (xy 387.136867 -181.812754) (xy 387.127505 -181.792596)
			(xy 387.119368 -181.785006) (xy 387.09865 -181.766802) (xy 387.062182 -181.725431) (xy 387.032051 -181.679239)
			(xy 387.008887 -181.62919) (xy 386.993172 -181.576327) (xy 386.985233 -181.521751) (xy 386.984748 -181.494176)
			(xy 386.985263 -181.465222) (xy 386.994024 -181.40798) (xy 387.011328 -181.352717) (xy 387.036778 -181.3007)
			(xy 387.069789 -181.253122) (xy 387.109605 -181.211074) (xy 387.155313 -181.175519) (xy 387.180328 -181.160928)
			(xy 387.190742 -181.15534) (xy 387.20395 -181.136544) (xy 387.220714 -181.035198) (xy 387.214364 -181.0131)
			(xy 387.20649 -181.004464) (xy 387.188663 -180.983825) (xy 387.158555 -180.938354) (xy 387.135392 -180.888983)
			(xy 387.119667 -180.836764) (xy 387.111717 -180.782811) (xy 387.11124 -180.755544) (xy 387.111775 -180.728929)
			(xy 387.119344 -180.676241) (xy 387.134335 -180.625165) (xy 387.156441 -180.576743) (xy 387.185214 -180.531961)
			(xy 387.220067 -180.491728) (xy 387.260292 -180.456866) (xy 387.305068 -180.428083) (xy 387.353485 -180.405965)
			(xy 387.404556 -180.390962) (xy 387.457243 -180.383381) (xy 387.483858 -180.382926) (xy 387.51028 -180.383368)
			(xy 387.562596 -180.390824) (xy 387.613334 -180.405594) (xy 387.661478 -180.427381) (xy 387.706062 -180.455748)
			(xy 387.726428 -180.472588) (xy 387.733286 -180.478684) (xy 387.750304 -180.48478) (xy 387.834632 -180.48478)
			(xy 387.85165 -180.478684) (xy 387.858508 -180.472588) (xy 387.878874 -180.455749) (xy 387.92346 -180.427384)
			(xy 387.971604 -180.405597) (xy 388.022341 -180.390826) (xy 388.074656 -180.383366) (xy 388.1275 -180.383366)
			(xy 388.179815 -180.390826) (xy 388.230552 -180.405597) (xy 388.278696 -180.427384) (xy 388.323282 -180.455749)
			(xy 388.343648 -180.472588) (xy 388.350506 -180.478684) (xy 388.367524 -180.48478) (xy 388.451852 -180.48478)
			(xy 388.46887 -180.478684) (xy 388.475728 -180.472588) (xy 388.496082 -180.455735) (xy 388.540675 -180.427383)
			(xy 388.588823 -180.405606) (xy 388.639562 -180.390842) (xy 388.691876 -180.383385) (xy 388.718298 -180.382926)
			(xy 388.746188 -180.383333) (xy 388.801345 -180.391646) (xy 388.854648 -180.408088) (xy 388.904904 -180.43229)
			(xy 388.950992 -180.463712) (xy 388.991882 -180.501652) (xy 389.026661 -180.545262) (xy 389.054551 -180.59357)
			(xy 389.07493 -180.645494) (xy 389.087342 -180.699876) (xy 389.091511 -180.7555) (xy 389.087342 -180.811124)
			(xy 389.07493 -180.865506) (xy 389.054551 -180.91743) (xy 389.026661 -180.965738) (xy 388.991882 -181.009348)
			(xy 388.950992 -181.047288) (xy 388.904904 -181.07871) (xy 388.854648 -181.102912) (xy 388.801345 -181.119354)
			(xy 388.746188 -181.127667) (xy 388.718298 -181.128162) (xy 388.691877 -181.127691) (xy 388.639563 -181.120242)
			(xy 388.588825 -181.105479) (xy 388.54068 -181.083699) (xy 388.496094 -181.055337) (xy 388.475728 -181.0385)
			(xy 388.46887 -181.032404) (xy 388.451852 -181.026308) (xy 388.367524 -181.026308) (xy 388.350506 -181.032404)
			(xy 388.343648 -181.0385) (xy 388.323282 -181.055339) (xy 388.278696 -181.083704) (xy 388.230552 -181.105491)
			(xy 388.179815 -181.120262) (xy 388.1275 -181.127722) (xy 388.074656 -181.127722) (xy 388.022341 -181.120262)
			(xy 387.971604 -181.105491) (xy 387.92346 -181.083704) (xy 387.878874 -181.055339) (xy 387.858508 -181.0385)
			(xy 387.85165 -181.032404) (xy 387.834632 -181.026308) (xy 387.750304 -181.026308) (xy 387.733286 -181.032404)
			(xy 387.726428 -181.0385) (xy 387.713214 -181.04952) (xy 387.685103 -181.069365) (xy 387.670294 -181.078124)
			(xy 387.660134 -181.08422) (xy 387.64718 -181.103016) (xy 387.631686 -181.204616) (xy 387.63829 -181.22646)
			(xy 387.646418 -181.235096) (xy 387.665355 -181.256385) (xy 387.697366 -181.303519) (xy 387.722019 -181.354885)
			(xy 387.738766 -181.409345) (xy 387.747235 -181.465688) (xy 387.747764 -181.494176) (xy 387.747294 -181.521751)
			(xy 387.739344 -181.576324) (xy 387.723621 -181.629184) (xy 387.700452 -181.67923) (xy 387.670319 -181.72542)
			(xy 387.66235 -181.73446) (xy 392.71067 -181.73446) (xy 392.711144 -181.706549) (xy 392.719284 -181.651322)
			(xy 392.735384 -181.597871) (xy 392.759101 -181.547337) (xy 392.789928 -181.500798) (xy 392.808206 -181.479698)
			(xy 392.814556 -181.472586) (xy 392.82116 -181.455314) (xy 392.82116 -181.368192) (xy 392.814556 -181.35092)
			(xy 392.808206 -181.343808) (xy 392.789911 -181.322722) (xy 392.759086 -181.27618) (xy 392.735374 -181.225642)
			(xy 392.719281 -181.172188) (xy 392.711152 -181.116958) (xy 392.71067 -181.089046) (xy 392.711156 -181.061795)
			(xy 392.718912 -181.007847) (xy 392.734267 -180.955552) (xy 392.756909 -180.905975) (xy 392.786375 -180.860125)
			(xy 392.822066 -180.818934) (xy 392.863257 -180.783243) (xy 392.909107 -180.753777) (xy 392.958684 -180.731135)
			(xy 393.010979 -180.71578) (xy 393.064927 -180.708024) (xy 393.119429 -180.708024) (xy 393.173377 -180.71578)
			(xy 393.225672 -180.731135) (xy 393.275249 -180.753777) (xy 393.321099 -180.783243) (xy 393.36229 -180.818934)
			(xy 393.397981 -180.860125) (xy 393.427447 -180.905975) (xy 393.450089 -180.955552) (xy 393.465444 -181.007847)
			(xy 393.4732 -181.061795) (xy 393.473686 -181.089046) (xy 393.473202 -181.116957) (xy 393.465062 -181.172182)
			(xy 393.448964 -181.225632) (xy 393.42525 -181.276167) (xy 393.394426 -181.322707) (xy 393.37615 -181.343808)
			(xy 393.3698 -181.35092) (xy 393.363196 -181.368192) (xy 393.363196 -181.455314) (xy 393.3698 -181.472586)
			(xy 393.37615 -181.479698) (xy 393.394409 -181.500813) (xy 393.425238 -181.547348) (xy 393.448956 -181.597879)
			(xy 393.465057 -181.651326) (xy 393.473197 -181.70655) (xy 393.473686 -181.73446) (xy 393.4732 -181.761711)
			(xy 393.465444 -181.815659) (xy 393.450089 -181.867954) (xy 393.427447 -181.917531) (xy 393.397981 -181.963381)
			(xy 393.36229 -182.004572) (xy 393.321099 -182.040263) (xy 393.275249 -182.069729) (xy 393.225672 -182.092371)
			(xy 393.173377 -182.107726) (xy 393.119429 -182.115482) (xy 393.064927 -182.115482) (xy 393.010979 -182.107726)
			(xy 392.958684 -182.092371) (xy 392.909107 -182.069729) (xy 392.863257 -182.040263) (xy 392.822066 -182.004572)
			(xy 392.786375 -181.963381) (xy 392.756909 -181.917531) (xy 392.734267 -181.867954) (xy 392.718912 -181.815659)
			(xy 392.711156 -181.761711) (xy 392.71067 -181.73446) (xy 387.66235 -181.73446) (xy 387.633851 -181.766791)
			(xy 387.613144 -181.785006) (xy 387.605019 -181.792602) (xy 387.595671 -181.812759) (xy 387.59511 -181.823868)
			(xy 387.59511 -181.901084) (xy 387.595668 -181.912195) (xy 387.605013 -181.932354) (xy 387.613144 -181.939946)
			(xy 387.633841 -181.958172) (xy 387.670311 -181.999539) (xy 387.700443 -182.045726) (xy 387.723611 -182.095771)
			(xy 387.739331 -182.14863) (xy 387.747276 -182.203202) (xy 387.747764 -182.230776) (xy 387.747278 -182.258027)
			(xy 387.739522 -182.311975) (xy 387.724167 -182.36427) (xy 387.701525 -182.413847) (xy 387.672059 -182.459697)
			(xy 387.636368 -182.500888) (xy 387.595177 -182.536579) (xy 387.549327 -182.566045) (xy 387.49975 -182.588687)
			(xy 387.447455 -182.604042) (xy 387.393507 -182.611798) (xy 387.339005 -182.611798) (xy 387.285057 -182.604042)
			(xy 387.232762 -182.588687) (xy 387.183185 -182.566045) (xy 387.137335 -182.536579) (xy 387.096144 -182.500888)
			(xy 387.060453 -182.459697) (xy 387.030987 -182.413847) (xy 387.008345 -182.36427) (xy 386.99299 -182.311975)
			(xy 386.985234 -182.258027) (xy 386.984748 -182.230776) (xy 379.416564 -182.230776) (xy 379.416078 -182.258027)
			(xy 379.408322 -182.311975) (xy 379.392967 -182.36427) (xy 379.370325 -182.413847) (xy 379.340859 -182.459697)
			(xy 379.305168 -182.500888) (xy 379.263977 -182.536579) (xy 379.218127 -182.566045) (xy 379.16855 -182.588687)
			(xy 379.116255 -182.604042) (xy 379.062307 -182.611798) (xy 379.007805 -182.611798) (xy 378.953857 -182.604042)
			(xy 378.901562 -182.588687) (xy 378.851985 -182.566045) (xy 378.806135 -182.536579) (xy 378.764944 -182.500888)
			(xy 378.729253 -182.459697) (xy 378.699787 -182.413847) (xy 378.677145 -182.36427) (xy 378.66179 -182.311975)
			(xy 378.654034 -182.258027) (xy 378.653548 -182.230776) (xy 370.900363 -182.230776) (xy 370.887269 -182.27537)
			(xy 370.864627 -182.324947) (xy 370.835161 -182.370797) (xy 370.79947 -182.411988) (xy 370.758279 -182.447679)
			(xy 370.712429 -182.477145) (xy 370.662852 -182.499787) (xy 370.610557 -182.515142) (xy 370.556609 -182.522898)
			(xy 370.502107 -182.522898) (xy 370.448159 -182.515142) (xy 370.395864 -182.499787) (xy 370.346287 -182.477145)
			(xy 370.300437 -182.447679) (xy 370.259246 -182.411988) (xy 370.223555 -182.370797) (xy 370.194089 -182.324947)
			(xy 370.171447 -182.27537) (xy 370.156092 -182.223075) (xy 370.148336 -182.169127) (xy 370.14785 -182.141876)
			(xy 360.161332 -182.141876) (xy 360.161332 -183.93537) (xy 360.161769 -183.945434) (xy 360.169504 -183.964017)
			(xy 360.176318 -183.971438) (xy 361.190794 -184.985914) (xy 361.198188 -184.992771) (xy 361.216787 -185.000521)
			(xy 361.226862 -185.0009) (xy 363.947202 -185.0009) (xy 363.957272 -185.001324) (xy 363.975876 -185.009039)
			(xy 363.98327 -185.015886) (xy 365.914432 -186.947048) (xy 404.034244 -186.947048) (xy 404.034727 -186.919678)
			(xy 404.042539 -186.8655) (xy 404.058024 -186.812996) (xy 404.080862 -186.763249) (xy 404.110584 -186.717282)
			(xy 404.128224 -186.69635) (xy 404.13432 -186.689238) (xy 404.14067 -186.67222) (xy 404.14067 -186.586876)
			(xy 404.13432 -186.569858) (xy 404.128224 -186.562746) (xy 404.11063 -186.541775) (xy 404.080904 -186.495814)
			(xy 404.058056 -186.446074) (xy 404.042556 -186.393578) (xy 404.034723 -186.339404) (xy 404.034718 -186.284668)
			(xy 404.042541 -186.230493) (xy 404.058031 -186.177994) (xy 404.080869 -186.12825) (xy 404.110587 -186.082283)
			(xy 404.128224 -186.06135) (xy 404.13432 -186.054238) (xy 404.14067 -186.03722) (xy 404.14067 -185.951876)
			(xy 404.13432 -185.934858) (xy 404.128224 -185.927746) (xy 404.11063 -185.906775) (xy 404.080904 -185.860814)
			(xy 404.058056 -185.811074) (xy 404.042556 -185.758578) (xy 404.034723 -185.704404) (xy 404.034718 -185.649668)
			(xy 404.042541 -185.595493) (xy 404.058031 -185.542994) (xy 404.080869 -185.49325) (xy 404.110587 -185.447283)
			(xy 404.128224 -185.42635) (xy 404.13432 -185.419238) (xy 404.14067 -185.40222) (xy 404.14067 -185.316876)
			(xy 404.13432 -185.299858) (xy 404.128224 -185.292746) (xy 404.11063 -185.271775) (xy 404.080904 -185.225814)
			(xy 404.058056 -185.176074) (xy 404.042556 -185.123578) (xy 404.034723 -185.069404) (xy 404.034718 -185.014668)
			(xy 404.042541 -184.960493) (xy 404.058031 -184.907994) (xy 404.080869 -184.85825) (xy 404.110587 -184.812283)
			(xy 404.128224 -184.79135) (xy 404.13432 -184.784238) (xy 404.14067 -184.76722) (xy 404.14067 -184.681876)
			(xy 404.13432 -184.664858) (xy 404.128224 -184.657746) (xy 404.11063 -184.636775) (xy 404.080904 -184.590814)
			(xy 404.058056 -184.541074) (xy 404.042556 -184.488578) (xy 404.034723 -184.434404) (xy 404.034718 -184.379668)
			(xy 404.042541 -184.325493) (xy 404.058031 -184.272994) (xy 404.080869 -184.22325) (xy 404.110587 -184.177283)
			(xy 404.128224 -184.15635) (xy 404.13432 -184.149238) (xy 404.14067 -184.13222) (xy 404.14067 -184.046876)
			(xy 404.13432 -184.029858) (xy 404.128224 -184.022746) (xy 404.110597 -184.001804) (xy 404.080882 -183.955835)
			(xy 404.058044 -183.90609) (xy 404.04255 -183.853591) (xy 404.034719 -183.799417) (xy 404.034244 -183.772048)
			(xy 404.034643 -183.746226) (xy 404.041601 -183.695052) (xy 404.055395 -183.645284) (xy 404.075773 -183.597831)
			(xy 404.102365 -183.553559) (xy 404.134683 -183.513276) (xy 404.153116 -183.495188) (xy 404.160482 -183.48833)
			(xy 404.168356 -183.471312) (xy 404.17369 -183.382412) (xy 404.167848 -183.364378) (xy 404.161498 -183.356758)
			(xy 404.144997 -183.336149) (xy 404.117263 -183.291225) (xy 404.095989 -183.242906) (xy 404.081579 -183.192116)
			(xy 404.07431 -183.139824) (xy 404.073868 -183.113426) (xy 404.074333 -183.086056) (xy 404.082148 -183.031876)
			(xy 404.097637 -182.979372) (xy 404.120479 -182.929625) (xy 404.150206 -182.883659) (xy 404.167848 -182.862728)
			(xy 404.173944 -182.855616) (xy 404.180294 -182.838598) (xy 404.180294 -182.753254) (xy 404.173944 -182.736236)
			(xy 404.167848 -182.729124) (xy 404.150232 -182.708171) (xy 404.120504 -182.662207) (xy 404.097656 -182.612464)
			(xy 404.082157 -182.559965) (xy 404.074326 -182.505789) (xy 404.074323 -182.45105) (xy 404.082149 -182.396873)
			(xy 404.097643 -182.344372) (xy 404.120486 -182.294627) (xy 404.150208 -182.24866) (xy 404.167848 -182.227728)
			(xy 404.173944 -182.220616) (xy 404.180294 -182.203598) (xy 404.180294 -182.118254) (xy 404.173944 -182.101236)
			(xy 404.167848 -182.094124) (xy 404.150232 -182.073171) (xy 404.120504 -182.027207) (xy 404.097656 -181.977464)
			(xy 404.082157 -181.924965) (xy 404.074326 -181.870789) (xy 404.074323 -181.81605) (xy 404.082149 -181.761873)
			(xy 404.097643 -181.709372) (xy 404.120486 -181.659627) (xy 404.150208 -181.61366) (xy 404.167848 -181.592728)
			(xy 404.173944 -181.585616) (xy 404.180294 -181.568598) (xy 404.180294 -181.483254) (xy 404.173944 -181.466236)
			(xy 404.167848 -181.459124) (xy 404.150214 -181.438188) (xy 404.1205 -181.392217) (xy 404.097662 -181.34247)
			(xy 404.08217 -181.28997) (xy 404.074342 -181.235795) (xy 404.073868 -181.208426) (xy 404.074379 -181.181175)
			(xy 404.082132 -181.127227) (xy 404.097484 -181.074931) (xy 404.120121 -181.025353) (xy 404.149585 -180.979501)
			(xy 404.185273 -180.938309) (xy 404.226461 -180.902615) (xy 404.272309 -180.873145) (xy 404.321885 -180.850501)
			(xy 404.374178 -180.835143) (xy 404.428125 -180.827383) (xy 404.455376 -180.826918) (xy 404.484853 -180.827468)
			(xy 404.543106 -180.836534) (xy 404.599271 -180.854454) (xy 404.65201 -180.880801) (xy 404.700069 -180.914948)
			(xy 404.721568 -180.935122) (xy 404.728916 -180.941639) (xy 404.747066 -180.949094) (xy 404.756874 -180.9496)
			(xy 404.810214 -180.9496) (xy 404.814278 -180.945028) (xy 404.820692 -180.937574) (xy 404.827887 -180.919294)
			(xy 404.828248 -180.909468) (xy 404.827994 -180.877718) (xy 404.827431 -180.867883) (xy 404.819867 -180.849718)
			(xy 404.813262 -180.842412) (xy 404.792587 -180.820843) (xy 404.757575 -180.772433) (xy 404.73054 -180.719156)
			(xy 404.712144 -180.662314) (xy 404.702839 -180.603298) (xy 404.702264 -180.573426) (xy 404.70275 -180.546175)
			(xy 404.710506 -180.492227) (xy 404.725861 -180.439932) (xy 404.748503 -180.390355) (xy 404.777969 -180.344505)
			(xy 404.81366 -180.303314) (xy 404.854851 -180.267623) (xy 404.900701 -180.238157) (xy 404.950278 -180.215515)
			(xy 405.002573 -180.20016) (xy 405.056521 -180.192404) (xy 405.111023 -180.192404) (xy 405.164971 -180.20016)
			(xy 405.217266 -180.215515) (xy 405.266843 -180.238157) (xy 405.312693 -180.267623) (xy 405.353884 -180.303314)
			(xy 405.389575 -180.344505) (xy 405.419041 -180.390355) (xy 405.441683 -180.439932) (xy 405.457038 -180.492227)
			(xy 405.464794 -180.546175) (xy 405.46528 -180.573426) (xy 405.464827 -180.600396) (xy 405.457217 -180.653797)
			(xy 405.442154 -180.705592) (xy 405.419938 -180.754745) (xy 405.391013 -180.800274) (xy 405.37384 -180.821076)
			(xy 405.367744 -180.828188) (xy 405.361648 -180.845206) (xy 405.36241 -180.930804) (xy 405.369014 -180.947568)
			(xy 405.375364 -180.95468) (xy 405.393471 -180.975739) (xy 405.423972 -181.022152) (xy 405.447429 -181.072495)
			(xy 405.463345 -181.125703) (xy 405.471387 -181.180657) (xy 405.471884 -181.208426) (xy 405.471437 -181.235797)
			(xy 405.463615 -181.289977) (xy 405.448122 -181.342481) (xy 405.425276 -181.392227) (xy 405.395547 -181.438193)
			(xy 405.377904 -181.459124) (xy 405.371808 -181.466236) (xy 405.365458 -181.483254) (xy 405.365458 -181.568598)
			(xy 405.371808 -181.585616) (xy 405.377904 -181.592728) (xy 405.395569 -181.613641) (xy 405.42529 -181.659613)
			(xy 405.448132 -181.709363) (xy 405.463625 -181.761867) (xy 405.471451 -181.816048) (xy 405.471448 -181.870791)
			(xy 405.463617 -181.924971) (xy 405.448118 -181.977474) (xy 405.425271 -182.027222) (xy 405.395545 -182.073191)
			(xy 405.377904 -182.094124) (xy 405.371808 -182.101236) (xy 405.365458 -182.118254) (xy 405.365458 -182.203598)
			(xy 405.371808 -182.220616) (xy 405.377904 -182.227728) (xy 405.395569 -182.248641) (xy 405.42529 -182.294613)
			(xy 405.448132 -182.344363) (xy 405.463625 -182.396867) (xy 405.471451 -182.451048) (xy 405.471448 -182.505791)
			(xy 405.463617 -182.559971) (xy 405.448118 -182.612474) (xy 405.425271 -182.662222) (xy 405.395545 -182.708191)
			(xy 405.377904 -182.729124) (xy 405.371808 -182.736236) (xy 405.365458 -182.753254) (xy 405.365458 -182.838598)
			(xy 405.371808 -182.855616) (xy 405.377904 -182.862728) (xy 405.395523 -182.883676) (xy 405.425238 -182.929644)
			(xy 405.448078 -182.979388) (xy 405.463573 -183.031885) (xy 405.471407 -183.086058) (xy 405.471884 -183.113426)
			(xy 405.47149 -183.139249) (xy 405.464535 -183.190423) (xy 405.450741 -183.240192) (xy 405.430361 -183.287646)
			(xy 405.403768 -183.331918) (xy 405.371447 -183.372199) (xy 405.353012 -183.390286) (xy 405.345646 -183.397144)
			(xy 405.337772 -183.414162) (xy 405.332438 -183.503062) (xy 405.33828 -183.521096) (xy 405.34463 -183.528716)
			(xy 405.361123 -183.549331) (xy 405.388857 -183.594254) (xy 405.410133 -183.642571) (xy 405.424544 -183.69336)
			(xy 405.431816 -183.745651) (xy 405.43226 -183.772048) (xy 405.431773 -183.799418) (xy 405.423962 -183.853596)
			(xy 405.408478 -183.906099) (xy 405.385641 -183.955847) (xy 405.35592 -184.001814) (xy 405.33828 -184.022746)
			(xy 405.332184 -184.029858) (xy 405.325834 -184.046876) (xy 405.325834 -184.13222) (xy 405.332184 -184.149238)
			(xy 405.33828 -184.15635) (xy 405.355967 -184.177245) (xy 405.38569 -184.223219) (xy 405.408532 -184.272972)
			(xy 405.424024 -184.32548) (xy 405.431848 -184.379663) (xy 405.431843 -184.434409) (xy 405.424009 -184.488591)
			(xy 405.408506 -184.541096) (xy 405.385655 -184.590844) (xy 405.355924 -184.636813) (xy 405.33828 -184.657746)
			(xy 405.332184 -184.664858) (xy 405.325834 -184.681876) (xy 405.325834 -184.76722) (xy 405.332184 -184.784238)
			(xy 405.33828 -184.79135) (xy 405.355967 -184.812245) (xy 405.38569 -184.858219) (xy 405.408532 -184.907972)
			(xy 405.424024 -184.96048) (xy 405.431848 -185.014663) (xy 405.431845 -185.042048) (xy 407.445464 -185.042048)
			(xy 407.445943 -185.014678) (xy 407.453755 -184.960499) (xy 407.46924 -184.907995) (xy 407.49208 -184.858248)
			(xy 407.521803 -184.812281) (xy 407.539444 -184.79135) (xy 407.54554 -184.784238) (xy 407.55189 -184.76722)
			(xy 407.55189 -184.681876) (xy 407.54554 -184.664858) (xy 407.539444 -184.657746) (xy 407.52185 -184.636776)
			(xy 407.492122 -184.590815) (xy 407.469272 -184.541075) (xy 407.453772 -184.488578) (xy 407.445938 -184.434405)
			(xy 407.445933 -184.379668) (xy 407.453756 -184.325492) (xy 407.469247 -184.272993) (xy 407.492087 -184.223249)
			(xy 407.521806 -184.177282) (xy 407.539444 -184.15635) (xy 407.54554 -184.149238) (xy 407.55189 -184.13222)
			(xy 407.55189 -184.046876) (xy 407.54554 -184.029858) (xy 407.539444 -184.022746) (xy 407.52182 -184.001802)
			(xy 407.492104 -183.955833) (xy 407.469265 -183.906089) (xy 407.45377 -183.85359) (xy 407.445939 -183.799416)
			(xy 407.445464 -183.772048) (xy 407.446035 -183.743037) (xy 407.454796 -183.685682) (xy 407.472139 -183.630313)
			(xy 407.497665 -183.578209) (xy 407.530784 -183.530569) (xy 407.550366 -183.509158) (xy 407.557224 -183.502046)
			(xy 407.564336 -183.48452) (xy 407.565352 -183.39562) (xy 407.558494 -183.37784) (xy 407.55189 -183.370728)
			(xy 407.533224 -183.349514) (xy 407.501686 -183.30263) (xy 407.477407 -183.251608) (xy 407.460918 -183.197564)
			(xy 407.452581 -183.141678) (xy 407.452068 -183.113426) (xy 407.452533 -183.086056) (xy 407.460348 -183.031876)
			(xy 407.475837 -182.979372) (xy 407.498679 -182.929625) (xy 407.528406 -182.883659) (xy 407.546048 -182.862728)
			(xy 407.552144 -182.855616) (xy 407.558494 -182.838598) (xy 407.558494 -182.753254) (xy 407.552144 -182.736236)
			(xy 407.546048 -182.729124) (xy 407.528432 -182.708171) (xy 407.498704 -182.662207) (xy 407.475856 -182.612464)
			(xy 407.460357 -182.559965) (xy 407.452526 -182.505789) (xy 407.452523 -182.45105) (xy 407.460349 -182.396873)
			(xy 407.475843 -182.344372) (xy 407.498686 -182.294627) (xy 407.528408 -182.24866) (xy 407.546048 -182.227728)
			(xy 407.552144 -182.220616) (xy 407.558494 -182.203598) (xy 407.558494 -182.118254) (xy 407.552144 -182.101236)
			(xy 407.546048 -182.094124) (xy 407.528432 -182.073171) (xy 407.498704 -182.027207) (xy 407.475856 -181.977464)
			(xy 407.460357 -181.924965) (xy 407.452526 -181.870789) (xy 407.452523 -181.81605) (xy 407.460349 -181.761873)
			(xy 407.475843 -181.709372) (xy 407.498686 -181.659627) (xy 407.528408 -181.61366) (xy 407.546048 -181.592728)
			(xy 407.552144 -181.585616) (xy 407.558494 -181.568598) (xy 407.558494 -181.483254) (xy 407.552144 -181.466236)
			(xy 407.546048 -181.459124) (xy 407.528414 -181.438188) (xy 407.4987 -181.392217) (xy 407.475862 -181.34247)
			(xy 407.46037 -181.28997) (xy 407.452542 -181.235795) (xy 407.452068 -181.208426) (xy 407.452518 -181.181291)
			(xy 407.460212 -181.127569) (xy 407.475448 -181.075482) (xy 407.497918 -181.026083) (xy 407.527168 -180.98037)
			(xy 407.544524 -180.959506) (xy 407.55062 -180.952394) (xy 407.556716 -180.935376) (xy 407.556208 -180.850032)
			(xy 407.549858 -180.833014) (xy 407.543508 -180.825902) (xy 407.52563 -180.804865) (xy 407.495432 -180.758651)
			(xy 407.472213 -180.708566) (xy 407.456458 -180.655657) (xy 407.448495 -180.601029) (xy 407.448004 -180.573426)
			(xy 407.44848 -180.546173) (xy 407.456233 -180.492222) (xy 407.471587 -180.439924) (xy 407.494227 -180.390343)
			(xy 407.523693 -180.344489) (xy 407.559386 -180.303296) (xy 407.600578 -180.267602) (xy 407.646431 -180.238134)
			(xy 407.696011 -180.215492) (xy 407.748308 -180.200136) (xy 407.802259 -180.192381) (xy 407.829512 -180.191918)
			(xy 407.856883 -180.192373) (xy 407.911062 -180.200193) (xy 407.963566 -180.215684) (xy 408.013313 -180.238528)
			(xy 408.059279 -180.268256) (xy 408.08021 -180.285898) (xy 408.087322 -180.291994) (xy 408.10434 -180.298344)
			(xy 408.189684 -180.298344) (xy 408.206702 -180.291994) (xy 408.213814 -180.285898) (xy 408.234747 -180.268257)
			(xy 408.280715 -180.238533) (xy 408.330461 -180.215687) (xy 408.382963 -180.200191) (xy 408.437141 -180.192362)
			(xy 408.491883 -180.192362) (xy 408.546061 -180.200191) (xy 408.598563 -180.215687) (xy 408.648309 -180.238533)
			(xy 408.694277 -180.268257) (xy 408.71521 -180.285898) (xy 408.722322 -180.291994) (xy 408.73934 -180.298344)
			(xy 408.824684 -180.298344) (xy 408.841702 -180.291994) (xy 408.848814 -180.285898) (xy 408.869767 -180.268285)
			(xy 408.915734 -180.23857) (xy 408.965476 -180.215729) (xy 409.017972 -180.200231) (xy 409.072144 -180.192396)
			(xy 409.099512 -180.191918) (xy 409.126766 -180.192344) (xy 409.18072 -180.200103) (xy 409.23302 -180.215462)
			(xy 409.282602 -180.238108) (xy 409.328457 -180.267579) (xy 409.36965 -180.303277) (xy 409.405343 -180.344474)
			(xy 409.43481 -180.390331) (xy 409.457451 -180.439915) (xy 409.472805 -180.492217) (xy 409.480559 -180.546172)
			(xy 409.48102 -180.573426) (xy 409.480529 -180.600759) (xy 409.472725 -180.654865) (xy 409.45728 -180.707303)
			(xy 409.43451 -180.757001) (xy 409.404881 -180.802942) (xy 409.387294 -180.82387) (xy 409.38069 -180.831236)
			(xy 409.374594 -180.84927) (xy 409.374655 -180.851048) (xy 412.39821 -180.851048) (xy 412.398702 -180.823679)
			(xy 412.406513 -180.769501) (xy 412.421996 -180.716998) (xy 412.444832 -180.66725) (xy 412.474551 -180.621282)
			(xy 412.49219 -180.60035) (xy 412.498286 -180.593238) (xy 412.504636 -180.57622) (xy 412.504636 -180.490876)
			(xy 412.498286 -180.473858) (xy 412.49219 -180.466746) (xy 412.474598 -180.445774) (xy 412.444874 -180.399812)
			(xy 412.422028 -180.350072) (xy 412.40653 -180.297577) (xy 412.398697 -180.243404) (xy 412.398692 -180.188668)
			(xy 412.406514 -180.134494) (xy 412.422003 -180.081995) (xy 412.444839 -180.032251) (xy 412.474554 -179.986283)
			(xy 412.49219 -179.96535) (xy 412.498286 -179.958238) (xy 412.504636 -179.94122) (xy 412.504636 -179.855876)
			(xy 412.498286 -179.838858) (xy 412.49219 -179.831746) (xy 412.474598 -179.810774) (xy 412.444874 -179.764812)
			(xy 412.422028 -179.715072) (xy 412.40653 -179.662577) (xy 412.398697 -179.608404) (xy 412.398692 -179.553668)
			(xy 412.406514 -179.499494) (xy 412.422003 -179.446995) (xy 412.444839 -179.397251) (xy 412.474554 -179.351283)
			(xy 412.49219 -179.33035) (xy 412.498286 -179.323238) (xy 412.504636 -179.30622) (xy 412.504636 -179.220876)
			(xy 412.498286 -179.203858) (xy 412.49219 -179.196746) (xy 412.474557 -179.175809) (xy 412.444845 -179.129837)
			(xy 412.422008 -179.080091) (xy 412.406515 -179.027592) (xy 412.398685 -178.973417) (xy 412.39821 -178.946048)
			(xy 412.398768 -178.917037) (xy 412.407531 -178.85968) (xy 412.424876 -178.804311) (xy 412.450405 -178.752207)
			(xy 412.483528 -178.704568) (xy 412.503112 -178.683158) (xy 412.50997 -178.676046) (xy 412.517082 -178.65852)
			(xy 412.518098 -178.56962) (xy 412.51124 -178.55184) (xy 412.504636 -178.544728) (xy 412.485962 -178.523521)
			(xy 412.454426 -178.476635) (xy 412.43015 -178.425611) (xy 412.413663 -178.371565) (xy 412.405327 -178.315678)
			(xy 412.404814 -178.287426) (xy 412.405292 -178.260056) (xy 412.413106 -178.205877) (xy 412.428592 -178.153374)
			(xy 412.451432 -178.103627) (xy 412.481154 -178.05766) (xy 412.498794 -178.036728) (xy 412.50489 -178.029616)
			(xy 412.51124 -178.012598) (xy 412.51124 -177.927254) (xy 412.50489 -177.910236) (xy 412.498794 -177.903124)
			(xy 412.48118 -177.88217) (xy 412.451457 -177.836205) (xy 412.428612 -177.786462) (xy 412.413115 -177.733964)
			(xy 412.405285 -177.679789) (xy 412.405282 -177.625051) (xy 412.413107 -177.570875) (xy 412.428598 -177.518375)
			(xy 412.451438 -177.468629) (xy 412.481157 -177.422661) (xy 412.498794 -177.401728) (xy 412.50489 -177.394616)
			(xy 412.51124 -177.377598) (xy 412.51124 -177.292254) (xy 412.50489 -177.275236) (xy 412.498794 -177.268124)
			(xy 412.48118 -177.24717) (xy 412.451457 -177.201205) (xy 412.428612 -177.151462) (xy 412.413115 -177.098964)
			(xy 412.405285 -177.044789) (xy 412.405282 -176.990051) (xy 412.413107 -176.935875) (xy 412.428598 -176.883375)
			(xy 412.451438 -176.833629) (xy 412.481157 -176.787661) (xy 412.498794 -176.766728) (xy 412.50489 -176.759616)
			(xy 412.51124 -176.742598) (xy 412.51124 -176.657254) (xy 412.50489 -176.640236) (xy 412.498794 -176.633124)
			(xy 412.481152 -176.612194) (xy 412.451441 -176.566221) (xy 412.428605 -176.516473) (xy 412.413115 -176.463972)
			(xy 412.405288 -176.409795) (xy 412.404814 -176.382426) (xy 412.405298 -176.355457) (xy 412.412901 -176.302057)
			(xy 412.427957 -176.250263) (xy 412.450166 -176.20111) (xy 412.479085 -176.155579) (xy 412.496254 -176.134776)
			(xy 412.50235 -176.127664) (xy 412.508446 -176.110646) (xy 412.507684 -176.025048) (xy 412.50108 -176.008284)
			(xy 412.49473 -176.001172) (xy 412.476663 -175.98008) (xy 412.446152 -175.933677) (xy 412.422686 -175.883344)
			(xy 412.406761 -175.830142) (xy 412.398711 -175.775193) (xy 412.39821 -175.747426) (xy 412.39868 -175.720173)
			(xy 412.406433 -175.666221) (xy 412.421787 -175.613922) (xy 412.444428 -175.564341) (xy 412.473895 -175.518487)
			(xy 412.509588 -175.477294) (xy 412.550781 -175.4416) (xy 412.596634 -175.412132) (xy 412.646215 -175.38949)
			(xy 412.698514 -175.374135) (xy 412.752465 -175.36638) (xy 412.779718 -175.365918) (xy 412.807089 -175.366369)
			(xy 412.861269 -175.37419) (xy 412.913772 -175.389682) (xy 412.963519 -175.412527) (xy 413.009485 -175.442255)
			(xy 413.030416 -175.459898) (xy 413.037528 -175.465994) (xy 413.054546 -175.472344) (xy 413.13989 -175.472344)
			(xy 413.156908 -175.465994) (xy 413.16402 -175.459898) (xy 413.184971 -175.442283) (xy 413.230939 -175.412567)
			(xy 413.280681 -175.389727) (xy 413.333178 -175.37423) (xy 413.38735 -175.366396) (xy 413.414718 -175.365918)
			(xy 413.441973 -175.366338) (xy 413.495926 -175.374098) (xy 413.548227 -175.389458) (xy 413.597809 -175.412104)
			(xy 413.643663 -175.441577) (xy 413.684856 -175.477275) (xy 413.72055 -175.518472) (xy 413.750017 -175.56433)
			(xy 413.772657 -175.613915) (xy 413.788011 -175.666217) (xy 413.795765 -175.720171) (xy 413.796226 -175.747426)
			(xy 413.795786 -175.774397) (xy 413.788175 -175.827799) (xy 413.773109 -175.879594) (xy 413.75089 -175.928747)
			(xy 413.721961 -175.974275) (xy 413.704786 -175.995076) (xy 413.69869 -176.002188) (xy 413.692594 -176.019206)
			(xy 413.693356 -176.104804) (xy 413.69996 -176.121568) (xy 413.70631 -176.12868) (xy 413.724408 -176.149746)
			(xy 413.754913 -176.196157) (xy 413.778372 -176.246497) (xy 413.79429 -176.299705) (xy 413.802333 -176.354657)
			(xy 413.80283 -176.382426) (xy 413.802396 -176.409798) (xy 413.794573 -176.463979) (xy 413.779078 -176.516483)
			(xy 413.756228 -176.566229) (xy 413.726495 -176.612194) (xy 413.70885 -176.633124) (xy 413.702754 -176.640236)
			(xy 413.696404 -176.657254) (xy 413.696404 -176.742598) (xy 413.702754 -176.759616) (xy 413.70885 -176.766728)
			(xy 413.726517 -176.78764) (xy 413.756243 -176.833611) (xy 413.779088 -176.88336) (xy 413.794583 -176.935866)
			(xy 413.80241 -176.990047) (xy 413.802407 -177.044792) (xy 413.794575 -177.098973) (xy 413.779074 -177.151477)
			(xy 413.756224 -177.201224) (xy 413.726493 -177.247192) (xy 413.70885 -177.268124) (xy 413.702754 -177.275236)
			(xy 413.696404 -177.292254) (xy 413.696404 -177.377598) (xy 413.702754 -177.394616) (xy 413.70885 -177.401728)
			(xy 413.726517 -177.42264) (xy 413.756243 -177.468611) (xy 413.779088 -177.51836) (xy 413.794583 -177.570866)
			(xy 413.80241 -177.625047) (xy 413.802407 -177.679792) (xy 413.794575 -177.733973) (xy 413.779074 -177.786477)
			(xy 413.756224 -177.836224) (xy 413.726493 -177.882192) (xy 413.70885 -177.903124) (xy 413.702754 -177.910236)
			(xy 413.696404 -177.927254) (xy 413.696404 -178.012598) (xy 413.702754 -178.029616) (xy 413.70885 -178.036728)
			(xy 413.726461 -178.057683) (xy 413.756179 -178.103649) (xy 413.779021 -178.15339) (xy 413.794518 -178.205886)
			(xy 413.802353 -178.260058) (xy 413.80283 -178.287426) (xy 413.802306 -178.316438) (xy 413.793534 -178.373796)
			(xy 413.77618 -178.429165) (xy 413.750644 -178.481269) (xy 413.717515 -178.528906) (xy 413.697928 -178.550316)
			(xy 413.69107 -178.557428) (xy 413.683958 -178.574954) (xy 413.682942 -178.663854) (xy 413.6898 -178.681634)
			(xy 413.696404 -178.688746) (xy 413.715056 -178.709972) (xy 413.746597 -178.756852) (xy 413.770879 -178.807871)
			(xy 413.78737 -178.861913) (xy 413.795711 -178.917797) (xy 413.796226 -178.946048) (xy 413.795747 -178.973418)
			(xy 413.787935 -179.027597) (xy 413.77245 -179.080101) (xy 413.749611 -179.129848) (xy 413.719887 -179.175815)
			(xy 413.702246 -179.196746) (xy 413.69615 -179.203858) (xy 413.6898 -179.220876) (xy 413.6898 -179.30622)
			(xy 413.69615 -179.323238) (xy 413.702246 -179.33035) (xy 413.719935 -179.351244) (xy 413.74966 -179.397218)
			(xy 413.772504 -179.44697) (xy 413.787998 -179.499479) (xy 413.795822 -179.553663) (xy 413.795817 -179.608409)
			(xy 413.787982 -179.662592) (xy 413.772479 -179.715097) (xy 413.749625 -179.764846) (xy 413.719891 -179.810814)
			(xy 413.702246 -179.831746) (xy 413.69615 -179.838858) (xy 413.6898 -179.855876) (xy 413.6898 -179.94122)
			(xy 413.69615 -179.958238) (xy 413.702246 -179.96535) (xy 413.719935 -179.986244) (xy 413.74966 -180.032218)
			(xy 413.772504 -180.08197) (xy 413.787998 -180.134479) (xy 413.795822 -180.188663) (xy 413.795817 -180.243409)
			(xy 413.787982 -180.297592) (xy 413.772479 -180.350097) (xy 413.749625 -180.399846) (xy 413.719891 -180.445814)
			(xy 413.702246 -180.466746) (xy 413.69615 -180.473858) (xy 413.6898 -180.490876) (xy 413.6898 -180.57622)
			(xy 413.69615 -180.593238) (xy 413.702246 -180.60035) (xy 413.719867 -180.621297) (xy 413.749583 -180.667265)
			(xy 413.772424 -180.717008) (xy 413.787919 -180.769506) (xy 413.79575 -180.82368) (xy 413.796049 -180.840888)
			(xy 415.76625 -180.840888) (xy 415.766697 -180.813517) (xy 415.774517 -180.759337) (xy 415.79001 -180.706833)
			(xy 415.812857 -180.657086) (xy 415.842586 -180.611121) (xy 415.86023 -180.59019) (xy 415.866326 -180.583078)
			(xy 415.872676 -180.56606) (xy 415.872676 -180.480716) (xy 415.866326 -180.463698) (xy 415.86023 -180.456586)
			(xy 415.842577 -180.435663) (xy 415.812853 -180.389693) (xy 415.790008 -180.339946) (xy 415.774513 -180.287442)
			(xy 415.766685 -180.233262) (xy 415.766686 -180.17852) (xy 415.774516 -180.12434) (xy 415.790014 -180.071837)
			(xy 415.812862 -180.022091) (xy 415.842588 -179.976123) (xy 415.86023 -179.95519) (xy 415.866326 -179.948078)
			(xy 415.872676 -179.93106) (xy 415.872676 -179.845716) (xy 415.866326 -179.828698) (xy 415.86023 -179.821586)
			(xy 415.842577 -179.800663) (xy 415.812853 -179.754693) (xy 415.790008 -179.704946) (xy 415.774513 -179.652442)
			(xy 415.766685 -179.598262) (xy 415.766686 -179.54352) (xy 415.774516 -179.48934) (xy 415.790014 -179.436837)
			(xy 415.812862 -179.387091) (xy 415.842588 -179.341123) (xy 415.86023 -179.32019) (xy 415.866326 -179.313078)
			(xy 415.872676 -179.29606) (xy 415.872676 -179.210716) (xy 415.866326 -179.193698) (xy 415.86023 -179.186586)
			(xy 415.842622 -179.165628) (xy 415.812905 -179.119663) (xy 415.790062 -179.069922) (xy 415.774564 -179.017427)
			(xy 415.766728 -178.963256) (xy 415.76625 -178.935888) (xy 415.766777 -178.906805) (xy 415.775602 -178.849312)
			(xy 415.793047 -178.793823) (xy 415.818707 -178.741622) (xy 415.851989 -178.693918) (xy 415.87166 -178.67249)
			(xy 415.878518 -178.665632) (xy 415.88563 -178.64836) (xy 415.887662 -178.560984) (xy 415.881566 -178.543458)
			(xy 415.875216 -178.536092) (xy 415.857881 -178.515257) (xy 415.828724 -178.469568) (xy 415.806329 -178.420211)
			(xy 415.791147 -178.368181) (xy 415.783485 -178.314526) (xy 415.783014 -178.287426) (xy 415.783492 -178.260056)
			(xy 415.791306 -178.205877) (xy 415.806792 -178.153374) (xy 415.829632 -178.103627) (xy 415.859354 -178.05766)
			(xy 415.876994 -178.036728) (xy 415.88309 -178.029616) (xy 415.88944 -178.012598) (xy 415.88944 -177.927254)
			(xy 415.88309 -177.910236) (xy 415.876994 -177.903124) (xy 415.85938 -177.88217) (xy 415.829657 -177.836205)
			(xy 415.806812 -177.786462) (xy 415.791315 -177.733964) (xy 415.783485 -177.679789) (xy 415.783482 -177.625051)
			(xy 415.791307 -177.570875) (xy 415.806798 -177.518375) (xy 415.829638 -177.468629) (xy 415.859357 -177.422661)
			(xy 415.876994 -177.401728) (xy 415.88309 -177.394616) (xy 415.88944 -177.377598) (xy 415.88944 -177.292254)
			(xy 415.88309 -177.275236) (xy 415.876994 -177.268124) (xy 415.85938 -177.24717) (xy 415.829657 -177.201205)
			(xy 415.806812 -177.151462) (xy 415.791315 -177.098964) (xy 415.783485 -177.044789) (xy 415.783482 -176.990051)
			(xy 415.791307 -176.935875) (xy 415.806798 -176.883375) (xy 415.829638 -176.833629) (xy 415.859357 -176.787661)
			(xy 415.876994 -176.766728) (xy 415.88309 -176.759616) (xy 415.88944 -176.742598) (xy 415.88944 -176.657254)
			(xy 415.88309 -176.640236) (xy 415.876994 -176.633124) (xy 415.859352 -176.612194) (xy 415.829641 -176.566221)
			(xy 415.806805 -176.516473) (xy 415.791315 -176.463972) (xy 415.783488 -176.409795) (xy 415.783014 -176.382426)
			(xy 415.783477 -176.355292) (xy 415.79117 -176.301571) (xy 415.806404 -176.249484) (xy 415.82887 -176.200085)
			(xy 415.858116 -176.154371) (xy 415.87547 -176.133506) (xy 415.881566 -176.126394) (xy 415.887662 -176.109376)
			(xy 415.887154 -176.024032) (xy 415.880804 -176.007014) (xy 415.874454 -175.999902) (xy 415.856568 -175.978872)
			(xy 415.826373 -175.932655) (xy 415.803156 -175.882568) (xy 415.787403 -175.829658) (xy 415.779441 -175.775029)
			(xy 415.77895 -175.747426) (xy 415.779502 -175.720177) (xy 415.787254 -175.666234) (xy 415.802604 -175.613943)
			(xy 415.825239 -175.564369) (xy 415.854699 -175.518521) (xy 415.890383 -175.477331) (xy 415.931566 -175.441639)
			(xy 415.977409 -175.412172) (xy 416.02698 -175.389528) (xy 416.079268 -175.374169) (xy 416.133209 -175.366407)
			(xy 416.160458 -175.365918) (xy 416.187828 -175.366404) (xy 416.242006 -175.374217) (xy 416.294509 -175.389701)
			(xy 416.344256 -175.412538) (xy 416.390224 -175.442259) (xy 416.411156 -175.459898) (xy 416.418268 -175.465994)
			(xy 416.435286 -175.472344) (xy 416.52063 -175.472344) (xy 416.537648 -175.465994) (xy 416.54476 -175.459898)
			(xy 416.565693 -175.442257) (xy 416.611661 -175.412533) (xy 416.661407 -175.389687) (xy 416.713909 -175.374191)
			(xy 416.768087 -175.366362) (xy 416.822829 -175.366362) (xy 416.877007 -175.374191) (xy 416.929509 -175.389687)
			(xy 416.979255 -175.412533) (xy 417.025223 -175.442257) (xy 417.046156 -175.459898) (xy 417.053268 -175.465994)
			(xy 417.070286 -175.472344) (xy 417.15563 -175.472344) (xy 417.172648 -175.465994) (xy 417.17976 -175.459898)
			(xy 417.200696 -175.442264) (xy 417.246668 -175.412551) (xy 417.296414 -175.389715) (xy 417.348914 -175.374222)
			(xy 417.403089 -175.366393) (xy 417.430458 -175.365918) (xy 417.457711 -175.366394) (xy 417.511663 -175.374146)
			(xy 417.563962 -175.389498) (xy 417.613544 -175.412138) (xy 417.659398 -175.441604) (xy 417.700592 -175.477297)
			(xy 417.736286 -175.518489) (xy 417.765754 -175.564342) (xy 417.788396 -175.613923) (xy 417.80375 -175.666222)
			(xy 417.811504 -175.720173) (xy 417.811966 -175.747426) (xy 417.811488 -175.77476) (xy 417.803683 -175.828867)
			(xy 417.788235 -175.881306) (xy 417.765462 -175.931004) (xy 417.735829 -175.976943) (xy 417.71824 -175.99787)
			(xy 417.711636 -176.005236) (xy 417.70554 -176.02327) (xy 417.708588 -176.11217) (xy 417.715954 -176.129442)
			(xy 417.723066 -176.136554) (xy 417.74386 -176.158159) (xy 417.779117 -176.206658) (xy 417.806349 -176.260077)
			(xy 417.824885 -176.317101) (xy 417.834268 -176.376322) (xy 417.834826 -176.406302) (xy 417.834379 -176.433673)
			(xy 417.826559 -176.487854) (xy 417.811067 -176.540358) (xy 417.78822 -176.590104) (xy 417.75849 -176.63607)
			(xy 417.740846 -176.657) (xy 417.73475 -176.664112) (xy 417.7284 -176.68113) (xy 417.7284 -176.766474)
			(xy 417.73475 -176.783492) (xy 417.740846 -176.790604) (xy 417.75849 -176.811535) (xy 417.788217 -176.857502)
			(xy 417.789456 -176.8602) (xy 421.86225 -176.8602) (xy 421.862749 -176.831282) (xy 421.87148 -176.774109)
			(xy 421.88874 -176.718909) (xy 421.914135 -176.666947) (xy 421.947083 -176.619414) (xy 421.986828 -176.577399)
			(xy 422.009316 -176.55921) (xy 422.018072 -176.551642) (xy 422.028258 -176.530888) (xy 422.028874 -176.519332)
			(xy 422.028874 -176.439068) (xy 422.028274 -176.427504) (xy 422.018101 -176.406732) (xy 422.009316 -176.39919)
			(xy 421.986831 -176.381001) (xy 421.947095 -176.338981) (xy 421.914156 -176.291446) (xy 421.888768 -176.239484)
			(xy 421.871512 -176.184286) (xy 421.862784 -176.127116) (xy 421.86225 -176.0982) (xy 421.862736 -176.070949)
			(xy 421.870492 -176.017001) (xy 421.885847 -175.964706) (xy 421.908489 -175.915129) (xy 421.937955 -175.869279)
			(xy 421.973646 -175.828088) (xy 422.014837 -175.792397) (xy 422.060687 -175.762931) (xy 422.110264 -175.740289)
			(xy 422.162559 -175.724934) (xy 422.216507 -175.717178) (xy 422.271009 -175.717178) (xy 422.324957 -175.724934)
			(xy 422.377252 -175.740289) (xy 422.426829 -175.762931) (xy 422.472679 -175.792397) (xy 422.51387 -175.828088)
			(xy 422.549561 -175.869279) (xy 422.579027 -175.915129) (xy 422.601669 -175.964706) (xy 422.617024 -176.017001)
			(xy 422.62478 -176.070949) (xy 422.625266 -176.0982) (xy 422.62476 -176.127118) (xy 422.616031 -176.18429)
			(xy 422.598771 -176.23949) (xy 422.573377 -176.291451) (xy 422.540431 -176.338985) (xy 422.500687 -176.381001)
			(xy 422.4782 -176.39919) (xy 422.469447 -176.406761) (xy 422.459259 -176.427513) (xy 422.458642 -176.439068)
			(xy 422.458642 -176.519332) (xy 422.459237 -176.530897) (xy 422.469413 -176.551669) (xy 422.4782 -176.55921)
			(xy 422.500688 -176.577395) (xy 422.540423 -176.619416) (xy 422.573362 -176.666952) (xy 422.598749 -176.718915)
			(xy 422.616004 -176.774113) (xy 422.624732 -176.831284) (xy 422.625266 -176.8602) (xy 422.62478 -176.887451)
			(xy 422.617024 -176.941399) (xy 422.601669 -176.993694) (xy 422.579027 -177.043271) (xy 422.549561 -177.089121)
			(xy 422.51387 -177.130312) (xy 422.472679 -177.166003) (xy 422.426829 -177.195469) (xy 422.377252 -177.218111)
			(xy 422.324957 -177.233466) (xy 422.271009 -177.241222) (xy 422.216507 -177.241222) (xy 422.162559 -177.233466)
			(xy 422.110264 -177.218111) (xy 422.060687 -177.195469) (xy 422.014837 -177.166003) (xy 421.973646 -177.130312)
			(xy 421.937955 -177.089121) (xy 421.908489 -177.043271) (xy 421.885847 -176.993694) (xy 421.870492 -176.941399)
			(xy 421.862736 -176.887451) (xy 421.86225 -176.8602) (xy 417.789456 -176.8602) (xy 417.811063 -176.907249)
			(xy 417.826561 -176.959751) (xy 417.83439 -177.01393) (xy 417.83439 -177.068673) (xy 417.82656 -177.122852)
			(xy 417.811062 -177.175354) (xy 417.788215 -177.225101) (xy 417.758488 -177.271068) (xy 417.740846 -177.292)
			(xy 417.73475 -177.299112) (xy 417.7284 -177.31613) (xy 417.7284 -177.401474) (xy 417.73475 -177.418492)
			(xy 417.740846 -177.425604) (xy 417.75849 -177.446535) (xy 417.788217 -177.492502) (xy 417.811063 -177.542249)
			(xy 417.826561 -177.594751) (xy 417.83439 -177.64893) (xy 417.83439 -177.703673) (xy 417.82656 -177.757852)
			(xy 417.811062 -177.810354) (xy 417.788215 -177.860101) (xy 417.758488 -177.906068) (xy 417.740846 -177.927)
			(xy 417.73475 -177.934112) (xy 417.7284 -177.95113) (xy 417.7284 -178.036474) (xy 417.73475 -178.053492)
			(xy 417.740846 -178.060604) (xy 417.758492 -178.081531) (xy 417.788205 -178.127504) (xy 417.81104 -178.177253)
			(xy 417.826529 -178.229755) (xy 417.834354 -178.283932) (xy 417.834826 -178.311302) (xy 417.834273 -178.340815)
			(xy 417.825182 -178.399136) (xy 417.807217 -178.455361) (xy 417.780808 -178.508149) (xy 417.746584 -178.55624)
			(xy 417.726368 -178.577748) (xy 417.719764 -178.584606) (xy 417.712398 -178.601116) (xy 417.707572 -178.68646)
			(xy 417.71316 -178.703732) (xy 417.718748 -178.711098) (xy 417.73393 -178.731286) (xy 417.759435 -178.774884)
			(xy 417.778966 -178.821465) (xy 417.792183 -178.870216) (xy 417.798853 -178.920285) (xy 417.799266 -178.94554)
			(xy 417.798773 -178.972909) (xy 417.790963 -179.027088) (xy 417.775481 -179.079591) (xy 417.752645 -179.129338)
			(xy 417.722925 -179.175306) (xy 417.705286 -179.196238) (xy 417.69919 -179.20335) (xy 417.69284 -179.220368)
			(xy 417.69284 -179.305712) (xy 417.69919 -179.32273) (xy 417.705286 -179.329842) (xy 417.722965 -179.350743)
			(xy 417.752688 -179.396717) (xy 417.77553 -179.446468) (xy 417.791022 -179.498975) (xy 417.798847 -179.553158)
			(xy 417.798843 -179.607902) (xy 417.791009 -179.662084) (xy 417.775509 -179.714588) (xy 417.752658 -179.764336)
			(xy 417.722929 -179.810305) (xy 417.705286 -179.831238) (xy 417.69919 -179.83835) (xy 417.69284 -179.855368)
			(xy 417.69284 -179.940712) (xy 417.69919 -179.95773) (xy 417.705286 -179.964842) (xy 417.722965 -179.985743)
			(xy 417.752688 -180.031717) (xy 417.77553 -180.081468) (xy 417.791022 -180.133975) (xy 417.798847 -180.188158)
			(xy 417.798843 -180.242902) (xy 417.791009 -180.297084) (xy 417.775509 -180.349588) (xy 417.752658 -180.399336)
			(xy 417.722929 -180.445305) (xy 417.705286 -180.466238) (xy 417.69919 -180.47335) (xy 417.69284 -180.490368)
			(xy 417.69284 -180.575712) (xy 417.69919 -180.59273) (xy 417.705286 -180.599842) (xy 417.722909 -180.620787)
			(xy 417.752624 -180.666756) (xy 417.775463 -180.7165) (xy 417.790958 -180.768998) (xy 417.79879 -180.823172)
			(xy 417.799266 -180.85054) (xy 417.798882 -180.877796) (xy 417.791119 -180.931752) (xy 417.775755 -180.984054)
			(xy 417.753105 -181.033637) (xy 417.723629 -181.079492) (xy 417.687927 -181.120685) (xy 417.646726 -181.156378)
			(xy 417.600865 -181.185845) (xy 417.551277 -181.208484) (xy 417.498972 -181.223836) (xy 417.445014 -181.231588)
			(xy 417.417758 -181.232048) (xy 417.389811 -181.231583) (xy 417.334518 -181.223411) (xy 417.281008 -181.207262)
			(xy 417.230426 -181.183481) (xy 417.183852 -181.152578) (xy 417.162742 -181.134258) (xy 417.15563 -181.127908)
			(xy 417.138866 -181.121304) (xy 417.053268 -181.120034) (xy 417.03625 -181.12613) (xy 417.029138 -181.132226)
			(xy 417.008385 -181.149181) (xy 416.96302 -181.17771) (xy 416.91411 -181.199611) (xy 416.862617 -181.214454)
			(xy 416.809553 -181.221946) (xy 416.782758 -181.222396) (xy 416.755389 -181.221897) (xy 416.701211 -181.214087)
			(xy 416.648708 -181.198606) (xy 416.598961 -181.175771) (xy 416.552993 -181.146054) (xy 416.53206 -181.128416)
			(xy 416.524948 -181.12232) (xy 416.50793 -181.11597) (xy 416.422586 -181.11597) (xy 416.405568 -181.12232)
			(xy 416.398456 -181.128416) (xy 416.377516 -181.146045) (xy 416.331545 -181.175758) (xy 416.281799 -181.198595)
			(xy 416.229301 -181.214089) (xy 416.175127 -181.22192) (xy 416.147758 -181.222396) (xy 416.120505 -181.221961)
			(xy 416.066555 -181.214199) (xy 416.014259 -181.198838) (xy 415.96468 -181.176191) (xy 415.91883 -181.146719)
			(xy 415.87764 -181.111022) (xy 415.841949 -181.069827) (xy 415.812483 -181.023972) (xy 415.789843 -180.974391)
			(xy 415.77449 -180.922092) (xy 415.766735 -180.868141) (xy 415.76625 -180.840888) (xy 413.796049 -180.840888)
			(xy 413.796226 -180.851048) (xy 413.795767 -180.8783) (xy 413.788004 -180.932247) (xy 413.772644 -180.984541)
			(xy 413.749999 -181.034118) (xy 413.720529 -181.079967) (xy 413.684835 -181.121156) (xy 413.643643 -181.156847)
			(xy 413.597791 -181.186313) (xy 413.548213 -181.208955) (xy 413.495918 -181.224311) (xy 413.44197 -181.232069)
			(xy 413.414718 -181.232556) (xy 413.387348 -181.23209) (xy 413.333168 -181.224274) (xy 413.280665 -181.208785)
			(xy 413.230918 -181.185943) (xy 413.184951 -181.156218) (xy 413.16402 -181.138576) (xy 413.156908 -181.13248)
			(xy 413.13989 -181.12613) (xy 413.054546 -181.12613) (xy 413.037528 -181.13248) (xy 413.030416 -181.138576)
			(xy 413.009486 -181.156217) (xy 412.963513 -181.18593) (xy 412.913765 -181.208766) (xy 412.861264 -181.224256)
			(xy 412.807087 -181.232083) (xy 412.779718 -181.232556) (xy 412.752469 -181.232005) (xy 412.698527 -181.224252)
			(xy 412.646236 -181.208902) (xy 412.596662 -181.186266) (xy 412.550814 -181.156807) (xy 412.509625 -181.121122)
			(xy 412.473933 -181.079939) (xy 412.444465 -181.034096) (xy 412.421821 -180.984526) (xy 412.406462 -180.932238)
			(xy 412.3987 -180.878297) (xy 412.39821 -180.851048) (xy 409.374655 -180.851048) (xy 409.377642 -180.93817)
			(xy 409.385008 -180.955442) (xy 409.39212 -180.962554) (xy 409.412923 -180.98415) (xy 409.448177 -181.032653)
			(xy 409.475406 -181.086074) (xy 409.49394 -181.143099) (xy 409.503322 -181.202321) (xy 409.50388 -181.232302)
			(xy 409.50342 -181.259673) (xy 409.495601 -181.313852) (xy 409.480111 -181.366355) (xy 409.457268 -181.416102)
			(xy 409.427542 -181.462069) (xy 409.4099 -181.483) (xy 409.403804 -181.490112) (xy 409.397454 -181.50713)
			(xy 409.397454 -181.592474) (xy 409.403804 -181.609492) (xy 409.4099 -181.616604) (xy 409.427542 -181.637536)
			(xy 409.457264 -181.683504) (xy 409.480108 -181.733251) (xy 409.495603 -181.785753) (xy 409.503431 -181.839931)
			(xy 409.50343 -181.894672) (xy 409.495602 -181.94885) (xy 409.480107 -182.001352) (xy 409.457263 -182.051098)
			(xy 409.42754 -182.097067) (xy 409.4099 -182.118) (xy 409.403804 -182.125112) (xy 409.397454 -182.14213)
			(xy 409.397454 -182.227474) (xy 409.403804 -182.244492) (xy 409.4099 -182.251604) (xy 409.427542 -182.272536)
			(xy 409.457264 -182.318504) (xy 409.480108 -182.368251) (xy 409.495603 -182.420753) (xy 409.503431 -182.474931)
			(xy 409.50343 -182.529672) (xy 409.495602 -182.58385) (xy 409.480107 -182.636352) (xy 409.457263 -182.686098)
			(xy 409.42754 -182.732067) (xy 409.4099 -182.753) (xy 409.403804 -182.760112) (xy 409.397454 -182.77713)
			(xy 409.397454 -182.862474) (xy 409.403804 -182.879492) (xy 409.4099 -182.886604) (xy 409.427554 -182.907524)
			(xy 409.457264 -182.9535) (xy 409.480097 -183.003251) (xy 409.495584 -183.055754) (xy 409.503408 -183.109932)
			(xy 409.50388 -183.137302) (xy 409.503376 -183.16622) (xy 409.494639 -183.223394) (xy 409.477365 -183.278591)
			(xy 409.451952 -183.330545) (xy 409.418982 -183.378065) (xy 409.399486 -183.39943) (xy 409.393136 -183.406288)
			(xy 409.386024 -183.422798) (xy 409.382722 -183.508396) (xy 409.38831 -183.525668) (xy 409.394152 -183.533034)
			(xy 409.410035 -183.553429) (xy 409.436709 -183.597709) (xy 409.457164 -183.645184) (xy 409.471023 -183.694985)
			(xy 409.478034 -183.746201) (xy 409.47848 -183.772048) (xy 409.478067 -183.799302) (xy 409.470303 -183.853253)
			(xy 409.45494 -183.905551) (xy 409.432292 -183.955131) (xy 409.402818 -184.000982) (xy 409.367119 -184.042172)
			(xy 409.325921 -184.077863) (xy 409.280064 -184.107328) (xy 409.23048 -184.129967) (xy 409.178179 -184.145319)
			(xy 409.124226 -184.153072) (xy 409.096972 -184.153556) (xy 409.067496 -184.152983) (xy 409.009243 -184.143924)
			(xy 408.953078 -184.126009) (xy 408.900339 -184.099667) (xy 408.85228 -184.065524) (xy 408.83078 -184.045352)
			(xy 408.823452 -184.038809) (xy 408.805286 -184.03137) (xy 408.795474 -184.030874) (xy 408.742134 -184.030874)
			(xy 408.735276 -184.03824) (xy 408.728728 -184.045564) (xy 408.721291 -184.063733) (xy 408.720798 -184.073546)
			(xy 408.720798 -184.10555) (xy 408.721268 -184.115366) (xy 408.728724 -184.13353) (xy 408.735276 -184.140856)
			(xy 408.755433 -184.16237) (xy 408.789579 -184.210426) (xy 408.815928 -184.263162) (xy 408.833853 -184.319323)
			(xy 408.842928 -184.377572) (xy 408.84348 -184.407048) (xy 408.843067 -184.434302) (xy 408.835303 -184.488253)
			(xy 408.81994 -184.540551) (xy 408.797292 -184.590131) (xy 408.767818 -184.635982) (xy 408.732119 -184.677172)
			(xy 408.690921 -184.712863) (xy 408.645064 -184.742328) (xy 408.59548 -184.764967) (xy 408.543179 -184.780319)
			(xy 408.489226 -184.788072) (xy 408.461972 -184.788556) (xy 408.432496 -184.787983) (xy 408.374243 -184.778924)
			(xy 408.318078 -184.761009) (xy 408.265339 -184.734667) (xy 408.21728 -184.700524) (xy 408.19578 -184.680352)
			(xy 408.188452 -184.673809) (xy 408.170286 -184.66637) (xy 408.160474 -184.665874) (xy 408.107134 -184.665874)
			(xy 408.100276 -184.67324) (xy 408.093728 -184.680564) (xy 408.086291 -184.698733) (xy 408.085798 -184.708546)
			(xy 408.085798 -184.74055) (xy 408.086268 -184.750366) (xy 408.093724 -184.76853) (xy 408.100276 -184.775856)
			(xy 408.120433 -184.79737) (xy 408.154579 -184.845426) (xy 408.180928 -184.898162) (xy 408.198853 -184.954323)
			(xy 408.207928 -185.012572) (xy 408.20848 -185.042048) (xy 408.207994 -185.069299) (xy 408.200238 -185.123247)
			(xy 408.184883 -185.175542) (xy 408.162241 -185.225119) (xy 408.132775 -185.270969) (xy 408.097084 -185.31216)
			(xy 408.055893 -185.347851) (xy 408.010043 -185.377317) (xy 407.960466 -185.399959) (xy 407.908171 -185.415314)
			(xy 407.854223 -185.42307) (xy 407.799721 -185.42307) (xy 407.745773 -185.415314) (xy 407.693478 -185.399959)
			(xy 407.643901 -185.377317) (xy 407.598051 -185.347851) (xy 407.55686 -185.31216) (xy 407.521169 -185.270969)
			(xy 407.491703 -185.225119) (xy 407.469061 -185.175542) (xy 407.453706 -185.123247) (xy 407.44595 -185.069299)
			(xy 407.445464 -185.042048) (xy 405.431845 -185.042048) (xy 405.431843 -185.069409) (xy 405.424009 -185.123591)
			(xy 405.408506 -185.176096) (xy 405.385655 -185.225844) (xy 405.355924 -185.271813) (xy 405.33828 -185.292746)
			(xy 405.332184 -185.299858) (xy 405.325834 -185.316876) (xy 405.325834 -185.40222) (xy 405.332184 -185.419238)
			(xy 405.33828 -185.42635) (xy 405.355967 -185.447245) (xy 405.38569 -185.493219) (xy 405.408532 -185.542972)
			(xy 405.424024 -185.59548) (xy 405.431848 -185.649663) (xy 405.431843 -185.704409) (xy 405.424009 -185.758591)
			(xy 405.408506 -185.811096) (xy 405.385655 -185.860844) (xy 405.355924 -185.906813) (xy 405.33828 -185.927746)
			(xy 405.332184 -185.934858) (xy 405.325834 -185.951876) (xy 405.325834 -186.03722) (xy 405.332184 -186.054238)
			(xy 405.33828 -186.06135) (xy 405.355967 -186.082245) (xy 405.38569 -186.128219) (xy 405.408532 -186.177972)
			(xy 405.424024 -186.23048) (xy 405.431848 -186.284663) (xy 405.431843 -186.339409) (xy 405.424009 -186.393591)
			(xy 405.408506 -186.446096) (xy 405.385655 -186.495844) (xy 405.355924 -186.541813) (xy 405.33828 -186.562746)
			(xy 405.332184 -186.569858) (xy 405.325834 -186.586876) (xy 405.325834 -186.67222) (xy 405.332184 -186.689238)
			(xy 405.33828 -186.69635) (xy 405.355906 -186.717293) (xy 405.38562 -186.763262) (xy 405.408459 -186.813007)
			(xy 405.423953 -186.865505) (xy 405.431785 -186.91968) (xy 405.43226 -186.947048) (xy 405.431867 -186.974303)
			(xy 405.424102 -187.028256) (xy 405.408739 -187.080556) (xy 405.386089 -187.130136) (xy 405.356613 -187.175989)
			(xy 405.320912 -187.21718) (xy 405.279712 -187.25287) (xy 405.233852 -187.282335) (xy 405.184265 -187.304972)
			(xy 405.131962 -187.320323) (xy 405.078007 -187.328074) (xy 405.050752 -187.328556) (xy 405.023382 -187.32807)
			(xy 404.969204 -187.320259) (xy 404.9167 -187.304775) (xy 404.866953 -187.281937) (xy 404.820986 -187.252216)
			(xy 404.800054 -187.234576) (xy 404.792942 -187.22848) (xy 404.775924 -187.22213) (xy 404.69058 -187.22213)
			(xy 404.673562 -187.22848) (xy 404.66645 -187.234576) (xy 404.645507 -187.252201) (xy 404.599537 -187.281916)
			(xy 404.549793 -187.304755) (xy 404.497294 -187.320249) (xy 404.44312 -187.328081) (xy 404.415752 -187.328556)
			(xy 404.388502 -187.328067) (xy 404.334557 -187.320305) (xy 404.282265 -187.304946) (xy 404.232691 -187.282303)
			(xy 404.186843 -187.252836) (xy 404.145654 -187.217146) (xy 404.109964 -187.175957) (xy 404.080497 -187.130109)
			(xy 404.057854 -187.080535) (xy 404.042495 -187.028243) (xy 404.034733 -186.974298) (xy 404.034244 -186.947048)
			(xy 365.914432 -186.947048) (xy 368.118136 -189.150752) (xy 395.017244 -189.150752) (xy 395.017733 -189.123502)
			(xy 395.025495 -189.069557) (xy 395.040854 -189.017265) (xy 395.063497 -188.967691) (xy 395.092964 -188.921843)
			(xy 395.128654 -188.880654) (xy 395.169843 -188.844964) (xy 395.215691 -188.815497) (xy 395.265265 -188.792854)
			(xy 395.317557 -188.777495) (xy 395.371502 -188.769733) (xy 395.398752 -188.769244) (xy 395.426122 -188.769727)
			(xy 395.4803 -188.777539) (xy 395.532804 -188.793024) (xy 395.582551 -188.815862) (xy 395.628518 -188.845584)
			(xy 395.64945 -188.863224) (xy 395.656562 -188.86932) (xy 395.67358 -188.87567) (xy 395.758924 -188.87567)
			(xy 395.775942 -188.86932) (xy 395.783054 -188.863224) (xy 395.803987 -188.845583) (xy 395.849955 -188.815859)
			(xy 395.899701 -188.793013) (xy 395.952203 -188.777517) (xy 396.006381 -188.769688) (xy 396.061123 -188.769688)
			(xy 396.115301 -188.777517) (xy 396.167803 -188.793013) (xy 396.217549 -188.815859) (xy 396.263517 -188.845583)
			(xy 396.28445 -188.863224) (xy 396.291562 -188.86932) (xy 396.30858 -188.87567) (xy 396.393924 -188.87567)
			(xy 396.410942 -188.86932) (xy 396.418054 -188.863224) (xy 396.438996 -188.845597) (xy 396.484965 -188.815882)
			(xy 396.53471 -188.793044) (xy 396.587209 -188.77755) (xy 396.641383 -188.769719) (xy 396.668752 -188.769244)
			(xy 396.696 -188.769823) (xy 396.749942 -188.777571) (xy 396.802232 -188.792918) (xy 396.851806 -188.81555)
			(xy 396.897654 -188.845007) (xy 396.938843 -188.880689) (xy 396.974536 -188.921869) (xy 397.004004 -188.96771)
			(xy 397.026648 -189.017278) (xy 397.042008 -189.069564) (xy 397.04977 -189.123504) (xy 397.05026 -189.150752)
			(xy 399.032984 -189.150752) (xy 399.033433 -189.1235) (xy 399.041196 -189.069551) (xy 399.056557 -189.017256)
			(xy 399.079203 -188.96768) (xy 399.108673 -188.92183) (xy 399.144369 -188.88064) (xy 399.185562 -188.844949)
			(xy 399.231415 -188.815484) (xy 399.280994 -188.792843) (xy 399.33329 -188.777487) (xy 399.38724 -188.76973)
			(xy 399.414492 -188.769244) (xy 399.441863 -188.769704) (xy 399.496042 -188.777522) (xy 399.548546 -188.793012)
			(xy 399.598293 -188.815855) (xy 399.644259 -188.845582) (xy 399.66519 -188.863224) (xy 399.672302 -188.86932)
			(xy 399.68932 -188.87567) (xy 399.774664 -188.87567) (xy 399.791682 -188.86932) (xy 399.798794 -188.863224)
			(xy 399.819727 -188.845583) (xy 399.865695 -188.815859) (xy 399.915441 -188.793013) (xy 399.967943 -188.777517)
			(xy 400.022121 -188.769688) (xy 400.076863 -188.769688) (xy 400.131041 -188.777517) (xy 400.183543 -188.793013)
			(xy 400.233289 -188.815859) (xy 400.279257 -188.845583) (xy 400.30019 -188.863224) (xy 400.307302 -188.86932)
			(xy 400.32432 -188.87567) (xy 400.409664 -188.87567) (xy 400.426682 -188.86932) (xy 400.433794 -188.863224)
			(xy 400.454721 -188.845578) (xy 400.500695 -188.815866) (xy 400.550443 -188.793031) (xy 400.602945 -188.777542)
			(xy 400.657122 -188.769716) (xy 400.684492 -188.769244) (xy 400.711741 -188.769785) (xy 400.765684 -188.777539)
			(xy 400.817975 -188.792891) (xy 400.867549 -188.815528) (xy 400.913397 -188.844989) (xy 400.954586 -188.880674)
			(xy 400.990278 -188.921858) (xy 401.019745 -188.967702) (xy 401.042389 -189.017273) (xy 401.057749 -189.069561)
			(xy 401.065511 -189.123503) (xy 401.066 -189.150752) (xy 401.065529 -189.178086) (xy 401.057721 -189.232193)
			(xy 401.042271 -189.284632) (xy 401.019497 -189.334329) (xy 400.989863 -189.380268) (xy 400.972274 -189.401196)
			(xy 400.96567 -189.408562) (xy 400.959574 -189.426596) (xy 400.962622 -189.515496) (xy 400.969988 -189.532768)
			(xy 400.9771 -189.53988) (xy 400.997912 -189.561467) (xy 401.033165 -189.609972) (xy 401.060393 -189.663396)
			(xy 401.078925 -189.720423) (xy 401.088304 -189.779647) (xy 401.08886 -189.809628) (xy 401.08842 -189.836999)
			(xy 401.080597 -189.89118) (xy 401.065103 -189.943684) (xy 401.042255 -189.99343) (xy 401.012524 -190.039395)
			(xy 400.99488 -190.060326) (xy 400.988784 -190.067438) (xy 400.982434 -190.084456) (xy 400.982434 -190.1698)
			(xy 400.988784 -190.186818) (xy 400.99488 -190.19393) (xy 401.012548 -190.214841) (xy 401.042271 -190.260812)
			(xy 401.065114 -190.310562) (xy 401.080608 -190.363068) (xy 401.088434 -190.417249) (xy 401.088431 -190.471993)
			(xy 401.080599 -190.526173) (xy 401.065099 -190.578677) (xy 401.042251 -190.628425) (xy 401.012522 -190.674393)
			(xy 400.99488 -190.695326) (xy 400.988784 -190.702438) (xy 400.982434 -190.719456) (xy 400.982434 -190.8048)
			(xy 400.988784 -190.821818) (xy 400.99488 -190.82893) (xy 401.012548 -190.849841) (xy 401.042271 -190.895812)
			(xy 401.065114 -190.945562) (xy 401.080608 -190.998068) (xy 401.088434 -191.052249) (xy 401.088431 -191.106993)
			(xy 401.080599 -191.161173) (xy 401.065099 -191.213677) (xy 401.042251 -191.263425) (xy 401.012522 -191.309393)
			(xy 400.99488 -191.330326) (xy 400.988784 -191.337438) (xy 400.982434 -191.354456) (xy 400.982434 -191.4398)
			(xy 400.988784 -191.456818) (xy 400.99488 -191.46393) (xy 401.012497 -191.48488) (xy 401.042213 -191.530848)
			(xy 401.065053 -191.580591) (xy 401.080549 -191.633087) (xy 401.088383 -191.68726) (xy 401.08886 -191.714628)
			(xy 401.088471 -191.741884) (xy 401.080709 -191.79584) (xy 401.065347 -191.848142) (xy 401.042698 -191.897726)
			(xy 401.013222 -191.943581) (xy 400.977521 -191.984775) (xy 400.93632 -192.020468) (xy 400.890459 -192.049934)
			(xy 400.840871 -192.072574) (xy 400.788566 -192.087925) (xy 400.734608 -192.095676) (xy 400.707352 -192.096136)
			(xy 400.680648 -192.095706) (xy 400.627762 -192.088251) (xy 400.576432 -192.073494) (xy 400.527662 -192.051723)
			(xy 400.482405 -192.023363) (xy 400.441545 -191.98897) (xy 400.42338 -191.96939) (xy 400.416144 -191.962107)
			(xy 400.397544 -191.953459) (xy 400.387312 -191.952626) (xy 400.332956 -191.950594) (xy 400.324066 -191.959738)
			(xy 400.31713 -191.967446) (xy 400.309518 -191.98671) (xy 400.309334 -191.997076) (xy 400.310096 -192.029334)
			(xy 400.310885 -192.039673) (xy 400.319677 -192.058429) (xy 400.327114 -192.065656) (xy 400.346701 -192.083813)
			(xy 400.381094 -192.124674) (xy 400.409451 -192.169933) (xy 400.431218 -192.218705) (xy 400.445968 -192.270036)
			(xy 400.453414 -192.322924) (xy 400.45386 -192.349628) (xy 400.453471 -192.376884) (xy 400.445709 -192.43084)
			(xy 400.430347 -192.483142) (xy 400.407698 -192.532726) (xy 400.378222 -192.578581) (xy 400.342521 -192.619775)
			(xy 400.30132 -192.655468) (xy 400.255459 -192.684934) (xy 400.205871 -192.707574) (xy 400.153566 -192.722925)
			(xy 400.099608 -192.730676) (xy 400.072352 -192.731136) (xy 400.042875 -192.730581) (xy 399.984621 -192.721518)
			(xy 399.928456 -192.7036) (xy 399.875717 -192.677254) (xy 399.827659 -192.643106) (xy 399.80616 -192.622932)
			(xy 399.798841 -192.616378) (xy 399.780668 -192.608946) (xy 399.770854 -192.608454) (xy 399.717514 -192.608454)
			(xy 399.710656 -192.61582) (xy 399.704114 -192.623148) (xy 399.696674 -192.641314) (xy 399.696178 -192.651126)
			(xy 399.696178 -192.68313) (xy 399.696664 -192.692944) (xy 399.70411 -192.711108) (xy 399.710656 -192.718436)
			(xy 399.730847 -192.739919) (xy 399.76499 -192.787983) (xy 399.791333 -192.840727) (xy 399.809249 -192.896895)
			(xy 399.818314 -192.95515) (xy 399.81886 -192.984628) (xy 399.818374 -193.011879) (xy 399.810618 -193.065827)
			(xy 399.795263 -193.118122) (xy 399.772621 -193.167699) (xy 399.743155 -193.213549) (xy 399.707464 -193.25474)
			(xy 399.666273 -193.290431) (xy 399.620423 -193.319897) (xy 399.570846 -193.342539) (xy 399.518551 -193.357894)
			(xy 399.464603 -193.36565) (xy 399.410101 -193.36565) (xy 399.356153 -193.357894) (xy 399.303858 -193.342539)
			(xy 399.254281 -193.319897) (xy 399.208431 -193.290431) (xy 399.16724 -193.25474) (xy 399.131549 -193.213549)
			(xy 399.102083 -193.167699) (xy 399.079441 -193.118122) (xy 399.064086 -193.065827) (xy 399.05633 -193.011879)
			(xy 399.055844 -192.984628) (xy 399.056316 -192.957258) (xy 399.064131 -192.903079) (xy 399.079618 -192.850575)
			(xy 399.102458 -192.800828) (xy 399.132183 -192.754861) (xy 399.149824 -192.73393) (xy 399.15592 -192.726818)
			(xy 399.16227 -192.7098) (xy 399.16227 -192.624456) (xy 399.15592 -192.607438) (xy 399.149824 -192.600326)
			(xy 399.132187 -192.579392) (xy 399.102474 -192.53342) (xy 399.079638 -192.483673) (xy 399.064146 -192.431173)
			(xy 399.056318 -192.376997) (xy 399.055844 -192.349628) (xy 399.056294 -192.322058) (xy 399.064231 -192.267491)
			(xy 399.079943 -192.214636) (xy 399.103103 -192.164595) (xy 399.133228 -192.11841) (xy 399.151094 -192.097406)
			(xy 399.157698 -192.09004) (xy 399.164048 -192.07226) (xy 399.161508 -191.98336) (xy 399.154142 -191.965834)
			(xy 399.14703 -191.958976) (xy 399.126553 -191.937383) (xy 399.091827 -191.889064) (xy 399.065027 -191.835937)
			(xy 399.046804 -191.779292) (xy 399.0376 -191.720504) (xy 399.037048 -191.690752) (xy 399.037533 -191.663382)
			(xy 399.045344 -191.609204) (xy 399.060828 -191.5567) (xy 399.083666 -191.506953) (xy 399.113388 -191.460986)
			(xy 399.131028 -191.440054) (xy 399.137124 -191.432942) (xy 399.143474 -191.415924) (xy 399.143474 -191.33058)
			(xy 399.137124 -191.313562) (xy 399.131028 -191.30645) (xy 399.11334 -191.285555) (xy 399.083617 -191.239581)
			(xy 399.060775 -191.189828) (xy 399.045282 -191.137321) (xy 399.037458 -191.083137) (xy 399.037463 -191.028391)
			(xy 399.045298 -190.974209) (xy 399.0608 -190.921704) (xy 399.083652 -190.871956) (xy 399.113384 -190.825987)
			(xy 399.131028 -190.805054) (xy 399.137124 -190.797942) (xy 399.143474 -190.780924) (xy 399.143474 -190.69558)
			(xy 399.137124 -190.678562) (xy 399.131028 -190.67145) (xy 399.11334 -190.650555) (xy 399.083617 -190.604581)
			(xy 399.060775 -190.554828) (xy 399.045282 -190.502321) (xy 399.037458 -190.448137) (xy 399.037463 -190.393391)
			(xy 399.045298 -190.339209) (xy 399.0608 -190.286704) (xy 399.083652 -190.236956) (xy 399.113384 -190.190987)
			(xy 399.131028 -190.170054) (xy 399.137124 -190.162942) (xy 399.143474 -190.145924) (xy 399.143474 -190.06058)
			(xy 399.137124 -190.043562) (xy 399.131028 -190.03645) (xy 399.113403 -190.015506) (xy 399.083688 -189.969537)
			(xy 399.060849 -189.919793) (xy 399.045355 -189.867294) (xy 399.037524 -189.81312) (xy 399.037048 -189.785752)
			(xy 399.037518 -189.758618) (xy 399.045208 -189.704897) (xy 399.06044 -189.65281) (xy 399.082905 -189.603411)
			(xy 399.11215 -189.557697) (xy 399.129504 -189.536832) (xy 399.1356 -189.52972) (xy 399.141696 -189.512702)
			(xy 399.141188 -189.427358) (xy 399.134838 -189.41034) (xy 399.128488 -189.403228) (xy 399.110572 -189.382222)
			(xy 399.080381 -189.335999) (xy 399.057169 -189.285906) (xy 399.041422 -189.23299) (xy 399.033469 -189.178357)
			(xy 399.032984 -189.150752) (xy 397.05026 -189.150752) (xy 397.049769 -189.177721) (xy 397.042169 -189.231121)
			(xy 397.027115 -189.282915) (xy 397.004907 -189.332069) (xy 396.975989 -189.377599) (xy 396.95882 -189.398402)
			(xy 396.952724 -189.405514) (xy 396.946628 -189.422532) (xy 396.94739 -189.50813) (xy 396.953994 -189.524894)
			(xy 396.960344 -189.532006) (xy 396.978413 -189.553096) (xy 397.00892 -189.599501) (xy 397.032385 -189.649835)
			(xy 397.04831 -189.703037) (xy 397.056361 -189.757985) (xy 397.056864 -189.785752) (xy 397.056379 -189.813122)
			(xy 397.048567 -189.8673) (xy 397.033083 -189.919803) (xy 397.010245 -189.969551) (xy 396.980524 -190.015518)
			(xy 396.962884 -190.03645) (xy 396.956788 -190.043562) (xy 396.950438 -190.06058) (xy 396.950438 -190.145924)
			(xy 396.956788 -190.162942) (xy 396.962884 -190.170054) (xy 396.980477 -190.191025) (xy 397.010203 -190.236986)
			(xy 397.033051 -190.286726) (xy 397.04855 -190.339223) (xy 397.056383 -190.393396) (xy 397.056388 -190.448132)
			(xy 397.048566 -190.502307) (xy 397.033076 -190.554806) (xy 397.010238 -190.60455) (xy 396.980521 -190.650517)
			(xy 396.962884 -190.67145) (xy 396.956788 -190.678562) (xy 396.950438 -190.69558) (xy 396.950438 -190.780924)
			(xy 396.956788 -190.797942) (xy 396.962884 -190.805054) (xy 396.980477 -190.826025) (xy 397.010203 -190.871986)
			(xy 397.033051 -190.921726) (xy 397.04855 -190.974223) (xy 397.056383 -191.028396) (xy 397.056388 -191.083132)
			(xy 397.048566 -191.137307) (xy 397.033076 -191.189806) (xy 397.010238 -191.23955) (xy 396.980521 -191.285517)
			(xy 396.962884 -191.30645) (xy 396.956788 -191.313562) (xy 396.950438 -191.33058) (xy 396.950438 -191.415924)
			(xy 396.956788 -191.432942) (xy 396.962884 -191.440054) (xy 396.980513 -191.460995) (xy 397.010226 -191.506965)
			(xy 397.033065 -191.55671) (xy 397.048558 -191.609209) (xy 397.056389 -191.663383) (xy 397.056864 -191.690752)
			(xy 397.056355 -191.719491) (xy 397.047726 -191.776318) (xy 397.030672 -191.831209) (xy 397.005577 -191.88292)
			(xy 396.973011 -191.930283) (xy 396.95374 -191.95161) (xy 396.947136 -191.958722) (xy 396.940024 -191.976248)
			(xy 396.93977 -192.065402) (xy 396.946882 -192.082928) (xy 396.953486 -192.09004) (xy 396.972533 -192.111328)
			(xy 397.004699 -192.15853) (xy 397.029473 -192.209999) (xy 397.046302 -192.264584) (xy 397.054809 -192.321068)
			(xy 397.05534 -192.349628) (xy 397.054905 -192.377) (xy 397.047082 -192.431181) (xy 397.031586 -192.483685)
			(xy 397.008737 -192.533431) (xy 396.979005 -192.579396) (xy 396.96136 -192.600326) (xy 396.955264 -192.607438)
			(xy 396.948914 -192.624456) (xy 396.948914 -192.7098) (xy 396.955264 -192.726818) (xy 396.96136 -192.73393)
			(xy 396.979029 -192.75484) (xy 397.008753 -192.800812) (xy 397.031598 -192.850562) (xy 397.047092 -192.903067)
			(xy 397.054919 -192.957249) (xy 397.054916 -193.011993) (xy 397.047083 -193.066174) (xy 397.031583 -193.118678)
			(xy 397.008733 -193.168425) (xy 396.979003 -193.214393) (xy 396.96136 -193.235326) (xy 396.955264 -193.242438)
			(xy 396.948914 -193.259456) (xy 396.948914 -193.3448) (xy 396.955264 -193.361818) (xy 396.96136 -193.36893)
			(xy 396.979029 -193.38984) (xy 397.008753 -193.435812) (xy 397.031598 -193.485562) (xy 397.047092 -193.538067)
			(xy 397.054919 -193.592249) (xy 397.054916 -193.646993) (xy 397.047083 -193.701174) (xy 397.031583 -193.753678)
			(xy 397.008733 -193.803425) (xy 396.979003 -193.849393) (xy 396.96136 -193.870326) (xy 396.955264 -193.877438)
			(xy 396.948914 -193.894456) (xy 396.948914 -193.9798) (xy 396.955264 -193.996818) (xy 396.96136 -194.00393)
			(xy 396.979029 -194.02484) (xy 397.008753 -194.070812) (xy 397.031598 -194.120562) (xy 397.047092 -194.173067)
			(xy 397.054919 -194.227249) (xy 397.054916 -194.281993) (xy 397.047083 -194.336174) (xy 397.031583 -194.388678)
			(xy 397.008733 -194.438425) (xy 396.979003 -194.484393) (xy 396.96136 -194.505326) (xy 396.955264 -194.512438)
			(xy 396.948914 -194.529456) (xy 396.948914 -194.6148) (xy 396.955264 -194.631818) (xy 396.96136 -194.63893)
			(xy 396.979029 -194.65984) (xy 397.008753 -194.705812) (xy 397.031598 -194.755562) (xy 397.047092 -194.808067)
			(xy 397.054919 -194.862249) (xy 397.054916 -194.916993) (xy 397.047083 -194.971174) (xy 397.031583 -195.023678)
			(xy 397.008733 -195.073425) (xy 396.979003 -195.119393) (xy 396.96136 -195.140326) (xy 396.955264 -195.147438)
			(xy 396.948914 -195.164456) (xy 396.948914 -195.2498) (xy 396.955264 -195.266818) (xy 396.96136 -195.27393)
			(xy 396.978974 -195.294883) (xy 397.008691 -195.340849) (xy 397.031532 -195.390591) (xy 397.047029 -195.443088)
			(xy 397.054863 -195.49726) (xy 397.05534 -195.524628) (xy 397.054848 -195.551878) (xy 397.047089 -195.605824)
			(xy 397.031732 -195.658117) (xy 397.00909 -195.707692) (xy 396.979623 -195.753541) (xy 396.943933 -195.79473)
			(xy 396.902744 -195.830421) (xy 396.856896 -195.859888) (xy 396.807321 -195.88253) (xy 396.755028 -195.897888)
			(xy 396.701082 -195.905648) (xy 396.673832 -195.906136) (xy 396.646462 -195.905667) (xy 396.592282 -195.897852)
			(xy 396.539778 -195.882365) (xy 396.490031 -195.859523) (xy 396.444065 -195.829798) (xy 396.423134 -195.812156)
			(xy 396.416022 -195.80606) (xy 396.399004 -195.79971) (xy 396.31366 -195.79971) (xy 396.296642 -195.80606)
			(xy 396.28953 -195.812156) (xy 396.268597 -195.829797) (xy 396.222629 -195.859521) (xy 396.172883 -195.882367)
			(xy 396.120381 -195.897863) (xy 396.066203 -195.905692) (xy 396.011461 -195.905692) (xy 395.957283 -195.897863)
			(xy 395.904781 -195.882367) (xy 395.855035 -195.859521) (xy 395.809067 -195.829797) (xy 395.788134 -195.812156)
			(xy 395.781022 -195.80606) (xy 395.764004 -195.79971) (xy 395.67866 -195.79971) (xy 395.661642 -195.80606)
			(xy 395.65453 -195.812156) (xy 395.633592 -195.829788) (xy 395.587621 -195.859502) (xy 395.537876 -195.88234)
			(xy 395.485376 -195.897833) (xy 395.431201 -195.905662) (xy 395.403832 -195.906136) (xy 395.376581 -195.905615)
			(xy 395.322634 -195.897863) (xy 395.270339 -195.882513) (xy 395.220761 -195.859876) (xy 395.174909 -195.830414)
			(xy 395.133716 -195.794726) (xy 395.098022 -195.753539) (xy 395.068553 -195.707692) (xy 395.045908 -195.658118)
			(xy 395.03055 -195.605825) (xy 395.022789 -195.551879) (xy 395.022324 -195.524628) (xy 395.022801 -195.497258)
			(xy 395.030615 -195.443079) (xy 395.046101 -195.390576) (xy 395.068941 -195.340829) (xy 395.098664 -195.294862)
			(xy 395.116304 -195.27393) (xy 395.1224 -195.266818) (xy 395.12875 -195.2498) (xy 395.12875 -195.164456)
			(xy 395.1224 -195.147438) (xy 395.116304 -195.140326) (xy 395.098692 -195.119371) (xy 395.068968 -195.073406)
			(xy 395.046122 -195.023664) (xy 395.030624 -194.971165) (xy 395.022794 -194.91699) (xy 395.022791 -194.862252)
			(xy 395.030615 -194.808076) (xy 395.046107 -194.755576) (xy 395.068947 -194.705831) (xy 395.098666 -194.659863)
			(xy 395.116304 -194.63893) (xy 395.1224 -194.631818) (xy 395.12875 -194.6148) (xy 395.12875 -194.529456)
			(xy 395.1224 -194.512438) (xy 395.116304 -194.505326) (xy 395.098692 -194.484371) (xy 395.068968 -194.438406)
			(xy 395.046122 -194.388664) (xy 395.030624 -194.336165) (xy 395.022794 -194.28199) (xy 395.022791 -194.227252)
			(xy 395.030615 -194.173076) (xy 395.046107 -194.120576) (xy 395.068947 -194.070831) (xy 395.098666 -194.024863)
			(xy 395.116304 -194.00393) (xy 395.1224 -193.996818) (xy 395.12875 -193.9798) (xy 395.12875 -193.894456)
			(xy 395.1224 -193.877438) (xy 395.116304 -193.870326) (xy 395.098692 -193.849371) (xy 395.068968 -193.803406)
			(xy 395.046122 -193.753664) (xy 395.030624 -193.701165) (xy 395.022794 -193.64699) (xy 395.022791 -193.592252)
			(xy 395.030615 -193.538076) (xy 395.046107 -193.485576) (xy 395.068947 -193.435831) (xy 395.098666 -193.389863)
			(xy 395.116304 -193.36893) (xy 395.1224 -193.361818) (xy 395.12875 -193.3448) (xy 395.12875 -193.259456)
			(xy 395.1224 -193.242438) (xy 395.116304 -193.235326) (xy 395.098692 -193.214371) (xy 395.068968 -193.168406)
			(xy 395.046122 -193.118664) (xy 395.030624 -193.066165) (xy 395.022794 -193.01199) (xy 395.022791 -192.957252)
			(xy 395.030615 -192.903076) (xy 395.046107 -192.850576) (xy 395.068947 -192.800831) (xy 395.098666 -192.754863)
			(xy 395.116304 -192.73393) (xy 395.1224 -192.726818) (xy 395.12875 -192.7098) (xy 395.12875 -192.624456)
			(xy 395.1224 -192.607438) (xy 395.116304 -192.600326) (xy 395.098692 -192.579371) (xy 395.068968 -192.533406)
			(xy 395.046122 -192.483664) (xy 395.030624 -192.431165) (xy 395.022794 -192.37699) (xy 395.022791 -192.322252)
			(xy 395.030615 -192.268076) (xy 395.046107 -192.215576) (xy 395.068947 -192.165831) (xy 395.098666 -192.119863)
			(xy 395.116304 -192.09893) (xy 395.1224 -192.091818) (xy 395.12875 -192.0748) (xy 395.12875 -191.989456)
			(xy 395.1224 -191.972438) (xy 395.116304 -191.965326) (xy 395.098692 -191.944371) (xy 395.068968 -191.898406)
			(xy 395.046122 -191.848664) (xy 395.030624 -191.796165) (xy 395.022794 -191.74199) (xy 395.022791 -191.687252)
			(xy 395.030615 -191.633076) (xy 395.046107 -191.580576) (xy 395.068947 -191.530831) (xy 395.098666 -191.484863)
			(xy 395.116304 -191.46393) (xy 395.1224 -191.456818) (xy 395.12875 -191.4398) (xy 395.12875 -191.354456)
			(xy 395.1224 -191.337438) (xy 395.116304 -191.330326) (xy 395.098692 -191.309371) (xy 395.068968 -191.263406)
			(xy 395.046122 -191.213664) (xy 395.030624 -191.161165) (xy 395.022794 -191.10699) (xy 395.022791 -191.052252)
			(xy 395.030615 -190.998076) (xy 395.046107 -190.945576) (xy 395.068947 -190.895831) (xy 395.098666 -190.849863)
			(xy 395.116304 -190.82893) (xy 395.1224 -190.821818) (xy 395.12875 -190.8048) (xy 395.12875 -190.719456)
			(xy 395.1224 -190.702438) (xy 395.116304 -190.695326) (xy 395.098692 -190.674371) (xy 395.068968 -190.628406)
			(xy 395.046122 -190.578664) (xy 395.030624 -190.526165) (xy 395.022794 -190.47199) (xy 395.022791 -190.417252)
			(xy 395.030615 -190.363076) (xy 395.046107 -190.310576) (xy 395.068947 -190.260831) (xy 395.098666 -190.214863)
			(xy 395.116304 -190.19393) (xy 395.1224 -190.186818) (xy 395.12875 -190.1698) (xy 395.12875 -190.084456)
			(xy 395.1224 -190.067438) (xy 395.116304 -190.060326) (xy 395.098664 -190.039394) (xy 395.068952 -189.993422)
			(xy 395.046116 -189.943674) (xy 395.030626 -189.891173) (xy 395.022798 -189.836997) (xy 395.022324 -189.809628)
			(xy 395.022851 -189.781268) (xy 395.03124 -189.725173) (xy 395.04785 -189.670941) (xy 395.072315 -189.619771)
			(xy 395.104095 -189.572791) (xy 395.122908 -189.551564) (xy 395.129512 -189.544452) (xy 395.13637 -189.526672)
			(xy 395.135608 -189.437772) (xy 395.128496 -189.420246) (xy 395.121638 -189.413134) (xy 395.102126 -189.39175)
			(xy 395.069135 -189.344185) (xy 395.043718 -189.292177) (xy 395.026459 -189.236924) (xy 395.017756 -189.179696)
			(xy 395.017244 -189.150752) (xy 368.118136 -189.150752) (xy 368.757454 -189.79007) (xy 368.764058 -189.795658)
			(xy 368.764312 -189.795658) (xy 368.77084 -189.799956) (xy 368.785712 -189.80474) (xy 368.793522 -189.805056)
			(xy 387.703314 -189.805056) (xy 387.713382 -189.805483) (xy 387.731977 -189.813207) (xy 387.739382 -189.820042)
			(xy 394.881354 -196.962014) (xy 394.881862 -196.962522) (xy 394.889242 -196.969106) (xy 394.907542 -196.976558)
			(xy 394.917422 -196.977)
		)
		(stroke
			(width 0)
			(type solid)
		)
		(fill yes)
		(layer "In4.Cu")
		(net "GND")
	)
	(gr_poly
		(pts
			(xy 328.209656 -374.625616) (xy 328.218462 -374.62519) (xy 328.235007 -374.619139) (xy 328.248545 -374.607866)
			(xy 328.253344 -374.60047) (xy 328.292039 -374.535717) (xy 328.375622 -374.410124) (xy 328.466036 -374.289356)
			(xy 328.563004 -374.173784) (xy 328.666227 -374.063764) (xy 328.775389 -373.959632) (xy 328.890154 -373.861711)
			(xy 329.01017 -373.770299) (xy 329.135066 -373.685679) (xy 329.199494 -373.646446) (xy 344.339926 -364.57128)
			(xy 344.349832 -364.56366) (xy 346.466922 -362.44657) (xy 346.614275 -362.437413) (xy 346.909272 -362.424664)
			(xy 347.204476 -362.418277) (xy 347.352112 -362.417868) (xy 347.918786 -362.417868) (xy 347.925595 -362.41765)
			(xy 347.938727 -362.414044) (xy 347.944694 -362.410756) (xy 353.544632 -359.054146) (xy 353.548355 -359.051815)
			(xy 353.554995 -359.046063) (xy 353.55784 -359.042716) (xy 363.021626 -347.489018) (xy 363.071789 -347.426971)
			(xy 363.166907 -347.298845) (xy 363.255883 -347.166381) (xy 363.338521 -347.029872) (xy 363.414635 -346.889621)
			(xy 363.484058 -346.74594) (xy 363.546634 -346.599148) (xy 363.602226 -346.449571) (xy 363.650709 -346.297542)
			(xy 363.691976 -346.143397) (xy 363.725936 -345.987479) (xy 363.739684 -345.908884) (xy 363.740192 -345.900502)
			(xy 363.740192 -339.072474) (xy 363.73966 -338.925556) (xy 363.731034 -338.631847) (xy 363.713786 -338.338518)
			(xy 363.68793 -338.045822) (xy 363.653488 -337.754012) (xy 363.61049 -337.463339) (xy 363.585252 -337.318604)
			(xy 363.56671 -337.216496) (xy 363.52988 -337.01101) (xy 363.502956 -336.987642) (xy 363.485176 -336.98688)
			(xy 363.458681 -336.985329) (xy 363.40647 -336.97581) (xy 363.356082 -336.959144) (xy 363.308491 -336.935654)
			(xy 363.264617 -336.905792) (xy 363.225307 -336.870135) (xy 363.19132 -336.829373) (xy 363.163313 -336.784292)
			(xy 363.141826 -336.735764) (xy 363.127275 -336.684725) (xy 363.119941 -336.632162) (xy 363.119416 -336.605626)
			(xy 363.119922 -336.577077) (xy 363.128432 -336.520617) (xy 363.145266 -336.466057) (xy 363.170048 -336.414617)
			(xy 363.18571 -336.390742) (xy 363.19206 -336.381344) (xy 363.195616 -336.359246) (xy 363.168438 -336.262472)
			(xy 363.153452 -336.245454) (xy 363.143292 -336.240882) (xy 363.118449 -336.22924) (xy 363.072103 -336.199881)
			(xy 363.030443 -336.164185) (xy 362.994327 -336.122887) (xy 362.964502 -336.07684) (xy 362.941583 -336.026994)
			(xy 362.926043 -335.974379) (xy 362.918203 -335.920079) (xy 362.91774 -335.892648) (xy 362.918172 -335.866812)
			(xy 362.925148 -335.815614) (xy 362.938967 -335.765824) (xy 362.959375 -335.718354) (xy 362.986 -335.67407)
			(xy 363.001814 -335.653634) (xy 363.009688 -335.643982) (xy 363.014514 -335.620614) (xy 362.986828 -335.51749)
			(xy 362.970826 -335.49971) (xy 362.959396 -335.495138) (xy 362.932864 -335.484321) (xy 362.883123 -335.455882)
			(xy 362.838201 -335.420317) (xy 362.799108 -335.378429) (xy 362.766727 -335.33116) (xy 362.741786 -335.279577)
			(xy 362.724848 -335.224841) (xy 362.716295 -335.168186) (xy 362.71581 -335.139538) (xy 362.716377 -335.109348)
			(xy 362.725886 -335.049722) (xy 362.744688 -334.992345) (xy 362.772312 -334.938655) (xy 362.789724 -334.913986)
			(xy 362.79709 -334.903826) (xy 362.800646 -334.878934) (xy 362.763816 -334.77581) (xy 362.745274 -334.758792)
			(xy 362.733082 -334.75549) (xy 362.706131 -334.748052) (xy 362.654599 -334.726366) (xy 362.606789 -334.697382)
			(xy 362.563726 -334.661725) (xy 362.526336 -334.620159) (xy 362.495419 -334.573575) (xy 362.471641 -334.522975)
			(xy 362.455511 -334.469443) (xy 362.447375 -334.414129) (xy 362.446824 -334.386174) (xy 362.447486 -334.354079)
			(xy 362.458228 -334.290793) (xy 362.479406 -334.230197) (xy 362.494322 -334.20177) (xy 362.502704 -334.186784)
			(xy 362.497878 -334.15351) (xy 357.185976 -328.841608) (xy 357.178864 -328.834242) (xy 357.160068 -328.826622)
			(xy 347.085412 -328.826622) (xy 347.07534 -328.826202) (xy 347.056731 -328.818493) (xy 347.049344 -328.811636)
			(xy 346.751656 -328.513948) (xy 346.748626 -328.51096) (xy 346.741731 -328.505975) (xy 346.73794 -328.504042)
			(xy 346.73032 -328.500486) (xy 346.721938 -328.499216) (xy 346.695641 -328.495438) (xy 346.644813 -328.479999)
			(xy 346.597418 -328.456008) (xy 346.554881 -328.424188) (xy 346.536264 -328.405236) (xy 346.535756 -328.404474)
			(xy 342.23833 -324.107302) (xy 342.230928 -324.100466) (xy 342.21233 -324.092757) (xy 342.202262 -324.092316)
			(xy 318.569086 -324.092316) (xy 318.559017 -324.092742) (xy 318.540418 -324.100462) (xy 318.533018 -324.107302)
			(xy 311.725564 -330.914756) (xy 311.718198 -330.921868) (xy 311.710578 -330.940664) (xy 311.710578 -333.058262)
			(xy 311.711045 -333.068136) (xy 311.718497 -333.086425) (xy 311.725056 -333.093822) (xy 311.72531 -333.094076)
			(xy 311.741312 -333.110078) (xy 311.748156 -333.117476) (xy 311.755876 -333.136076) (xy 311.756298 -333.146146)
			(xy 311.756298 -334.84185) (xy 311.755866 -334.851916) (xy 311.748138 -334.870507) (xy 311.741312 -334.877918)
			(xy 311.24525 -335.37398) (xy 311.237884 -335.381092) (xy 311.230264 -335.399888) (xy 311.230264 -335.410048)
			(xy 311.219342 -335.42097) (xy 311.211942 -335.42781) (xy 311.193343 -335.435528) (xy 311.183274 -335.435956)
			(xy 304.712116 -335.435956) (xy 304.702054 -335.435516) (xy 304.683476 -335.427775) (xy 304.676048 -335.42097)
			(xy 304.24882 -334.993742) (xy 304.241981 -334.986341) (xy 304.234264 -334.967743) (xy 304.233834 -334.957674)
			(xy 304.233834 -325.526654) (xy 304.212752 -325.499222) (xy 304.195734 -325.494904) (xy 304.15216 -325.483214)
			(xy 304.067155 -325.452974) (xy 303.985251 -325.415131) (xy 303.907127 -325.369999) (xy 303.833429 -325.317951)
			(xy 303.764768 -325.259419) (xy 303.701713 -325.194887) (xy 303.644785 -325.12489) (xy 303.594457 -325.050008)
			(xy 303.551145 -324.97086) (xy 303.515207 -324.888102) (xy 303.486942 -324.80242) (xy 303.466584 -324.714523)
			(xy 303.454301 -324.62514) (xy 303.450195 -324.535009) (xy 303.454299 -324.444879) (xy 303.466581 -324.355495)
			(xy 303.486937 -324.267598) (xy 303.515201 -324.181915) (xy 303.551136 -324.099157) (xy 303.594447 -324.020008)
			(xy 303.644774 -323.945125) (xy 303.7017 -323.875127) (xy 303.764754 -323.810594) (xy 303.833414 -323.75206)
			(xy 303.907111 -323.700011) (xy 303.985234 -323.654878) (xy 304.067138 -323.617033) (xy 304.152142 -323.586792)
			(xy 304.195734 -323.575172) (xy 304.212752 -323.570854) (xy 304.233834 -323.543422) (xy 304.233834 -320.776346)
			(xy 304.233399 -320.766282) (xy 304.225664 -320.747698) (xy 304.218848 -320.740278) (xy 303.791112 -320.312542)
			(xy 303.784 -320.305176) (xy 303.765204 -320.297556) (xy 261.584186 -320.297556) (xy 261.574118 -320.297983)
			(xy 261.555523 -320.305707) (xy 261.548118 -320.312542) (xy 260.327648 -321.533012) (xy 260.320798 -321.540409)
			(xy 260.31306 -321.559007) (xy 260.312662 -321.56908) (xy 260.312662 -324.102984) (xy 262.047228 -324.102984)
			(xy 262.04764 -324.075729) (xy 262.0554 -324.021774) (xy 262.07076 -323.969473) (xy 262.093407 -323.919891)
			(xy 262.12288 -323.874036) (xy 262.158579 -323.832842) (xy 262.199778 -323.797149) (xy 262.245636 -323.767682)
			(xy 262.295222 -323.745042) (xy 262.347525 -323.729689) (xy 262.401481 -323.721936) (xy 262.428736 -323.721476)
			(xy 262.457923 -323.722026) (xy 262.515615 -323.730929) (xy 262.57128 -323.748508) (xy 262.623622 -323.774352)
			(xy 262.671421 -323.80786) (xy 262.713565 -323.848251) (xy 262.731758 -323.871082) (xy 262.739886 -323.88175)
			(xy 262.763762 -323.892164) (xy 262.876792 -323.880226) (xy 262.898128 -323.86524) (xy 262.90397 -323.853048)
			(xy 262.915962 -323.829003) (xy 262.945644 -323.784216) (xy 262.981318 -323.744038) (xy 263.022276 -323.709263)
			(xy 263.067709 -323.680579) (xy 263.116717 -323.658554) (xy 263.168331 -323.643624) (xy 263.221529 -323.636083)
			(xy 263.248394 -323.635624) (xy 263.277413 -323.636205) (xy 263.334783 -323.644995) (xy 263.390159 -323.662371)
			(xy 263.442264 -323.687935) (xy 263.489897 -323.721095) (xy 263.531958 -323.761087) (xy 263.550146 -323.783706)
			(xy 263.55802 -323.793612) (xy 263.58088 -323.804026) (xy 263.689592 -323.797676) (xy 263.711182 -323.784722)
			(xy 263.717532 -323.774054) (xy 263.732422 -323.75023) (xy 263.768091 -323.706826) (xy 263.809739 -323.669121)
			(xy 263.856464 -323.637929) (xy 263.907257 -323.613925) (xy 263.961022 -323.597627) (xy 264.016594 -323.589388)
			(xy 264.044684 -323.588888) (xy 264.074105 -323.589449) (xy 264.132249 -323.598494) (xy 264.188315 -323.616358)
			(xy 264.240974 -323.642616) (xy 264.288978 -323.676646) (xy 264.33119 -323.717642) (xy 264.366608 -323.764632)
			(xy 264.38098 -323.79031) (xy 264.387584 -323.802502) (xy 264.410698 -323.816726) (xy 264.526776 -323.81952)
			(xy 264.550652 -323.806312) (xy 264.557764 -323.794374) (xy 264.572655 -323.770504) (xy 264.608307 -323.726987)
			(xy 264.649964 -323.689177) (xy 264.696721 -323.657895) (xy 264.747566 -323.633819) (xy 264.801395 -323.61747)
			(xy 264.857042 -323.609204) (xy 264.88517 -323.6087) (xy 264.912425 -323.609145) (xy 264.96638 -323.616899)
			(xy 265.018683 -323.632253) (xy 265.068268 -323.654894) (xy 265.114125 -323.684362) (xy 265.155323 -323.720056)
			(xy 265.19102 -323.761251) (xy 265.220492 -323.807106) (xy 265.243137 -323.856689) (xy 265.258495 -323.908991)
			(xy 265.266253 -323.962945) (xy 265.266253 -324.017455) (xy 265.258495 -324.071409) (xy 265.243137 -324.123711)
			(xy 265.220492 -324.173294) (xy 265.19102 -324.219149) (xy 265.155323 -324.260344) (xy 265.114125 -324.296038)
			(xy 265.068268 -324.325506) (xy 265.018683 -324.348147) (xy 264.96638 -324.363501) (xy 264.912425 -324.371255)
			(xy 264.88517 -324.371716) (xy 264.85575 -324.37111) (xy 264.797609 -324.362072) (xy 264.741544 -324.344217)
			(xy 264.688885 -324.317966) (xy 264.64088 -324.283943) (xy 264.598667 -324.242953) (xy 264.563247 -324.195969)
			(xy 264.548874 -324.170294) (xy 264.54227 -324.158102) (xy 264.519156 -324.143878) (xy 264.403078 -324.141084)
			(xy 264.379202 -324.154292) (xy 264.37209 -324.16623) (xy 264.355509 -324.192731) (xy 264.31513 -324.240447)
			(xy 264.267502 -324.280928) (xy 264.241026 -324.297548) (xy 264.229342 -324.30466) (xy 264.216388 -324.328028)
			(xy 264.218166 -324.443344) (xy 264.231882 -324.466458) (xy 264.24382 -324.473316) (xy 264.266861 -324.486704)
			(xy 264.309326 -324.518897) (xy 264.346909 -324.556676) (xy 264.378881 -324.599307) (xy 264.392156 -324.622414)
			(xy 264.397998 -324.633336) (xy 264.418064 -324.646798) (xy 264.523982 -324.66026) (xy 264.546588 -324.652132)
			(xy 264.555224 -324.642988) (xy 264.573309 -324.624411) (xy 264.61364 -324.591832) (xy 264.658014 -324.565019)
			(xy 264.705611 -324.544466) (xy 264.755555 -324.530551) (xy 264.806923 -324.523533) (xy 264.832846 -324.5231)
			(xy 264.860096 -324.523573) (xy 264.91404 -324.531335) (xy 264.96633 -324.546694) (xy 265.015902 -324.569339)
			(xy 265.061748 -324.598807) (xy 265.102934 -324.634499) (xy 265.138621 -324.675689) (xy 265.168083 -324.721538)
			(xy 265.190722 -324.771113) (xy 265.206075 -324.823405) (xy 265.21383 -324.87735) (xy 265.21383 -324.93185)
			(xy 265.206075 -324.985795) (xy 265.190722 -325.038087) (xy 265.168083 -325.087662) (xy 265.138621 -325.133511)
			(xy 265.102934 -325.174701) (xy 265.061748 -325.210393) (xy 265.015902 -325.239861) (xy 264.96633 -325.262506)
			(xy 264.91404 -325.277865) (xy 264.860096 -325.285627) (xy 264.832846 -325.286116) (xy 264.803734 -325.285528)
			(xy 264.746184 -325.276687) (xy 264.690646 -325.259203) (xy 264.638411 -325.233483) (xy 264.59069 -325.200123)
			(xy 264.548593 -325.159899) (xy 264.513098 -325.113745) (xy 264.498582 -325.088504) (xy 264.49274 -325.077582)
			(xy 264.472674 -325.06412) (xy 264.366756 -325.050658) (xy 264.34415 -325.058786) (xy 264.335514 -325.06793)
			(xy 264.317414 -325.086492) (xy 264.277086 -325.119071) (xy 264.232715 -325.145886) (xy 264.185121 -325.166442)
			(xy 264.13518 -325.18036) (xy 264.083814 -325.187383) (xy 264.057892 -325.187818) (xy 264.028871 -325.187269)
			(xy 263.971499 -325.178476) (xy 263.916122 -325.161094) (xy 263.864016 -325.135525) (xy 263.816384 -325.102358)
			(xy 263.774326 -325.062358) (xy 263.75614 -325.039736) (xy 263.748266 -325.02983) (xy 263.725406 -325.019416)
			(xy 263.616694 -325.025766) (xy 263.595104 -325.03872) (xy 263.588754 -325.049388) (xy 263.573888 -325.073228)
			(xy 263.538214 -325.11663) (xy 263.496561 -325.154333) (xy 263.449832 -325.185522) (xy 263.399035 -325.209523)
			(xy 263.345268 -325.225818) (xy 263.289693 -325.234055) (xy 263.261602 -325.234554) (xy 263.232415 -325.234004)
			(xy 263.174722 -325.225105) (xy 263.119055 -325.207528) (xy 263.066713 -325.181684) (xy 263.018913 -325.148174)
			(xy 262.976771 -325.10778) (xy 262.95858 -325.084948) (xy 262.950452 -325.07428) (xy 262.926576 -325.063866)
			(xy 262.813546 -325.075804) (xy 262.79221 -325.09079) (xy 262.786368 -325.102982) (xy 262.774361 -325.127019)
			(xy 262.744679 -325.171803) (xy 262.709007 -325.211981) (xy 262.66805 -325.246756) (xy 262.62262 -325.27544)
			(xy 262.573615 -325.297467) (xy 262.522004 -325.3124) (xy 262.468808 -325.319945) (xy 262.441944 -325.320406)
			(xy 262.414692 -325.319904) (xy 262.360742 -325.312153) (xy 262.308445 -325.296802) (xy 262.258865 -325.274165)
			(xy 262.213012 -325.244701) (xy 262.171818 -325.209011) (xy 262.136124 -325.167822) (xy 262.106656 -325.121972)
			(xy 262.084013 -325.072394) (xy 262.068656 -325.020099) (xy 262.060899 -324.96615) (xy 262.060436 -324.938898)
			(xy 262.060903 -324.910805) (xy 262.069132 -324.855226) (xy 262.085426 -324.801455) (xy 262.109433 -324.750656)
			(xy 262.140632 -324.70393) (xy 262.17835 -324.662286) (xy 262.221769 -324.626627) (xy 262.245602 -324.611746)
			(xy 262.257286 -324.604634) (xy 262.27024 -324.581266) (xy 262.268462 -324.46595) (xy 262.254746 -324.442836)
			(xy 262.242808 -324.435978) (xy 262.217786 -324.421427) (xy 262.172076 -324.385919) (xy 262.132259 -324.34391)
			(xy 262.099249 -324.296365) (xy 262.073805 -324.244377) (xy 262.05651 -324.189141) (xy 262.047764 -324.131924)
			(xy 262.047228 -324.102984) (xy 260.312662 -324.102984) (xy 260.312662 -332.029562) (xy 267.631416 -332.029562)
			(xy 267.635487 -331.97394) (xy 267.647613 -331.919503) (xy 267.667536 -331.867412) (xy 267.694832 -331.818777)
			(xy 267.728918 -331.774634) (xy 267.769067 -331.735925) (xy 267.814425 -331.703474) (xy 267.864025 -331.677973)
			(xy 267.916809 -331.659966) (xy 267.971652 -331.649836) (xy 268.027386 -331.647799) (xy 268.082823 -331.653899)
			(xy 268.13678 -331.668005) (xy 268.188109 -331.689817) (xy 268.235715 -331.718871) (xy 268.278583 -331.754546)
			(xy 268.3158 -331.796083) (xy 268.346573 -331.842596) (xy 268.370245 -331.893093) (xy 268.386313 -331.9465)
			(xy 268.394433 -332.001676) (xy 268.394942 -332.029562) (xy 268.394433 -332.057448) (xy 268.386313 -332.112624)
			(xy 268.370245 -332.166031) (xy 268.346573 -332.216528) (xy 268.3158 -332.263041) (xy 268.278583 -332.304578)
			(xy 268.235715 -332.340253) (xy 268.188109 -332.369307) (xy 268.13678 -332.391119) (xy 268.082823 -332.405225)
			(xy 268.027386 -332.411325) (xy 267.971652 -332.409288) (xy 267.916809 -332.399158) (xy 267.864025 -332.381151)
			(xy 267.814425 -332.35565) (xy 267.769067 -332.323199) (xy 267.728918 -332.28449) (xy 267.694832 -332.240347)
			(xy 267.667536 -332.191712) (xy 267.647613 -332.139621) (xy 267.635487 -332.085184) (xy 267.631416 -332.029562)
			(xy 260.312662 -332.029562) (xy 260.312662 -333.045562) (xy 267.631416 -333.045562) (xy 267.635487 -332.98994)
			(xy 267.647613 -332.935503) (xy 267.667536 -332.883412) (xy 267.694832 -332.834777) (xy 267.728918 -332.790634)
			(xy 267.769067 -332.751925) (xy 267.814425 -332.719474) (xy 267.864025 -332.693973) (xy 267.916809 -332.675966)
			(xy 267.971652 -332.665836) (xy 268.027386 -332.663799) (xy 268.082823 -332.669899) (xy 268.13678 -332.684005)
			(xy 268.188109 -332.705817) (xy 268.235715 -332.734871) (xy 268.278583 -332.770546) (xy 268.3158 -332.812083)
			(xy 268.346573 -332.858596) (xy 268.370245 -332.909093) (xy 268.386313 -332.9625) (xy 268.394433 -333.017676)
			(xy 268.394942 -333.045562) (xy 268.394433 -333.073448) (xy 268.386313 -333.128624) (xy 268.370245 -333.182031)
			(xy 268.346573 -333.232528) (xy 268.3158 -333.279041) (xy 268.278583 -333.320578) (xy 268.235715 -333.356253)
			(xy 268.188109 -333.385307) (xy 268.13678 -333.407119) (xy 268.082823 -333.421225) (xy 268.027386 -333.427325)
			(xy 267.971652 -333.425288) (xy 267.916809 -333.415158) (xy 267.864025 -333.397151) (xy 267.814425 -333.37165)
			(xy 267.769067 -333.339199) (xy 267.728918 -333.30049) (xy 267.694832 -333.256347) (xy 267.667536 -333.207712)
			(xy 267.647613 -333.155621) (xy 267.635487 -333.101184) (xy 267.631416 -333.045562) (xy 260.312662 -333.045562)
			(xy 260.312662 -334.736694) (xy 272.516854 -334.736694) (xy 272.517303 -334.709323) (xy 272.525123 -334.655143)
			(xy 272.540615 -334.602639) (xy 272.563461 -334.552892) (xy 272.59319 -334.506927) (xy 272.610834 -334.485996)
			(xy 272.61693 -334.478884) (xy 272.62328 -334.461866) (xy 272.62328 -334.376522) (xy 272.61693 -334.359504)
			(xy 272.610834 -334.352392) (xy 272.593187 -334.331464) (xy 272.563462 -334.285496) (xy 272.540617 -334.235749)
			(xy 272.525121 -334.183246) (xy 272.517292 -334.129066) (xy 272.517293 -334.074325) (xy 272.525122 -334.020145)
			(xy 272.54062 -333.967643) (xy 272.563466 -333.917896) (xy 272.593193 -333.871929) (xy 272.610834 -333.850996)
			(xy 272.61693 -333.843884) (xy 272.62328 -333.826866) (xy 272.62328 -333.741522) (xy 272.61693 -333.724504)
			(xy 272.610834 -333.717392) (xy 272.593187 -333.696464) (xy 272.563462 -333.650496) (xy 272.540617 -333.600749)
			(xy 272.525121 -333.548246) (xy 272.517292 -333.494066) (xy 272.517293 -333.439325) (xy 272.525122 -333.385145)
			(xy 272.54062 -333.332643) (xy 272.563466 -333.282896) (xy 272.593193 -333.236929) (xy 272.610834 -333.215996)
			(xy 272.61693 -333.208884) (xy 272.62328 -333.191866) (xy 272.62328 -333.106522) (xy 272.61693 -333.089504)
			(xy 272.610834 -333.082392) (xy 272.593187 -333.061464) (xy 272.563462 -333.015496) (xy 272.540617 -332.965749)
			(xy 272.525121 -332.913246) (xy 272.517292 -332.859066) (xy 272.517293 -332.804325) (xy 272.525122 -332.750145)
			(xy 272.54062 -332.697643) (xy 272.563466 -332.647896) (xy 272.593193 -332.601929) (xy 272.610834 -332.580996)
			(xy 272.61693 -332.573884) (xy 272.62328 -332.556866) (xy 272.62328 -332.471522) (xy 272.61693 -332.454504)
			(xy 272.610834 -332.447392) (xy 272.593187 -332.426464) (xy 272.563462 -332.380496) (xy 272.540617 -332.330749)
			(xy 272.525121 -332.278246) (xy 272.517292 -332.224066) (xy 272.517293 -332.169325) (xy 272.525122 -332.115145)
			(xy 272.54062 -332.062643) (xy 272.563466 -332.012896) (xy 272.593193 -331.966929) (xy 272.610834 -331.945996)
			(xy 272.61693 -331.938884) (xy 272.62328 -331.921866) (xy 272.62328 -331.836522) (xy 272.61693 -331.819504)
			(xy 272.610834 -331.812392) (xy 272.593187 -331.791464) (xy 272.563462 -331.745496) (xy 272.540617 -331.695749)
			(xy 272.525121 -331.643246) (xy 272.517292 -331.589066) (xy 272.517293 -331.534325) (xy 272.525122 -331.480145)
			(xy 272.54062 -331.427643) (xy 272.563466 -331.377896) (xy 272.593193 -331.331929) (xy 272.610834 -331.310996)
			(xy 272.61693 -331.303884) (xy 272.62328 -331.286866) (xy 272.62328 -331.201522) (xy 272.61693 -331.184504)
			(xy 272.610834 -331.177392) (xy 272.593187 -331.156464) (xy 272.563462 -331.110496) (xy 272.540617 -331.060749)
			(xy 272.525121 -331.008246) (xy 272.517292 -330.954066) (xy 272.517293 -330.899325) (xy 272.525122 -330.845145)
			(xy 272.54062 -330.792643) (xy 272.563466 -330.742896) (xy 272.593193 -330.696929) (xy 272.610834 -330.675996)
			(xy 272.61693 -330.668884) (xy 272.62328 -330.651866) (xy 272.62328 -330.566522) (xy 272.61693 -330.549504)
			(xy 272.610834 -330.542392) (xy 272.593183 -330.521469) (xy 272.563472 -330.475495) (xy 272.540638 -330.425745)
			(xy 272.525149 -330.373242) (xy 272.517325 -330.319064) (xy 272.516854 -330.291694) (xy 272.517372 -330.264444)
			(xy 272.525128 -330.2105) (xy 272.540482 -330.158208) (xy 272.563121 -330.108633) (xy 272.592585 -330.062785)
			(xy 272.628273 -330.021595) (xy 272.669459 -329.985904) (xy 272.715305 -329.956437) (xy 272.764878 -329.933794)
			(xy 272.817168 -329.918435) (xy 272.871112 -329.910674) (xy 272.898362 -329.910186) (xy 272.925731 -329.910678)
			(xy 272.979909 -329.91849) (xy 273.032412 -329.933973) (xy 273.082159 -329.956809) (xy 273.128127 -329.986528)
			(xy 273.14906 -330.004166) (xy 273.156172 -330.010262) (xy 273.17319 -330.016612) (xy 273.258534 -330.016612)
			(xy 273.275552 -330.010262) (xy 273.282664 -330.004166) (xy 273.303597 -329.986525) (xy 273.349565 -329.956801)
			(xy 273.399311 -329.933955) (xy 273.451813 -329.918459) (xy 273.505991 -329.91063) (xy 273.560733 -329.91063)
			(xy 273.614911 -329.918459) (xy 273.667413 -329.933955) (xy 273.717159 -329.956801) (xy 273.763127 -329.986525)
			(xy 273.78406 -330.004166) (xy 273.791172 -330.010262) (xy 273.80819 -330.016612) (xy 273.893534 -330.016612)
			(xy 273.910552 -330.010262) (xy 273.917664 -330.004166) (xy 273.938594 -329.986525) (xy 273.984568 -329.956815)
			(xy 274.034316 -329.93398) (xy 274.086817 -329.918489) (xy 274.140993 -329.91066) (xy 274.168362 -329.910186)
			(xy 274.195614 -329.910691) (xy 274.249563 -329.918442) (xy 274.30186 -329.933793) (xy 274.351439 -329.956431)
			(xy 274.397292 -329.985894) (xy 274.438485 -330.021584) (xy 274.474179 -330.062773) (xy 274.503648 -330.108622)
			(xy 274.526291 -330.158199) (xy 274.541648 -330.210494) (xy 274.549406 -330.264442) (xy 274.54987 -330.291694)
			(xy 274.549408 -330.319064) (xy 274.54159 -330.373244) (xy 274.526101 -330.425747) (xy 274.503258 -330.475494)
			(xy 274.473532 -330.521461) (xy 274.45589 -330.542392) (xy 274.449794 -330.549504) (xy 274.443444 -330.566522)
			(xy 274.443444 -330.651866) (xy 274.449794 -330.668884) (xy 274.45589 -330.675996) (xy 274.473524 -330.696934)
			(xy 274.503248 -330.742901) (xy 274.526093 -330.792647) (xy 274.541589 -330.845148) (xy 274.549417 -330.899325)
			(xy 274.549418 -330.954066) (xy 274.54159 -331.008243) (xy 274.526096 -331.060745) (xy 274.503252 -331.110491)
			(xy 274.47353 -331.156459) (xy 274.45589 -331.177392) (xy 274.449794 -331.184504) (xy 274.443444 -331.201522)
			(xy 274.443444 -331.286866) (xy 274.449794 -331.303884) (xy 274.45589 -331.310996) (xy 274.473524 -331.331934)
			(xy 274.503248 -331.377901) (xy 274.526093 -331.427647) (xy 274.541589 -331.480148) (xy 274.549417 -331.534325)
			(xy 274.549418 -331.589066) (xy 274.54159 -331.643243) (xy 274.526096 -331.695745) (xy 274.503252 -331.745491)
			(xy 274.47353 -331.791459) (xy 274.45589 -331.812392) (xy 274.449794 -331.819504) (xy 274.443444 -331.836522)
			(xy 274.443444 -331.921866) (xy 274.449794 -331.938884) (xy 274.45589 -331.945996) (xy 274.473524 -331.966934)
			(xy 274.503248 -332.012901) (xy 274.526093 -332.062647) (xy 274.541589 -332.115148) (xy 274.549417 -332.169325)
			(xy 274.549418 -332.224066) (xy 274.54159 -332.278243) (xy 274.526096 -332.330745) (xy 274.503252 -332.380491)
			(xy 274.47353 -332.426459) (xy 274.45589 -332.447392) (xy 274.449794 -332.454504) (xy 274.443444 -332.471522)
			(xy 274.443444 -332.556866) (xy 274.449794 -332.573884) (xy 274.45589 -332.580996) (xy 274.473524 -332.601934)
			(xy 274.503248 -332.647901) (xy 274.526093 -332.697647) (xy 274.541589 -332.750148) (xy 274.549417 -332.804325)
			(xy 274.549418 -332.859066) (xy 274.54159 -332.913243) (xy 274.526096 -332.965745) (xy 274.503252 -333.015491)
			(xy 274.47353 -333.061459) (xy 274.45589 -333.082392) (xy 274.449794 -333.089504) (xy 274.443444 -333.106522)
			(xy 274.443444 -333.191866) (xy 274.449794 -333.208884) (xy 274.45589 -333.215996) (xy 274.473524 -333.236934)
			(xy 274.503248 -333.282901) (xy 274.526093 -333.332647) (xy 274.541589 -333.385148) (xy 274.549417 -333.439325)
			(xy 274.549418 -333.494066) (xy 274.54159 -333.548243) (xy 274.526096 -333.600745) (xy 274.503252 -333.650491)
			(xy 274.47353 -333.696459) (xy 274.45589 -333.717392) (xy 274.449794 -333.724504) (xy 274.443444 -333.741522)
			(xy 274.443444 -333.826866) (xy 274.449794 -333.843884) (xy 274.45589 -333.850996) (xy 274.473524 -333.871934)
			(xy 274.503248 -333.917901) (xy 274.526093 -333.967647) (xy 274.541589 -334.020148) (xy 274.549417 -334.074325)
			(xy 274.549418 -334.129066) (xy 274.54159 -334.183243) (xy 274.526096 -334.235745) (xy 274.503252 -334.285491)
			(xy 274.47353 -334.331459) (xy 274.45589 -334.352392) (xy 274.449794 -334.359504) (xy 274.443444 -334.376522)
			(xy 274.443444 -334.461866) (xy 274.449794 -334.478884) (xy 274.45589 -334.485996) (xy 274.473539 -334.50692)
			(xy 274.50325 -334.552895) (xy 274.526084 -334.602644) (xy 274.541573 -334.655147) (xy 274.549398 -334.709324)
			(xy 274.54987 -334.736694) (xy 276.530054 -334.736694) (xy 276.530503 -334.709323) (xy 276.538323 -334.655143)
			(xy 276.553815 -334.602639) (xy 276.576661 -334.552892) (xy 276.60639 -334.506927) (xy 276.624034 -334.485996)
			(xy 276.63013 -334.478884) (xy 276.63648 -334.461866) (xy 276.63648 -334.376522) (xy 276.63013 -334.359504)
			(xy 276.624034 -334.352392) (xy 276.606387 -334.331464) (xy 276.576662 -334.285496) (xy 276.553817 -334.235749)
			(xy 276.538321 -334.183246) (xy 276.530492 -334.129066) (xy 276.530493 -334.074325) (xy 276.538322 -334.020145)
			(xy 276.55382 -333.967643) (xy 276.576666 -333.917896) (xy 276.606393 -333.871929) (xy 276.624034 -333.850996)
			(xy 276.63013 -333.843884) (xy 276.63648 -333.826866) (xy 276.63648 -333.741522) (xy 276.63013 -333.724504)
			(xy 276.624034 -333.717392) (xy 276.606387 -333.696464) (xy 276.576662 -333.650496) (xy 276.553817 -333.600749)
			(xy 276.538321 -333.548246) (xy 276.530492 -333.494066) (xy 276.530493 -333.439325) (xy 276.538322 -333.385145)
			(xy 276.55382 -333.332643) (xy 276.576666 -333.282896) (xy 276.606393 -333.236929) (xy 276.624034 -333.215996)
			(xy 276.63013 -333.208884) (xy 276.63648 -333.191866) (xy 276.63648 -333.106522) (xy 276.63013 -333.089504)
			(xy 276.624034 -333.082392) (xy 276.606387 -333.061464) (xy 276.576662 -333.015496) (xy 276.553817 -332.965749)
			(xy 276.538321 -332.913246) (xy 276.530492 -332.859066) (xy 276.530493 -332.804325) (xy 276.538322 -332.750145)
			(xy 276.55382 -332.697643) (xy 276.576666 -332.647896) (xy 276.606393 -332.601929) (xy 276.624034 -332.580996)
			(xy 276.63013 -332.573884) (xy 276.63648 -332.556866) (xy 276.63648 -332.471522) (xy 276.63013 -332.454504)
			(xy 276.624034 -332.447392) (xy 276.606387 -332.426464) (xy 276.576662 -332.380496) (xy 276.553817 -332.330749)
			(xy 276.538321 -332.278246) (xy 276.530492 -332.224066) (xy 276.530493 -332.169325) (xy 276.538322 -332.115145)
			(xy 276.55382 -332.062643) (xy 276.576666 -332.012896) (xy 276.606393 -331.966929) (xy 276.624034 -331.945996)
			(xy 276.63013 -331.938884) (xy 276.63648 -331.921866) (xy 276.63648 -331.836522) (xy 276.63013 -331.819504)
			(xy 276.624034 -331.812392) (xy 276.606387 -331.791464) (xy 276.576662 -331.745496) (xy 276.553817 -331.695749)
			(xy 276.538321 -331.643246) (xy 276.530492 -331.589066) (xy 276.530493 -331.534325) (xy 276.538322 -331.480145)
			(xy 276.55382 -331.427643) (xy 276.576666 -331.377896) (xy 276.606393 -331.331929) (xy 276.624034 -331.310996)
			(xy 276.63013 -331.303884) (xy 276.63648 -331.286866) (xy 276.63648 -331.201522) (xy 276.63013 -331.184504)
			(xy 276.624034 -331.177392) (xy 276.606387 -331.156464) (xy 276.576662 -331.110496) (xy 276.553817 -331.060749)
			(xy 276.538321 -331.008246) (xy 276.530492 -330.954066) (xy 276.530493 -330.899325) (xy 276.538322 -330.845145)
			(xy 276.55382 -330.792643) (xy 276.576666 -330.742896) (xy 276.606393 -330.696929) (xy 276.624034 -330.675996)
			(xy 276.63013 -330.668884) (xy 276.63648 -330.651866) (xy 276.63648 -330.566522) (xy 276.63013 -330.549504)
			(xy 276.624034 -330.542392) (xy 276.606383 -330.521469) (xy 276.576672 -330.475495) (xy 276.553838 -330.425745)
			(xy 276.538349 -330.373242) (xy 276.530525 -330.319064) (xy 276.530054 -330.291694) (xy 276.530572 -330.264444)
			(xy 276.538328 -330.2105) (xy 276.553682 -330.158208) (xy 276.576321 -330.108633) (xy 276.605785 -330.062785)
			(xy 276.641473 -330.021595) (xy 276.682659 -329.985904) (xy 276.728505 -329.956437) (xy 276.778078 -329.933794)
			(xy 276.830368 -329.918435) (xy 276.884312 -329.910674) (xy 276.911562 -329.910186) (xy 276.938931 -329.910678)
			(xy 276.993109 -329.91849) (xy 277.045612 -329.933973) (xy 277.095359 -329.956809) (xy 277.141327 -329.986528)
			(xy 277.16226 -330.004166) (xy 277.169372 -330.010262) (xy 277.18639 -330.016612) (xy 277.271734 -330.016612)
			(xy 277.288752 -330.010262) (xy 277.295864 -330.004166) (xy 277.316797 -329.986525) (xy 277.362765 -329.956801)
			(xy 277.412511 -329.933955) (xy 277.465013 -329.918459) (xy 277.519191 -329.91063) (xy 277.573933 -329.91063)
			(xy 277.628111 -329.918459) (xy 277.680613 -329.933955) (xy 277.730359 -329.956801) (xy 277.776327 -329.986525)
			(xy 277.79726 -330.004166) (xy 277.804372 -330.010262) (xy 277.82139 -330.016612) (xy 277.906734 -330.016612)
			(xy 277.923752 -330.010262) (xy 277.930864 -330.004166) (xy 277.951794 -329.986525) (xy 277.997768 -329.956815)
			(xy 278.047516 -329.93398) (xy 278.100017 -329.918489) (xy 278.154193 -329.91066) (xy 278.181562 -329.910186)
			(xy 278.208814 -329.910691) (xy 278.262763 -329.918442) (xy 278.31506 -329.933793) (xy 278.364639 -329.956431)
			(xy 278.410492 -329.985894) (xy 278.451685 -330.021584) (xy 278.487379 -330.062773) (xy 278.516848 -330.108622)
			(xy 278.539491 -330.158199) (xy 278.554848 -330.210494) (xy 278.562606 -330.264442) (xy 278.56307 -330.291694)
			(xy 278.562608 -330.319064) (xy 278.55479 -330.373244) (xy 278.539301 -330.425747) (xy 278.516458 -330.475494)
			(xy 278.486732 -330.521461) (xy 278.46909 -330.542392) (xy 278.462994 -330.549504) (xy 278.456644 -330.566522)
			(xy 278.456644 -330.651866) (xy 278.462994 -330.668884) (xy 278.46909 -330.675996) (xy 278.486724 -330.696934)
			(xy 278.516448 -330.742901) (xy 278.539293 -330.792647) (xy 278.554789 -330.845148) (xy 278.562617 -330.899325)
			(xy 278.562618 -330.954066) (xy 278.55479 -331.008243) (xy 278.539296 -331.060745) (xy 278.516452 -331.110491)
			(xy 278.48673 -331.156459) (xy 278.46909 -331.177392) (xy 278.462994 -331.184504) (xy 278.456644 -331.201522)
			(xy 278.456644 -331.286866) (xy 278.462994 -331.303884) (xy 278.46909 -331.310996) (xy 278.486724 -331.331934)
			(xy 278.516448 -331.377901) (xy 278.539293 -331.427647) (xy 278.554789 -331.480148) (xy 278.562617 -331.534325)
			(xy 278.562618 -331.589066) (xy 278.55479 -331.643243) (xy 278.539296 -331.695745) (xy 278.516452 -331.745491)
			(xy 278.48673 -331.791459) (xy 278.46909 -331.812392) (xy 278.462994 -331.819504) (xy 278.456644 -331.836522)
			(xy 278.456644 -331.921866) (xy 278.462994 -331.938884) (xy 278.46909 -331.945996) (xy 278.486724 -331.966934)
			(xy 278.516448 -332.012901) (xy 278.539293 -332.062647) (xy 278.554789 -332.115148) (xy 278.562617 -332.169325)
			(xy 278.562618 -332.224066) (xy 278.55479 -332.278243) (xy 278.539296 -332.330745) (xy 278.516452 -332.380491)
			(xy 278.48673 -332.426459) (xy 278.46909 -332.447392) (xy 278.462994 -332.454504) (xy 278.456644 -332.471522)
			(xy 278.456644 -332.556866) (xy 278.462994 -332.573884) (xy 278.46909 -332.580996) (xy 278.486724 -332.601934)
			(xy 278.516448 -332.647901) (xy 278.539293 -332.697647) (xy 278.554789 -332.750148) (xy 278.562617 -332.804325)
			(xy 278.562618 -332.859066) (xy 278.55479 -332.913243) (xy 278.539296 -332.965745) (xy 278.516452 -333.015491)
			(xy 278.48673 -333.061459) (xy 278.46909 -333.082392) (xy 278.462994 -333.089504) (xy 278.456644 -333.106522)
			(xy 278.456644 -333.191866) (xy 278.462994 -333.208884) (xy 278.46909 -333.215996) (xy 278.486724 -333.236934)
			(xy 278.516448 -333.282901) (xy 278.539293 -333.332647) (xy 278.554789 -333.385148) (xy 278.562617 -333.439325)
			(xy 278.562618 -333.494066) (xy 278.55479 -333.548243) (xy 278.539296 -333.600745) (xy 278.516452 -333.650491)
			(xy 278.48673 -333.696459) (xy 278.46909 -333.717392) (xy 278.462994 -333.724504) (xy 278.456644 -333.741522)
			(xy 278.456644 -333.826866) (xy 278.462994 -333.843884) (xy 278.46909 -333.850996) (xy 278.486724 -333.871934)
			(xy 278.516448 -333.917901) (xy 278.539293 -333.967647) (xy 278.554789 -334.020148) (xy 278.562617 -334.074325)
			(xy 278.562618 -334.129066) (xy 278.55479 -334.183243) (xy 278.539296 -334.235745) (xy 278.516452 -334.285491)
			(xy 278.48673 -334.331459) (xy 278.46909 -334.352392) (xy 278.462994 -334.359504) (xy 278.456644 -334.376522)
			(xy 278.456644 -334.461866) (xy 278.462994 -334.478884) (xy 278.46909 -334.485996) (xy 278.486739 -334.50692)
			(xy 278.51645 -334.552895) (xy 278.539284 -334.602644) (xy 278.554773 -334.655147) (xy 278.562598 -334.709324)
			(xy 278.56307 -334.736694) (xy 280.797254 -334.736694) (xy 280.797703 -334.709323) (xy 280.805523 -334.655143)
			(xy 280.821015 -334.602639) (xy 280.843861 -334.552892) (xy 280.87359 -334.506927) (xy 280.891234 -334.485996)
			(xy 280.89733 -334.478884) (xy 280.90368 -334.461866) (xy 280.90368 -334.376522) (xy 280.89733 -334.359504)
			(xy 280.891234 -334.352392) (xy 280.873587 -334.331464) (xy 280.843862 -334.285496) (xy 280.821017 -334.235749)
			(xy 280.805521 -334.183246) (xy 280.797692 -334.129066) (xy 280.797693 -334.074325) (xy 280.805522 -334.020145)
			(xy 280.82102 -333.967643) (xy 280.843866 -333.917896) (xy 280.873593 -333.871929) (xy 280.891234 -333.850996)
			(xy 280.89733 -333.843884) (xy 280.90368 -333.826866) (xy 280.90368 -333.741522) (xy 280.89733 -333.724504)
			(xy 280.891234 -333.717392) (xy 280.873587 -333.696464) (xy 280.843862 -333.650496) (xy 280.821017 -333.600749)
			(xy 280.805521 -333.548246) (xy 280.797692 -333.494066) (xy 280.797693 -333.439325) (xy 280.805522 -333.385145)
			(xy 280.82102 -333.332643) (xy 280.843866 -333.282896) (xy 280.873593 -333.236929) (xy 280.891234 -333.215996)
			(xy 280.89733 -333.208884) (xy 280.90368 -333.191866) (xy 280.90368 -333.106522) (xy 280.89733 -333.089504)
			(xy 280.891234 -333.082392) (xy 280.873587 -333.061464) (xy 280.843862 -333.015496) (xy 280.821017 -332.965749)
			(xy 280.805521 -332.913246) (xy 280.797692 -332.859066) (xy 280.797693 -332.804325) (xy 280.805522 -332.750145)
			(xy 280.82102 -332.697643) (xy 280.843866 -332.647896) (xy 280.873593 -332.601929) (xy 280.891234 -332.580996)
			(xy 280.89733 -332.573884) (xy 280.90368 -332.556866) (xy 280.90368 -332.471522) (xy 280.89733 -332.454504)
			(xy 280.891234 -332.447392) (xy 280.873587 -332.426464) (xy 280.843862 -332.380496) (xy 280.821017 -332.330749)
			(xy 280.805521 -332.278246) (xy 280.797692 -332.224066) (xy 280.797693 -332.169325) (xy 280.805522 -332.115145)
			(xy 280.82102 -332.062643) (xy 280.843866 -332.012896) (xy 280.873593 -331.966929) (xy 280.891234 -331.945996)
			(xy 280.89733 -331.938884) (xy 280.90368 -331.921866) (xy 280.90368 -331.836522) (xy 280.89733 -331.819504)
			(xy 280.891234 -331.812392) (xy 280.873587 -331.791464) (xy 280.843862 -331.745496) (xy 280.821017 -331.695749)
			(xy 280.805521 -331.643246) (xy 280.797692 -331.589066) (xy 280.797693 -331.534325) (xy 280.805522 -331.480145)
			(xy 280.82102 -331.427643) (xy 280.843866 -331.377896) (xy 280.873593 -331.331929) (xy 280.891234 -331.310996)
			(xy 280.89733 -331.303884) (xy 280.90368 -331.286866) (xy 280.90368 -331.201522) (xy 280.89733 -331.184504)
			(xy 280.891234 -331.177392) (xy 280.873587 -331.156464) (xy 280.843862 -331.110496) (xy 280.821017 -331.060749)
			(xy 280.805521 -331.008246) (xy 280.797692 -330.954066) (xy 280.797693 -330.899325) (xy 280.805522 -330.845145)
			(xy 280.82102 -330.792643) (xy 280.843866 -330.742896) (xy 280.873593 -330.696929) (xy 280.891234 -330.675996)
			(xy 280.89733 -330.668884) (xy 280.90368 -330.651866) (xy 280.90368 -330.566522) (xy 280.89733 -330.549504)
			(xy 280.891234 -330.542392) (xy 280.873583 -330.521469) (xy 280.843872 -330.475495) (xy 280.821038 -330.425745)
			(xy 280.805549 -330.373242) (xy 280.797725 -330.319064) (xy 280.797254 -330.291694) (xy 280.797772 -330.264444)
			(xy 280.805528 -330.2105) (xy 280.820882 -330.158208) (xy 280.843521 -330.108633) (xy 280.872985 -330.062785)
			(xy 280.908673 -330.021595) (xy 280.949859 -329.985904) (xy 280.995705 -329.956437) (xy 281.045278 -329.933794)
			(xy 281.097568 -329.918435) (xy 281.151512 -329.910674) (xy 281.178762 -329.910186) (xy 281.206131 -329.910678)
			(xy 281.260309 -329.91849) (xy 281.312812 -329.933973) (xy 281.362559 -329.956809) (xy 281.408527 -329.986528)
			(xy 281.42946 -330.004166) (xy 281.436572 -330.010262) (xy 281.45359 -330.016612) (xy 281.538934 -330.016612)
			(xy 281.555952 -330.010262) (xy 281.563064 -330.004166) (xy 281.583997 -329.986525) (xy 281.629965 -329.956801)
			(xy 281.679711 -329.933955) (xy 281.732213 -329.918459) (xy 281.786391 -329.91063) (xy 281.841133 -329.91063)
			(xy 281.895311 -329.918459) (xy 281.947813 -329.933955) (xy 281.997559 -329.956801) (xy 282.043527 -329.986525)
			(xy 282.06446 -330.004166) (xy 282.071572 -330.010262) (xy 282.08859 -330.016612) (xy 282.173934 -330.016612)
			(xy 282.190952 -330.010262) (xy 282.198064 -330.004166) (xy 282.218994 -329.986525) (xy 282.264968 -329.956815)
			(xy 282.314716 -329.93398) (xy 282.367217 -329.918489) (xy 282.421393 -329.91066) (xy 282.448762 -329.910186)
			(xy 282.476014 -329.910691) (xy 282.529963 -329.918442) (xy 282.58226 -329.933793) (xy 282.631839 -329.956431)
			(xy 282.677692 -329.985894) (xy 282.718885 -330.021584) (xy 282.754579 -330.062773) (xy 282.784048 -330.108622)
			(xy 282.806691 -330.158199) (xy 282.822048 -330.210494) (xy 282.829806 -330.264442) (xy 282.83027 -330.291694)
			(xy 282.829808 -330.319064) (xy 282.82199 -330.373244) (xy 282.806501 -330.425747) (xy 282.783658 -330.475494)
			(xy 282.753932 -330.521461) (xy 282.73629 -330.542392) (xy 282.730194 -330.549504) (xy 282.723844 -330.566522)
			(xy 282.723844 -330.651866) (xy 282.730194 -330.668884) (xy 282.73629 -330.675996) (xy 282.753924 -330.696934)
			(xy 282.783648 -330.742901) (xy 282.806493 -330.792647) (xy 282.821989 -330.845148) (xy 282.829817 -330.899325)
			(xy 282.829818 -330.954066) (xy 282.82199 -331.008243) (xy 282.806496 -331.060745) (xy 282.783652 -331.110491)
			(xy 282.75393 -331.156459) (xy 282.73629 -331.177392) (xy 282.730194 -331.184504) (xy 282.723844 -331.201522)
			(xy 282.723844 -331.286866) (xy 282.730194 -331.303884) (xy 282.73629 -331.310996) (xy 282.753924 -331.331934)
			(xy 282.783648 -331.377901) (xy 282.806493 -331.427647) (xy 282.821989 -331.480148) (xy 282.829817 -331.534325)
			(xy 282.829818 -331.589066) (xy 282.82199 -331.643243) (xy 282.806496 -331.695745) (xy 282.783652 -331.745491)
			(xy 282.75393 -331.791459) (xy 282.73629 -331.812392) (xy 282.730194 -331.819504) (xy 282.723844 -331.836522)
			(xy 282.723844 -331.921866) (xy 282.730194 -331.938884) (xy 282.73629 -331.945996) (xy 282.753924 -331.966934)
			(xy 282.783648 -332.012901) (xy 282.806493 -332.062647) (xy 282.821989 -332.115148) (xy 282.829817 -332.169325)
			(xy 282.829818 -332.224066) (xy 282.82199 -332.278243) (xy 282.806496 -332.330745) (xy 282.783652 -332.380491)
			(xy 282.75393 -332.426459) (xy 282.73629 -332.447392) (xy 282.730194 -332.454504) (xy 282.723844 -332.471522)
			(xy 282.723844 -332.556866) (xy 282.730194 -332.573884) (xy 282.73629 -332.580996) (xy 282.753924 -332.601934)
			(xy 282.783648 -332.647901) (xy 282.806493 -332.697647) (xy 282.821989 -332.750148) (xy 282.829817 -332.804325)
			(xy 282.829818 -332.859066) (xy 282.82199 -332.913243) (xy 282.806496 -332.965745) (xy 282.783652 -333.015491)
			(xy 282.75393 -333.061459) (xy 282.73629 -333.082392) (xy 282.730194 -333.089504) (xy 282.723844 -333.106522)
			(xy 282.723844 -333.191866) (xy 282.730194 -333.208884) (xy 282.73629 -333.215996) (xy 282.753924 -333.236934)
			(xy 282.783648 -333.282901) (xy 282.806493 -333.332647) (xy 282.821989 -333.385148) (xy 282.829817 -333.439325)
			(xy 282.829818 -333.494066) (xy 282.82199 -333.548243) (xy 282.806496 -333.600745) (xy 282.783652 -333.650491)
			(xy 282.75393 -333.696459) (xy 282.73629 -333.717392) (xy 282.730194 -333.724504) (xy 282.723844 -333.741522)
			(xy 282.723844 -333.826866) (xy 282.730194 -333.843884) (xy 282.73629 -333.850996) (xy 282.753924 -333.871934)
			(xy 282.783648 -333.917901) (xy 282.806493 -333.967647) (xy 282.821989 -334.020148) (xy 282.829817 -334.074325)
			(xy 282.829818 -334.129066) (xy 282.82199 -334.183243) (xy 282.806496 -334.235745) (xy 282.783652 -334.285491)
			(xy 282.75393 -334.331459) (xy 282.73629 -334.352392) (xy 282.730194 -334.359504) (xy 282.723844 -334.376522)
			(xy 282.723844 -334.461866) (xy 282.730194 -334.478884) (xy 282.73629 -334.485996) (xy 282.753939 -334.50692)
			(xy 282.78365 -334.552895) (xy 282.806484 -334.602644) (xy 282.821973 -334.655147) (xy 282.829798 -334.709324)
			(xy 282.83027 -334.736694) (xy 284.810454 -334.736694) (xy 284.810903 -334.709323) (xy 284.818723 -334.655143)
			(xy 284.834215 -334.602639) (xy 284.857061 -334.552892) (xy 284.88679 -334.506927) (xy 284.904434 -334.485996)
			(xy 284.91053 -334.478884) (xy 284.91688 -334.461866) (xy 284.91688 -334.376522) (xy 284.91053 -334.359504)
			(xy 284.904434 -334.352392) (xy 284.886787 -334.331464) (xy 284.857062 -334.285496) (xy 284.834217 -334.235749)
			(xy 284.818721 -334.183246) (xy 284.810892 -334.129066) (xy 284.810893 -334.074325) (xy 284.818722 -334.020145)
			(xy 284.83422 -333.967643) (xy 284.857066 -333.917896) (xy 284.886793 -333.871929) (xy 284.904434 -333.850996)
			(xy 284.91053 -333.843884) (xy 284.91688 -333.826866) (xy 284.91688 -333.741522) (xy 284.91053 -333.724504)
			(xy 284.904434 -333.717392) (xy 284.886787 -333.696464) (xy 284.857062 -333.650496) (xy 284.834217 -333.600749)
			(xy 284.818721 -333.548246) (xy 284.810892 -333.494066) (xy 284.810893 -333.439325) (xy 284.818722 -333.385145)
			(xy 284.83422 -333.332643) (xy 284.857066 -333.282896) (xy 284.886793 -333.236929) (xy 284.904434 -333.215996)
			(xy 284.91053 -333.208884) (xy 284.91688 -333.191866) (xy 284.91688 -333.106522) (xy 284.91053 -333.089504)
			(xy 284.904434 -333.082392) (xy 284.886787 -333.061464) (xy 284.857062 -333.015496) (xy 284.834217 -332.965749)
			(xy 284.818721 -332.913246) (xy 284.810892 -332.859066) (xy 284.810893 -332.804325) (xy 284.818722 -332.750145)
			(xy 284.83422 -332.697643) (xy 284.857066 -332.647896) (xy 284.886793 -332.601929) (xy 284.904434 -332.580996)
			(xy 284.91053 -332.573884) (xy 284.91688 -332.556866) (xy 284.91688 -332.471522) (xy 284.91053 -332.454504)
			(xy 284.904434 -332.447392) (xy 284.886787 -332.426464) (xy 284.857062 -332.380496) (xy 284.834217 -332.330749)
			(xy 284.818721 -332.278246) (xy 284.810892 -332.224066) (xy 284.810893 -332.169325) (xy 284.818722 -332.115145)
			(xy 284.83422 -332.062643) (xy 284.857066 -332.012896) (xy 284.886793 -331.966929) (xy 284.904434 -331.945996)
			(xy 284.91053 -331.938884) (xy 284.91688 -331.921866) (xy 284.91688 -331.836522) (xy 284.91053 -331.819504)
			(xy 284.904434 -331.812392) (xy 284.886787 -331.791464) (xy 284.857062 -331.745496) (xy 284.834217 -331.695749)
			(xy 284.818721 -331.643246) (xy 284.810892 -331.589066) (xy 284.810893 -331.534325) (xy 284.818722 -331.480145)
			(xy 284.83422 -331.427643) (xy 284.857066 -331.377896) (xy 284.886793 -331.331929) (xy 284.904434 -331.310996)
			(xy 284.91053 -331.303884) (xy 284.91688 -331.286866) (xy 284.91688 -331.201522) (xy 284.91053 -331.184504)
			(xy 284.904434 -331.177392) (xy 284.886787 -331.156464) (xy 284.857062 -331.110496) (xy 284.834217 -331.060749)
			(xy 284.818721 -331.008246) (xy 284.810892 -330.954066) (xy 284.810893 -330.899325) (xy 284.818722 -330.845145)
			(xy 284.83422 -330.792643) (xy 284.857066 -330.742896) (xy 284.886793 -330.696929) (xy 284.904434 -330.675996)
			(xy 284.91053 -330.668884) (xy 284.91688 -330.651866) (xy 284.91688 -330.566522) (xy 284.91053 -330.549504)
			(xy 284.904434 -330.542392) (xy 284.886783 -330.521469) (xy 284.857072 -330.475495) (xy 284.834238 -330.425745)
			(xy 284.818749 -330.373242) (xy 284.810925 -330.319064) (xy 284.810454 -330.291694) (xy 284.810972 -330.264444)
			(xy 284.818728 -330.2105) (xy 284.834082 -330.158208) (xy 284.856721 -330.108633) (xy 284.886185 -330.062785)
			(xy 284.921873 -330.021595) (xy 284.963059 -329.985904) (xy 285.008905 -329.956437) (xy 285.058478 -329.933794)
			(xy 285.110768 -329.918435) (xy 285.164712 -329.910674) (xy 285.191962 -329.910186) (xy 285.219331 -329.910678)
			(xy 285.273509 -329.91849) (xy 285.326012 -329.933973) (xy 285.375759 -329.956809) (xy 285.421727 -329.986528)
			(xy 285.44266 -330.004166) (xy 285.449772 -330.010262) (xy 285.46679 -330.016612) (xy 285.552134 -330.016612)
			(xy 285.569152 -330.010262) (xy 285.576264 -330.004166) (xy 285.597197 -329.986525) (xy 285.643165 -329.956801)
			(xy 285.692911 -329.933955) (xy 285.745413 -329.918459) (xy 285.799591 -329.91063) (xy 285.854333 -329.91063)
			(xy 285.908511 -329.918459) (xy 285.961013 -329.933955) (xy 286.010759 -329.956801) (xy 286.056727 -329.986525)
			(xy 286.07766 -330.004166) (xy 286.084772 -330.010262) (xy 286.10179 -330.016612) (xy 286.187134 -330.016612)
			(xy 286.204152 -330.010262) (xy 286.211264 -330.004166) (xy 286.232194 -329.986525) (xy 286.278168 -329.956815)
			(xy 286.327916 -329.93398) (xy 286.380417 -329.918489) (xy 286.434593 -329.91066) (xy 286.461962 -329.910186)
			(xy 286.489214 -329.910691) (xy 286.543163 -329.918442) (xy 286.59546 -329.933793) (xy 286.645039 -329.956431)
			(xy 286.690892 -329.985894) (xy 286.732085 -330.021584) (xy 286.767779 -330.062773) (xy 286.797248 -330.108622)
			(xy 286.819891 -330.158199) (xy 286.835248 -330.210494) (xy 286.843006 -330.264442) (xy 286.84347 -330.291694)
			(xy 286.843008 -330.319064) (xy 286.83519 -330.373244) (xy 286.819701 -330.425747) (xy 286.796858 -330.475494)
			(xy 286.767132 -330.521461) (xy 286.74949 -330.542392) (xy 286.743394 -330.549504) (xy 286.737044 -330.566522)
			(xy 286.737044 -330.651866) (xy 286.743394 -330.668884) (xy 286.74949 -330.675996) (xy 286.767124 -330.696934)
			(xy 286.796848 -330.742901) (xy 286.819693 -330.792647) (xy 286.835189 -330.845148) (xy 286.843017 -330.899325)
			(xy 286.843018 -330.954066) (xy 286.83519 -331.008243) (xy 286.819696 -331.060745) (xy 286.796852 -331.110491)
			(xy 286.76713 -331.156459) (xy 286.74949 -331.177392) (xy 286.743394 -331.184504) (xy 286.737044 -331.201522)
			(xy 286.737044 -331.286866) (xy 286.743394 -331.303884) (xy 286.74949 -331.310996) (xy 286.767124 -331.331934)
			(xy 286.796848 -331.377901) (xy 286.819693 -331.427647) (xy 286.835189 -331.480148) (xy 286.843017 -331.534325)
			(xy 286.843018 -331.589066) (xy 286.83519 -331.643243) (xy 286.819696 -331.695745) (xy 286.796852 -331.745491)
			(xy 286.76713 -331.791459) (xy 286.74949 -331.812392) (xy 286.743394 -331.819504) (xy 286.737044 -331.836522)
			(xy 286.737044 -331.921866) (xy 286.743394 -331.938884) (xy 286.74949 -331.945996) (xy 286.767124 -331.966934)
			(xy 286.796848 -332.012901) (xy 286.819693 -332.062647) (xy 286.835189 -332.115148) (xy 286.843017 -332.169325)
			(xy 286.843018 -332.224066) (xy 286.83519 -332.278243) (xy 286.819696 -332.330745) (xy 286.796852 -332.380491)
			(xy 286.76713 -332.426459) (xy 286.74949 -332.447392) (xy 286.743394 -332.454504) (xy 286.737044 -332.471522)
			(xy 286.737044 -332.556866) (xy 286.743394 -332.573884) (xy 286.74949 -332.580996) (xy 286.767124 -332.601934)
			(xy 286.796848 -332.647901) (xy 286.819693 -332.697647) (xy 286.835189 -332.750148) (xy 286.843017 -332.804325)
			(xy 286.843018 -332.859066) (xy 286.83519 -332.913243) (xy 286.819696 -332.965745) (xy 286.796852 -333.015491)
			(xy 286.76713 -333.061459) (xy 286.74949 -333.082392) (xy 286.743394 -333.089504) (xy 286.737044 -333.106522)
			(xy 286.737044 -333.191866) (xy 286.743394 -333.208884) (xy 286.74949 -333.215996) (xy 286.767124 -333.236934)
			(xy 286.796848 -333.282901) (xy 286.819693 -333.332647) (xy 286.835189 -333.385148) (xy 286.843017 -333.439325)
			(xy 286.843018 -333.494066) (xy 286.83519 -333.548243) (xy 286.819696 -333.600745) (xy 286.796852 -333.650491)
			(xy 286.76713 -333.696459) (xy 286.74949 -333.717392) (xy 286.743394 -333.724504) (xy 286.737044 -333.741522)
			(xy 286.737044 -333.826866) (xy 286.743394 -333.843884) (xy 286.74949 -333.850996) (xy 286.767124 -333.871934)
			(xy 286.796848 -333.917901) (xy 286.819693 -333.967647) (xy 286.835189 -334.020148) (xy 286.843017 -334.074325)
			(xy 286.843018 -334.129066) (xy 286.83519 -334.183243) (xy 286.819696 -334.235745) (xy 286.796852 -334.285491)
			(xy 286.76713 -334.331459) (xy 286.74949 -334.352392) (xy 286.743394 -334.359504) (xy 286.737044 -334.376522)
			(xy 286.737044 -334.461866) (xy 286.743394 -334.478884) (xy 286.74949 -334.485996) (xy 286.767139 -334.50692)
			(xy 286.79685 -334.552895) (xy 286.819684 -334.602644) (xy 286.835173 -334.655147) (xy 286.842998 -334.709324)
			(xy 286.84347 -334.736694) (xy 289.103054 -334.736694) (xy 289.103503 -334.709323) (xy 289.111323 -334.655143)
			(xy 289.126815 -334.602639) (xy 289.149661 -334.552892) (xy 289.17939 -334.506927) (xy 289.197034 -334.485996)
			(xy 289.20313 -334.478884) (xy 289.20948 -334.461866) (xy 289.20948 -334.376522) (xy 289.20313 -334.359504)
			(xy 289.197034 -334.352392) (xy 289.179387 -334.331464) (xy 289.149662 -334.285496) (xy 289.126817 -334.235749)
			(xy 289.111321 -334.183246) (xy 289.103492 -334.129066) (xy 289.103493 -334.074325) (xy 289.111322 -334.020145)
			(xy 289.12682 -333.967643) (xy 289.149666 -333.917896) (xy 289.179393 -333.871929) (xy 289.197034 -333.850996)
			(xy 289.20313 -333.843884) (xy 289.20948 -333.826866) (xy 289.20948 -333.741522) (xy 289.20313 -333.724504)
			(xy 289.197034 -333.717392) (xy 289.179387 -333.696464) (xy 289.149662 -333.650496) (xy 289.126817 -333.600749)
			(xy 289.111321 -333.548246) (xy 289.103492 -333.494066) (xy 289.103493 -333.439325) (xy 289.111322 -333.385145)
			(xy 289.12682 -333.332643) (xy 289.149666 -333.282896) (xy 289.179393 -333.236929) (xy 289.197034 -333.215996)
			(xy 289.20313 -333.208884) (xy 289.20948 -333.191866) (xy 289.20948 -333.106522) (xy 289.20313 -333.089504)
			(xy 289.197034 -333.082392) (xy 289.179387 -333.061464) (xy 289.149662 -333.015496) (xy 289.126817 -332.965749)
			(xy 289.111321 -332.913246) (xy 289.103492 -332.859066) (xy 289.103493 -332.804325) (xy 289.111322 -332.750145)
			(xy 289.12682 -332.697643) (xy 289.149666 -332.647896) (xy 289.179393 -332.601929) (xy 289.197034 -332.580996)
			(xy 289.20313 -332.573884) (xy 289.20948 -332.556866) (xy 289.20948 -332.471522) (xy 289.20313 -332.454504)
			(xy 289.197034 -332.447392) (xy 289.179387 -332.426464) (xy 289.149662 -332.380496) (xy 289.126817 -332.330749)
			(xy 289.111321 -332.278246) (xy 289.103492 -332.224066) (xy 289.103493 -332.169325) (xy 289.111322 -332.115145)
			(xy 289.12682 -332.062643) (xy 289.149666 -332.012896) (xy 289.179393 -331.966929) (xy 289.197034 -331.945996)
			(xy 289.20313 -331.938884) (xy 289.20948 -331.921866) (xy 289.20948 -331.836522) (xy 289.20313 -331.819504)
			(xy 289.197034 -331.812392) (xy 289.179387 -331.791464) (xy 289.149662 -331.745496) (xy 289.126817 -331.695749)
			(xy 289.111321 -331.643246) (xy 289.103492 -331.589066) (xy 289.103493 -331.534325) (xy 289.111322 -331.480145)
			(xy 289.12682 -331.427643) (xy 289.149666 -331.377896) (xy 289.179393 -331.331929) (xy 289.197034 -331.310996)
			(xy 289.20313 -331.303884) (xy 289.20948 -331.286866) (xy 289.20948 -331.201522) (xy 289.20313 -331.184504)
			(xy 289.197034 -331.177392) (xy 289.179387 -331.156464) (xy 289.149662 -331.110496) (xy 289.126817 -331.060749)
			(xy 289.111321 -331.008246) (xy 289.103492 -330.954066) (xy 289.103493 -330.899325) (xy 289.111322 -330.845145)
			(xy 289.12682 -330.792643) (xy 289.149666 -330.742896) (xy 289.179393 -330.696929) (xy 289.197034 -330.675996)
			(xy 289.20313 -330.668884) (xy 289.20948 -330.651866) (xy 289.20948 -330.566522) (xy 289.20313 -330.549504)
			(xy 289.197034 -330.542392) (xy 289.179383 -330.521469) (xy 289.149672 -330.475495) (xy 289.126838 -330.425745)
			(xy 289.111349 -330.373242) (xy 289.103525 -330.319064) (xy 289.103054 -330.291694) (xy 289.103572 -330.264444)
			(xy 289.111328 -330.2105) (xy 289.126682 -330.158208) (xy 289.149321 -330.108633) (xy 289.178785 -330.062785)
			(xy 289.214473 -330.021595) (xy 289.255659 -329.985904) (xy 289.301505 -329.956437) (xy 289.351078 -329.933794)
			(xy 289.403368 -329.918435) (xy 289.457312 -329.910674) (xy 289.484562 -329.910186) (xy 289.511931 -329.910678)
			(xy 289.566109 -329.91849) (xy 289.618612 -329.933973) (xy 289.668359 -329.956809) (xy 289.714327 -329.986528)
			(xy 289.73526 -330.004166) (xy 289.742372 -330.010262) (xy 289.75939 -330.016612) (xy 289.844734 -330.016612)
			(xy 289.861752 -330.010262) (xy 289.868864 -330.004166) (xy 289.889797 -329.986525) (xy 289.935765 -329.956801)
			(xy 289.985511 -329.933955) (xy 290.038013 -329.918459) (xy 290.092191 -329.91063) (xy 290.146933 -329.91063)
			(xy 290.201111 -329.918459) (xy 290.253613 -329.933955) (xy 290.303359 -329.956801) (xy 290.349327 -329.986525)
			(xy 290.37026 -330.004166) (xy 290.377372 -330.010262) (xy 290.39439 -330.016612) (xy 290.479734 -330.016612)
			(xy 290.496752 -330.010262) (xy 290.503864 -330.004166) (xy 290.524794 -329.986525) (xy 290.570768 -329.956815)
			(xy 290.620516 -329.93398) (xy 290.673017 -329.918489) (xy 290.727193 -329.91066) (xy 290.754562 -329.910186)
			(xy 290.781814 -329.910691) (xy 290.835763 -329.918442) (xy 290.88806 -329.933793) (xy 290.937639 -329.956431)
			(xy 290.983492 -329.985894) (xy 291.024685 -330.021584) (xy 291.060379 -330.062773) (xy 291.089848 -330.108622)
			(xy 291.112491 -330.158199) (xy 291.127848 -330.210494) (xy 291.135606 -330.264442) (xy 291.13607 -330.291694)
			(xy 291.135608 -330.319064) (xy 291.12779 -330.373244) (xy 291.112301 -330.425747) (xy 291.089458 -330.475494)
			(xy 291.059732 -330.521461) (xy 291.04209 -330.542392) (xy 291.035994 -330.549504) (xy 291.029644 -330.566522)
			(xy 291.029644 -330.651866) (xy 291.035994 -330.668884) (xy 291.04209 -330.675996) (xy 291.059724 -330.696934)
			(xy 291.089448 -330.742901) (xy 291.112293 -330.792647) (xy 291.127789 -330.845148) (xy 291.135617 -330.899325)
			(xy 291.135618 -330.954066) (xy 291.12779 -331.008243) (xy 291.112296 -331.060745) (xy 291.089452 -331.110491)
			(xy 291.05973 -331.156459) (xy 291.04209 -331.177392) (xy 291.035994 -331.184504) (xy 291.029644 -331.201522)
			(xy 291.029644 -331.286866) (xy 291.035994 -331.303884) (xy 291.04209 -331.310996) (xy 291.059724 -331.331934)
			(xy 291.089448 -331.377901) (xy 291.112293 -331.427647) (xy 291.127789 -331.480148) (xy 291.135617 -331.534325)
			(xy 291.135618 -331.589066) (xy 291.12779 -331.643243) (xy 291.112296 -331.695745) (xy 291.089452 -331.745491)
			(xy 291.05973 -331.791459) (xy 291.04209 -331.812392) (xy 291.035994 -331.819504) (xy 291.029644 -331.836522)
			(xy 291.029644 -331.921866) (xy 291.035994 -331.938884) (xy 291.04209 -331.945996) (xy 291.059724 -331.966934)
			(xy 291.089448 -332.012901) (xy 291.112293 -332.062647) (xy 291.127789 -332.115148) (xy 291.135617 -332.169325)
			(xy 291.135618 -332.224066) (xy 291.12779 -332.278243) (xy 291.112296 -332.330745) (xy 291.089452 -332.380491)
			(xy 291.05973 -332.426459) (xy 291.04209 -332.447392) (xy 291.035994 -332.454504) (xy 291.029644 -332.471522)
			(xy 291.029644 -332.556866) (xy 291.035994 -332.573884) (xy 291.04209 -332.580996) (xy 291.059724 -332.601934)
			(xy 291.089448 -332.647901) (xy 291.112293 -332.697647) (xy 291.127789 -332.750148) (xy 291.135617 -332.804325)
			(xy 291.135618 -332.859066) (xy 291.12779 -332.913243) (xy 291.112296 -332.965745) (xy 291.089452 -333.015491)
			(xy 291.05973 -333.061459) (xy 291.04209 -333.082392) (xy 291.035994 -333.089504) (xy 291.029644 -333.106522)
			(xy 291.029644 -333.191866) (xy 291.035994 -333.208884) (xy 291.04209 -333.215996) (xy 291.059724 -333.236934)
			(xy 291.089448 -333.282901) (xy 291.112293 -333.332647) (xy 291.127789 -333.385148) (xy 291.135617 -333.439325)
			(xy 291.135618 -333.494066) (xy 291.12779 -333.548243) (xy 291.112296 -333.600745) (xy 291.089452 -333.650491)
			(xy 291.05973 -333.696459) (xy 291.04209 -333.717392) (xy 291.035994 -333.724504) (xy 291.029644 -333.741522)
			(xy 291.029644 -333.826866) (xy 291.035994 -333.843884) (xy 291.04209 -333.850996) (xy 291.059724 -333.871934)
			(xy 291.089448 -333.917901) (xy 291.112293 -333.967647) (xy 291.127789 -334.020148) (xy 291.135617 -334.074325)
			(xy 291.135618 -334.129066) (xy 291.12779 -334.183243) (xy 291.112296 -334.235745) (xy 291.089452 -334.285491)
			(xy 291.05973 -334.331459) (xy 291.04209 -334.352392) (xy 291.035994 -334.359504) (xy 291.029644 -334.376522)
			(xy 291.029644 -334.461866) (xy 291.035994 -334.478884) (xy 291.04209 -334.485996) (xy 291.059739 -334.50692)
			(xy 291.08945 -334.552895) (xy 291.112284 -334.602644) (xy 291.127773 -334.655147) (xy 291.135598 -334.709324)
			(xy 291.13607 -334.736694) (xy 293.116254 -334.736694) (xy 293.116703 -334.709323) (xy 293.124523 -334.655143)
			(xy 293.140015 -334.602639) (xy 293.162861 -334.552892) (xy 293.19259 -334.506927) (xy 293.210234 -334.485996)
			(xy 293.21633 -334.478884) (xy 293.22268 -334.461866) (xy 293.22268 -334.376522) (xy 293.21633 -334.359504)
			(xy 293.210234 -334.352392) (xy 293.192587 -334.331464) (xy 293.162862 -334.285496) (xy 293.140017 -334.235749)
			(xy 293.124521 -334.183246) (xy 293.116692 -334.129066) (xy 293.116693 -334.074325) (xy 293.124522 -334.020145)
			(xy 293.14002 -333.967643) (xy 293.162866 -333.917896) (xy 293.192593 -333.871929) (xy 293.210234 -333.850996)
			(xy 293.21633 -333.843884) (xy 293.22268 -333.826866) (xy 293.22268 -333.741522) (xy 293.21633 -333.724504)
			(xy 293.210234 -333.717392) (xy 293.192587 -333.696464) (xy 293.162862 -333.650496) (xy 293.140017 -333.600749)
			(xy 293.124521 -333.548246) (xy 293.116692 -333.494066) (xy 293.116693 -333.439325) (xy 293.124522 -333.385145)
			(xy 293.14002 -333.332643) (xy 293.162866 -333.282896) (xy 293.192593 -333.236929) (xy 293.210234 -333.215996)
			(xy 293.21633 -333.208884) (xy 293.22268 -333.191866) (xy 293.22268 -333.106522) (xy 293.21633 -333.089504)
			(xy 293.210234 -333.082392) (xy 293.192587 -333.061464) (xy 293.162862 -333.015496) (xy 293.140017 -332.965749)
			(xy 293.124521 -332.913246) (xy 293.116692 -332.859066) (xy 293.116693 -332.804325) (xy 293.124522 -332.750145)
			(xy 293.14002 -332.697643) (xy 293.162866 -332.647896) (xy 293.192593 -332.601929) (xy 293.210234 -332.580996)
			(xy 293.21633 -332.573884) (xy 293.22268 -332.556866) (xy 293.22268 -332.471522) (xy 293.21633 -332.454504)
			(xy 293.210234 -332.447392) (xy 293.192587 -332.426464) (xy 293.162862 -332.380496) (xy 293.140017 -332.330749)
			(xy 293.124521 -332.278246) (xy 293.116692 -332.224066) (xy 293.116693 -332.169325) (xy 293.124522 -332.115145)
			(xy 293.14002 -332.062643) (xy 293.162866 -332.012896) (xy 293.192593 -331.966929) (xy 293.210234 -331.945996)
			(xy 293.21633 -331.938884) (xy 293.22268 -331.921866) (xy 293.22268 -331.836522) (xy 293.21633 -331.819504)
			(xy 293.210234 -331.812392) (xy 293.192587 -331.791464) (xy 293.162862 -331.745496) (xy 293.140017 -331.695749)
			(xy 293.124521 -331.643246) (xy 293.116692 -331.589066) (xy 293.116693 -331.534325) (xy 293.124522 -331.480145)
			(xy 293.14002 -331.427643) (xy 293.162866 -331.377896) (xy 293.192593 -331.331929) (xy 293.210234 -331.310996)
			(xy 293.21633 -331.303884) (xy 293.22268 -331.286866) (xy 293.22268 -331.201522) (xy 293.21633 -331.184504)
			(xy 293.210234 -331.177392) (xy 293.192587 -331.156464) (xy 293.162862 -331.110496) (xy 293.140017 -331.060749)
			(xy 293.124521 -331.008246) (xy 293.116692 -330.954066) (xy 293.116693 -330.899325) (xy 293.124522 -330.845145)
			(xy 293.14002 -330.792643) (xy 293.162866 -330.742896) (xy 293.192593 -330.696929) (xy 293.210234 -330.675996)
			(xy 293.21633 -330.668884) (xy 293.22268 -330.651866) (xy 293.22268 -330.566522) (xy 293.21633 -330.549504)
			(xy 293.210234 -330.542392) (xy 293.192583 -330.521469) (xy 293.162872 -330.475495) (xy 293.140038 -330.425745)
			(xy 293.124549 -330.373242) (xy 293.116725 -330.319064) (xy 293.116254 -330.291694) (xy 293.116772 -330.264444)
			(xy 293.124528 -330.2105) (xy 293.139882 -330.158208) (xy 293.162521 -330.108633) (xy 293.191985 -330.062785)
			(xy 293.227673 -330.021595) (xy 293.268859 -329.985904) (xy 293.314705 -329.956437) (xy 293.364278 -329.933794)
			(xy 293.416568 -329.918435) (xy 293.470512 -329.910674) (xy 293.497762 -329.910186) (xy 293.525131 -329.910678)
			(xy 293.579309 -329.91849) (xy 293.631812 -329.933973) (xy 293.681559 -329.956809) (xy 293.727527 -329.986528)
			(xy 293.74846 -330.004166) (xy 293.755572 -330.010262) (xy 293.77259 -330.016612) (xy 293.857934 -330.016612)
			(xy 293.874952 -330.010262) (xy 293.882064 -330.004166) (xy 293.902997 -329.986525) (xy 293.948965 -329.956801)
			(xy 293.998711 -329.933955) (xy 294.051213 -329.918459) (xy 294.105391 -329.91063) (xy 294.160133 -329.91063)
			(xy 294.214311 -329.918459) (xy 294.266813 -329.933955) (xy 294.316559 -329.956801) (xy 294.362527 -329.986525)
			(xy 294.38346 -330.004166) (xy 294.390572 -330.010262) (xy 294.40759 -330.016612) (xy 294.492934 -330.016612)
			(xy 294.509952 -330.010262) (xy 294.517064 -330.004166) (xy 294.537994 -329.986525) (xy 294.583968 -329.956815)
			(xy 294.633716 -329.93398) (xy 294.686217 -329.918489) (xy 294.740393 -329.91066) (xy 294.767762 -329.910186)
			(xy 294.795014 -329.910691) (xy 294.848963 -329.918442) (xy 294.90126 -329.933793) (xy 294.950839 -329.956431)
			(xy 294.996692 -329.985894) (xy 295.037885 -330.021584) (xy 295.073579 -330.062773) (xy 295.103048 -330.108622)
			(xy 295.125691 -330.158199) (xy 295.141048 -330.210494) (xy 295.148806 -330.264442) (xy 295.14927 -330.291694)
			(xy 295.148808 -330.319064) (xy 295.14099 -330.373244) (xy 295.125501 -330.425747) (xy 295.102658 -330.475494)
			(xy 295.072932 -330.521461) (xy 295.05529 -330.542392) (xy 295.049194 -330.549504) (xy 295.042844 -330.566522)
			(xy 295.042844 -330.651866) (xy 295.049194 -330.668884) (xy 295.05529 -330.675996) (xy 295.072924 -330.696934)
			(xy 295.102648 -330.742901) (xy 295.125493 -330.792647) (xy 295.140989 -330.845148) (xy 295.148817 -330.899325)
			(xy 295.148818 -330.954066) (xy 295.14099 -331.008243) (xy 295.125496 -331.060745) (xy 295.102652 -331.110491)
			(xy 295.07293 -331.156459) (xy 295.05529 -331.177392) (xy 295.049194 -331.184504) (xy 295.042844 -331.201522)
			(xy 295.042844 -331.286866) (xy 295.049194 -331.303884) (xy 295.05529 -331.310996) (xy 295.072924 -331.331934)
			(xy 295.102648 -331.377901) (xy 295.125493 -331.427647) (xy 295.140989 -331.480148) (xy 295.148817 -331.534325)
			(xy 295.148818 -331.589066) (xy 295.14099 -331.643243) (xy 295.125496 -331.695745) (xy 295.102652 -331.745491)
			(xy 295.07293 -331.791459) (xy 295.05529 -331.812392) (xy 295.049194 -331.819504) (xy 295.042844 -331.836522)
			(xy 295.042844 -331.921866) (xy 295.049194 -331.938884) (xy 295.05529 -331.945996) (xy 295.072924 -331.966934)
			(xy 295.102648 -332.012901) (xy 295.125493 -332.062647) (xy 295.140989 -332.115148) (xy 295.148817 -332.169325)
			(xy 295.148818 -332.224066) (xy 295.14099 -332.278243) (xy 295.125496 -332.330745) (xy 295.102652 -332.380491)
			(xy 295.07293 -332.426459) (xy 295.05529 -332.447392) (xy 295.049194 -332.454504) (xy 295.042844 -332.471522)
			(xy 295.042844 -332.556866) (xy 295.049194 -332.573884) (xy 295.05529 -332.580996) (xy 295.072924 -332.601934)
			(xy 295.102648 -332.647901) (xy 295.125493 -332.697647) (xy 295.140989 -332.750148) (xy 295.148817 -332.804325)
			(xy 295.148818 -332.859066) (xy 295.14099 -332.913243) (xy 295.125496 -332.965745) (xy 295.102652 -333.015491)
			(xy 295.07293 -333.061459) (xy 295.05529 -333.082392) (xy 295.049194 -333.089504) (xy 295.042844 -333.106522)
			(xy 295.042844 -333.191866) (xy 295.049194 -333.208884) (xy 295.05529 -333.215996) (xy 295.072924 -333.236934)
			(xy 295.102648 -333.282901) (xy 295.125493 -333.332647) (xy 295.140989 -333.385148) (xy 295.148817 -333.439325)
			(xy 295.148818 -333.494066) (xy 295.14099 -333.548243) (xy 295.125496 -333.600745) (xy 295.102652 -333.650491)
			(xy 295.07293 -333.696459) (xy 295.05529 -333.717392) (xy 295.049194 -333.724504) (xy 295.042844 -333.741522)
			(xy 295.042844 -333.826866) (xy 295.049194 -333.843884) (xy 295.05529 -333.850996) (xy 295.072924 -333.871934)
			(xy 295.102648 -333.917901) (xy 295.125493 -333.967647) (xy 295.140989 -334.020148) (xy 295.148817 -334.074325)
			(xy 295.148818 -334.129066) (xy 295.14099 -334.183243) (xy 295.125496 -334.235745) (xy 295.102652 -334.285491)
			(xy 295.07293 -334.331459) (xy 295.05529 -334.352392) (xy 295.049194 -334.359504) (xy 295.042844 -334.376522)
			(xy 295.042844 -334.461866) (xy 295.049194 -334.478884) (xy 295.05529 -334.485996) (xy 295.072939 -334.50692)
			(xy 295.10265 -334.552895) (xy 295.125484 -334.602644) (xy 295.140973 -334.655147) (xy 295.148798 -334.709324)
			(xy 295.14927 -334.736694) (xy 297.459654 -334.736694) (xy 297.460103 -334.709323) (xy 297.467923 -334.655143)
			(xy 297.483415 -334.602639) (xy 297.506261 -334.552892) (xy 297.53599 -334.506927) (xy 297.553634 -334.485996)
			(xy 297.55973 -334.478884) (xy 297.56608 -334.461866) (xy 297.56608 -334.376522) (xy 297.55973 -334.359504)
			(xy 297.553634 -334.352392) (xy 297.535987 -334.331464) (xy 297.506262 -334.285496) (xy 297.483417 -334.235749)
			(xy 297.467921 -334.183246) (xy 297.460092 -334.129066) (xy 297.460093 -334.074325) (xy 297.467922 -334.020145)
			(xy 297.48342 -333.967643) (xy 297.506266 -333.917896) (xy 297.535993 -333.871929) (xy 297.553634 -333.850996)
			(xy 297.55973 -333.843884) (xy 297.56608 -333.826866) (xy 297.56608 -333.741522) (xy 297.55973 -333.724504)
			(xy 297.553634 -333.717392) (xy 297.535987 -333.696464) (xy 297.506262 -333.650496) (xy 297.483417 -333.600749)
			(xy 297.467921 -333.548246) (xy 297.460092 -333.494066) (xy 297.460093 -333.439325) (xy 297.467922 -333.385145)
			(xy 297.48342 -333.332643) (xy 297.506266 -333.282896) (xy 297.535993 -333.236929) (xy 297.553634 -333.215996)
			(xy 297.55973 -333.208884) (xy 297.56608 -333.191866) (xy 297.56608 -333.106522) (xy 297.55973 -333.089504)
			(xy 297.553634 -333.082392) (xy 297.535987 -333.061464) (xy 297.506262 -333.015496) (xy 297.483417 -332.965749)
			(xy 297.467921 -332.913246) (xy 297.460092 -332.859066) (xy 297.460093 -332.804325) (xy 297.467922 -332.750145)
			(xy 297.48342 -332.697643) (xy 297.506266 -332.647896) (xy 297.535993 -332.601929) (xy 297.553634 -332.580996)
			(xy 297.55973 -332.573884) (xy 297.56608 -332.556866) (xy 297.56608 -332.471522) (xy 297.55973 -332.454504)
			(xy 297.553634 -332.447392) (xy 297.535987 -332.426464) (xy 297.506262 -332.380496) (xy 297.483417 -332.330749)
			(xy 297.467921 -332.278246) (xy 297.460092 -332.224066) (xy 297.460093 -332.169325) (xy 297.467922 -332.115145)
			(xy 297.48342 -332.062643) (xy 297.506266 -332.012896) (xy 297.535993 -331.966929) (xy 297.553634 -331.945996)
			(xy 297.55973 -331.938884) (xy 297.56608 -331.921866) (xy 297.56608 -331.836522) (xy 297.55973 -331.819504)
			(xy 297.553634 -331.812392) (xy 297.535987 -331.791464) (xy 297.506262 -331.745496) (xy 297.483417 -331.695749)
			(xy 297.467921 -331.643246) (xy 297.460092 -331.589066) (xy 297.460093 -331.534325) (xy 297.467922 -331.480145)
			(xy 297.48342 -331.427643) (xy 297.506266 -331.377896) (xy 297.535993 -331.331929) (xy 297.553634 -331.310996)
			(xy 297.55973 -331.303884) (xy 297.56608 -331.286866) (xy 297.56608 -331.201522) (xy 297.55973 -331.184504)
			(xy 297.553634 -331.177392) (xy 297.535987 -331.156464) (xy 297.506262 -331.110496) (xy 297.483417 -331.060749)
			(xy 297.467921 -331.008246) (xy 297.460092 -330.954066) (xy 297.460093 -330.899325) (xy 297.467922 -330.845145)
			(xy 297.48342 -330.792643) (xy 297.506266 -330.742896) (xy 297.535993 -330.696929) (xy 297.553634 -330.675996)
			(xy 297.55973 -330.668884) (xy 297.56608 -330.651866) (xy 297.56608 -330.566522) (xy 297.55973 -330.549504)
			(xy 297.553634 -330.542392) (xy 297.535983 -330.521469) (xy 297.506272 -330.475495) (xy 297.483438 -330.425745)
			(xy 297.467949 -330.373242) (xy 297.460125 -330.319064) (xy 297.459654 -330.291694) (xy 297.460172 -330.264444)
			(xy 297.467928 -330.2105) (xy 297.483282 -330.158208) (xy 297.505921 -330.108633) (xy 297.535385 -330.062785)
			(xy 297.571073 -330.021595) (xy 297.612259 -329.985904) (xy 297.658105 -329.956437) (xy 297.707678 -329.933794)
			(xy 297.759968 -329.918435) (xy 297.813912 -329.910674) (xy 297.841162 -329.910186) (xy 297.868531 -329.910678)
			(xy 297.922709 -329.91849) (xy 297.975212 -329.933973) (xy 298.024959 -329.956809) (xy 298.070927 -329.986528)
			(xy 298.09186 -330.004166) (xy 298.098972 -330.010262) (xy 298.11599 -330.016612) (xy 298.201334 -330.016612)
			(xy 298.218352 -330.010262) (xy 298.225464 -330.004166) (xy 298.246397 -329.986525) (xy 298.292365 -329.956801)
			(xy 298.342111 -329.933955) (xy 298.394613 -329.918459) (xy 298.448791 -329.91063) (xy 298.503533 -329.91063)
			(xy 298.557711 -329.918459) (xy 298.610213 -329.933955) (xy 298.659959 -329.956801) (xy 298.705927 -329.986525)
			(xy 298.72686 -330.004166) (xy 298.733972 -330.010262) (xy 298.75099 -330.016612) (xy 298.836334 -330.016612)
			(xy 298.853352 -330.010262) (xy 298.860464 -330.004166) (xy 298.881394 -329.986525) (xy 298.927368 -329.956815)
			(xy 298.977116 -329.93398) (xy 299.029617 -329.918489) (xy 299.083793 -329.91066) (xy 299.111162 -329.910186)
			(xy 299.138414 -329.910691) (xy 299.192363 -329.918442) (xy 299.24466 -329.933793) (xy 299.294239 -329.956431)
			(xy 299.340092 -329.985894) (xy 299.381285 -330.021584) (xy 299.416979 -330.062773) (xy 299.446448 -330.108622)
			(xy 299.469091 -330.158199) (xy 299.484448 -330.210494) (xy 299.492206 -330.264442) (xy 299.49267 -330.291694)
			(xy 299.492208 -330.319064) (xy 299.48439 -330.373244) (xy 299.468901 -330.425747) (xy 299.446058 -330.475494)
			(xy 299.416332 -330.521461) (xy 299.39869 -330.542392) (xy 299.392594 -330.549504) (xy 299.386244 -330.566522)
			(xy 299.386244 -330.651866) (xy 299.392594 -330.668884) (xy 299.39869 -330.675996) (xy 299.416324 -330.696934)
			(xy 299.446048 -330.742901) (xy 299.468893 -330.792647) (xy 299.484389 -330.845148) (xy 299.492217 -330.899325)
			(xy 299.492218 -330.954066) (xy 299.48439 -331.008243) (xy 299.468896 -331.060745) (xy 299.446052 -331.110491)
			(xy 299.41633 -331.156459) (xy 299.39869 -331.177392) (xy 299.392594 -331.184504) (xy 299.386244 -331.201522)
			(xy 299.386244 -331.286866) (xy 299.392594 -331.303884) (xy 299.39869 -331.310996) (xy 299.416324 -331.331934)
			(xy 299.446048 -331.377901) (xy 299.468893 -331.427647) (xy 299.484389 -331.480148) (xy 299.492217 -331.534325)
			(xy 299.492218 -331.589066) (xy 299.48439 -331.643243) (xy 299.468896 -331.695745) (xy 299.446052 -331.745491)
			(xy 299.41633 -331.791459) (xy 299.39869 -331.812392) (xy 299.392594 -331.819504) (xy 299.386244 -331.836522)
			(xy 299.386244 -331.921866) (xy 299.392594 -331.938884) (xy 299.39869 -331.945996) (xy 299.416324 -331.966934)
			(xy 299.446048 -332.012901) (xy 299.468893 -332.062647) (xy 299.484389 -332.115148) (xy 299.492217 -332.169325)
			(xy 299.492218 -332.224066) (xy 299.48439 -332.278243) (xy 299.468896 -332.330745) (xy 299.446052 -332.380491)
			(xy 299.41633 -332.426459) (xy 299.39869 -332.447392) (xy 299.392594 -332.454504) (xy 299.386244 -332.471522)
			(xy 299.386244 -332.556866) (xy 299.392594 -332.573884) (xy 299.39869 -332.580996) (xy 299.416324 -332.601934)
			(xy 299.446048 -332.647901) (xy 299.468893 -332.697647) (xy 299.484389 -332.750148) (xy 299.492217 -332.804325)
			(xy 299.492218 -332.859066) (xy 299.48439 -332.913243) (xy 299.468896 -332.965745) (xy 299.446052 -333.015491)
			(xy 299.41633 -333.061459) (xy 299.39869 -333.082392) (xy 299.392594 -333.089504) (xy 299.386244 -333.106522)
			(xy 299.386244 -333.191866) (xy 299.392594 -333.208884) (xy 299.39869 -333.215996) (xy 299.416324 -333.236934)
			(xy 299.446048 -333.282901) (xy 299.468893 -333.332647) (xy 299.484389 -333.385148) (xy 299.492217 -333.439325)
			(xy 299.492218 -333.494066) (xy 299.48439 -333.548243) (xy 299.468896 -333.600745) (xy 299.446052 -333.650491)
			(xy 299.41633 -333.696459) (xy 299.39869 -333.717392) (xy 299.392594 -333.724504) (xy 299.386244 -333.741522)
			(xy 299.386244 -333.826866) (xy 299.392594 -333.843884) (xy 299.39869 -333.850996) (xy 299.416324 -333.871934)
			(xy 299.446048 -333.917901) (xy 299.468893 -333.967647) (xy 299.484389 -334.020148) (xy 299.492217 -334.074325)
			(xy 299.492218 -334.129066) (xy 299.48439 -334.183243) (xy 299.468896 -334.235745) (xy 299.446052 -334.285491)
			(xy 299.41633 -334.331459) (xy 299.39869 -334.352392) (xy 299.392594 -334.359504) (xy 299.386244 -334.376522)
			(xy 299.386244 -334.461866) (xy 299.392594 -334.478884) (xy 299.39869 -334.485996) (xy 299.416339 -334.50692)
			(xy 299.44605 -334.552895) (xy 299.468884 -334.602644) (xy 299.484373 -334.655147) (xy 299.492198 -334.709324)
			(xy 299.49267 -334.736694) (xy 301.472854 -334.736694) (xy 301.473303 -334.709323) (xy 301.481123 -334.655143)
			(xy 301.496615 -334.602639) (xy 301.519461 -334.552892) (xy 301.54919 -334.506927) (xy 301.566834 -334.485996)
			(xy 301.57293 -334.478884) (xy 301.57928 -334.461866) (xy 301.57928 -334.376522) (xy 301.57293 -334.359504)
			(xy 301.566834 -334.352392) (xy 301.549187 -334.331464) (xy 301.519462 -334.285496) (xy 301.496617 -334.235749)
			(xy 301.481121 -334.183246) (xy 301.473292 -334.129066) (xy 301.473293 -334.074325) (xy 301.481122 -334.020145)
			(xy 301.49662 -333.967643) (xy 301.519466 -333.917896) (xy 301.549193 -333.871929) (xy 301.566834 -333.850996)
			(xy 301.57293 -333.843884) (xy 301.57928 -333.826866) (xy 301.57928 -333.741522) (xy 301.57293 -333.724504)
			(xy 301.566834 -333.717392) (xy 301.549187 -333.696464) (xy 301.519462 -333.650496) (xy 301.496617 -333.600749)
			(xy 301.481121 -333.548246) (xy 301.473292 -333.494066) (xy 301.473293 -333.439325) (xy 301.481122 -333.385145)
			(xy 301.49662 -333.332643) (xy 301.519466 -333.282896) (xy 301.549193 -333.236929) (xy 301.566834 -333.215996)
			(xy 301.57293 -333.208884) (xy 301.57928 -333.191866) (xy 301.57928 -333.106522) (xy 301.57293 -333.089504)
			(xy 301.566834 -333.082392) (xy 301.549187 -333.061464) (xy 301.519462 -333.015496) (xy 301.496617 -332.965749)
			(xy 301.481121 -332.913246) (xy 301.473292 -332.859066) (xy 301.473293 -332.804325) (xy 301.481122 -332.750145)
			(xy 301.49662 -332.697643) (xy 301.519466 -332.647896) (xy 301.549193 -332.601929) (xy 301.566834 -332.580996)
			(xy 301.57293 -332.573884) (xy 301.57928 -332.556866) (xy 301.57928 -332.471522) (xy 301.57293 -332.454504)
			(xy 301.566834 -332.447392) (xy 301.549187 -332.426464) (xy 301.519462 -332.380496) (xy 301.496617 -332.330749)
			(xy 301.481121 -332.278246) (xy 301.473292 -332.224066) (xy 301.473293 -332.169325) (xy 301.481122 -332.115145)
			(xy 301.49662 -332.062643) (xy 301.519466 -332.012896) (xy 301.549193 -331.966929) (xy 301.566834 -331.945996)
			(xy 301.57293 -331.938884) (xy 301.57928 -331.921866) (xy 301.57928 -331.836522) (xy 301.57293 -331.819504)
			(xy 301.566834 -331.812392) (xy 301.549187 -331.791464) (xy 301.519462 -331.745496) (xy 301.496617 -331.695749)
			(xy 301.481121 -331.643246) (xy 301.473292 -331.589066) (xy 301.473293 -331.534325) (xy 301.481122 -331.480145)
			(xy 301.49662 -331.427643) (xy 301.519466 -331.377896) (xy 301.549193 -331.331929) (xy 301.566834 -331.310996)
			(xy 301.57293 -331.303884) (xy 301.57928 -331.286866) (xy 301.57928 -331.201522) (xy 301.57293 -331.184504)
			(xy 301.566834 -331.177392) (xy 301.549187 -331.156464) (xy 301.519462 -331.110496) (xy 301.496617 -331.060749)
			(xy 301.481121 -331.008246) (xy 301.473292 -330.954066) (xy 301.473293 -330.899325) (xy 301.481122 -330.845145)
			(xy 301.49662 -330.792643) (xy 301.519466 -330.742896) (xy 301.549193 -330.696929) (xy 301.566834 -330.675996)
			(xy 301.57293 -330.668884) (xy 301.57928 -330.651866) (xy 301.57928 -330.566522) (xy 301.57293 -330.549504)
			(xy 301.566834 -330.542392) (xy 301.549183 -330.521469) (xy 301.519472 -330.475495) (xy 301.496638 -330.425745)
			(xy 301.481149 -330.373242) (xy 301.473325 -330.319064) (xy 301.472854 -330.291694) (xy 301.473372 -330.264444)
			(xy 301.481128 -330.2105) (xy 301.496482 -330.158208) (xy 301.519121 -330.108633) (xy 301.548585 -330.062785)
			(xy 301.584273 -330.021595) (xy 301.625459 -329.985904) (xy 301.671305 -329.956437) (xy 301.720878 -329.933794)
			(xy 301.773168 -329.918435) (xy 301.827112 -329.910674) (xy 301.854362 -329.910186) (xy 301.881731 -329.910678)
			(xy 301.935909 -329.91849) (xy 301.988412 -329.933973) (xy 302.038159 -329.956809) (xy 302.084127 -329.986528)
			(xy 302.10506 -330.004166) (xy 302.112172 -330.010262) (xy 302.12919 -330.016612) (xy 302.214534 -330.016612)
			(xy 302.231552 -330.010262) (xy 302.238664 -330.004166) (xy 302.259597 -329.986525) (xy 302.305565 -329.956801)
			(xy 302.355311 -329.933955) (xy 302.407813 -329.918459) (xy 302.461991 -329.91063) (xy 302.516733 -329.91063)
			(xy 302.570911 -329.918459) (xy 302.623413 -329.933955) (xy 302.673159 -329.956801) (xy 302.719127 -329.986525)
			(xy 302.74006 -330.004166) (xy 302.747172 -330.010262) (xy 302.76419 -330.016612) (xy 302.849534 -330.016612)
			(xy 302.866552 -330.010262) (xy 302.873664 -330.004166) (xy 302.894594 -329.986525) (xy 302.940568 -329.956815)
			(xy 302.990316 -329.93398) (xy 303.042817 -329.918489) (xy 303.096993 -329.91066) (xy 303.124362 -329.910186)
			(xy 303.151614 -329.910691) (xy 303.205563 -329.918442) (xy 303.25786 -329.933793) (xy 303.307439 -329.956431)
			(xy 303.353292 -329.985894) (xy 303.394485 -330.021584) (xy 303.430179 -330.062773) (xy 303.459648 -330.108622)
			(xy 303.482291 -330.158199) (xy 303.497648 -330.210494) (xy 303.505406 -330.264442) (xy 303.50587 -330.291694)
			(xy 303.505408 -330.319064) (xy 303.49759 -330.373244) (xy 303.482101 -330.425747) (xy 303.459258 -330.475494)
			(xy 303.429532 -330.521461) (xy 303.41189 -330.542392) (xy 303.405794 -330.549504) (xy 303.399444 -330.566522)
			(xy 303.399444 -330.651866) (xy 303.405794 -330.668884) (xy 303.41189 -330.675996) (xy 303.429524 -330.696934)
			(xy 303.459248 -330.742901) (xy 303.482093 -330.792647) (xy 303.497589 -330.845148) (xy 303.505417 -330.899325)
			(xy 303.505418 -330.954066) (xy 303.49759 -331.008243) (xy 303.482096 -331.060745) (xy 303.459252 -331.110491)
			(xy 303.42953 -331.156459) (xy 303.41189 -331.177392) (xy 303.405794 -331.184504) (xy 303.399444 -331.201522)
			(xy 303.399444 -331.286866) (xy 303.405794 -331.303884) (xy 303.41189 -331.310996) (xy 303.429524 -331.331934)
			(xy 303.459248 -331.377901) (xy 303.482093 -331.427647) (xy 303.497589 -331.480148) (xy 303.505417 -331.534325)
			(xy 303.505418 -331.589066) (xy 303.49759 -331.643243) (xy 303.482096 -331.695745) (xy 303.459252 -331.745491)
			(xy 303.42953 -331.791459) (xy 303.41189 -331.812392) (xy 303.405794 -331.819504) (xy 303.399444 -331.836522)
			(xy 303.399444 -331.921866) (xy 303.405794 -331.938884) (xy 303.41189 -331.945996) (xy 303.429524 -331.966934)
			(xy 303.459248 -332.012901) (xy 303.482093 -332.062647) (xy 303.497589 -332.115148) (xy 303.505417 -332.169325)
			(xy 303.505418 -332.224066) (xy 303.49759 -332.278243) (xy 303.482096 -332.330745) (xy 303.459252 -332.380491)
			(xy 303.42953 -332.426459) (xy 303.41189 -332.447392) (xy 303.405794 -332.454504) (xy 303.399444 -332.471522)
			(xy 303.399444 -332.556866) (xy 303.405794 -332.573884) (xy 303.41189 -332.580996) (xy 303.429524 -332.601934)
			(xy 303.459248 -332.647901) (xy 303.482093 -332.697647) (xy 303.497589 -332.750148) (xy 303.505417 -332.804325)
			(xy 303.505418 -332.859066) (xy 303.49759 -332.913243) (xy 303.482096 -332.965745) (xy 303.459252 -333.015491)
			(xy 303.42953 -333.061459) (xy 303.41189 -333.082392) (xy 303.405794 -333.089504) (xy 303.399444 -333.106522)
			(xy 303.399444 -333.191866) (xy 303.405794 -333.208884) (xy 303.41189 -333.215996) (xy 303.429524 -333.236934)
			(xy 303.459248 -333.282901) (xy 303.482093 -333.332647) (xy 303.497589 -333.385148) (xy 303.505417 -333.439325)
			(xy 303.505418 -333.494066) (xy 303.49759 -333.548243) (xy 303.482096 -333.600745) (xy 303.459252 -333.650491)
			(xy 303.42953 -333.696459) (xy 303.41189 -333.717392) (xy 303.405794 -333.724504) (xy 303.399444 -333.741522)
			(xy 303.399444 -333.826866) (xy 303.405794 -333.843884) (xy 303.41189 -333.850996) (xy 303.429524 -333.871934)
			(xy 303.459248 -333.917901) (xy 303.482093 -333.967647) (xy 303.497589 -334.020148) (xy 303.505417 -334.074325)
			(xy 303.505418 -334.129066) (xy 303.49759 -334.183243) (xy 303.482096 -334.235745) (xy 303.459252 -334.285491)
			(xy 303.42953 -334.331459) (xy 303.41189 -334.352392) (xy 303.405794 -334.359504) (xy 303.399444 -334.376522)
			(xy 303.399444 -334.461866) (xy 303.405794 -334.478884) (xy 303.41189 -334.485996) (xy 303.429539 -334.50692)
			(xy 303.45925 -334.552895) (xy 303.482084 -334.602644) (xy 303.497573 -334.655147) (xy 303.505398 -334.709324)
			(xy 303.50587 -334.736694) (xy 303.505439 -334.763948) (xy 303.497682 -334.817902) (xy 303.482325 -334.870203)
			(xy 303.45968 -334.919786) (xy 303.430209 -334.965641) (xy 303.394512 -335.006835) (xy 303.353315 -335.042528)
			(xy 303.307458 -335.071995) (xy 303.257873 -335.094636) (xy 303.205571 -335.109989) (xy 303.151616 -335.117741)
			(xy 303.124362 -335.118202) (xy 303.096993 -335.117699) (xy 303.042816 -335.10989) (xy 302.990313 -335.09441)
			(xy 302.940565 -335.071576) (xy 302.894597 -335.041859) (xy 302.873664 -335.024222) (xy 302.866552 -335.018126)
			(xy 302.849534 -335.011776) (xy 302.76419 -335.011776) (xy 302.747172 -335.018126) (xy 302.74006 -335.024222)
			(xy 302.719127 -335.041863) (xy 302.673159 -335.071587) (xy 302.623413 -335.094433) (xy 302.570911 -335.109929)
			(xy 302.516733 -335.117758) (xy 302.461991 -335.117758) (xy 302.407813 -335.109929) (xy 302.355311 -335.094433)
			(xy 302.305565 -335.071587) (xy 302.259597 -335.041863) (xy 302.238664 -335.024222) (xy 302.231552 -335.018126)
			(xy 302.214534 -335.011776) (xy 302.12919 -335.011776) (xy 302.112172 -335.018126) (xy 302.10506 -335.024222)
			(xy 302.084119 -335.04185) (xy 302.038148 -335.071563) (xy 301.988403 -335.0944) (xy 301.935904 -335.109894)
			(xy 301.88173 -335.117726) (xy 301.854362 -335.118202) (xy 301.82711 -335.117758) (xy 301.77316 -335.109996)
			(xy 301.720864 -335.094635) (xy 301.671286 -335.071989) (xy 301.625436 -335.042519) (xy 301.584246 -335.006823)
			(xy 301.548555 -334.965629) (xy 301.519089 -334.919775) (xy 301.496449 -334.870195) (xy 301.481095 -334.817897)
			(xy 301.473339 -334.763947) (xy 301.472854 -334.736694) (xy 299.49267 -334.736694) (xy 299.492239 -334.763948)
			(xy 299.484482 -334.817902) (xy 299.469125 -334.870203) (xy 299.44648 -334.919786) (xy 299.417009 -334.965641)
			(xy 299.381312 -335.006835) (xy 299.340115 -335.042528) (xy 299.294258 -335.071995) (xy 299.244673 -335.094636)
			(xy 299.192371 -335.109989) (xy 299.138416 -335.117741) (xy 299.111162 -335.118202) (xy 299.083793 -335.117699)
			(xy 299.029616 -335.10989) (xy 298.977113 -335.09441) (xy 298.927365 -335.071576) (xy 298.881397 -335.041859)
			(xy 298.860464 -335.024222) (xy 298.853352 -335.018126) (xy 298.836334 -335.011776) (xy 298.75099 -335.011776)
			(xy 298.733972 -335.018126) (xy 298.72686 -335.024222) (xy 298.705927 -335.041863) (xy 298.659959 -335.071587)
			(xy 298.610213 -335.094433) (xy 298.557711 -335.109929) (xy 298.503533 -335.117758) (xy 298.448791 -335.117758)
			(xy 298.394613 -335.109929) (xy 298.342111 -335.094433) (xy 298.292365 -335.071587) (xy 298.246397 -335.041863)
			(xy 298.225464 -335.024222) (xy 298.218352 -335.018126) (xy 298.201334 -335.011776) (xy 298.11599 -335.011776)
			(xy 298.098972 -335.018126) (xy 298.09186 -335.024222) (xy 298.070919 -335.04185) (xy 298.024948 -335.071563)
			(xy 297.975203 -335.0944) (xy 297.922704 -335.109894) (xy 297.86853 -335.117726) (xy 297.841162 -335.118202)
			(xy 297.81391 -335.117758) (xy 297.75996 -335.109996) (xy 297.707664 -335.094635) (xy 297.658086 -335.071989)
			(xy 297.612236 -335.042519) (xy 297.571046 -335.006823) (xy 297.535355 -334.965629) (xy 297.505889 -334.919775)
			(xy 297.483249 -334.870195) (xy 297.467895 -334.817897) (xy 297.460139 -334.763947) (xy 297.459654 -334.736694)
			(xy 295.14927 -334.736694) (xy 295.148839 -334.763948) (xy 295.141082 -334.817902) (xy 295.125725 -334.870203)
			(xy 295.10308 -334.919786) (xy 295.073609 -334.965641) (xy 295.037912 -335.006835) (xy 294.996715 -335.042528)
			(xy 294.950858 -335.071995) (xy 294.901273 -335.094636) (xy 294.848971 -335.109989) (xy 294.795016 -335.117741)
			(xy 294.767762 -335.118202) (xy 294.740393 -335.117699) (xy 294.686216 -335.10989) (xy 294.633713 -335.09441)
			(xy 294.583965 -335.071576) (xy 294.537997 -335.041859) (xy 294.517064 -335.024222) (xy 294.509952 -335.018126)
			(xy 294.492934 -335.011776) (xy 294.40759 -335.011776) (xy 294.390572 -335.018126) (xy 294.38346 -335.024222)
			(xy 294.362527 -335.041863) (xy 294.316559 -335.071587) (xy 294.266813 -335.094433) (xy 294.214311 -335.109929)
			(xy 294.160133 -335.117758) (xy 294.105391 -335.117758) (xy 294.051213 -335.109929) (xy 293.998711 -335.094433)
			(xy 293.948965 -335.071587) (xy 293.902997 -335.041863) (xy 293.882064 -335.024222) (xy 293.874952 -335.018126)
			(xy 293.857934 -335.011776) (xy 293.77259 -335.011776) (xy 293.755572 -335.018126) (xy 293.74846 -335.024222)
			(xy 293.727519 -335.04185) (xy 293.681548 -335.071563) (xy 293.631803 -335.0944) (xy 293.579304 -335.109894)
			(xy 293.52513 -335.117726) (xy 293.497762 -335.118202) (xy 293.47051 -335.117758) (xy 293.41656 -335.109996)
			(xy 293.364264 -335.094635) (xy 293.314686 -335.071989) (xy 293.268836 -335.042519) (xy 293.227646 -335.006823)
			(xy 293.191955 -334.965629) (xy 293.162489 -334.919775) (xy 293.139849 -334.870195) (xy 293.124495 -334.817897)
			(xy 293.116739 -334.763947) (xy 293.116254 -334.736694) (xy 291.13607 -334.736694) (xy 291.135639 -334.763948)
			(xy 291.127882 -334.817902) (xy 291.112525 -334.870203) (xy 291.08988 -334.919786) (xy 291.060409 -334.965641)
			(xy 291.024712 -335.006835) (xy 290.983515 -335.042528) (xy 290.937658 -335.071995) (xy 290.888073 -335.094636)
			(xy 290.835771 -335.109989) (xy 290.781816 -335.117741) (xy 290.754562 -335.118202) (xy 290.727193 -335.117699)
			(xy 290.673016 -335.10989) (xy 290.620513 -335.09441) (xy 290.570765 -335.071576) (xy 290.524797 -335.041859)
			(xy 290.503864 -335.024222) (xy 290.496752 -335.018126) (xy 290.479734 -335.011776) (xy 290.39439 -335.011776)
			(xy 290.377372 -335.018126) (xy 290.37026 -335.024222) (xy 290.349327 -335.041863) (xy 290.303359 -335.071587)
			(xy 290.253613 -335.094433) (xy 290.201111 -335.109929) (xy 290.146933 -335.117758) (xy 290.092191 -335.117758)
			(xy 290.038013 -335.109929) (xy 289.985511 -335.094433) (xy 289.935765 -335.071587) (xy 289.889797 -335.041863)
			(xy 289.868864 -335.024222) (xy 289.861752 -335.018126) (xy 289.844734 -335.011776) (xy 289.75939 -335.011776)
			(xy 289.742372 -335.018126) (xy 289.73526 -335.024222) (xy 289.714319 -335.04185) (xy 289.668348 -335.071563)
			(xy 289.618603 -335.0944) (xy 289.566104 -335.109894) (xy 289.51193 -335.117726) (xy 289.484562 -335.118202)
			(xy 289.45731 -335.117758) (xy 289.40336 -335.109996) (xy 289.351064 -335.094635) (xy 289.301486 -335.071989)
			(xy 289.255636 -335.042519) (xy 289.214446 -335.006823) (xy 289.178755 -334.965629) (xy 289.149289 -334.919775)
			(xy 289.126649 -334.870195) (xy 289.111295 -334.817897) (xy 289.103539 -334.763947) (xy 289.103054 -334.736694)
			(xy 286.84347 -334.736694) (xy 286.843039 -334.763948) (xy 286.835282 -334.817902) (xy 286.819925 -334.870203)
			(xy 286.79728 -334.919786) (xy 286.767809 -334.965641) (xy 286.732112 -335.006835) (xy 286.690915 -335.042528)
			(xy 286.645058 -335.071995) (xy 286.595473 -335.094636) (xy 286.543171 -335.109989) (xy 286.489216 -335.117741)
			(xy 286.461962 -335.118202) (xy 286.434593 -335.117699) (xy 286.380416 -335.10989) (xy 286.327913 -335.09441)
			(xy 286.278165 -335.071576) (xy 286.232197 -335.041859) (xy 286.211264 -335.024222) (xy 286.204152 -335.018126)
			(xy 286.187134 -335.011776) (xy 286.10179 -335.011776) (xy 286.084772 -335.018126) (xy 286.07766 -335.024222)
			(xy 286.056727 -335.041863) (xy 286.010759 -335.071587) (xy 285.961013 -335.094433) (xy 285.908511 -335.109929)
			(xy 285.854333 -335.117758) (xy 285.799591 -335.117758) (xy 285.745413 -335.109929) (xy 285.692911 -335.094433)
			(xy 285.643165 -335.071587) (xy 285.597197 -335.041863) (xy 285.576264 -335.024222) (xy 285.569152 -335.018126)
			(xy 285.552134 -335.011776) (xy 285.46679 -335.011776) (xy 285.449772 -335.018126) (xy 285.44266 -335.024222)
			(xy 285.421719 -335.04185) (xy 285.375748 -335.071563) (xy 285.326003 -335.0944) (xy 285.273504 -335.109894)
			(xy 285.21933 -335.117726) (xy 285.191962 -335.118202) (xy 285.16471 -335.117758) (xy 285.11076 -335.109996)
			(xy 285.058464 -335.094635) (xy 285.008886 -335.071989) (xy 284.963036 -335.042519) (xy 284.921846 -335.006823)
			(xy 284.886155 -334.965629) (xy 284.856689 -334.919775) (xy 284.834049 -334.870195) (xy 284.818695 -334.817897)
			(xy 284.810939 -334.763947) (xy 284.810454 -334.736694) (xy 282.83027 -334.736694) (xy 282.829839 -334.763948)
			(xy 282.822082 -334.817902) (xy 282.806725 -334.870203) (xy 282.78408 -334.919786) (xy 282.754609 -334.965641)
			(xy 282.718912 -335.006835) (xy 282.677715 -335.042528) (xy 282.631858 -335.071995) (xy 282.582273 -335.094636)
			(xy 282.529971 -335.109989) (xy 282.476016 -335.117741) (xy 282.448762 -335.118202) (xy 282.421393 -335.117699)
			(xy 282.367216 -335.10989) (xy 282.314713 -335.09441) (xy 282.264965 -335.071576) (xy 282.218997 -335.041859)
			(xy 282.198064 -335.024222) (xy 282.190952 -335.018126) (xy 282.173934 -335.011776) (xy 282.08859 -335.011776)
			(xy 282.071572 -335.018126) (xy 282.06446 -335.024222) (xy 282.043527 -335.041863) (xy 281.997559 -335.071587)
			(xy 281.947813 -335.094433) (xy 281.895311 -335.109929) (xy 281.841133 -335.117758) (xy 281.786391 -335.117758)
			(xy 281.732213 -335.109929) (xy 281.679711 -335.094433) (xy 281.629965 -335.071587) (xy 281.583997 -335.041863)
			(xy 281.563064 -335.024222) (xy 281.555952 -335.018126) (xy 281.538934 -335.011776) (xy 281.45359 -335.011776)
			(xy 281.436572 -335.018126) (xy 281.42946 -335.024222) (xy 281.408519 -335.04185) (xy 281.362548 -335.071563)
			(xy 281.312803 -335.0944) (xy 281.260304 -335.109894) (xy 281.20613 -335.117726) (xy 281.178762 -335.118202)
			(xy 281.15151 -335.117758) (xy 281.09756 -335.109996) (xy 281.045264 -335.094635) (xy 280.995686 -335.071989)
			(xy 280.949836 -335.042519) (xy 280.908646 -335.006823) (xy 280.872955 -334.965629) (xy 280.843489 -334.919775)
			(xy 280.820849 -334.870195) (xy 280.805495 -334.817897) (xy 280.797739 -334.763947) (xy 280.797254 -334.736694)
			(xy 278.56307 -334.736694) (xy 278.562639 -334.763948) (xy 278.554882 -334.817902) (xy 278.539525 -334.870203)
			(xy 278.51688 -334.919786) (xy 278.487409 -334.965641) (xy 278.451712 -335.006835) (xy 278.410515 -335.042528)
			(xy 278.364658 -335.071995) (xy 278.315073 -335.094636) (xy 278.262771 -335.109989) (xy 278.208816 -335.117741)
			(xy 278.181562 -335.118202) (xy 278.154193 -335.117699) (xy 278.100016 -335.10989) (xy 278.047513 -335.09441)
			(xy 277.997765 -335.071576) (xy 277.951797 -335.041859) (xy 277.930864 -335.024222) (xy 277.923752 -335.018126)
			(xy 277.906734 -335.011776) (xy 277.82139 -335.011776) (xy 277.804372 -335.018126) (xy 277.79726 -335.024222)
			(xy 277.776327 -335.041863) (xy 277.730359 -335.071587) (xy 277.680613 -335.094433) (xy 277.628111 -335.109929)
			(xy 277.573933 -335.117758) (xy 277.519191 -335.117758) (xy 277.465013 -335.109929) (xy 277.412511 -335.094433)
			(xy 277.362765 -335.071587) (xy 277.316797 -335.041863) (xy 277.295864 -335.024222) (xy 277.288752 -335.018126)
			(xy 277.271734 -335.011776) (xy 277.18639 -335.011776) (xy 277.169372 -335.018126) (xy 277.16226 -335.024222)
			(xy 277.141319 -335.04185) (xy 277.095348 -335.071563) (xy 277.045603 -335.0944) (xy 276.993104 -335.109894)
			(xy 276.93893 -335.117726) (xy 276.911562 -335.118202) (xy 276.88431 -335.117758) (xy 276.83036 -335.109996)
			(xy 276.778064 -335.094635) (xy 276.728486 -335.071989) (xy 276.682636 -335.042519) (xy 276.641446 -335.006823)
			(xy 276.605755 -334.965629) (xy 276.576289 -334.919775) (xy 276.553649 -334.870195) (xy 276.538295 -334.817897)
			(xy 276.530539 -334.763947) (xy 276.530054 -334.736694) (xy 274.54987 -334.736694) (xy 274.549439 -334.763948)
			(xy 274.541682 -334.817902) (xy 274.526325 -334.870203) (xy 274.50368 -334.919786) (xy 274.474209 -334.965641)
			(xy 274.438512 -335.006835) (xy 274.397315 -335.042528) (xy 274.351458 -335.071995) (xy 274.301873 -335.094636)
			(xy 274.249571 -335.109989) (xy 274.195616 -335.117741) (xy 274.168362 -335.118202) (xy 274.140993 -335.117699)
			(xy 274.086816 -335.10989) (xy 274.034313 -335.09441) (xy 273.984565 -335.071576) (xy 273.938597 -335.041859)
			(xy 273.917664 -335.024222) (xy 273.910552 -335.018126) (xy 273.893534 -335.011776) (xy 273.80819 -335.011776)
			(xy 273.791172 -335.018126) (xy 273.78406 -335.024222) (xy 273.763127 -335.041863) (xy 273.717159 -335.071587)
			(xy 273.667413 -335.094433) (xy 273.614911 -335.109929) (xy 273.560733 -335.117758) (xy 273.505991 -335.117758)
			(xy 273.451813 -335.109929) (xy 273.399311 -335.094433) (xy 273.349565 -335.071587) (xy 273.303597 -335.041863)
			(xy 273.282664 -335.024222) (xy 273.275552 -335.018126) (xy 273.258534 -335.011776) (xy 273.17319 -335.011776)
			(xy 273.156172 -335.018126) (xy 273.14906 -335.024222) (xy 273.128119 -335.04185) (xy 273.082148 -335.071563)
			(xy 273.032403 -335.0944) (xy 272.979904 -335.109894) (xy 272.92573 -335.117726) (xy 272.898362 -335.118202)
			(xy 272.87111 -335.117758) (xy 272.81716 -335.109996) (xy 272.764864 -335.094635) (xy 272.715286 -335.071989)
			(xy 272.669436 -335.042519) (xy 272.628246 -335.006823) (xy 272.592555 -334.965629) (xy 272.563089 -334.919775)
			(xy 272.540449 -334.870195) (xy 272.525095 -334.817897) (xy 272.517339 -334.763947) (xy 272.516854 -334.736694)
			(xy 260.312662 -334.736694) (xy 260.312662 -336.650076) (xy 314.281312 -336.650076) (xy 314.28181 -336.622166)
			(xy 314.289946 -336.566941) (xy 314.306042 -336.513491) (xy 314.329753 -336.462956) (xy 314.360573 -336.416415)
			(xy 314.378848 -336.395314) (xy 314.385198 -336.388202) (xy 314.391802 -336.37093) (xy 314.391802 -336.283808)
			(xy 314.385198 -336.266536) (xy 314.378848 -336.259424) (xy 314.360552 -336.23834) (xy 314.329729 -336.191796)
			(xy 314.306018 -336.141258) (xy 314.289925 -336.087803) (xy 314.281795 -336.032574) (xy 314.281312 -336.004662)
			(xy 314.281798 -335.977411) (xy 314.289554 -335.923463) (xy 314.304909 -335.871168) (xy 314.327551 -335.821591)
			(xy 314.357017 -335.775741) (xy 314.392708 -335.73455) (xy 314.433899 -335.698859) (xy 314.479749 -335.669393)
			(xy 314.529326 -335.646751) (xy 314.581621 -335.631396) (xy 314.635569 -335.62364) (xy 314.690071 -335.62364)
			(xy 314.744019 -335.631396) (xy 314.796314 -335.646751) (xy 314.845891 -335.669393) (xy 314.891741 -335.698859)
			(xy 314.932932 -335.73455) (xy 314.968623 -335.775741) (xy 314.998089 -335.821591) (xy 315.020731 -335.871168)
			(xy 315.036086 -335.923463) (xy 315.043842 -335.977411) (xy 315.044328 -336.004662) (xy 315.043868 -336.032574)
			(xy 315.035725 -336.087801) (xy 315.019621 -336.141252) (xy 314.995902 -336.191786) (xy 314.965071 -336.238325)
			(xy 314.946792 -336.259424) (xy 314.940442 -336.266536) (xy 314.933838 -336.283808) (xy 314.933838 -336.37093)
			(xy 314.940442 -336.388202) (xy 314.946792 -336.395314) (xy 314.965049 -336.416431) (xy 314.99588 -336.462964)
			(xy 315.0196 -336.513494) (xy 315.035701 -336.566942) (xy 315.04384 -336.622166) (xy 315.044328 -336.650076)
			(xy 315.043842 -336.677327) (xy 315.036086 -336.731275) (xy 315.020731 -336.78357) (xy 314.998089 -336.833147)
			(xy 314.968623 -336.878997) (xy 314.932932 -336.920188) (xy 314.891741 -336.955879) (xy 314.848606 -336.9836)
			(xy 318.663538 -336.9836) (xy 318.667705 -336.927983) (xy 318.680116 -336.873608) (xy 318.700492 -336.821691)
			(xy 318.728379 -336.77339) (xy 318.763153 -336.729785) (xy 318.804037 -336.69185) (xy 318.850119 -336.660432)
			(xy 318.900368 -336.636233) (xy 318.953664 -336.619793) (xy 319.008814 -336.611481) (xy 319.0367 -336.61096)
			(xy 319.063121 -336.611427) (xy 319.115436 -336.618876) (xy 319.166174 -336.63364) (xy 319.214319 -336.655421)
			(xy 319.258904 -336.683784) (xy 319.27927 -336.700622) (xy 319.286128 -336.706718) (xy 319.303146 -336.712814)
			(xy 319.387474 -336.712814) (xy 319.404492 -336.706718) (xy 319.41135 -336.700622) (xy 319.431716 -336.683783)
			(xy 319.476302 -336.655418) (xy 319.524446 -336.633631) (xy 319.575183 -336.61886) (xy 319.627498 -336.6114)
			(xy 319.680342 -336.6114) (xy 319.732657 -336.61886) (xy 319.783394 -336.633631) (xy 319.831538 -336.655418)
			(xy 319.876124 -336.683783) (xy 319.89649 -336.700622) (xy 319.903348 -336.706718) (xy 319.920366 -336.712814)
			(xy 320.004694 -336.712814) (xy 320.021712 -336.706718) (xy 320.02857 -336.700622) (xy 320.052017 -336.681287)
			(xy 320.103963 -336.649751) (xy 320.160337 -336.627059) (xy 320.18986 -336.61985) (xy 320.20256 -336.617056)
			(xy 320.221864 -336.600546) (xy 320.261234 -336.497422) (xy 320.257932 -336.472022) (xy 320.250566 -336.461608)
			(xy 320.233767 -336.437185) (xy 320.207124 -336.384235) (xy 320.188982 -336.327805) (xy 320.179776 -336.269249)
			(xy 320.179192 -336.239612) (xy 320.179669 -336.212038) (xy 320.187619 -336.157466) (xy 320.203342 -336.104606)
			(xy 320.22651 -336.05456) (xy 320.256641 -336.00837) (xy 320.293106 -335.966998) (xy 320.313812 -335.948782)
			(xy 320.321936 -335.941184) (xy 320.331287 -335.921029) (xy 320.331846 -335.90992) (xy 320.331846 -335.832704)
			(xy 320.331309 -335.82159) (xy 320.321951 -335.80143) (xy 320.313812 -335.793842) (xy 320.29312 -335.77561)
			(xy 320.256648 -335.734246) (xy 320.226513 -335.68806) (xy 320.203344 -335.638016) (xy 320.187623 -335.585157)
			(xy 320.17968 -335.530586) (xy 320.179192 -335.503012) (xy 320.179678 -335.475761) (xy 320.187434 -335.421813)
			(xy 320.202789 -335.369518) (xy 320.225431 -335.319941) (xy 320.254897 -335.274091) (xy 320.290588 -335.2329)
			(xy 320.331779 -335.197209) (xy 320.377629 -335.167743) (xy 320.427206 -335.145101) (xy 320.479501 -335.129746)
			(xy 320.533449 -335.12199) (xy 320.587951 -335.12199) (xy 320.641899 -335.129746) (xy 320.694194 -335.145101)
			(xy 320.743771 -335.167743) (xy 320.789621 -335.197209) (xy 320.830812 -335.2329) (xy 320.866503 -335.274091)
			(xy 320.895969 -335.319941) (xy 320.918611 -335.369518) (xy 320.933966 -335.421813) (xy 320.941722 -335.475761)
			(xy 320.942208 -335.503012) (xy 320.941679 -335.530584) (xy 320.933739 -335.585154) (xy 320.918026 -335.638013)
			(xy 320.894868 -335.688059) (xy 320.864747 -335.73425) (xy 320.82829 -335.775624) (xy 320.807588 -335.793842)
			(xy 320.799453 -335.80143) (xy 320.790109 -335.821592) (xy 320.789554 -335.832704) (xy 320.789554 -335.90992)
			(xy 320.790078 -335.921036) (xy 320.799446 -335.941195) (xy 320.807588 -335.948782) (xy 320.828291 -335.967002)
			(xy 320.864763 -336.008368) (xy 320.894896 -336.054556) (xy 320.918063 -336.104603) (xy 320.933781 -336.157464)
			(xy 320.941722 -336.212038) (xy 320.942208 -336.239612) (xy 320.941626 -336.268528) (xy 320.932909 -336.3257)
			(xy 320.915662 -336.380901) (xy 320.89028 -336.432865) (xy 320.857344 -336.480403) (xy 320.81761 -336.522424)
			(xy 320.771988 -336.557966) (xy 320.721524 -336.586213) (xy 320.667373 -336.606519) (xy 320.639186 -336.612992)
			(xy 320.62674 -336.615532) (xy 320.607182 -336.632042) (xy 320.602856 -336.642964) (xy 322.636896 -336.642964)
			(xy 322.637366 -336.615052) (xy 322.645505 -336.559825) (xy 322.661606 -336.506374) (xy 322.685324 -336.45584)
			(xy 322.716153 -336.409301) (xy 322.734432 -336.388202) (xy 322.740782 -336.38109) (xy 322.747386 -336.363818)
			(xy 322.747386 -336.276696) (xy 322.740782 -336.259424) (xy 322.734432 -336.252312) (xy 322.716127 -336.231235)
			(xy 322.685306 -336.184689) (xy 322.661597 -336.134149) (xy 322.645507 -336.080693) (xy 322.637378 -336.025463)
			(xy 322.636896 -335.99755) (xy 322.637382 -335.970299) (xy 322.645138 -335.916351) (xy 322.660493 -335.864056)
			(xy 322.683135 -335.814479) (xy 322.712601 -335.768629) (xy 322.748292 -335.727438) (xy 322.789483 -335.691747)
			(xy 322.835333 -335.662281) (xy 322.88491 -335.639639) (xy 322.937205 -335.624284) (xy 322.991153 -335.616528)
			(xy 323.045655 -335.616528) (xy 323.099603 -335.624284) (xy 323.151898 -335.639639) (xy 323.201475 -335.662281)
			(xy 323.247325 -335.691747) (xy 323.288516 -335.727438) (xy 323.324207 -335.768629) (xy 323.353673 -335.814479)
			(xy 323.376315 -335.864056) (xy 323.39167 -335.916351) (xy 323.399426 -335.970299) (xy 323.399912 -335.99755)
			(xy 323.399449 -336.025462) (xy 323.391307 -336.080689) (xy 323.375205 -336.13414) (xy 323.351485 -336.184674)
			(xy 323.320655 -336.231213) (xy 323.302376 -336.252312) (xy 323.296026 -336.259424) (xy 323.289422 -336.276696)
			(xy 323.289422 -336.363818) (xy 323.296026 -336.38109) (xy 323.302376 -336.388202) (xy 323.320625 -336.409326)
			(xy 323.351457 -336.455857) (xy 323.375179 -336.506385) (xy 323.391282 -336.559832) (xy 323.399423 -336.615054)
			(xy 323.399912 -336.642964) (xy 323.399426 -336.670215) (xy 323.39167 -336.724163) (xy 323.376315 -336.776458)
			(xy 323.353673 -336.826035) (xy 323.324207 -336.871885) (xy 323.288516 -336.913076) (xy 323.247325 -336.948767)
			(xy 323.204172 -336.9765) (xy 327.019125 -336.9765) (xy 327.023293 -336.920883) (xy 327.035704 -336.866508)
			(xy 327.056079 -336.81459) (xy 327.083965 -336.766288) (xy 327.118739 -336.722682) (xy 327.159622 -336.684746)
			(xy 327.205703 -336.653327) (xy 327.255953 -336.629126) (xy 327.309247 -336.612685) (xy 327.364397 -336.60437)
			(xy 327.392284 -336.603848) (xy 327.418705 -336.604327) (xy 327.471019 -336.611774) (xy 327.521757 -336.626535)
			(xy 327.569901 -336.648313) (xy 327.614488 -336.676673) (xy 327.634854 -336.69351) (xy 327.641712 -336.699606)
			(xy 327.65873 -336.705702) (xy 327.743058 -336.705702) (xy 327.760076 -336.699606) (xy 327.766934 -336.69351)
			(xy 327.7873 -336.676671) (xy 327.831886 -336.648306) (xy 327.88003 -336.626519) (xy 327.930767 -336.611748)
			(xy 327.983082 -336.604288) (xy 328.035926 -336.604288) (xy 328.088241 -336.611748) (xy 328.138978 -336.626519)
			(xy 328.187122 -336.648306) (xy 328.231708 -336.676671) (xy 328.252074 -336.69351) (xy 328.258932 -336.699606)
			(xy 328.27595 -336.705702) (xy 328.360278 -336.705702) (xy 328.377296 -336.699606) (xy 328.384154 -336.69351)
			(xy 328.406536 -336.675093) (xy 328.455867 -336.644668) (xy 328.509312 -336.622245) (xy 328.537316 -336.61477)
			(xy 328.549508 -336.611722) (xy 328.567796 -336.59572) (xy 328.607674 -336.495644) (xy 328.605134 -336.47126)
			(xy 328.59853 -336.460846) (xy 328.584049 -336.437615) (xy 328.561184 -336.387877) (xy 328.545663 -336.335382)
			(xy 328.537805 -336.281207) (xy 328.537316 -336.253836) (xy 328.537801 -336.226262) (xy 328.545749 -336.17169)
			(xy 328.56147 -336.11883) (xy 328.584636 -336.068784) (xy 328.614765 -336.022594) (xy 328.65123 -335.981222)
			(xy 328.671936 -335.963006) (xy 328.680053 -335.955402) (xy 328.689407 -335.935252) (xy 328.68997 -335.924144)
			(xy 328.68997 -335.846928) (xy 328.689412 -335.835817) (xy 328.680067 -335.815657) (xy 328.671936 -335.808066)
			(xy 328.651212 -335.789868) (xy 328.614742 -335.748498) (xy 328.58461 -335.702305) (xy 328.561446 -335.652254)
			(xy 328.545733 -335.599389) (xy 328.537798 -335.544812) (xy 328.537316 -335.517236) (xy 328.537802 -335.489985)
			(xy 328.545558 -335.436037) (xy 328.560913 -335.383742) (xy 328.583555 -335.334165) (xy 328.613021 -335.288315)
			(xy 328.648712 -335.247124) (xy 328.689903 -335.211433) (xy 328.735753 -335.181967) (xy 328.78533 -335.159325)
			(xy 328.837625 -335.14397) (xy 328.891573 -335.136214) (xy 328.946075 -335.136214) (xy 329.000023 -335.14397)
			(xy 329.052318 -335.159325) (xy 329.101895 -335.181967) (xy 329.147745 -335.211433) (xy 329.188936 -335.247124)
			(xy 329.224627 -335.288315) (xy 329.254093 -335.334165) (xy 329.276735 -335.383742) (xy 329.29209 -335.436037)
			(xy 329.299846 -335.489985) (xy 329.300332 -335.517236) (xy 329.299811 -335.544808) (xy 329.291868 -335.599378)
			(xy 329.276153 -335.652237) (xy 329.252994 -335.702283) (xy 329.222871 -335.748474) (xy 329.186414 -335.789848)
			(xy 329.165712 -335.808066) (xy 329.157615 -335.815688) (xy 329.148248 -335.835825) (xy 329.147678 -335.846928)
			(xy 329.147678 -335.924144) (xy 329.148236 -335.935256) (xy 329.157579 -335.955416) (xy 329.165712 -335.963006)
			(xy 329.186432 -335.981208) (xy 329.222901 -336.022579) (xy 329.253032 -336.068771) (xy 329.276196 -336.118821)
			(xy 329.29191 -336.171685) (xy 329.299848 -336.226261) (xy 329.300332 -336.253836) (xy 329.299861 -336.282294)
			(xy 329.291415 -336.338579) (xy 329.274699 -336.392985) (xy 329.250086 -336.444304) (xy 329.218122 -336.491396)
			(xy 329.179515 -336.533216) (xy 329.135124 -336.568837) (xy 329.085933 -336.597466) (xy 329.033035 -336.61847)
			(xy 329.005438 -336.625438) (xy 328.993246 -336.628232) (xy 328.992947 -336.628486) (xy 330.994512 -336.628486)
			(xy 330.995016 -336.600576) (xy 331.003151 -336.545351) (xy 331.019245 -336.491901) (xy 331.042954 -336.441367)
			(xy 331.073774 -336.394825) (xy 331.092048 -336.373724) (xy 331.098398 -336.366612) (xy 331.105002 -336.34934)
			(xy 331.105002 -336.262218) (xy 331.098398 -336.244946) (xy 331.092048 -336.237834) (xy 331.073756 -336.216746)
			(xy 331.042933 -336.170204) (xy 331.019221 -336.119666) (xy 331.003127 -336.066212) (xy 330.994996 -336.010984)
			(xy 330.994512 -335.983072) (xy 330.994998 -335.955821) (xy 331.002754 -335.901873) (xy 331.018109 -335.849578)
			(xy 331.040751 -335.800001) (xy 331.070217 -335.754151) (xy 331.105908 -335.71296) (xy 331.147099 -335.677269)
			(xy 331.192949 -335.647803) (xy 331.242526 -335.625161) (xy 331.294821 -335.609806) (xy 331.348769 -335.60205)
			(xy 331.403271 -335.60205) (xy 331.457219 -335.609806) (xy 331.509514 -335.625161) (xy 331.559091 -335.647803)
			(xy 331.604941 -335.677269) (xy 331.646132 -335.71296) (xy 331.681823 -335.754151) (xy 331.711289 -335.800001)
			(xy 331.733931 -335.849578) (xy 331.749286 -335.901873) (xy 331.757042 -335.955821) (xy 331.757528 -335.983072)
			(xy 331.757074 -336.010984) (xy 331.748929 -336.066211) (xy 331.732825 -336.119663) (xy 331.709103 -336.170197)
			(xy 331.678272 -336.216735) (xy 331.659992 -336.237834) (xy 331.653642 -336.244946) (xy 331.647038 -336.262218)
			(xy 331.647038 -336.34934) (xy 331.653642 -336.366612) (xy 331.659992 -336.373724) (xy 331.678254 -336.394837)
			(xy 331.709084 -336.441371) (xy 331.732803 -336.491903) (xy 331.748903 -336.545351) (xy 331.757041 -336.600576)
			(xy 331.757528 -336.628486) (xy 331.757042 -336.655737) (xy 331.749286 -336.709685) (xy 331.733931 -336.76198)
			(xy 331.711289 -336.811557) (xy 331.681823 -336.857407) (xy 331.646132 -336.898598) (xy 331.604941 -336.934289)
			(xy 331.561822 -336.962) (xy 335.376748 -336.962) (xy 335.380915 -336.906385) (xy 335.393326 -336.852011)
			(xy 335.413701 -336.800095) (xy 335.441587 -336.751796) (xy 335.47636 -336.708192) (xy 335.517243 -336.670258)
			(xy 335.563324 -336.63884) (xy 335.613572 -336.614642) (xy 335.666866 -336.598203) (xy 335.722014 -336.589891)
			(xy 335.7499 -336.58937) (xy 335.776321 -336.589835) (xy 335.828636 -336.597284) (xy 335.879375 -336.612048)
			(xy 335.927519 -336.63383) (xy 335.972104 -336.662193) (xy 335.99247 -336.679032) (xy 335.999328 -336.685128)
			(xy 336.016346 -336.691224) (xy 336.100674 -336.691224) (xy 336.117692 -336.685128) (xy 336.12455 -336.679032)
			(xy 336.144916 -336.662193) (xy 336.189502 -336.633828) (xy 336.237646 -336.612041) (xy 336.288383 -336.59727)
			(xy 336.340698 -336.58981) (xy 336.393542 -336.58981) (xy 336.445857 -336.59727) (xy 336.496594 -336.612041)
			(xy 336.544738 -336.633828) (xy 336.589324 -336.662193) (xy 336.60969 -336.679032) (xy 336.616548 -336.685128)
			(xy 336.633566 -336.691224) (xy 336.717894 -336.691224) (xy 336.734912 -336.685128) (xy 336.74177 -336.679032)
			(xy 336.763705 -336.660961) (xy 336.811982 -336.630975) (xy 336.864242 -336.608646) (xy 336.89163 -336.601054)
			(xy 336.903314 -336.598006) (xy 336.921602 -336.582258) (xy 336.96148 -336.484722) (xy 336.959702 -336.460592)
			(xy 336.953606 -336.450432) (xy 336.940633 -336.428091) (xy 336.920214 -336.380636) (xy 336.906392 -336.330857)
			(xy 336.899422 -336.279667) (xy 336.898996 -336.253836) (xy 336.899488 -336.226262) (xy 336.907435 -336.171691)
			(xy 336.923155 -336.118831) (xy 336.94632 -336.068785) (xy 336.976448 -336.022595) (xy 337.012911 -335.981223)
			(xy 337.033616 -335.963006) (xy 337.04173 -335.955399) (xy 337.051086 -335.935251) (xy 337.05165 -335.924144)
			(xy 337.05165 -335.846928) (xy 337.051098 -335.835816) (xy 337.04175 -335.815656) (xy 337.033616 -335.808066)
			(xy 337.012888 -335.789873) (xy 336.976419 -335.748501) (xy 336.946288 -335.702307) (xy 336.923125 -335.652255)
			(xy 336.907413 -335.59939) (xy 336.899478 -335.544812) (xy 336.898996 -335.517236) (xy 336.899482 -335.489985)
			(xy 336.907238 -335.436037) (xy 336.922593 -335.383742) (xy 336.945235 -335.334165) (xy 336.974701 -335.288315)
			(xy 337.010392 -335.247124) (xy 337.051583 -335.211433) (xy 337.097433 -335.181967) (xy 337.14701 -335.159325)
			(xy 337.199305 -335.14397) (xy 337.253253 -335.136214) (xy 337.307755 -335.136214) (xy 337.361703 -335.14397)
			(xy 337.413998 -335.159325) (xy 337.463575 -335.181967) (xy 337.509425 -335.211433) (xy 337.550616 -335.247124)
			(xy 337.586307 -335.288315) (xy 337.615773 -335.334165) (xy 337.638415 -335.383742) (xy 337.65377 -335.436037)
			(xy 337.661526 -335.489985) (xy 337.662012 -335.517236) (xy 337.661498 -335.544809) (xy 337.653555 -335.599379)
			(xy 337.637839 -335.652238) (xy 337.614678 -335.702284) (xy 337.584554 -335.748475) (xy 337.548095 -335.789849)
			(xy 337.527392 -335.808066) (xy 337.519292 -335.815685) (xy 337.509928 -335.835824) (xy 337.509358 -335.846928)
			(xy 337.509358 -335.924144) (xy 337.509923 -335.935255) (xy 337.519261 -335.955415) (xy 337.527392 -335.963006)
			(xy 337.548108 -335.981212) (xy 337.584578 -336.022582) (xy 337.61471 -336.068773) (xy 337.637875 -336.118822)
			(xy 337.65359 -336.171685) (xy 337.661528 -336.226261) (xy 337.662012 -336.253836) (xy 337.661456 -336.282114)
			(xy 337.653115 -336.338051) (xy 337.636607 -336.392144) (xy 337.612293 -336.443206) (xy 337.580706 -336.490119)
			(xy 337.542539 -336.531855) (xy 337.498629 -336.567497) (xy 337.449937 -336.596266) (xy 337.397531 -336.61753)
			(xy 337.370166 -336.624676) (xy 337.358482 -336.62747) (xy 337.340194 -336.642964) (xy 337.298792 -336.739992)
			(xy 337.300316 -336.764122) (xy 337.306412 -336.774536) (xy 337.318417 -336.795967) (xy 337.337324 -336.841304)
			(xy 337.350114 -336.888731) (xy 337.356566 -336.937427) (xy 337.356958 -336.961988) (xy 337.356432 -336.988602)
			(xy 337.348859 -337.041289) (xy 337.333866 -337.092362) (xy 337.311756 -337.140781) (xy 337.282982 -337.185561)
			(xy 337.248127 -337.22579) (xy 337.207903 -337.26065) (xy 337.163126 -337.289431) (xy 337.11471 -337.311547)
			(xy 337.06364 -337.326548) (xy 337.010954 -337.334129) (xy 336.98434 -337.334606) (xy 336.957917 -337.334182)
			(xy 336.9056 -337.326723) (xy 336.854861 -337.311951) (xy 336.806718 -337.290159) (xy 336.762134 -337.261787)
			(xy 336.74177 -337.244944) (xy 336.734912 -337.238848) (xy 336.717894 -337.232752) (xy 336.633566 -337.232752)
			(xy 336.616548 -337.238848) (xy 336.60969 -337.244944) (xy 336.589324 -337.261783) (xy 336.544738 -337.290148)
			(xy 336.496594 -337.311935) (xy 336.445857 -337.326706) (xy 336.393542 -337.334166) (xy 336.340698 -337.334166)
			(xy 336.288383 -337.326706) (xy 336.237646 -337.311935) (xy 336.189502 -337.290148) (xy 336.144916 -337.261783)
			(xy 336.12455 -337.244944) (xy 336.117692 -337.238848) (xy 336.100674 -337.232752) (xy 336.016346 -337.232752)
			(xy 335.999328 -337.238848) (xy 335.99247 -337.244944) (xy 335.972109 -337.261787) (xy 335.927518 -337.290144)
			(xy 335.879373 -337.311923) (xy 335.828635 -337.326689) (xy 335.776321 -337.334147) (xy 335.7499 -337.334606)
			(xy 335.722014 -337.334109) (xy 335.666866 -337.325797) (xy 335.613572 -337.309358) (xy 335.563324 -337.28516)
			(xy 335.517243 -337.253742) (xy 335.47636 -337.215808) (xy 335.441587 -337.172204) (xy 335.413701 -337.123905)
			(xy 335.393326 -337.071989) (xy 335.380915 -337.017615) (xy 335.376748 -336.962) (xy 331.561822 -336.962)
			(xy 331.559091 -336.963755) (xy 331.509514 -336.986397) (xy 331.457219 -337.001752) (xy 331.403271 -337.009508)
			(xy 331.348769 -337.009508) (xy 331.294821 -337.001752) (xy 331.242526 -336.986397) (xy 331.192949 -336.963755)
			(xy 331.147099 -336.934289) (xy 331.105908 -336.898598) (xy 331.070217 -336.857407) (xy 331.040751 -336.811557)
			(xy 331.018109 -336.76198) (xy 331.002754 -336.709685) (xy 330.994998 -336.655737) (xy 330.994512 -336.628486)
			(xy 328.992947 -336.628486) (xy 328.974704 -336.64398) (xy 328.933556 -336.743548) (xy 328.935588 -336.767932)
			(xy 328.942192 -336.778346) (xy 328.955716 -336.800704) (xy 328.977062 -336.848398) (xy 328.991544 -336.898604)
			(xy 328.998881 -336.95034) (xy 328.999342 -336.976466) (xy 328.998834 -337.003082) (xy 328.991263 -337.055772)
			(xy 328.976271 -337.106849) (xy 328.954161 -337.155272) (xy 328.925386 -337.200056) (xy 328.89053 -337.240289)
			(xy 328.850303 -337.275151) (xy 328.805523 -337.303934) (xy 328.757104 -337.32605) (xy 328.706029 -337.341051)
			(xy 328.65334 -337.34863) (xy 328.626724 -337.349084) (xy 328.600304 -337.348593) (xy 328.54799 -337.341148)
			(xy 328.497253 -337.326389) (xy 328.449108 -337.304614) (xy 328.404521 -337.276257) (xy 328.384154 -337.259422)
			(xy 328.377296 -337.253326) (xy 328.360278 -337.24723) (xy 328.27595 -337.24723) (xy 328.258932 -337.253326)
			(xy 328.252074 -337.259422) (xy 328.231708 -337.276261) (xy 328.187122 -337.304626) (xy 328.138978 -337.326413)
			(xy 328.088241 -337.341184) (xy 328.035926 -337.348644) (xy 327.983082 -337.348644) (xy 327.930767 -337.341184)
			(xy 327.88003 -337.326413) (xy 327.831886 -337.304626) (xy 327.7873 -337.276261) (xy 327.766934 -337.259422)
			(xy 327.760076 -337.253326) (xy 327.743058 -337.24723) (xy 327.65873 -337.24723) (xy 327.641712 -337.253326)
			(xy 327.634854 -337.259422) (xy 327.614496 -337.27627) (xy 327.569905 -337.304626) (xy 327.521759 -337.326404)
			(xy 327.47102 -337.34117) (xy 327.418706 -337.348626) (xy 327.392284 -337.349084) (xy 327.364397 -337.34863)
			(xy 327.309247 -337.340315) (xy 327.255953 -337.323874) (xy 327.205703 -337.299673) (xy 327.159622 -337.268254)
			(xy 327.118739 -337.230318) (xy 327.083965 -337.186712) (xy 327.056079 -337.13841) (xy 327.035704 -337.086492)
			(xy 327.023293 -337.032117) (xy 327.019125 -336.9765) (xy 323.204172 -336.9765) (xy 323.201475 -336.978233)
			(xy 323.151898 -337.000875) (xy 323.099603 -337.01623) (xy 323.045655 -337.023986) (xy 322.991153 -337.023986)
			(xy 322.937205 -337.01623) (xy 322.88491 -337.000875) (xy 322.835333 -336.978233) (xy 322.789483 -336.948767)
			(xy 322.748292 -336.913076) (xy 322.712601 -336.871885) (xy 322.683135 -336.826035) (xy 322.660493 -336.776458)
			(xy 322.645138 -336.724163) (xy 322.637382 -336.670215) (xy 322.636896 -336.642964) (xy 320.602856 -336.642964)
			(xy 320.566542 -336.734658) (xy 320.56959 -336.760058) (xy 320.576702 -336.770472) (xy 320.592505 -336.794045)
			(xy 320.617534 -336.844979) (xy 320.634565 -336.899114) (xy 320.643204 -336.955203) (xy 320.643758 -336.983578)
			(xy 320.643223 -337.010192) (xy 320.635651 -337.062878) (xy 320.620659 -337.113951) (xy 320.598551 -337.16237)
			(xy 320.569777 -337.20715) (xy 320.534924 -337.24738) (xy 320.4947 -337.28224) (xy 320.449924 -337.311021)
			(xy 320.401509 -337.333137) (xy 320.350439 -337.348138) (xy 320.297754 -337.355719) (xy 320.27114 -337.356196)
			(xy 320.244717 -337.355774) (xy 320.1924 -337.348316) (xy 320.141661 -337.333542) (xy 320.093517 -337.311751)
			(xy 320.048934 -337.283377) (xy 320.02857 -337.266534) (xy 320.021712 -337.260438) (xy 320.004694 -337.254342)
			(xy 319.920366 -337.254342) (xy 319.903348 -337.260438) (xy 319.89649 -337.266534) (xy 319.876124 -337.283373)
			(xy 319.831538 -337.311738) (xy 319.783394 -337.333525) (xy 319.732657 -337.348296) (xy 319.680342 -337.355756)
			(xy 319.627498 -337.355756) (xy 319.575183 -337.348296) (xy 319.524446 -337.333525) (xy 319.476302 -337.311738)
			(xy 319.431716 -337.283373) (xy 319.41135 -337.266534) (xy 319.404492 -337.260438) (xy 319.387474 -337.254342)
			(xy 319.303146 -337.254342) (xy 319.286128 -337.260438) (xy 319.27927 -337.266534) (xy 319.258907 -337.283376)
			(xy 319.214318 -337.311733) (xy 319.166172 -337.333512) (xy 319.115435 -337.348279) (xy 319.063121 -337.355737)
			(xy 319.0367 -337.356196) (xy 319.008814 -337.355719) (xy 318.953664 -337.347407) (xy 318.900368 -337.330967)
			(xy 318.850119 -337.306768) (xy 318.804037 -337.27535) (xy 318.763153 -337.237415) (xy 318.728379 -337.19381)
			(xy 318.700492 -337.145509) (xy 318.680116 -337.093592) (xy 318.667705 -337.039217) (xy 318.663538 -336.9836)
			(xy 314.848606 -336.9836) (xy 314.845891 -336.985345) (xy 314.796314 -337.007987) (xy 314.744019 -337.023342)
			(xy 314.690071 -337.031098) (xy 314.635569 -337.031098) (xy 314.581621 -337.023342) (xy 314.529326 -337.007987)
			(xy 314.479749 -336.985345) (xy 314.433899 -336.955879) (xy 314.392708 -336.920188) (xy 314.357017 -336.878997)
			(xy 314.327551 -336.833147) (xy 314.304909 -336.78357) (xy 314.289554 -336.731275) (xy 314.281798 -336.677327)
			(xy 314.281312 -336.650076) (xy 260.312662 -336.650076) (xy 260.312662 -337.881722) (xy 315.239144 -337.881722)
			(xy 315.243215 -337.8261) (xy 315.255341 -337.771663) (xy 315.275264 -337.719572) (xy 315.30256 -337.670937)
			(xy 315.336646 -337.626794) (xy 315.376795 -337.588085) (xy 315.422153 -337.555634) (xy 315.471753 -337.530133)
			(xy 315.524537 -337.512126) (xy 315.57938 -337.501996) (xy 315.635114 -337.499959) (xy 315.690551 -337.506059)
			(xy 315.744508 -337.520165) (xy 315.795837 -337.541977) (xy 315.843443 -337.571031) (xy 315.886311 -337.606706)
			(xy 315.923528 -337.648243) (xy 315.954301 -337.694756) (xy 315.977973 -337.745253) (xy 315.994041 -337.79866)
			(xy 316.002161 -337.853836) (xy 316.00267 -337.881722) (xy 316.002161 -337.909608) (xy 315.994041 -337.964784)
			(xy 315.977973 -338.018191) (xy 315.954301 -338.068688) (xy 315.923528 -338.115201) (xy 315.886311 -338.156738)
			(xy 315.843443 -338.192413) (xy 315.795837 -338.221467) (xy 315.744508 -338.243279) (xy 315.690551 -338.257385)
			(xy 315.635114 -338.263485) (xy 315.57938 -338.261448) (xy 315.524537 -338.251318) (xy 315.471753 -338.233311)
			(xy 315.422153 -338.20781) (xy 315.376795 -338.175359) (xy 315.336646 -338.13665) (xy 315.30256 -338.092507)
			(xy 315.275264 -338.043872) (xy 315.255341 -337.991781) (xy 315.243215 -337.937344) (xy 315.239144 -337.881722)
			(xy 260.312662 -337.881722) (xy 260.312662 -338.777072) (xy 314.660024 -338.777072) (xy 314.664095 -338.72145)
			(xy 314.676221 -338.667013) (xy 314.696144 -338.614922) (xy 314.72344 -338.566287) (xy 314.757526 -338.522144)
			(xy 314.797675 -338.483435) (xy 314.843033 -338.450984) (xy 314.892633 -338.425483) (xy 314.945417 -338.407476)
			(xy 315.00026 -338.397346) (xy 315.055994 -338.395309) (xy 315.111431 -338.401409) (xy 315.165388 -338.415515)
			(xy 315.216717 -338.437327) (xy 315.264323 -338.466381) (xy 315.307191 -338.502056) (xy 315.344408 -338.543593)
			(xy 315.375181 -338.590106) (xy 315.398853 -338.640603) (xy 315.414921 -338.69401) (xy 315.423041 -338.749186)
			(xy 315.42355 -338.777072) (xy 315.423041 -338.804958) (xy 315.414921 -338.860134) (xy 315.398853 -338.913541)
			(xy 315.375181 -338.964038) (xy 315.344408 -339.010551) (xy 315.307191 -339.052088) (xy 315.264323 -339.087763)
			(xy 315.216717 -339.116817) (xy 315.165388 -339.138629) (xy 315.111431 -339.152735) (xy 315.055994 -339.158835)
			(xy 315.00026 -339.156798) (xy 314.945417 -339.146668) (xy 314.892633 -339.128661) (xy 314.843033 -339.10316)
			(xy 314.797675 -339.070709) (xy 314.757526 -339.032) (xy 314.72344 -338.987857) (xy 314.696144 -338.939222)
			(xy 314.676221 -338.887131) (xy 314.664095 -338.832694) (xy 314.660024 -338.777072) (xy 260.312662 -338.777072)
			(xy 260.312662 -339.452712) (xy 315.99886 -339.452712) (xy 315.999363 -339.425238) (xy 316.007253 -339.37086)
			(xy 316.022869 -339.318178) (xy 316.04589 -339.268285) (xy 316.075837 -339.222215) (xy 316.093602 -339.201252)
			(xy 316.099698 -339.19414) (xy 316.106048 -339.177122) (xy 316.106048 -339.09127) (xy 316.099698 -339.074252)
			(xy 316.093602 -339.06714) (xy 316.075876 -339.046147) (xy 316.045945 -339.000074) (xy 316.022925 -338.950187)
			(xy 316.007291 -338.897517) (xy 315.999364 -338.84315) (xy 315.99886 -338.81568) (xy 315.999346 -338.788429)
			(xy 316.007102 -338.734481) (xy 316.022457 -338.682186) (xy 316.045099 -338.632609) (xy 316.074565 -338.586759)
			(xy 316.110256 -338.545568) (xy 316.151447 -338.509877) (xy 316.197297 -338.480411) (xy 316.246874 -338.457769)
			(xy 316.299169 -338.442414) (xy 316.353117 -338.434658) (xy 316.407619 -338.434658) (xy 316.461567 -338.442414)
			(xy 316.513862 -338.457769) (xy 316.563439 -338.480411) (xy 316.609289 -338.509877) (xy 316.65048 -338.545568)
			(xy 316.686171 -338.586759) (xy 316.715637 -338.632609) (xy 316.738279 -338.682186) (xy 316.753634 -338.734481)
			(xy 316.76139 -338.788429) (xy 316.761876 -338.81568) (xy 316.761384 -338.843154) (xy 316.753494 -338.897534)
			(xy 316.737876 -338.950217) (xy 316.714852 -339.000109) (xy 316.684901 -339.046178) (xy 316.667134 -339.06714)
			(xy 316.661038 -339.074252) (xy 316.654688 -339.09127) (xy 316.654688 -339.177122) (xy 316.661038 -339.19414)
			(xy 316.667134 -339.201252) (xy 316.684862 -339.222243) (xy 316.714791 -339.268318) (xy 316.73781 -339.318204)
			(xy 316.753444 -339.370875) (xy 316.761371 -339.425242) (xy 316.761876 -339.452712) (xy 316.76139 -339.479963)
			(xy 316.753634 -339.533911) (xy 316.738279 -339.586206) (xy 316.715637 -339.635783) (xy 316.686171 -339.681633)
			(xy 316.65048 -339.722824) (xy 316.609289 -339.758515) (xy 316.563439 -339.787981) (xy 316.513862 -339.810623)
			(xy 316.461567 -339.825978) (xy 316.407619 -339.833734) (xy 316.353117 -339.833734) (xy 316.299169 -339.825978)
			(xy 316.246874 -339.810623) (xy 316.197297 -339.787981) (xy 316.151447 -339.758515) (xy 316.110256 -339.722824)
			(xy 316.074565 -339.681633) (xy 316.045099 -339.635783) (xy 316.022457 -339.586206) (xy 316.007102 -339.533911)
			(xy 315.999346 -339.479963) (xy 315.99886 -339.452712) (xy 260.312662 -339.452712) (xy 260.312662 -348.37116)
			(xy 271.357598 -348.37116) (xy 271.358065 -348.343248) (xy 271.366205 -348.288021) (xy 271.382307 -348.23457)
			(xy 271.406025 -348.184036) (xy 271.436855 -348.137497) (xy 271.455134 -348.116398) (xy 271.461484 -348.109286)
			(xy 271.468088 -348.092014) (xy 271.468088 -348.004892) (xy 271.461484 -347.98762) (xy 271.455134 -347.980508)
			(xy 271.436828 -347.959432) (xy 271.406007 -347.912886) (xy 271.382298 -347.862345) (xy 271.366208 -347.808889)
			(xy 271.35808 -347.753659) (xy 271.357598 -347.725746) (xy 271.358084 -347.698495) (xy 271.36584 -347.644547)
			(xy 271.381195 -347.592252) (xy 271.403837 -347.542675) (xy 271.433303 -347.496825) (xy 271.468994 -347.455634)
			(xy 271.510185 -347.419943) (xy 271.556035 -347.390477) (xy 271.605612 -347.367835) (xy 271.657907 -347.35248)
			(xy 271.711855 -347.344724) (xy 271.766357 -347.344724) (xy 271.820305 -347.35248) (xy 271.8726 -347.367835)
			(xy 271.922177 -347.390477) (xy 271.968027 -347.419943) (xy 272.009218 -347.455634) (xy 272.044909 -347.496825)
			(xy 272.074375 -347.542675) (xy 272.097017 -347.592252) (xy 272.112372 -347.644547) (xy 272.120128 -347.698495)
			(xy 272.120614 -347.725746) (xy 272.120148 -347.753658) (xy 272.112007 -347.808885) (xy 272.095905 -347.862336)
			(xy 272.072186 -347.91287) (xy 272.041357 -347.959409) (xy 272.023078 -347.980508) (xy 272.016728 -347.98762)
			(xy 272.010124 -348.004892) (xy 272.010124 -348.092014) (xy 272.016728 -348.109286) (xy 272.023078 -348.116398)
			(xy 272.041326 -348.137523) (xy 272.072158 -348.184054) (xy 272.09588 -348.234582) (xy 272.111983 -348.288028)
			(xy 272.120125 -348.34325) (xy 272.120614 -348.37116) (xy 272.120128 -348.398411) (xy 272.112372 -348.452359)
			(xy 272.097017 -348.504654) (xy 272.074375 -348.554231) (xy 272.044909 -348.600081) (xy 272.009218 -348.641272)
			(xy 271.968027 -348.676963) (xy 271.924867 -348.7047) (xy 275.739821 -348.7047) (xy 275.743989 -348.649082)
			(xy 275.7564 -348.594706) (xy 275.776776 -348.542788) (xy 275.804662 -348.494485) (xy 275.839436 -348.450879)
			(xy 275.880321 -348.412942) (xy 275.926403 -348.381523) (xy 275.976653 -348.357322) (xy 276.029948 -348.340881)
			(xy 276.085099 -348.332566) (xy 276.112986 -348.332044) (xy 276.139407 -348.332523) (xy 276.191721 -348.33997)
			(xy 276.242459 -348.354731) (xy 276.290603 -348.376509) (xy 276.33519 -348.404869) (xy 276.355556 -348.421706)
			(xy 276.362414 -348.427802) (xy 276.379432 -348.433898) (xy 276.46376 -348.433898) (xy 276.480778 -348.427802)
			(xy 276.487636 -348.421706) (xy 276.508002 -348.404867) (xy 276.552588 -348.376502) (xy 276.600732 -348.354715)
			(xy 276.651469 -348.339944) (xy 276.703784 -348.332484) (xy 276.756628 -348.332484) (xy 276.808943 -348.339944)
			(xy 276.85968 -348.354715) (xy 276.907824 -348.376502) (xy 276.95241 -348.404867) (xy 276.972776 -348.421706)
			(xy 276.979634 -348.427802) (xy 276.996652 -348.433898) (xy 277.08098 -348.433898) (xy 277.097998 -348.427802)
			(xy 277.104856 -348.421706) (xy 277.128853 -348.401962) (xy 277.182096 -348.369922) (xy 277.210774 -348.357952)
			(xy 277.221188 -348.353888) (xy 277.236428 -348.33814) (xy 277.269448 -348.244668) (xy 277.267416 -348.223078)
			(xy 277.261828 -348.213426) (xy 277.250031 -348.191825) (xy 277.231486 -348.146234) (xy 277.218961 -348.098636)
			(xy 277.212665 -348.049822) (xy 277.212298 -348.025212) (xy 277.212773 -347.997638) (xy 277.220723 -347.943065)
			(xy 277.236447 -347.890206) (xy 277.259615 -347.84016) (xy 277.289746 -347.79397) (xy 277.326212 -347.752598)
			(xy 277.346918 -347.734382) (xy 277.355043 -347.726785) (xy 277.364393 -347.706629) (xy 277.364952 -347.69552)
			(xy 277.364952 -347.618304) (xy 277.364413 -347.60719) (xy 277.355056 -347.587031) (xy 277.346918 -347.579442)
			(xy 277.326228 -347.561208) (xy 277.289755 -347.519845) (xy 277.25962 -347.47366) (xy 277.23645 -347.423616)
			(xy 277.22073 -347.370757) (xy 277.212786 -347.316185) (xy 277.212298 -347.288612) (xy 277.212784 -347.261361)
			(xy 277.22054 -347.207413) (xy 277.235895 -347.155118) (xy 277.258537 -347.105541) (xy 277.288003 -347.059691)
			(xy 277.323694 -347.0185) (xy 277.364885 -346.982809) (xy 277.410735 -346.953343) (xy 277.460312 -346.930701)
			(xy 277.512607 -346.915346) (xy 277.566555 -346.90759) (xy 277.621057 -346.90759) (xy 277.675005 -346.915346)
			(xy 277.7273 -346.930701) (xy 277.776877 -346.953343) (xy 277.822727 -346.982809) (xy 277.863918 -347.0185)
			(xy 277.899609 -347.059691) (xy 277.929075 -347.105541) (xy 277.951717 -347.155118) (xy 277.967072 -347.207413)
			(xy 277.974828 -347.261361) (xy 277.975314 -347.288612) (xy 277.974783 -347.316184) (xy 277.966843 -347.370754)
			(xy 277.951131 -347.423612) (xy 277.927973 -347.473658) (xy 277.897852 -347.51985) (xy 277.861396 -347.561224)
			(xy 277.840694 -347.579442) (xy 277.83256 -347.587031) (xy 277.823215 -347.607193) (xy 277.82266 -347.618304)
			(xy 277.82266 -347.69552) (xy 277.823182 -347.706636) (xy 277.832551 -347.726795) (xy 277.840694 -347.734382)
			(xy 277.861398 -347.7526) (xy 277.89787 -347.793967) (xy 277.928003 -347.840156) (xy 277.95117 -347.890202)
			(xy 277.966887 -347.943064) (xy 277.974828 -347.997638) (xy 277.975314 -348.025212) (xy 277.974776 -348.054113)
			(xy 277.966042 -348.111252) (xy 277.948791 -348.16642) (xy 277.923417 -348.218355) (xy 277.890501 -348.265869)
			(xy 277.850796 -348.307877) (xy 277.80521 -348.343415) (xy 277.755699 -348.37116) (xy 279.637998 -348.37116)
			(xy 279.638465 -348.343248) (xy 279.646605 -348.288021) (xy 279.662707 -348.23457) (xy 279.686425 -348.184036)
			(xy 279.717255 -348.137497) (xy 279.735534 -348.116398) (xy 279.741884 -348.109286) (xy 279.748488 -348.092014)
			(xy 279.748488 -348.004892) (xy 279.741884 -347.98762) (xy 279.735534 -347.980508) (xy 279.717228 -347.959432)
			(xy 279.686407 -347.912886) (xy 279.662698 -347.862345) (xy 279.646608 -347.808889) (xy 279.63848 -347.753659)
			(xy 279.637998 -347.725746) (xy 279.638484 -347.698495) (xy 279.64624 -347.644547) (xy 279.661595 -347.592252)
			(xy 279.684237 -347.542675) (xy 279.713703 -347.496825) (xy 279.749394 -347.455634) (xy 279.790585 -347.419943)
			(xy 279.836435 -347.390477) (xy 279.886012 -347.367835) (xy 279.938307 -347.35248) (xy 279.992255 -347.344724)
			(xy 280.046757 -347.344724) (xy 280.100705 -347.35248) (xy 280.153 -347.367835) (xy 280.202577 -347.390477)
			(xy 280.248427 -347.419943) (xy 280.289618 -347.455634) (xy 280.325309 -347.496825) (xy 280.354775 -347.542675)
			(xy 280.377417 -347.592252) (xy 280.392772 -347.644547) (xy 280.400528 -347.698495) (xy 280.401014 -347.725746)
			(xy 280.400548 -347.753658) (xy 280.392407 -347.808885) (xy 280.376305 -347.862336) (xy 280.352586 -347.91287)
			(xy 280.321757 -347.959409) (xy 280.303478 -347.980508) (xy 280.297128 -347.98762) (xy 280.290524 -348.004892)
			(xy 280.290524 -348.092014) (xy 280.297128 -348.109286) (xy 280.303478 -348.116398) (xy 280.321726 -348.137523)
			(xy 280.352558 -348.184054) (xy 280.37628 -348.234582) (xy 280.392383 -348.288028) (xy 280.400525 -348.34325)
			(xy 280.401014 -348.37116) (xy 280.400528 -348.398411) (xy 280.392772 -348.452359) (xy 280.377417 -348.504654)
			(xy 280.354775 -348.554231) (xy 280.325309 -348.600081) (xy 280.289618 -348.641272) (xy 280.248427 -348.676963)
			(xy 280.205267 -348.7047) (xy 284.020221 -348.7047) (xy 284.024389 -348.649082) (xy 284.0368 -348.594706)
			(xy 284.057176 -348.542788) (xy 284.085062 -348.494485) (xy 284.119836 -348.450879) (xy 284.160721 -348.412942)
			(xy 284.206803 -348.381523) (xy 284.257053 -348.357322) (xy 284.310348 -348.340881) (xy 284.365499 -348.332566)
			(xy 284.393386 -348.332044) (xy 284.419807 -348.332523) (xy 284.472121 -348.33997) (xy 284.522859 -348.354731)
			(xy 284.571003 -348.376509) (xy 284.61559 -348.404869) (xy 284.635956 -348.421706) (xy 284.642814 -348.427802)
			(xy 284.659832 -348.433898) (xy 284.74416 -348.433898) (xy 284.761178 -348.427802) (xy 284.768036 -348.421706)
			(xy 284.788402 -348.404867) (xy 284.832988 -348.376502) (xy 284.881132 -348.354715) (xy 284.931869 -348.339944)
			(xy 284.984184 -348.332484) (xy 285.037028 -348.332484) (xy 285.089343 -348.339944) (xy 285.14008 -348.354715)
			(xy 285.188224 -348.376502) (xy 285.23281 -348.404867) (xy 285.253176 -348.421706) (xy 285.260034 -348.427802)
			(xy 285.277052 -348.433898) (xy 285.36138 -348.433898) (xy 285.378398 -348.427802) (xy 285.385256 -348.421706)
			(xy 285.403098 -348.4069) (xy 285.441797 -348.381362) (xy 285.483363 -348.360819) (xy 285.505144 -348.352872)
			(xy 285.516574 -348.348808) (xy 285.533084 -348.332044) (xy 285.565596 -348.232222) (xy 285.562294 -348.208854)
			(xy 285.555436 -348.198948) (xy 285.539474 -348.174897) (xy 285.514145 -348.123033) (xy 285.496913 -348.067945)
			(xy 285.488173 -348.010891) (xy 285.487618 -347.982032) (xy 285.488099 -347.954458) (xy 285.496048 -347.899886)
			(xy 285.511769 -347.847026) (xy 285.534936 -347.79698) (xy 285.565066 -347.75079) (xy 285.601532 -347.709418)
			(xy 285.622238 -347.691202) (xy 285.630357 -347.6836) (xy 285.63971 -347.663448) (xy 285.640272 -347.65234)
			(xy 285.640272 -347.575124) (xy 285.639716 -347.564013) (xy 285.63037 -347.543853) (xy 285.622238 -347.536262)
			(xy 285.601513 -347.518066) (xy 285.565042 -347.476695) (xy 285.534911 -347.430502) (xy 285.511747 -347.380451)
			(xy 285.496034 -347.327585) (xy 285.4881 -347.273008) (xy 285.487618 -347.245432) (xy 285.488104 -347.218181)
			(xy 285.49586 -347.164233) (xy 285.511215 -347.111938) (xy 285.533857 -347.062361) (xy 285.563323 -347.016511)
			(xy 285.599014 -346.97532) (xy 285.640205 -346.939629) (xy 285.686055 -346.910163) (xy 285.735632 -346.887521)
			(xy 285.787927 -346.872166) (xy 285.841875 -346.86441) (xy 285.896377 -346.86441) (xy 285.950325 -346.872166)
			(xy 286.00262 -346.887521) (xy 286.052197 -346.910163) (xy 286.098047 -346.939629) (xy 286.139238 -346.97532)
			(xy 286.174929 -347.016511) (xy 286.204395 -347.062361) (xy 286.227037 -347.111938) (xy 286.242392 -347.164233)
			(xy 286.250148 -347.218181) (xy 286.250634 -347.245432) (xy 286.250145 -347.273006) (xy 286.2422 -347.327579)
			(xy 286.226481 -347.380439) (xy 286.203316 -347.430486) (xy 286.173186 -347.476676) (xy 286.136721 -347.518047)
			(xy 286.116014 -347.536262) (xy 286.107919 -347.543886) (xy 286.098551 -347.564021) (xy 286.09798 -347.575124)
			(xy 286.09798 -347.65234) (xy 286.098484 -347.663458) (xy 286.107865 -347.683618) (xy 286.116014 -347.691202)
			(xy 286.136732 -347.709405) (xy 286.173201 -347.750776) (xy 286.203332 -347.796968) (xy 286.226497 -347.847017)
			(xy 286.242212 -347.899881) (xy 286.25015 -347.954457) (xy 286.250634 -347.982032) (xy 286.250151 -348.008525)
			(xy 286.242802 -348.061) (xy 286.228264 -348.111954) (xy 286.206817 -348.160406) (xy 286.178873 -348.205426)
			(xy 286.144969 -348.246146) (xy 286.105757 -348.281785) (xy 286.061993 -348.311655) (xy 286.014516 -348.335184)
			(xy 285.989522 -348.343982) (xy 285.978092 -348.347792) (xy 285.961328 -348.364556) (xy 285.959076 -348.37116)
			(xy 287.943798 -348.37116) (xy 287.944265 -348.343248) (xy 287.952405 -348.288021) (xy 287.968507 -348.23457)
			(xy 287.992225 -348.184036) (xy 288.023055 -348.137497) (xy 288.041334 -348.116398) (xy 288.047684 -348.109286)
			(xy 288.054288 -348.092014) (xy 288.054288 -348.004892) (xy 288.047684 -347.98762) (xy 288.041334 -347.980508)
			(xy 288.023028 -347.959432) (xy 287.992207 -347.912886) (xy 287.968498 -347.862345) (xy 287.952408 -347.808889)
			(xy 287.94428 -347.753659) (xy 287.943798 -347.725746) (xy 287.944284 -347.698495) (xy 287.95204 -347.644547)
			(xy 287.967395 -347.592252) (xy 287.990037 -347.542675) (xy 288.019503 -347.496825) (xy 288.055194 -347.455634)
			(xy 288.096385 -347.419943) (xy 288.142235 -347.390477) (xy 288.191812 -347.367835) (xy 288.244107 -347.35248)
			(xy 288.298055 -347.344724) (xy 288.352557 -347.344724) (xy 288.406505 -347.35248) (xy 288.4588 -347.367835)
			(xy 288.508377 -347.390477) (xy 288.554227 -347.419943) (xy 288.595418 -347.455634) (xy 288.631109 -347.496825)
			(xy 288.660575 -347.542675) (xy 288.683217 -347.592252) (xy 288.698572 -347.644547) (xy 288.706328 -347.698495)
			(xy 288.706814 -347.725746) (xy 288.706348 -347.753658) (xy 288.698207 -347.808885) (xy 288.682105 -347.862336)
			(xy 288.658386 -347.91287) (xy 288.627557 -347.959409) (xy 288.609278 -347.980508) (xy 288.602928 -347.98762)
			(xy 288.596324 -348.004892) (xy 288.596324 -348.092014) (xy 288.602928 -348.109286) (xy 288.609278 -348.116398)
			(xy 288.627526 -348.137523) (xy 288.658358 -348.184054) (xy 288.68208 -348.234582) (xy 288.698183 -348.288028)
			(xy 288.706325 -348.34325) (xy 288.706814 -348.37116) (xy 288.706328 -348.398411) (xy 288.698572 -348.452359)
			(xy 288.683217 -348.504654) (xy 288.660575 -348.554231) (xy 288.631109 -348.600081) (xy 288.595418 -348.641272)
			(xy 288.554227 -348.676963) (xy 288.511067 -348.7047) (xy 292.326021 -348.7047) (xy 292.330189 -348.649082)
			(xy 292.3426 -348.594706) (xy 292.362976 -348.542788) (xy 292.390862 -348.494485) (xy 292.425636 -348.450879)
			(xy 292.466521 -348.412942) (xy 292.512603 -348.381523) (xy 292.562853 -348.357322) (xy 292.616148 -348.340881)
			(xy 292.671299 -348.332566) (xy 292.699186 -348.332044) (xy 292.725607 -348.332523) (xy 292.777921 -348.33997)
			(xy 292.828659 -348.354731) (xy 292.876803 -348.376509) (xy 292.92139 -348.404869) (xy 292.941756 -348.421706)
			(xy 292.948614 -348.427802) (xy 292.965632 -348.433898) (xy 293.04996 -348.433898) (xy 293.066978 -348.427802)
			(xy 293.073836 -348.421706) (xy 293.094202 -348.404867) (xy 293.138788 -348.376502) (xy 293.186932 -348.354715)
			(xy 293.237669 -348.339944) (xy 293.289984 -348.332484) (xy 293.342828 -348.332484) (xy 293.395143 -348.339944)
			(xy 293.44588 -348.354715) (xy 293.494024 -348.376502) (xy 293.53861 -348.404867) (xy 293.558976 -348.421706)
			(xy 293.565834 -348.427802) (xy 293.582852 -348.433898) (xy 293.66718 -348.433898) (xy 293.684198 -348.427802)
			(xy 293.691056 -348.421706) (xy 293.716613 -348.400749) (xy 293.77359 -348.367271) (xy 293.80434 -348.355158)
			(xy 293.81577 -348.351094) (xy 293.83228 -348.33306) (xy 293.860982 -348.23019) (xy 293.856156 -348.206314)
			(xy 293.848536 -348.196662) (xy 293.832909 -348.17632) (xy 293.806631 -348.132266) (xy 293.786484 -348.085093)
			(xy 293.772831 -348.035647) (xy 293.765917 -347.984819) (xy 293.765478 -347.959172) (xy 293.766001 -347.9316)
			(xy 293.773943 -347.87703) (xy 293.789657 -347.824171) (xy 293.812816 -347.774125) (xy 293.842938 -347.727934)
			(xy 293.879396 -347.68656) (xy 293.900098 -347.668342) (xy 293.908193 -347.660718) (xy 293.91756 -347.640583)
			(xy 293.918132 -347.62948) (xy 293.918132 -347.552264) (xy 293.917622 -347.541147) (xy 293.908245 -347.520987)
			(xy 293.900098 -347.513402) (xy 293.879384 -347.495194) (xy 293.842914 -347.453824) (xy 293.812782 -347.407634)
			(xy 293.789617 -347.357585) (xy 293.773901 -347.304722) (xy 293.765963 -347.250147) (xy 293.765478 -347.222572)
			(xy 293.765964 -347.195321) (xy 293.77372 -347.141373) (xy 293.789075 -347.089078) (xy 293.811717 -347.039501)
			(xy 293.841183 -346.993651) (xy 293.876874 -346.95246) (xy 293.918065 -346.916769) (xy 293.963915 -346.887303)
			(xy 294.013492 -346.864661) (xy 294.065787 -346.849306) (xy 294.119735 -346.84155) (xy 294.174237 -346.84155)
			(xy 294.228185 -346.849306) (xy 294.28048 -346.864661) (xy 294.330057 -346.887303) (xy 294.375907 -346.916769)
			(xy 294.417098 -346.95246) (xy 294.452789 -346.993651) (xy 294.482255 -347.039501) (xy 294.504897 -347.089078)
			(xy 294.520252 -347.141373) (xy 294.528008 -347.195321) (xy 294.528494 -347.222572) (xy 294.528011 -347.250146)
			(xy 294.520062 -347.304718) (xy 294.504341 -347.357578) (xy 294.481174 -347.407624) (xy 294.451045 -347.453814)
			(xy 294.41458 -347.495186) (xy 294.393874 -347.513402) (xy 294.385755 -347.521004) (xy 294.376402 -347.541156)
			(xy 294.37584 -347.552264) (xy 294.37584 -347.62948) (xy 294.37639 -347.640592) (xy 294.38574 -347.660752)
			(xy 294.393874 -347.668342) (xy 294.414555 -347.686586) (xy 294.451029 -347.727947) (xy 294.481165 -347.77413)
			(xy 294.504337 -347.824172) (xy 294.520059 -347.877029) (xy 294.528005 -347.931599) (xy 294.528494 -347.959172)
			(xy 294.527984 -347.988496) (xy 294.518985 -348.046451) (xy 294.501226 -348.102346) (xy 294.475124 -348.154867)
			(xy 294.441295 -348.202776) (xy 294.400534 -348.244945) (xy 294.353802 -348.280382) (xy 294.302198 -348.308253)
			(xy 294.274748 -348.318582) (xy 294.263064 -348.3229) (xy 294.2463 -348.340426) (xy 294.237323 -348.37116)
			(xy 296.300398 -348.37116) (xy 296.300865 -348.343248) (xy 296.309005 -348.288021) (xy 296.325107 -348.23457)
			(xy 296.348825 -348.184036) (xy 296.379655 -348.137497) (xy 296.397934 -348.116398) (xy 296.404284 -348.109286)
			(xy 296.410888 -348.092014) (xy 296.410888 -348.004892) (xy 296.404284 -347.98762) (xy 296.397934 -347.980508)
			(xy 296.379628 -347.959432) (xy 296.348807 -347.912886) (xy 296.325098 -347.862345) (xy 296.309008 -347.808889)
			(xy 296.30088 -347.753659) (xy 296.300398 -347.725746) (xy 296.300884 -347.698495) (xy 296.30864 -347.644547)
			(xy 296.323995 -347.592252) (xy 296.346637 -347.542675) (xy 296.376103 -347.496825) (xy 296.411794 -347.455634)
			(xy 296.452985 -347.419943) (xy 296.498835 -347.390477) (xy 296.548412 -347.367835) (xy 296.600707 -347.35248)
			(xy 296.654655 -347.344724) (xy 296.709157 -347.344724) (xy 296.763105 -347.35248) (xy 296.8154 -347.367835)
			(xy 296.864977 -347.390477) (xy 296.910827 -347.419943) (xy 296.952018 -347.455634) (xy 296.987709 -347.496825)
			(xy 297.017175 -347.542675) (xy 297.039817 -347.592252) (xy 297.055172 -347.644547) (xy 297.062928 -347.698495)
			(xy 297.063414 -347.725746) (xy 297.062948 -347.753658) (xy 297.054807 -347.808885) (xy 297.038705 -347.862336)
			(xy 297.014986 -347.91287) (xy 296.984157 -347.959409) (xy 296.965878 -347.980508) (xy 296.959528 -347.98762)
			(xy 296.952924 -348.004892) (xy 296.952924 -348.092014) (xy 296.959528 -348.109286) (xy 296.965878 -348.116398)
			(xy 296.984126 -348.137523) (xy 297.014958 -348.184054) (xy 297.03868 -348.234582) (xy 297.054783 -348.288028)
			(xy 297.062925 -348.34325) (xy 297.063414 -348.37116) (xy 297.062928 -348.398411) (xy 297.055172 -348.452359)
			(xy 297.039817 -348.504654) (xy 297.017175 -348.554231) (xy 296.987709 -348.600081) (xy 296.952018 -348.641272)
			(xy 296.910827 -348.676963) (xy 296.867667 -348.7047) (xy 300.682621 -348.7047) (xy 300.686789 -348.649082)
			(xy 300.6992 -348.594706) (xy 300.719576 -348.542788) (xy 300.747462 -348.494485) (xy 300.782236 -348.450879)
			(xy 300.823121 -348.412942) (xy 300.869203 -348.381523) (xy 300.919453 -348.357322) (xy 300.972748 -348.340881)
			(xy 301.027899 -348.332566) (xy 301.055786 -348.332044) (xy 301.082207 -348.332523) (xy 301.134521 -348.33997)
			(xy 301.185259 -348.354731) (xy 301.233403 -348.376509) (xy 301.27799 -348.404869) (xy 301.298356 -348.421706)
			(xy 301.305214 -348.427802) (xy 301.322232 -348.433898) (xy 301.40656 -348.433898) (xy 301.423578 -348.427802)
			(xy 301.430436 -348.421706) (xy 301.450802 -348.404867) (xy 301.495388 -348.376502) (xy 301.543532 -348.354715)
			(xy 301.594269 -348.339944) (xy 301.646584 -348.332484) (xy 301.699428 -348.332484) (xy 301.751743 -348.339944)
			(xy 301.80248 -348.354715) (xy 301.850624 -348.376502) (xy 301.89521 -348.404867) (xy 301.915576 -348.421706)
			(xy 301.922434 -348.427802) (xy 301.939452 -348.433898) (xy 302.02378 -348.433898) (xy 302.040798 -348.427802)
			(xy 302.047656 -348.421706) (xy 302.072125 -348.40159) (xy 302.12653 -348.369155) (xy 302.15586 -348.35719)
			(xy 302.166782 -348.352872) (xy 302.182276 -348.336616) (xy 302.214026 -348.239842) (xy 302.211232 -348.21749)
			(xy 302.204882 -348.207584) (xy 302.190712 -348.184479) (xy 302.168299 -348.13513) (xy 302.153099 -348.083105)
			(xy 302.145418 -348.029452) (xy 302.144938 -348.002352) (xy 302.145426 -347.974778) (xy 302.153372 -347.920206)
			(xy 302.169092 -347.867346) (xy 302.192258 -347.817299) (xy 302.222387 -347.771109) (xy 302.258852 -347.729738)
			(xy 302.279558 -347.711522) (xy 302.287671 -347.703915) (xy 302.297026 -347.683767) (xy 302.297592 -347.67266)
			(xy 302.297592 -347.595444) (xy 302.297018 -347.584335) (xy 302.287684 -347.564176) (xy 302.279558 -347.556582)
			(xy 302.258827 -347.538393) (xy 302.22236 -347.497019) (xy 302.192231 -347.450824) (xy 302.169069 -347.400772)
			(xy 302.153357 -347.347906) (xy 302.145421 -347.293328) (xy 302.144938 -347.265752) (xy 302.145424 -347.238501)
			(xy 302.15318 -347.184553) (xy 302.168535 -347.132258) (xy 302.191177 -347.082681) (xy 302.220643 -347.036831)
			(xy 302.256334 -346.99564) (xy 302.297525 -346.959949) (xy 302.343375 -346.930483) (xy 302.392952 -346.907841)
			(xy 302.445247 -346.892486) (xy 302.499195 -346.88473) (xy 302.553697 -346.88473) (xy 302.607645 -346.892486)
			(xy 302.65994 -346.907841) (xy 302.709517 -346.930483) (xy 302.755367 -346.959949) (xy 302.796558 -346.99564)
			(xy 302.832249 -347.036831) (xy 302.861715 -347.082681) (xy 302.884357 -347.132258) (xy 302.899712 -347.184553)
			(xy 302.907468 -347.238501) (xy 302.907954 -347.265752) (xy 302.907471 -347.293326) (xy 302.899525 -347.347899)
			(xy 302.883804 -347.400759) (xy 302.860637 -347.450806) (xy 302.830507 -347.496995) (xy 302.794041 -347.538367)
			(xy 302.773334 -347.556582) (xy 302.765218 -347.564186) (xy 302.755865 -347.584337) (xy 302.7553 -347.595444)
			(xy 302.7553 -347.67266) (xy 302.755874 -347.683769) (xy 302.765208 -347.703928) (xy 302.773334 -347.711522)
			(xy 302.794066 -347.72971) (xy 302.830533 -347.771085) (xy 302.860662 -347.81728) (xy 302.883824 -347.867332)
			(xy 302.899536 -347.920198) (xy 302.907471 -347.974776) (xy 302.907954 -348.002352) (xy 302.907398 -348.031389)
			(xy 302.898589 -348.088791) (xy 302.881184 -348.144195) (xy 302.855582 -348.196322) (xy 302.822378 -348.243967)
			(xy 302.782336 -348.28603) (xy 302.736382 -348.321538) (xy 302.685578 -348.349673) (xy 302.658526 -348.360238)
			(xy 302.647604 -348.364302) (xy 302.640855 -348.37116) (xy 304.631598 -348.37116) (xy 304.632065 -348.343248)
			(xy 304.640205 -348.288021) (xy 304.656307 -348.23457) (xy 304.680025 -348.184036) (xy 304.710855 -348.137497)
			(xy 304.729134 -348.116398) (xy 304.735484 -348.109286) (xy 304.742088 -348.092014) (xy 304.742088 -348.004892)
			(xy 304.735484 -347.98762) (xy 304.729134 -347.980508) (xy 304.710828 -347.959432) (xy 304.680007 -347.912886)
			(xy 304.656298 -347.862345) (xy 304.640208 -347.808889) (xy 304.63208 -347.753659) (xy 304.631598 -347.725746)
			(xy 304.632084 -347.698495) (xy 304.63984 -347.644547) (xy 304.655195 -347.592252) (xy 304.677837 -347.542675)
			(xy 304.707303 -347.496825) (xy 304.742994 -347.455634) (xy 304.784185 -347.419943) (xy 304.830035 -347.390477)
			(xy 304.879612 -347.367835) (xy 304.931907 -347.35248) (xy 304.985855 -347.344724) (xy 305.040357 -347.344724)
			(xy 305.094305 -347.35248) (xy 305.1466 -347.367835) (xy 305.196177 -347.390477) (xy 305.242027 -347.419943)
			(xy 305.283218 -347.455634) (xy 305.318909 -347.496825) (xy 305.348375 -347.542675) (xy 305.371017 -347.592252)
			(xy 305.386372 -347.644547) (xy 305.394128 -347.698495) (xy 305.394614 -347.725746) (xy 305.394148 -347.753658)
			(xy 305.386007 -347.808885) (xy 305.369905 -347.862336) (xy 305.346186 -347.91287) (xy 305.315357 -347.959409)
			(xy 305.297078 -347.980508) (xy 305.290728 -347.98762) (xy 305.284124 -348.004892) (xy 305.284124 -348.092014)
			(xy 305.290728 -348.109286) (xy 305.297078 -348.116398) (xy 305.315326 -348.137523) (xy 305.346158 -348.184054)
			(xy 305.36988 -348.234582) (xy 305.385983 -348.288028) (xy 305.394125 -348.34325) (xy 305.394614 -348.37116)
			(xy 305.394128 -348.398411) (xy 305.386372 -348.452359) (xy 305.371017 -348.504654) (xy 305.348375 -348.554231)
			(xy 305.318909 -348.600081) (xy 305.283218 -348.641272) (xy 305.242027 -348.676963) (xy 305.198867 -348.7047)
			(xy 309.013821 -348.7047) (xy 309.017989 -348.649082) (xy 309.0304 -348.594706) (xy 309.050776 -348.542788)
			(xy 309.078662 -348.494485) (xy 309.113436 -348.450879) (xy 309.154321 -348.412942) (xy 309.200403 -348.381523)
			(xy 309.250653 -348.357322) (xy 309.303948 -348.340881) (xy 309.359099 -348.332566) (xy 309.386986 -348.332044)
			(xy 309.413407 -348.332523) (xy 309.465721 -348.33997) (xy 309.516459 -348.354731) (xy 309.564603 -348.376509)
			(xy 309.60919 -348.404869) (xy 309.629556 -348.421706) (xy 309.636414 -348.427802) (xy 309.653432 -348.433898)
			(xy 309.73776 -348.433898) (xy 309.754778 -348.427802) (xy 309.761636 -348.421706) (xy 309.782002 -348.404867)
			(xy 309.826588 -348.376502) (xy 309.874732 -348.354715) (xy 309.925469 -348.339944) (xy 309.977784 -348.332484)
			(xy 310.030628 -348.332484) (xy 310.082943 -348.339944) (xy 310.13368 -348.354715) (xy 310.181824 -348.376502)
			(xy 310.22641 -348.404867) (xy 310.246776 -348.421706) (xy 310.253634 -348.427802) (xy 310.270652 -348.433898)
			(xy 310.35498 -348.433898) (xy 310.371998 -348.427802) (xy 310.378856 -348.421706) (xy 310.404711 -348.400478)
			(xy 310.462474 -348.366746) (xy 310.493664 -348.35465) (xy 310.504332 -348.35084) (xy 310.520334 -348.33433)
			(xy 310.553608 -348.23781) (xy 310.550814 -348.21495) (xy 310.544718 -348.205298) (xy 310.530854 -348.182405)
			(xy 310.509015 -348.133543) (xy 310.494215 -348.082109) (xy 310.486745 -348.029112) (xy 310.486298 -348.002352)
			(xy 310.4868 -347.974779) (xy 310.494745 -347.920208) (xy 310.510463 -347.867348) (xy 310.533626 -347.817302)
			(xy 310.563752 -347.771112) (xy 310.600214 -347.729739) (xy 310.620918 -347.711522) (xy 310.629025 -347.703909)
			(xy 310.638385 -347.683765) (xy 310.638952 -347.67266) (xy 310.638952 -347.595444) (xy 310.638391 -347.584333)
			(xy 310.629049 -347.564173) (xy 310.620918 -347.556582) (xy 310.600199 -347.53838) (xy 310.563728 -347.49701)
			(xy 310.533597 -347.450818) (xy 310.510432 -347.400768) (xy 310.494718 -347.347904) (xy 310.486781 -347.293327)
			(xy 310.486298 -347.265752) (xy 310.486784 -347.238501) (xy 310.49454 -347.184553) (xy 310.509895 -347.132258)
			(xy 310.532537 -347.082681) (xy 310.562003 -347.036831) (xy 310.597694 -346.99564) (xy 310.638885 -346.959949)
			(xy 310.684735 -346.930483) (xy 310.734312 -346.907841) (xy 310.786607 -346.892486) (xy 310.840555 -346.88473)
			(xy 310.895057 -346.88473) (xy 310.949005 -346.892486) (xy 311.0013 -346.907841) (xy 311.050877 -346.930483)
			(xy 311.096727 -346.959949) (xy 311.137918 -346.99564) (xy 311.173609 -347.036831) (xy 311.203075 -347.082681)
			(xy 311.225717 -347.132258) (xy 311.241072 -347.184553) (xy 311.248828 -347.238501) (xy 311.249314 -347.265752)
			(xy 311.24881 -347.293325) (xy 311.240865 -347.347896) (xy 311.225147 -347.400755) (xy 311.201984 -347.450801)
			(xy 311.171859 -347.496992) (xy 311.135398 -347.538365) (xy 311.114694 -347.556582) (xy 311.106587 -347.564195)
			(xy 311.097227 -347.584339) (xy 311.09666 -347.595444) (xy 311.09666 -347.67266) (xy 311.097215 -347.683772)
			(xy 311.106561 -347.703932) (xy 311.114694 -347.711522) (xy 311.135418 -347.729719) (xy 311.171887 -347.771091)
			(xy 311.202018 -347.817284) (xy 311.225182 -347.867334) (xy 311.240895 -347.920199) (xy 311.248831 -347.974776)
			(xy 311.249314 -348.002352) (xy 311.248909 -348.028552) (xy 311.241751 -348.08046) (xy 311.227549 -348.130898)
			(xy 311.206572 -348.178915) (xy 311.179215 -348.223605) (xy 311.145994 -348.264127) (xy 311.107534 -348.299715)
			(xy 311.064562 -348.3297) (xy 311.017888 -348.353515) (xy 310.993282 -348.362524) (xy 310.98236 -348.366334)
			(xy 310.966104 -348.38259) (xy 310.93156 -348.478602) (xy 310.933846 -348.501462) (xy 310.939942 -348.511368)
			(xy 310.95275 -348.533323) (xy 310.972985 -348.579949) (xy 310.98669 -348.628894) (xy 310.993609 -348.679248)
			(xy 310.994044 -348.704662) (xy 310.993531 -348.731278) (xy 310.98596 -348.783968) (xy 310.970968 -348.835044)
			(xy 310.94886 -348.883467) (xy 310.920085 -348.928251) (xy 310.885229 -348.968484) (xy 310.845002 -349.003346)
			(xy 310.800224 -349.032129) (xy 310.751805 -349.054246) (xy 310.700731 -349.069247) (xy 310.648042 -349.076826)
			(xy 310.621426 -349.07728) (xy 310.595006 -349.076788) (xy 310.542692 -349.069344) (xy 310.491955 -349.054585)
			(xy 310.44381 -349.03281) (xy 310.399223 -349.004453) (xy 310.378856 -348.987618) (xy 310.371998 -348.981522)
			(xy 310.35498 -348.975426) (xy 310.270652 -348.975426) (xy 310.253634 -348.981522) (xy 310.246776 -348.987618)
			(xy 310.22641 -349.004457) (xy 310.181824 -349.032822) (xy 310.13368 -349.054609) (xy 310.082943 -349.06938)
			(xy 310.030628 -349.07684) (xy 309.977784 -349.07684) (xy 309.925469 -349.06938) (xy 309.874732 -349.054609)
			(xy 309.826588 -349.032822) (xy 309.782002 -349.004457) (xy 309.761636 -348.987618) (xy 309.754778 -348.981522)
			(xy 309.73776 -348.975426) (xy 309.653432 -348.975426) (xy 309.636414 -348.981522) (xy 309.629556 -348.987618)
			(xy 309.609197 -349.004464) (xy 309.564606 -349.032821) (xy 309.51646 -349.0546) (xy 309.465722 -349.069365)
			(xy 309.413408 -349.076822) (xy 309.386986 -349.07728) (xy 309.359099 -349.076834) (xy 309.303948 -349.068519)
			(xy 309.250653 -349.052078) (xy 309.200403 -349.027877) (xy 309.154321 -348.996458) (xy 309.113436 -348.958521)
			(xy 309.078662 -348.914915) (xy 309.050776 -348.866612) (xy 309.0304 -348.814694) (xy 309.017989 -348.760318)
			(xy 309.013821 -348.7047) (xy 305.198867 -348.7047) (xy 305.196177 -348.706429) (xy 305.1466 -348.729071)
			(xy 305.094305 -348.744426) (xy 305.040357 -348.752182) (xy 304.985855 -348.752182) (xy 304.931907 -348.744426)
			(xy 304.879612 -348.729071) (xy 304.830035 -348.706429) (xy 304.784185 -348.676963) (xy 304.742994 -348.641272)
			(xy 304.707303 -348.600081) (xy 304.677837 -348.554231) (xy 304.655195 -348.504654) (xy 304.63984 -348.452359)
			(xy 304.632084 -348.398411) (xy 304.631598 -348.37116) (xy 302.640855 -348.37116) (xy 302.631856 -348.380304)
			(xy 302.598582 -348.47657) (xy 302.601122 -348.498922) (xy 302.607218 -348.508828) (xy 302.620417 -348.530985)
			(xy 302.641215 -348.57818) (xy 302.655303 -348.627793) (xy 302.66241 -348.678875) (xy 302.662844 -348.704662)
			(xy 302.662331 -348.731278) (xy 302.65476 -348.783968) (xy 302.639768 -348.835044) (xy 302.61766 -348.883467)
			(xy 302.588885 -348.928251) (xy 302.554029 -348.968484) (xy 302.513802 -349.003346) (xy 302.469024 -349.032129)
			(xy 302.420605 -349.054246) (xy 302.369531 -349.069247) (xy 302.316842 -349.076826) (xy 302.290226 -349.07728)
			(xy 302.263806 -349.076788) (xy 302.211492 -349.069344) (xy 302.160755 -349.054585) (xy 302.11261 -349.03281)
			(xy 302.068023 -349.004453) (xy 302.047656 -348.987618) (xy 302.040798 -348.981522) (xy 302.02378 -348.975426)
			(xy 301.939452 -348.975426) (xy 301.922434 -348.981522) (xy 301.915576 -348.987618) (xy 301.89521 -349.004457)
			(xy 301.850624 -349.032822) (xy 301.80248 -349.054609) (xy 301.751743 -349.06938) (xy 301.699428 -349.07684)
			(xy 301.646584 -349.07684) (xy 301.594269 -349.06938) (xy 301.543532 -349.054609) (xy 301.495388 -349.032822)
			(xy 301.450802 -349.004457) (xy 301.430436 -348.987618) (xy 301.423578 -348.981522) (xy 301.40656 -348.975426)
			(xy 301.322232 -348.975426) (xy 301.305214 -348.981522) (xy 301.298356 -348.987618) (xy 301.277997 -349.004464)
			(xy 301.233406 -349.032821) (xy 301.18526 -349.0546) (xy 301.134522 -349.069365) (xy 301.082208 -349.076822)
			(xy 301.055786 -349.07728) (xy 301.027899 -349.076834) (xy 300.972748 -349.068519) (xy 300.919453 -349.052078)
			(xy 300.869203 -349.027877) (xy 300.823121 -348.996458) (xy 300.782236 -348.958521) (xy 300.747462 -348.914915)
			(xy 300.719576 -348.866612) (xy 300.6992 -348.814694) (xy 300.686789 -348.760318) (xy 300.682621 -348.7047)
			(xy 296.867667 -348.7047) (xy 296.864977 -348.706429) (xy 296.8154 -348.729071) (xy 296.763105 -348.744426)
			(xy 296.709157 -348.752182) (xy 296.654655 -348.752182) (xy 296.600707 -348.744426) (xy 296.548412 -348.729071)
			(xy 296.498835 -348.706429) (xy 296.452985 -348.676963) (xy 296.411794 -348.641272) (xy 296.376103 -348.600081)
			(xy 296.346637 -348.554231) (xy 296.323995 -348.504654) (xy 296.30864 -348.452359) (xy 296.300884 -348.398411)
			(xy 296.300398 -348.37116) (xy 294.237323 -348.37116) (xy 294.216328 -348.443042) (xy 294.2209 -348.466918)
			(xy 294.228266 -348.47657) (xy 294.246588 -348.501214) (xy 294.275706 -348.555277) (xy 294.295563 -348.613383)
			(xy 294.305622 -348.673959) (xy 294.306244 -348.704662) (xy 294.305731 -348.731278) (xy 294.29816 -348.783968)
			(xy 294.283168 -348.835044) (xy 294.26106 -348.883467) (xy 294.232285 -348.928251) (xy 294.197429 -348.968484)
			(xy 294.157202 -349.003346) (xy 294.112424 -349.032129) (xy 294.064005 -349.054246) (xy 294.012931 -349.069247)
			(xy 293.960242 -349.076826) (xy 293.933626 -349.07728) (xy 293.907206 -349.076788) (xy 293.854892 -349.069344)
			(xy 293.804155 -349.054585) (xy 293.75601 -349.03281) (xy 293.711423 -349.004453) (xy 293.691056 -348.987618)
			(xy 293.684198 -348.981522) (xy 293.66718 -348.975426) (xy 293.582852 -348.975426) (xy 293.565834 -348.981522)
			(xy 293.558976 -348.987618) (xy 293.53861 -349.004457) (xy 293.494024 -349.032822) (xy 293.44588 -349.054609)
			(xy 293.395143 -349.06938) (xy 293.342828 -349.07684) (xy 293.289984 -349.07684) (xy 293.237669 -349.06938)
			(xy 293.186932 -349.054609) (xy 293.138788 -349.032822) (xy 293.094202 -349.004457) (xy 293.073836 -348.987618)
			(xy 293.066978 -348.981522) (xy 293.04996 -348.975426) (xy 292.965632 -348.975426) (xy 292.948614 -348.981522)
			(xy 292.941756 -348.987618) (xy 292.921397 -349.004464) (xy 292.876806 -349.032821) (xy 292.82866 -349.0546)
			(xy 292.777922 -349.069365) (xy 292.725608 -349.076822) (xy 292.699186 -349.07728) (xy 292.671299 -349.076834)
			(xy 292.616148 -349.068519) (xy 292.562853 -349.052078) (xy 292.512603 -349.027877) (xy 292.466521 -348.996458)
			(xy 292.425636 -348.958521) (xy 292.390862 -348.914915) (xy 292.362976 -348.866612) (xy 292.3426 -348.814694)
			(xy 292.330189 -348.760318) (xy 292.326021 -348.7047) (xy 288.511067 -348.7047) (xy 288.508377 -348.706429)
			(xy 288.4588 -348.729071) (xy 288.406505 -348.744426) (xy 288.352557 -348.752182) (xy 288.298055 -348.752182)
			(xy 288.244107 -348.744426) (xy 288.191812 -348.729071) (xy 288.142235 -348.706429) (xy 288.096385 -348.676963)
			(xy 288.055194 -348.641272) (xy 288.019503 -348.600081) (xy 287.990037 -348.554231) (xy 287.967395 -348.504654)
			(xy 287.95204 -348.452359) (xy 287.944284 -348.398411) (xy 287.943798 -348.37116) (xy 285.959076 -348.37116)
			(xy 285.927546 -348.463616) (xy 285.930594 -348.486984) (xy 285.937198 -348.497144) (xy 285.952118 -348.520284)
			(xy 285.975735 -348.570018) (xy 285.991787 -348.622682) (xy 285.999927 -348.677134) (xy 286.000444 -348.704662)
			(xy 285.999931 -348.731278) (xy 285.99236 -348.783968) (xy 285.977368 -348.835044) (xy 285.95526 -348.883467)
			(xy 285.926485 -348.928251) (xy 285.891629 -348.968484) (xy 285.851402 -349.003346) (xy 285.806624 -349.032129)
			(xy 285.758205 -349.054246) (xy 285.707131 -349.069247) (xy 285.654442 -349.076826) (xy 285.627826 -349.07728)
			(xy 285.601406 -349.076788) (xy 285.549092 -349.069344) (xy 285.498355 -349.054585) (xy 285.45021 -349.03281)
			(xy 285.405623 -349.004453) (xy 285.385256 -348.987618) (xy 285.378398 -348.981522) (xy 285.36138 -348.975426)
			(xy 285.277052 -348.975426) (xy 285.260034 -348.981522) (xy 285.253176 -348.987618) (xy 285.23281 -349.004457)
			(xy 285.188224 -349.032822) (xy 285.14008 -349.054609) (xy 285.089343 -349.06938) (xy 285.037028 -349.07684)
			(xy 284.984184 -349.07684) (xy 284.931869 -349.06938) (xy 284.881132 -349.054609) (xy 284.832988 -349.032822)
			(xy 284.788402 -349.004457) (xy 284.768036 -348.987618) (xy 284.761178 -348.981522) (xy 284.74416 -348.975426)
			(xy 284.659832 -348.975426) (xy 284.642814 -348.981522) (xy 284.635956 -348.987618) (xy 284.615597 -349.004464)
			(xy 284.571006 -349.032821) (xy 284.52286 -349.0546) (xy 284.472122 -349.069365) (xy 284.419808 -349.076822)
			(xy 284.393386 -349.07728) (xy 284.365499 -349.076834) (xy 284.310348 -349.068519) (xy 284.257053 -349.052078)
			(xy 284.206803 -349.027877) (xy 284.160721 -348.996458) (xy 284.119836 -348.958521) (xy 284.085062 -348.914915)
			(xy 284.057176 -348.866612) (xy 284.0368 -348.814694) (xy 284.024389 -348.760318) (xy 284.020221 -348.7047)
			(xy 280.205267 -348.7047) (xy 280.202577 -348.706429) (xy 280.153 -348.729071) (xy 280.100705 -348.744426)
			(xy 280.046757 -348.752182) (xy 279.992255 -348.752182) (xy 279.938307 -348.744426) (xy 279.886012 -348.729071)
			(xy 279.836435 -348.706429) (xy 279.790585 -348.676963) (xy 279.749394 -348.641272) (xy 279.713703 -348.600081)
			(xy 279.684237 -348.554231) (xy 279.661595 -348.504654) (xy 279.64624 -348.452359) (xy 279.638484 -348.398411)
			(xy 279.637998 -348.37116) (xy 277.755699 -348.37116) (xy 277.754785 -348.371672) (xy 277.727918 -348.382336)
			(xy 277.717504 -348.3864) (xy 277.70201 -348.40164) (xy 277.667466 -348.494604) (xy 277.669244 -348.516194)
			(xy 277.674578 -348.5261) (xy 277.688923 -348.553648) (xy 277.709201 -348.612352) (xy 277.719452 -348.673608)
			(xy 277.720044 -348.704662) (xy 277.719531 -348.731278) (xy 277.71196 -348.783968) (xy 277.696968 -348.835044)
			(xy 277.67486 -348.883467) (xy 277.646085 -348.928251) (xy 277.611229 -348.968484) (xy 277.571002 -349.003346)
			(xy 277.526224 -349.032129) (xy 277.477805 -349.054246) (xy 277.426731 -349.069247) (xy 277.374042 -349.076826)
			(xy 277.347426 -349.07728) (xy 277.321006 -349.076788) (xy 277.268692 -349.069344) (xy 277.217955 -349.054585)
			(xy 277.16981 -349.03281) (xy 277.125223 -349.004453) (xy 277.104856 -348.987618) (xy 277.097998 -348.981522)
			(xy 277.08098 -348.975426) (xy 276.996652 -348.975426) (xy 276.979634 -348.981522) (xy 276.972776 -348.987618)
			(xy 276.95241 -349.004457) (xy 276.907824 -349.032822) (xy 276.85968 -349.054609) (xy 276.808943 -349.06938)
			(xy 276.756628 -349.07684) (xy 276.703784 -349.07684) (xy 276.651469 -349.06938) (xy 276.600732 -349.054609)
			(xy 276.552588 -349.032822) (xy 276.508002 -349.004457) (xy 276.487636 -348.987618) (xy 276.480778 -348.981522)
			(xy 276.46376 -348.975426) (xy 276.379432 -348.975426) (xy 276.362414 -348.981522) (xy 276.355556 -348.987618)
			(xy 276.335197 -349.004464) (xy 276.290606 -349.032821) (xy 276.24246 -349.0546) (xy 276.191722 -349.069365)
			(xy 276.139408 -349.076822) (xy 276.112986 -349.07728) (xy 276.085099 -349.076834) (xy 276.029948 -349.068519)
			(xy 275.976653 -349.052078) (xy 275.926403 -349.027877) (xy 275.880321 -348.996458) (xy 275.839436 -348.958521)
			(xy 275.804662 -348.914915) (xy 275.776776 -348.866612) (xy 275.7564 -348.814694) (xy 275.743989 -348.760318)
			(xy 275.739821 -348.7047) (xy 271.924867 -348.7047) (xy 271.922177 -348.706429) (xy 271.8726 -348.729071)
			(xy 271.820305 -348.744426) (xy 271.766357 -348.752182) (xy 271.711855 -348.752182) (xy 271.657907 -348.744426)
			(xy 271.605612 -348.729071) (xy 271.556035 -348.706429) (xy 271.510185 -348.676963) (xy 271.468994 -348.641272)
			(xy 271.433303 -348.600081) (xy 271.403837 -348.554231) (xy 271.381195 -348.504654) (xy 271.36584 -348.452359)
			(xy 271.358084 -348.398411) (xy 271.357598 -348.37116) (xy 260.312662 -348.37116) (xy 260.312662 -349.602806)
			(xy 272.31543 -349.602806) (xy 272.319501 -349.547184) (xy 272.331627 -349.492747) (xy 272.35155 -349.440656)
			(xy 272.378846 -349.392021) (xy 272.412932 -349.347878) (xy 272.453081 -349.309169) (xy 272.498439 -349.276718)
			(xy 272.548039 -349.251217) (xy 272.600823 -349.23321) (xy 272.655666 -349.22308) (xy 272.7114 -349.221043)
			(xy 272.766837 -349.227143) (xy 272.820794 -349.241249) (xy 272.872123 -349.263061) (xy 272.919729 -349.292115)
			(xy 272.962597 -349.32779) (xy 272.999814 -349.369327) (xy 273.030587 -349.41584) (xy 273.054259 -349.466337)
			(xy 273.070327 -349.519744) (xy 273.078447 -349.57492) (xy 273.078956 -349.602806) (xy 273.078447 -349.630692)
			(xy 273.070327 -349.685868) (xy 273.054259 -349.739275) (xy 273.030587 -349.789772) (xy 272.999814 -349.836285)
			(xy 272.962597 -349.877822) (xy 272.919729 -349.913497) (xy 272.872123 -349.942551) (xy 272.820794 -349.964363)
			(xy 272.766837 -349.978469) (xy 272.7114 -349.984569) (xy 272.655666 -349.982532) (xy 272.600823 -349.972402)
			(xy 272.548039 -349.954395) (xy 272.498439 -349.928894) (xy 272.453081 -349.896443) (xy 272.412932 -349.857734)
			(xy 272.378846 -349.813591) (xy 272.35155 -349.764956) (xy 272.331627 -349.712865) (xy 272.319501 -349.658428)
			(xy 272.31543 -349.602806) (xy 260.312662 -349.602806) (xy 260.312662 -350.498156) (xy 271.73631 -350.498156)
			(xy 271.740381 -350.442534) (xy 271.752507 -350.388097) (xy 271.77243 -350.336006) (xy 271.799726 -350.287371)
			(xy 271.833812 -350.243228) (xy 271.873961 -350.204519) (xy 271.919319 -350.172068) (xy 271.968919 -350.146567)
			(xy 272.021703 -350.12856) (xy 272.076546 -350.11843) (xy 272.13228 -350.116393) (xy 272.187717 -350.122493)
			(xy 272.241674 -350.136599) (xy 272.293003 -350.158411) (xy 272.340609 -350.187465) (xy 272.383477 -350.22314)
			(xy 272.420694 -350.264677) (xy 272.451467 -350.31119) (xy 272.475139 -350.361687) (xy 272.491207 -350.415094)
			(xy 272.499327 -350.47027) (xy 272.499836 -350.498156) (xy 272.499327 -350.526042) (xy 272.491207 -350.581218)
			(xy 272.475139 -350.634625) (xy 272.451467 -350.685122) (xy 272.420694 -350.731635) (xy 272.383477 -350.773172)
			(xy 272.340609 -350.808847) (xy 272.293003 -350.837901) (xy 272.241674 -350.859713) (xy 272.187717 -350.873819)
			(xy 272.13228 -350.879919) (xy 272.076546 -350.877882) (xy 272.021703 -350.867752) (xy 271.968919 -350.849745)
			(xy 271.919319 -350.824244) (xy 271.873961 -350.791793) (xy 271.833812 -350.753084) (xy 271.799726 -350.708941)
			(xy 271.77243 -350.660306) (xy 271.752507 -350.608215) (xy 271.740381 -350.553778) (xy 271.73631 -350.498156)
			(xy 260.312662 -350.498156) (xy 260.312662 -351.173796) (xy 273.075146 -351.173796) (xy 273.075619 -351.146321)
			(xy 273.083512 -351.09194) (xy 273.099135 -351.039257) (xy 273.122163 -350.989365) (xy 273.152118 -350.943297)
			(xy 273.169888 -350.922336) (xy 273.175984 -350.915224) (xy 273.182334 -350.898206) (xy 273.182334 -350.812354)
			(xy 273.175984 -350.795336) (xy 273.169888 -350.788224) (xy 273.152152 -350.767239) (xy 273.122224 -350.721163)
			(xy 273.099206 -350.671275) (xy 273.083573 -350.618603) (xy 273.075649 -350.564235) (xy 273.075146 -350.536764)
			(xy 273.075632 -350.509513) (xy 273.083388 -350.455565) (xy 273.098743 -350.40327) (xy 273.121385 -350.353693)
			(xy 273.150851 -350.307843) (xy 273.186542 -350.266652) (xy 273.227733 -350.230961) (xy 273.273583 -350.201495)
			(xy 273.32316 -350.178853) (xy 273.375455 -350.163498) (xy 273.429403 -350.155742) (xy 273.483905 -350.155742)
			(xy 273.537853 -350.163498) (xy 273.590148 -350.178853) (xy 273.639725 -350.201495) (xy 273.685575 -350.230961)
			(xy 273.726766 -350.266652) (xy 273.762457 -350.307843) (xy 273.791923 -350.353693) (xy 273.814565 -350.40327)
			(xy 273.82992 -350.455565) (xy 273.837676 -350.509513) (xy 273.838162 -350.536764) (xy 273.837664 -350.564238)
			(xy 273.829776 -350.618618) (xy 273.814159 -350.6713) (xy 273.811506 -350.67705) (xy 274.079972 -350.67705)
			(xy 274.079972 -350.62255) (xy 274.087728 -350.568604) (xy 274.103081 -350.516311) (xy 274.125721 -350.466735)
			(xy 274.155185 -350.420885) (xy 274.190874 -350.379695) (xy 274.232061 -350.344003) (xy 274.277908 -350.314535)
			(xy 274.327482 -350.291892) (xy 274.379774 -350.276534) (xy 274.43372 -350.268774) (xy 274.46097 -350.268286)
			(xy 274.486206 -350.268654) (xy 274.536241 -350.275281) (xy 274.584962 -350.288463) (xy 274.631512 -350.307967)
			(xy 274.653502 -350.320356) (xy 274.663154 -350.326198) (xy 274.685252 -350.32823) (xy 274.77974 -350.294702)
			(xy 274.795742 -350.279208) (xy 274.799806 -350.268794) (xy 274.810477 -350.242007) (xy 274.838768 -350.191764)
			(xy 274.874301 -350.146354) (xy 274.916266 -350.106811) (xy 274.963707 -350.074039) (xy 275.015542 -350.048783)
			(xy 275.070589 -350.03162) (xy 275.127592 -350.022941) (xy 275.156422 -350.022414) (xy 275.183675 -350.022857)
			(xy 275.237625 -350.030617) (xy 275.289922 -350.045977) (xy 275.339501 -350.068622) (xy 275.385352 -350.098092)
			(xy 275.426543 -350.133788) (xy 275.462234 -350.174983) (xy 275.491699 -350.220838) (xy 275.514339 -350.270419)
			(xy 275.52706 -350.313752) (xy 277.667974 -350.313752) (xy 277.668485 -350.286179) (xy 277.676429 -350.231609)
			(xy 277.692146 -350.17875) (xy 277.715308 -350.128704) (xy 277.745432 -350.082513) (xy 277.781891 -350.04114)
			(xy 277.802594 -350.022922) (xy 277.810697 -350.015306) (xy 277.82006 -349.995165) (xy 277.820628 -349.98406)
			(xy 277.820628 -349.906844) (xy 277.820075 -349.895732) (xy 277.810728 -349.875572) (xy 277.802594 -349.867982)
			(xy 277.78187 -349.849785) (xy 277.745401 -349.808413) (xy 277.71527 -349.76222) (xy 277.692107 -349.71217)
			(xy 277.676393 -349.659304) (xy 277.668457 -349.604728) (xy 277.667974 -349.577152) (xy 277.668433 -349.5499)
			(xy 277.676196 -349.495953) (xy 277.691556 -349.443659) (xy 277.714201 -349.394082) (xy 277.743671 -349.348233)
			(xy 277.779365 -349.307044) (xy 277.820557 -349.271353) (xy 277.866409 -349.241887) (xy 277.915987 -349.219245)
			(xy 277.968282 -349.203889) (xy 278.02223 -349.196131) (xy 278.049482 -349.195644) (xy 278.083772 -349.197168)
			(xy 278.093932 -349.198184) (xy 278.113236 -349.192088) (xy 278.183848 -349.132906) (xy 278.193246 -349.114872)
			(xy 278.194262 -349.104712) (xy 278.197203 -349.076538) (xy 278.210381 -349.021447) (xy 278.231563 -348.968911)
			(xy 278.260283 -348.920087) (xy 278.295909 -348.876047) (xy 278.337657 -348.837761) (xy 278.384609 -348.806072)
			(xy 278.435731 -348.781676) (xy 278.4899 -348.76511) (xy 278.545923 -348.756738) (xy 278.574246 -348.756224)
			(xy 278.592265 -348.756444) (xy 278.62814 -348.759879) (xy 278.645874 -348.763082) (xy 278.655272 -348.76486)
			(xy 278.674322 -348.76105) (xy 278.749506 -348.713298) (xy 278.760936 -348.69755) (xy 278.763222 -348.688152)
			(xy 278.770612 -348.661106) (xy 278.792243 -348.609379) (xy 278.821208 -348.561373) (xy 278.856884 -348.518122)
			(xy 278.898505 -348.480555) (xy 278.945173 -348.449481) (xy 278.995885 -348.425569) (xy 279.04955 -348.409333)
			(xy 279.105013 -348.401122) (xy 279.133046 -348.400624) (xy 279.1603 -348.401035) (xy 279.214252 -348.408799)
			(xy 279.26655 -348.424161) (xy 279.31613 -348.44681) (xy 279.361981 -348.476284) (xy 279.403172 -348.511983)
			(xy 279.438863 -348.553181) (xy 279.468327 -348.599039) (xy 279.490966 -348.648623) (xy 279.506318 -348.700924)
			(xy 279.51407 -348.754878) (xy 279.514554 -348.782132) (xy 279.514058 -348.809706) (xy 279.506114 -348.864278)
			(xy 279.490396 -348.917138) (xy 279.467232 -348.967184) (xy 279.437104 -349.013375) (xy 279.40064 -349.054746)
			(xy 279.379934 -349.072962) (xy 279.371827 -349.080574) (xy 279.362469 -349.100719) (xy 279.3619 -349.111824)
			(xy 279.3619 -349.18904) (xy 279.36243 -349.200154) (xy 279.371796 -349.220313) (xy 279.379934 -349.227902)
			(xy 279.40067 -349.246084) (xy 279.43713 -349.287461) (xy 279.467254 -349.333656) (xy 279.490413 -349.383707)
			(xy 279.506124 -349.436571) (xy 279.514061 -349.491146) (xy 279.514058 -349.546295) (xy 279.506115 -349.60087)
			(xy 279.505539 -349.602806) (xy 280.59583 -349.602806) (xy 280.599901 -349.547184) (xy 280.612027 -349.492747)
			(xy 280.63195 -349.440656) (xy 280.659246 -349.392021) (xy 280.693332 -349.347878) (xy 280.733481 -349.309169)
			(xy 280.778839 -349.276718) (xy 280.828439 -349.251217) (xy 280.881223 -349.23321) (xy 280.936066 -349.22308)
			(xy 280.9918 -349.221043) (xy 281.047237 -349.227143) (xy 281.101194 -349.241249) (xy 281.152523 -349.263061)
			(xy 281.200129 -349.292115) (xy 281.242997 -349.32779) (xy 281.280214 -349.369327) (xy 281.310987 -349.41584)
			(xy 281.334659 -349.466337) (xy 281.350727 -349.519744) (xy 281.358847 -349.57492) (xy 281.359356 -349.602806)
			(xy 281.358847 -349.630692) (xy 281.350727 -349.685868) (xy 281.334659 -349.739275) (xy 281.310987 -349.789772)
			(xy 281.280214 -349.836285) (xy 281.242997 -349.877822) (xy 281.200129 -349.913497) (xy 281.152523 -349.942551)
			(xy 281.101194 -349.964363) (xy 281.047237 -349.978469) (xy 280.9918 -349.984569) (xy 280.936066 -349.982532)
			(xy 280.881223 -349.972402) (xy 280.828439 -349.954395) (xy 280.778839 -349.928894) (xy 280.733481 -349.896443)
			(xy 280.693332 -349.857734) (xy 280.659246 -349.813591) (xy 280.63195 -349.764956) (xy 280.612027 -349.712865)
			(xy 280.599901 -349.658428) (xy 280.59583 -349.602806) (xy 279.505539 -349.602806) (xy 279.490398 -349.653732)
			(xy 279.467234 -349.70378) (xy 279.437105 -349.749972) (xy 279.40064 -349.791345) (xy 279.379934 -349.809562)
			(xy 279.371827 -349.817174) (xy 279.362469 -349.837319) (xy 279.3619 -349.848424) (xy 279.3619 -349.92564)
			(xy 279.36243 -349.936754) (xy 279.371796 -349.956913) (xy 279.379934 -349.964502) (xy 279.400656 -349.982701)
			(xy 279.437124 -350.024073) (xy 279.467254 -350.070266) (xy 279.490418 -350.120316) (xy 279.506132 -350.17318)
			(xy 279.51407 -350.227757) (xy 279.514554 -350.255332) (xy 279.514052 -350.282582) (xy 279.506292 -350.336527)
			(xy 279.490936 -350.388818) (xy 279.468294 -350.438393) (xy 279.438829 -350.484241) (xy 279.426771 -350.498156)
			(xy 280.01671 -350.498156) (xy 280.020781 -350.442534) (xy 280.032907 -350.388097) (xy 280.05283 -350.336006)
			(xy 280.080126 -350.287371) (xy 280.114212 -350.243228) (xy 280.154361 -350.204519) (xy 280.199719 -350.172068)
			(xy 280.249319 -350.146567) (xy 280.302103 -350.12856) (xy 280.356946 -350.11843) (xy 280.41268 -350.116393)
			(xy 280.468117 -350.122493) (xy 280.522074 -350.136599) (xy 280.573403 -350.158411) (xy 280.621009 -350.187465)
			(xy 280.663877 -350.22314) (xy 280.701094 -350.264677) (xy 280.731867 -350.31119) (xy 280.755539 -350.361687)
			(xy 280.771607 -350.415094) (xy 280.779727 -350.47027) (xy 280.780236 -350.498156) (xy 280.779727 -350.526042)
			(xy 280.771607 -350.581218) (xy 280.755539 -350.634625) (xy 280.731867 -350.685122) (xy 280.701094 -350.731635)
			(xy 280.663877 -350.773172) (xy 280.621009 -350.808847) (xy 280.573403 -350.837901) (xy 280.522074 -350.859713)
			(xy 280.468117 -350.873819) (xy 280.41268 -350.879919) (xy 280.356946 -350.877882) (xy 280.302103 -350.867752)
			(xy 280.249319 -350.849745) (xy 280.199719 -350.824244) (xy 280.154361 -350.791793) (xy 280.114212 -350.753084)
			(xy 280.080126 -350.708941) (xy 280.05283 -350.660306) (xy 280.032907 -350.608215) (xy 280.020781 -350.553778)
			(xy 280.01671 -350.498156) (xy 279.426771 -350.498156) (xy 279.403139 -350.525429) (xy 279.361952 -350.56112)
			(xy 279.316105 -350.590587) (xy 279.266531 -350.613231) (xy 279.21424 -350.628589) (xy 279.160296 -350.636351)
			(xy 279.133046 -350.63684) (xy 279.105193 -350.636246) (xy 279.050082 -350.62813) (xy 278.996735 -350.612092)
			(xy 278.946285 -350.588474) (xy 278.899801 -350.557776) (xy 278.858271 -350.52065) (xy 278.822576 -350.477884)
			(xy 278.793473 -350.430385) (xy 278.771581 -350.379161) (xy 278.763984 -350.35236) (xy 278.761698 -350.34347)
			(xy 278.75103 -350.32823) (xy 278.679148 -350.280478) (xy 278.661114 -350.276414) (xy 278.65197 -350.277684)
			(xy 278.638954 -350.279354) (xy 278.612769 -350.281133) (xy 278.599646 -350.28124) (xy 278.585497 -350.281141)
			(xy 278.557274 -350.27911) (xy 278.543258 -350.277176) (xy 278.533098 -350.275652) (xy 278.51354 -350.280478)
			(xy 278.439118 -350.336358) (xy 278.428958 -350.353884) (xy 278.427688 -350.364044) (xy 278.423627 -350.391202)
			(xy 278.408653 -350.444035) (xy 278.386259 -350.494175) (xy 278.356909 -350.540587) (xy 278.321209 -350.582312)
			(xy 278.279895 -350.618488) (xy 278.233823 -350.648368) (xy 278.183943 -350.671335) (xy 278.131286 -350.686914)
			(xy 278.076939 -350.694784) (xy 278.049482 -350.69526) (xy 278.022226 -350.694862) (xy 277.968271 -350.687101)
			(xy 277.915969 -350.67174) (xy 277.866385 -350.649092) (xy 277.82053 -350.619618) (xy 277.779336 -350.583917)
			(xy 277.743643 -350.542717) (xy 277.714176 -350.496857) (xy 277.691537 -350.447269) (xy 277.676185 -350.394965)
			(xy 277.668434 -350.341008) (xy 277.667974 -350.313752) (xy 275.52706 -350.313752) (xy 275.529692 -350.322718)
			(xy 275.537446 -350.376669) (xy 275.53793 -350.403922) (xy 275.53726 -350.435484) (xy 275.526876 -350.497749)
			(xy 275.506395 -350.557459) (xy 275.491956 -350.585532) (xy 275.48713 -350.594422) (xy 275.485098 -350.61398)
			(xy 275.510752 -350.702118) (xy 275.523198 -350.717612) (xy 275.532088 -350.722692) (xy 275.557211 -350.737205)
			(xy 275.603094 -350.772714) (xy 275.643068 -350.814763) (xy 275.676212 -350.862383) (xy 275.701759 -350.914474)
			(xy 275.71912 -350.969834) (xy 275.727895 -351.027185) (xy 275.72843 -351.056194) (xy 275.728312 -351.071114)
			(xy 275.726021 -351.100867) (xy 275.723858 -351.11563) (xy 275.721826 -351.127822) (xy 275.729192 -351.150682)
			(xy 275.752317 -351.173796) (xy 281.355546 -351.173796) (xy 281.356019 -351.146321) (xy 281.363912 -351.09194)
			(xy 281.379535 -351.039257) (xy 281.402563 -350.989365) (xy 281.432518 -350.943297) (xy 281.450288 -350.922336)
			(xy 281.456384 -350.915224) (xy 281.462734 -350.898206) (xy 281.462734 -350.812354) (xy 281.456384 -350.795336)
			(xy 281.450288 -350.788224) (xy 281.432552 -350.767239) (xy 281.402624 -350.721163) (xy 281.379606 -350.671275)
			(xy 281.363973 -350.618603) (xy 281.356049 -350.564235) (xy 281.355546 -350.536764) (xy 281.356032 -350.509513)
			(xy 281.363788 -350.455565) (xy 281.379143 -350.40327) (xy 281.401785 -350.353693) (xy 281.431251 -350.307843)
			(xy 281.466942 -350.266652) (xy 281.508133 -350.230961) (xy 281.553983 -350.201495) (xy 281.60356 -350.178853)
			(xy 281.655855 -350.163498) (xy 281.709803 -350.155742) (xy 281.764305 -350.155742) (xy 281.818253 -350.163498)
			(xy 281.870548 -350.178853) (xy 281.920125 -350.201495) (xy 281.965975 -350.230961) (xy 282.007166 -350.266652)
			(xy 282.042857 -350.307843) (xy 282.072323 -350.353693) (xy 282.094965 -350.40327) (xy 282.11032 -350.455565)
			(xy 282.118076 -350.509513) (xy 282.118562 -350.536764) (xy 282.118064 -350.564238) (xy 282.110176 -350.618618)
			(xy 282.094559 -350.6713) (xy 282.091906 -350.67705) (xy 282.360372 -350.67705) (xy 282.360372 -350.62255)
			(xy 282.368128 -350.568604) (xy 282.383481 -350.516311) (xy 282.406121 -350.466735) (xy 282.435585 -350.420885)
			(xy 282.471274 -350.379695) (xy 282.512461 -350.344003) (xy 282.558308 -350.314535) (xy 282.607882 -350.291892)
			(xy 282.660174 -350.276534) (xy 282.71412 -350.268774) (xy 282.74137 -350.268286) (xy 282.766606 -350.268654)
			(xy 282.816641 -350.275281) (xy 282.865362 -350.288463) (xy 282.911912 -350.307967) (xy 282.933902 -350.320356)
			(xy 282.943554 -350.326198) (xy 282.965652 -350.32823) (xy 283.06014 -350.294702) (xy 283.076142 -350.279208)
			(xy 283.080206 -350.268794) (xy 283.090877 -350.242007) (xy 283.119168 -350.191764) (xy 283.154701 -350.146354)
			(xy 283.196666 -350.106811) (xy 283.244107 -350.074039) (xy 283.295942 -350.048783) (xy 283.350989 -350.03162)
			(xy 283.407992 -350.022941) (xy 283.436822 -350.022414) (xy 283.464075 -350.022857) (xy 283.518025 -350.030617)
			(xy 283.570322 -350.045977) (xy 283.619901 -350.068622) (xy 283.665752 -350.098092) (xy 283.706943 -350.133788)
			(xy 283.742634 -350.174983) (xy 283.772099 -350.220838) (xy 283.794739 -350.270419) (xy 283.80746 -350.313752)
			(xy 285.948374 -350.313752) (xy 285.948885 -350.286179) (xy 285.956829 -350.231609) (xy 285.972546 -350.17875)
			(xy 285.995708 -350.128704) (xy 286.025832 -350.082513) (xy 286.062291 -350.04114) (xy 286.082994 -350.022922)
			(xy 286.091097 -350.015306) (xy 286.10046 -349.995165) (xy 286.101028 -349.98406) (xy 286.101028 -349.906844)
			(xy 286.100475 -349.895732) (xy 286.091128 -349.875572) (xy 286.082994 -349.867982) (xy 286.06227 -349.849785)
			(xy 286.025801 -349.808413) (xy 285.99567 -349.76222) (xy 285.972507 -349.71217) (xy 285.956793 -349.659304)
			(xy 285.948857 -349.604728) (xy 285.948374 -349.577152) (xy 285.948833 -349.5499) (xy 285.956596 -349.495953)
			(xy 285.971956 -349.443659) (xy 285.994601 -349.394082) (xy 286.024071 -349.348233) (xy 286.059765 -349.307044)
			(xy 286.100957 -349.271353) (xy 286.146809 -349.241887) (xy 286.196387 -349.219245) (xy 286.248682 -349.203889)
			(xy 286.30263 -349.196131) (xy 286.329882 -349.195644) (xy 286.364172 -349.197168) (xy 286.374332 -349.198184)
			(xy 286.393636 -349.192088) (xy 286.464248 -349.132906) (xy 286.473646 -349.114872) (xy 286.474662 -349.104712)
			(xy 286.477603 -349.076538) (xy 286.490781 -349.021447) (xy 286.511963 -348.968911) (xy 286.540683 -348.920087)
			(xy 286.576309 -348.876047) (xy 286.618057 -348.837761) (xy 286.665009 -348.806072) (xy 286.716131 -348.781676)
			(xy 286.7703 -348.76511) (xy 286.826323 -348.756738) (xy 286.854646 -348.756224) (xy 286.872665 -348.756444)
			(xy 286.90854 -348.759879) (xy 286.926274 -348.763082) (xy 286.935672 -348.76486) (xy 286.954722 -348.76105)
			(xy 287.029906 -348.713298) (xy 287.041336 -348.69755) (xy 287.043622 -348.688152) (xy 287.051012 -348.661106)
			(xy 287.072643 -348.609379) (xy 287.101608 -348.561373) (xy 287.137284 -348.518122) (xy 287.178905 -348.480555)
			(xy 287.225573 -348.449481) (xy 287.276285 -348.425569) (xy 287.32995 -348.409333) (xy 287.385413 -348.401122)
			(xy 287.413446 -348.400624) (xy 287.4407 -348.401035) (xy 287.494652 -348.408799) (xy 287.54695 -348.424161)
			(xy 287.59653 -348.44681) (xy 287.642381 -348.476284) (xy 287.683572 -348.511983) (xy 287.719263 -348.553181)
			(xy 287.748727 -348.599039) (xy 287.771366 -348.648623) (xy 287.786718 -348.700924) (xy 287.79447 -348.754878)
			(xy 287.794954 -348.782132) (xy 287.794458 -348.809706) (xy 287.786514 -348.864278) (xy 287.770796 -348.917138)
			(xy 287.747632 -348.967184) (xy 287.717504 -349.013375) (xy 287.68104 -349.054746) (xy 287.660334 -349.072962)
			(xy 287.652227 -349.080574) (xy 287.642869 -349.100719) (xy 287.6423 -349.111824) (xy 287.6423 -349.18904)
			(xy 287.64283 -349.200154) (xy 287.652196 -349.220313) (xy 287.660334 -349.227902) (xy 287.68107 -349.246084)
			(xy 287.71753 -349.287461) (xy 287.747654 -349.333656) (xy 287.770813 -349.383707) (xy 287.786524 -349.436571)
			(xy 287.794461 -349.491146) (xy 287.794458 -349.546295) (xy 287.786515 -349.60087) (xy 287.785939 -349.602806)
			(xy 288.90163 -349.602806) (xy 288.905701 -349.547184) (xy 288.917827 -349.492747) (xy 288.93775 -349.440656)
			(xy 288.965046 -349.392021) (xy 288.999132 -349.347878) (xy 289.039281 -349.309169) (xy 289.084639 -349.276718)
			(xy 289.134239 -349.251217) (xy 289.187023 -349.23321) (xy 289.241866 -349.22308) (xy 289.2976 -349.221043)
			(xy 289.353037 -349.227143) (xy 289.406994 -349.241249) (xy 289.458323 -349.263061) (xy 289.505929 -349.292115)
			(xy 289.548797 -349.32779) (xy 289.586014 -349.369327) (xy 289.616787 -349.41584) (xy 289.640459 -349.466337)
			(xy 289.656527 -349.519744) (xy 289.664647 -349.57492) (xy 289.665156 -349.602806) (xy 289.664647 -349.630692)
			(xy 289.656527 -349.685868) (xy 289.640459 -349.739275) (xy 289.616787 -349.789772) (xy 289.586014 -349.836285)
			(xy 289.548797 -349.877822) (xy 289.505929 -349.913497) (xy 289.458323 -349.942551) (xy 289.406994 -349.964363)
			(xy 289.353037 -349.978469) (xy 289.2976 -349.984569) (xy 289.241866 -349.982532) (xy 289.187023 -349.972402)
			(xy 289.134239 -349.954395) (xy 289.084639 -349.928894) (xy 289.039281 -349.896443) (xy 288.999132 -349.857734)
			(xy 288.965046 -349.813591) (xy 288.93775 -349.764956) (xy 288.917827 -349.712865) (xy 288.905701 -349.658428)
			(xy 288.90163 -349.602806) (xy 287.785939 -349.602806) (xy 287.770798 -349.653732) (xy 287.747634 -349.70378)
			(xy 287.717505 -349.749972) (xy 287.68104 -349.791345) (xy 287.660334 -349.809562) (xy 287.652227 -349.817174)
			(xy 287.642869 -349.837319) (xy 287.6423 -349.848424) (xy 287.6423 -349.92564) (xy 287.64283 -349.936754)
			(xy 287.652196 -349.956913) (xy 287.660334 -349.964502) (xy 287.681056 -349.982701) (xy 287.717524 -350.024073)
			(xy 287.747654 -350.070266) (xy 287.770818 -350.120316) (xy 287.786532 -350.17318) (xy 287.79447 -350.227757)
			(xy 287.794954 -350.255332) (xy 287.794452 -350.282582) (xy 287.786692 -350.336527) (xy 287.771336 -350.388818)
			(xy 287.748694 -350.438393) (xy 287.719229 -350.484241) (xy 287.707171 -350.498156) (xy 288.32251 -350.498156)
			(xy 288.326581 -350.442534) (xy 288.338707 -350.388097) (xy 288.35863 -350.336006) (xy 288.385926 -350.287371)
			(xy 288.420012 -350.243228) (xy 288.460161 -350.204519) (xy 288.505519 -350.172068) (xy 288.555119 -350.146567)
			(xy 288.607903 -350.12856) (xy 288.662746 -350.11843) (xy 288.71848 -350.116393) (xy 288.773917 -350.122493)
			(xy 288.827874 -350.136599) (xy 288.879203 -350.158411) (xy 288.926809 -350.187465) (xy 288.969677 -350.22314)
			(xy 289.006894 -350.264677) (xy 289.037667 -350.31119) (xy 289.061339 -350.361687) (xy 289.077407 -350.415094)
			(xy 289.085527 -350.47027) (xy 289.086036 -350.498156) (xy 289.085527 -350.526042) (xy 289.077407 -350.581218)
			(xy 289.061339 -350.634625) (xy 289.037667 -350.685122) (xy 289.006894 -350.731635) (xy 288.969677 -350.773172)
			(xy 288.926809 -350.808847) (xy 288.879203 -350.837901) (xy 288.827874 -350.859713) (xy 288.773917 -350.873819)
			(xy 288.71848 -350.879919) (xy 288.662746 -350.877882) (xy 288.607903 -350.867752) (xy 288.555119 -350.849745)
			(xy 288.505519 -350.824244) (xy 288.460161 -350.791793) (xy 288.420012 -350.753084) (xy 288.385926 -350.708941)
			(xy 288.35863 -350.660306) (xy 288.338707 -350.608215) (xy 288.326581 -350.553778) (xy 288.32251 -350.498156)
			(xy 287.707171 -350.498156) (xy 287.683539 -350.525429) (xy 287.642352 -350.56112) (xy 287.596505 -350.590587)
			(xy 287.546931 -350.613231) (xy 287.49464 -350.628589) (xy 287.440696 -350.636351) (xy 287.413446 -350.63684)
			(xy 287.385593 -350.636246) (xy 287.330482 -350.62813) (xy 287.277135 -350.612092) (xy 287.226685 -350.588474)
			(xy 287.180201 -350.557776) (xy 287.138671 -350.52065) (xy 287.102976 -350.477884) (xy 287.073873 -350.430385)
			(xy 287.051981 -350.379161) (xy 287.044384 -350.35236) (xy 287.042098 -350.34347) (xy 287.03143 -350.32823)
			(xy 286.959548 -350.280478) (xy 286.941514 -350.276414) (xy 286.93237 -350.277684) (xy 286.919354 -350.279354)
			(xy 286.893169 -350.281133) (xy 286.880046 -350.28124) (xy 286.865897 -350.281141) (xy 286.837674 -350.27911)
			(xy 286.823658 -350.277176) (xy 286.813498 -350.275652) (xy 286.79394 -350.280478) (xy 286.719518 -350.336358)
			(xy 286.709358 -350.353884) (xy 286.708088 -350.364044) (xy 286.704027 -350.391202) (xy 286.689053 -350.444035)
			(xy 286.666659 -350.494175) (xy 286.637309 -350.540587) (xy 286.601609 -350.582312) (xy 286.560295 -350.618488)
			(xy 286.514223 -350.648368) (xy 286.464343 -350.671335) (xy 286.411686 -350.686914) (xy 286.357339 -350.694784)
			(xy 286.329882 -350.69526) (xy 286.302626 -350.694862) (xy 286.248671 -350.687101) (xy 286.196369 -350.67174)
			(xy 286.146785 -350.649092) (xy 286.10093 -350.619618) (xy 286.059736 -350.583917) (xy 286.024043 -350.542717)
			(xy 285.994576 -350.496857) (xy 285.971937 -350.447269) (xy 285.956585 -350.394965) (xy 285.948834 -350.341008)
			(xy 285.948374 -350.313752) (xy 283.80746 -350.313752) (xy 283.810092 -350.322718) (xy 283.817846 -350.376669)
			(xy 283.81833 -350.403922) (xy 283.81766 -350.435484) (xy 283.807276 -350.497749) (xy 283.786795 -350.557459)
			(xy 283.772356 -350.585532) (xy 283.76753 -350.594422) (xy 283.765498 -350.61398) (xy 283.791152 -350.702118)
			(xy 283.803598 -350.717612) (xy 283.812488 -350.722692) (xy 283.837611 -350.737205) (xy 283.883494 -350.772714)
			(xy 283.923468 -350.814763) (xy 283.956612 -350.862383) (xy 283.982159 -350.914474) (xy 283.99952 -350.969834)
			(xy 284.008295 -351.027185) (xy 284.00883 -351.056194) (xy 284.008712 -351.071114) (xy 284.006421 -351.100867)
			(xy 284.004258 -351.11563) (xy 284.002226 -351.127822) (xy 284.009592 -351.150682) (xy 284.032732 -351.173796)
			(xy 289.661346 -351.173796) (xy 289.661819 -351.146321) (xy 289.669712 -351.09194) (xy 289.685335 -351.039257)
			(xy 289.708363 -350.989365) (xy 289.738318 -350.943297) (xy 289.756088 -350.922336) (xy 289.762184 -350.915224)
			(xy 289.768534 -350.898206) (xy 289.768534 -350.812354) (xy 289.762184 -350.795336) (xy 289.756088 -350.788224)
			(xy 289.738352 -350.767239) (xy 289.708424 -350.721163) (xy 289.685406 -350.671275) (xy 289.669773 -350.618603)
			(xy 289.661849 -350.564235) (xy 289.661346 -350.536764) (xy 289.661832 -350.509513) (xy 289.669588 -350.455565)
			(xy 289.684943 -350.40327) (xy 289.707585 -350.353693) (xy 289.737051 -350.307843) (xy 289.772742 -350.266652)
			(xy 289.813933 -350.230961) (xy 289.859783 -350.201495) (xy 289.90936 -350.178853) (xy 289.961655 -350.163498)
			(xy 290.015603 -350.155742) (xy 290.070105 -350.155742) (xy 290.124053 -350.163498) (xy 290.176348 -350.178853)
			(xy 290.225925 -350.201495) (xy 290.271775 -350.230961) (xy 290.312966 -350.266652) (xy 290.348657 -350.307843)
			(xy 290.378123 -350.353693) (xy 290.400765 -350.40327) (xy 290.41612 -350.455565) (xy 290.423876 -350.509513)
			(xy 290.424362 -350.536764) (xy 290.423864 -350.564238) (xy 290.415976 -350.618618) (xy 290.400359 -350.6713)
			(xy 290.397706 -350.67705) (xy 290.666172 -350.67705) (xy 290.666172 -350.62255) (xy 290.673928 -350.568604)
			(xy 290.689281 -350.516311) (xy 290.711921 -350.466735) (xy 290.741385 -350.420885) (xy 290.777074 -350.379695)
			(xy 290.818261 -350.344003) (xy 290.864108 -350.314535) (xy 290.913682 -350.291892) (xy 290.965974 -350.276534)
			(xy 291.01992 -350.268774) (xy 291.04717 -350.268286) (xy 291.072406 -350.268654) (xy 291.122441 -350.275281)
			(xy 291.171162 -350.288463) (xy 291.217712 -350.307967) (xy 291.239702 -350.320356) (xy 291.249354 -350.326198)
			(xy 291.271452 -350.32823) (xy 291.36594 -350.294702) (xy 291.381942 -350.279208) (xy 291.386006 -350.268794)
			(xy 291.396677 -350.242007) (xy 291.424968 -350.191764) (xy 291.460501 -350.146354) (xy 291.502466 -350.106811)
			(xy 291.549907 -350.074039) (xy 291.601742 -350.048783) (xy 291.656789 -350.03162) (xy 291.713792 -350.022941)
			(xy 291.742622 -350.022414) (xy 291.769875 -350.022857) (xy 291.823825 -350.030617) (xy 291.876122 -350.045977)
			(xy 291.925701 -350.068622) (xy 291.971552 -350.098092) (xy 292.012743 -350.133788) (xy 292.048434 -350.174983)
			(xy 292.077899 -350.220838) (xy 292.100539 -350.270419) (xy 292.11326 -350.313752) (xy 294.254174 -350.313752)
			(xy 294.254685 -350.286179) (xy 294.262629 -350.231609) (xy 294.278346 -350.17875) (xy 294.301508 -350.128704)
			(xy 294.331632 -350.082513) (xy 294.368091 -350.04114) (xy 294.388794 -350.022922) (xy 294.396897 -350.015306)
			(xy 294.40626 -349.995165) (xy 294.406828 -349.98406) (xy 294.406828 -349.906844) (xy 294.406275 -349.895732)
			(xy 294.396928 -349.875572) (xy 294.388794 -349.867982) (xy 294.36807 -349.849785) (xy 294.331601 -349.808413)
			(xy 294.30147 -349.76222) (xy 294.278307 -349.71217) (xy 294.262593 -349.659304) (xy 294.254657 -349.604728)
			(xy 294.254174 -349.577152) (xy 294.254633 -349.5499) (xy 294.262396 -349.495953) (xy 294.277756 -349.443659)
			(xy 294.300401 -349.394082) (xy 294.329871 -349.348233) (xy 294.365565 -349.307044) (xy 294.406757 -349.271353)
			(xy 294.452609 -349.241887) (xy 294.502187 -349.219245) (xy 294.554482 -349.203889) (xy 294.60843 -349.196131)
			(xy 294.635682 -349.195644) (xy 294.669972 -349.197168) (xy 294.680132 -349.198184) (xy 294.699436 -349.192088)
			(xy 294.770048 -349.132906) (xy 294.779446 -349.114872) (xy 294.780462 -349.104712) (xy 294.783403 -349.076538)
			(xy 294.796581 -349.021447) (xy 294.817763 -348.968911) (xy 294.846483 -348.920087) (xy 294.882109 -348.876047)
			(xy 294.923857 -348.837761) (xy 294.970809 -348.806072) (xy 295.021931 -348.781676) (xy 295.0761 -348.76511)
			(xy 295.132123 -348.756738) (xy 295.160446 -348.756224) (xy 295.178465 -348.756444) (xy 295.21434 -348.759879)
			(xy 295.232074 -348.763082) (xy 295.241472 -348.76486) (xy 295.260522 -348.76105) (xy 295.335706 -348.713298)
			(xy 295.347136 -348.69755) (xy 295.349422 -348.688152) (xy 295.356812 -348.661106) (xy 295.378443 -348.609379)
			(xy 295.407408 -348.561373) (xy 295.443084 -348.518122) (xy 295.484705 -348.480555) (xy 295.531373 -348.449481)
			(xy 295.582085 -348.425569) (xy 295.63575 -348.409333) (xy 295.691213 -348.401122) (xy 295.719246 -348.400624)
			(xy 295.7465 -348.401035) (xy 295.800452 -348.408799) (xy 295.85275 -348.424161) (xy 295.90233 -348.44681)
			(xy 295.948181 -348.476284) (xy 295.989372 -348.511983) (xy 296.025063 -348.553181) (xy 296.054527 -348.599039)
			(xy 296.077166 -348.648623) (xy 296.092518 -348.700924) (xy 296.10027 -348.754878) (xy 296.100754 -348.782132)
			(xy 296.100258 -348.809706) (xy 296.092314 -348.864278) (xy 296.076596 -348.917138) (xy 296.053432 -348.967184)
			(xy 296.023304 -349.013375) (xy 295.98684 -349.054746) (xy 295.966134 -349.072962) (xy 295.958027 -349.080574)
			(xy 295.948669 -349.100719) (xy 295.9481 -349.111824) (xy 295.9481 -349.18904) (xy 295.94863 -349.200154)
			(xy 295.957996 -349.220313) (xy 295.966134 -349.227902) (xy 295.98687 -349.246084) (xy 296.02333 -349.287461)
			(xy 296.053454 -349.333656) (xy 296.076613 -349.383707) (xy 296.092324 -349.436571) (xy 296.100261 -349.491146)
			(xy 296.100258 -349.546295) (xy 296.092315 -349.60087) (xy 296.091739 -349.602806) (xy 297.25823 -349.602806)
			(xy 297.262301 -349.547184) (xy 297.274427 -349.492747) (xy 297.29435 -349.440656) (xy 297.321646 -349.392021)
			(xy 297.355732 -349.347878) (xy 297.395881 -349.309169) (xy 297.441239 -349.276718) (xy 297.490839 -349.251217)
			(xy 297.543623 -349.23321) (xy 297.598466 -349.22308) (xy 297.6542 -349.221043) (xy 297.709637 -349.227143)
			(xy 297.763594 -349.241249) (xy 297.814923 -349.263061) (xy 297.862529 -349.292115) (xy 297.905397 -349.32779)
			(xy 297.942614 -349.369327) (xy 297.973387 -349.41584) (xy 297.997059 -349.466337) (xy 298.013127 -349.519744)
			(xy 298.021247 -349.57492) (xy 298.021756 -349.602806) (xy 298.021247 -349.630692) (xy 298.013127 -349.685868)
			(xy 297.997059 -349.739275) (xy 297.973387 -349.789772) (xy 297.942614 -349.836285) (xy 297.905397 -349.877822)
			(xy 297.862529 -349.913497) (xy 297.814923 -349.942551) (xy 297.763594 -349.964363) (xy 297.709637 -349.978469)
			(xy 297.6542 -349.984569) (xy 297.598466 -349.982532) (xy 297.543623 -349.972402) (xy 297.490839 -349.954395)
			(xy 297.441239 -349.928894) (xy 297.395881 -349.896443) (xy 297.355732 -349.857734) (xy 297.321646 -349.813591)
			(xy 297.29435 -349.764956) (xy 297.274427 -349.712865) (xy 297.262301 -349.658428) (xy 297.25823 -349.602806)
			(xy 296.091739 -349.602806) (xy 296.076598 -349.653732) (xy 296.053434 -349.70378) (xy 296.023305 -349.749972)
			(xy 295.98684 -349.791345) (xy 295.966134 -349.809562) (xy 295.958027 -349.817174) (xy 295.948669 -349.837319)
			(xy 295.9481 -349.848424) (xy 295.9481 -349.92564) (xy 295.94863 -349.936754) (xy 295.957996 -349.956913)
			(xy 295.966134 -349.964502) (xy 295.986856 -349.982701) (xy 296.023324 -350.024073) (xy 296.053454 -350.070266)
			(xy 296.076618 -350.120316) (xy 296.092332 -350.17318) (xy 296.10027 -350.227757) (xy 296.100754 -350.255332)
			(xy 296.100252 -350.282582) (xy 296.092492 -350.336527) (xy 296.077136 -350.388818) (xy 296.054494 -350.438393)
			(xy 296.025029 -350.484241) (xy 296.012971 -350.498156) (xy 296.67911 -350.498156) (xy 296.683181 -350.442534)
			(xy 296.695307 -350.388097) (xy 296.71523 -350.336006) (xy 296.742526 -350.287371) (xy 296.776612 -350.243228)
			(xy 296.816761 -350.204519) (xy 296.862119 -350.172068) (xy 296.911719 -350.146567) (xy 296.964503 -350.12856)
			(xy 297.019346 -350.11843) (xy 297.07508 -350.116393) (xy 297.130517 -350.122493) (xy 297.184474 -350.136599)
			(xy 297.235803 -350.158411) (xy 297.283409 -350.187465) (xy 297.326277 -350.22314) (xy 297.363494 -350.264677)
			(xy 297.394267 -350.31119) (xy 297.417939 -350.361687) (xy 297.434007 -350.415094) (xy 297.442127 -350.47027)
			(xy 297.442636 -350.498156) (xy 297.442127 -350.526042) (xy 297.434007 -350.581218) (xy 297.417939 -350.634625)
			(xy 297.394267 -350.685122) (xy 297.363494 -350.731635) (xy 297.326277 -350.773172) (xy 297.283409 -350.808847)
			(xy 297.235803 -350.837901) (xy 297.184474 -350.859713) (xy 297.130517 -350.873819) (xy 297.07508 -350.879919)
			(xy 297.019346 -350.877882) (xy 296.964503 -350.867752) (xy 296.911719 -350.849745) (xy 296.862119 -350.824244)
			(xy 296.816761 -350.791793) (xy 296.776612 -350.753084) (xy 296.742526 -350.708941) (xy 296.71523 -350.660306)
			(xy 296.695307 -350.608215) (xy 296.683181 -350.553778) (xy 296.67911 -350.498156) (xy 296.012971 -350.498156)
			(xy 295.989339 -350.525429) (xy 295.948152 -350.56112) (xy 295.902305 -350.590587) (xy 295.852731 -350.613231)
			(xy 295.80044 -350.628589) (xy 295.746496 -350.636351) (xy 295.719246 -350.63684) (xy 295.691393 -350.636246)
			(xy 295.636282 -350.62813) (xy 295.582935 -350.612092) (xy 295.532485 -350.588474) (xy 295.486001 -350.557776)
			(xy 295.444471 -350.52065) (xy 295.408776 -350.477884) (xy 295.379673 -350.430385) (xy 295.357781 -350.379161)
			(xy 295.350184 -350.35236) (xy 295.347898 -350.34347) (xy 295.33723 -350.32823) (xy 295.265348 -350.280478)
			(xy 295.247314 -350.276414) (xy 295.23817 -350.277684) (xy 295.225154 -350.279354) (xy 295.198969 -350.281133)
			(xy 295.185846 -350.28124) (xy 295.171697 -350.281141) (xy 295.143474 -350.27911) (xy 295.129458 -350.277176)
			(xy 295.119298 -350.275652) (xy 295.09974 -350.280478) (xy 295.025318 -350.336358) (xy 295.015158 -350.353884)
			(xy 295.013888 -350.364044) (xy 295.009827 -350.391202) (xy 294.994853 -350.444035) (xy 294.972459 -350.494175)
			(xy 294.943109 -350.540587) (xy 294.907409 -350.582312) (xy 294.866095 -350.618488) (xy 294.820023 -350.648368)
			(xy 294.770143 -350.671335) (xy 294.717486 -350.686914) (xy 294.663139 -350.694784) (xy 294.635682 -350.69526)
			(xy 294.608426 -350.694862) (xy 294.554471 -350.687101) (xy 294.502169 -350.67174) (xy 294.452585 -350.649092)
			(xy 294.40673 -350.619618) (xy 294.365536 -350.583917) (xy 294.329843 -350.542717) (xy 294.300376 -350.496857)
			(xy 294.277737 -350.447269) (xy 294.262385 -350.394965) (xy 294.254634 -350.341008) (xy 294.254174 -350.313752)
			(xy 292.11326 -350.313752) (xy 292.115892 -350.322718) (xy 292.123646 -350.376669) (xy 292.12413 -350.403922)
			(xy 292.12346 -350.435484) (xy 292.113076 -350.497749) (xy 292.092595 -350.557459) (xy 292.078156 -350.585532)
			(xy 292.07333 -350.594422) (xy 292.071298 -350.61398) (xy 292.096952 -350.702118) (xy 292.109398 -350.717612)
			(xy 292.118288 -350.722692) (xy 292.143411 -350.737205) (xy 292.189294 -350.772714) (xy 292.229268 -350.814763)
			(xy 292.262412 -350.862383) (xy 292.287959 -350.914474) (xy 292.30532 -350.969834) (xy 292.314095 -351.027185)
			(xy 292.31463 -351.056194) (xy 292.314512 -351.071114) (xy 292.312221 -351.100867) (xy 292.310058 -351.11563)
			(xy 292.308026 -351.127822) (xy 292.315392 -351.150682) (xy 292.338507 -351.173796) (xy 298.017946 -351.173796)
			(xy 298.018419 -351.146321) (xy 298.026312 -351.09194) (xy 298.041935 -351.039257) (xy 298.064963 -350.989365)
			(xy 298.094918 -350.943297) (xy 298.112688 -350.922336) (xy 298.118784 -350.915224) (xy 298.125134 -350.898206)
			(xy 298.125134 -350.812354) (xy 298.118784 -350.795336) (xy 298.112688 -350.788224) (xy 298.094952 -350.767239)
			(xy 298.065024 -350.721163) (xy 298.042006 -350.671275) (xy 298.026373 -350.618603) (xy 298.018449 -350.564235)
			(xy 298.017946 -350.536764) (xy 298.018432 -350.509513) (xy 298.026188 -350.455565) (xy 298.041543 -350.40327)
			(xy 298.064185 -350.353693) (xy 298.093651 -350.307843) (xy 298.129342 -350.266652) (xy 298.170533 -350.230961)
			(xy 298.216383 -350.201495) (xy 298.26596 -350.178853) (xy 298.318255 -350.163498) (xy 298.372203 -350.155742)
			(xy 298.426705 -350.155742) (xy 298.480653 -350.163498) (xy 298.532948 -350.178853) (xy 298.582525 -350.201495)
			(xy 298.628375 -350.230961) (xy 298.669566 -350.266652) (xy 298.705257 -350.307843) (xy 298.734723 -350.353693)
			(xy 298.757365 -350.40327) (xy 298.77272 -350.455565) (xy 298.780476 -350.509513) (xy 298.780962 -350.536764)
			(xy 298.780464 -350.564238) (xy 298.772576 -350.618618) (xy 298.756959 -350.6713) (xy 298.733937 -350.721193)
			(xy 298.703987 -350.767262) (xy 298.68622 -350.788224) (xy 298.680124 -350.795336) (xy 298.673774 -350.812354)
			(xy 298.673774 -350.898206) (xy 298.680124 -350.915224) (xy 298.68622 -350.922336) (xy 298.703985 -350.943297)
			(xy 298.733909 -350.98938) (xy 298.756921 -351.039274) (xy 298.772547 -351.091951) (xy 298.780463 -351.146324)
			(xy 298.780962 -351.173796) (xy 298.780476 -351.201047) (xy 298.77272 -351.254995) (xy 298.757365 -351.30729)
			(xy 298.734723 -351.356867) (xy 298.705257 -351.402717) (xy 298.669566 -351.443908) (xy 298.628375 -351.479599)
			(xy 298.582525 -351.509065) (xy 298.532948 -351.531707) (xy 298.480653 -351.547062) (xy 298.426705 -351.554818)
			(xy 298.372203 -351.554818) (xy 298.318255 -351.547062) (xy 298.26596 -351.531707) (xy 298.216383 -351.509065)
			(xy 298.170533 -351.479599) (xy 298.129342 -351.443908) (xy 298.093651 -351.402717) (xy 298.064185 -351.356867)
			(xy 298.041543 -351.30729) (xy 298.026188 -351.254995) (xy 298.018432 -351.201047) (xy 298.017946 -351.173796)
			(xy 292.338507 -351.173796) (xy 299.991018 -358.826054) (xy 300.004875 -358.840508) (xy 300.027127 -358.873793)
			(xy 300.042451 -358.910783) (xy 300.050256 -358.950053) (xy 300.050708 -358.970072) (xy 300.050708 -361.06354)
			(xy 300.05116 -361.073415) (xy 300.058573 -361.091719) (xy 300.072332 -361.105886) (xy 300.081188 -361.110276)
			(xy 300.180756 -361.153456) (xy 300.210474 -361.148376) (xy 300.22165 -361.137962) (xy 300.242971 -361.118777)
			(xy 300.290248 -361.086307) (xy 300.341853 -361.061281) (xy 300.396623 -361.044261) (xy 300.453324 -361.035631)
			(xy 300.482 -361.035092) (xy 300.510854 -361.035654) (xy 300.567904 -361.044338) (xy 300.622993 -361.061523)
			(xy 300.674863 -361.086815) (xy 300.722327 -361.119637) (xy 300.764301 -361.159239) (xy 300.782482 -361.18165)
			(xy 300.792642 -361.194604) (xy 300.82363 -361.203748) (xy 300.930056 -361.167172) (xy 300.939773 -361.163169)
			(xy 300.95516 -361.148892) (xy 300.963565 -361.12966) (xy 300.964092 -361.119166) (xy 300.964092 -359.1814)
			(xy 300.964614 -359.161389) (xy 300.972433 -359.122138) (xy 300.987752 -359.085163) (xy 301.009982 -359.051882)
			(xy 301.023782 -359.037382) (xy 301.38116 -358.680258) (xy 301.387862 -358.672784) (xy 301.395447 -358.654219)
			(xy 301.395892 -358.64419) (xy 301.395892 -352.471482) (xy 301.395508 -352.461438) (xy 301.387929 -352.442842)
			(xy 301.38116 -352.435414) (xy 300.38421 -351.438464) (xy 300.36135 -351.431098) (xy 300.349158 -351.43313)
			(xy 300.334394 -351.435288) (xy 300.304642 -351.437577) (xy 300.289722 -351.437702) (xy 300.262469 -351.437224)
			(xy 300.208519 -351.42947) (xy 300.156221 -351.414117) (xy 300.10664 -351.391476) (xy 300.060787 -351.36201)
			(xy 300.019594 -351.326318) (xy 299.9839 -351.285126) (xy 299.954432 -351.239274) (xy 299.931789 -351.189694)
			(xy 299.916433 -351.137397) (xy 299.908677 -351.083447) (xy 299.908214 -351.056194) (xy 299.908885 -351.024632)
			(xy 299.919267 -350.962367) (xy 299.939749 -350.902657) (xy 299.954188 -350.874584) (xy 299.959014 -350.865694)
			(xy 299.961046 -350.846136) (xy 299.935392 -350.757998) (xy 299.922946 -350.742504) (xy 299.914056 -350.737424)
			(xy 299.90669 -350.73336) (xy 299.897038 -350.727518) (xy 299.87494 -350.725486) (xy 299.780452 -350.759014)
			(xy 299.76445 -350.774508) (xy 299.760386 -350.784922) (xy 299.74973 -350.811715) (xy 299.721437 -350.861958)
			(xy 299.685901 -350.907368) (xy 299.643933 -350.94691) (xy 299.59649 -350.979681) (xy 299.544654 -351.004936)
			(xy 299.489605 -351.022098) (xy 299.432601 -351.030775) (xy 299.40377 -351.031302) (xy 299.37652 -351.030826)
			(xy 299.322574 -351.023066) (xy 299.270282 -351.007708) (xy 299.220708 -350.985065) (xy 299.174861 -350.955597)
			(xy 299.133674 -350.919905) (xy 299.097985 -350.878715) (xy 299.068521 -350.832865) (xy 299.045881 -350.783289)
			(xy 299.030528 -350.730996) (xy 299.022772 -350.67705) (xy 299.022772 -350.62255) (xy 299.030528 -350.568604)
			(xy 299.045881 -350.516311) (xy 299.068521 -350.466735) (xy 299.097985 -350.420885) (xy 299.133674 -350.379695)
			(xy 299.174861 -350.344003) (xy 299.220708 -350.314535) (xy 299.270282 -350.291892) (xy 299.322574 -350.276534)
			(xy 299.37652 -350.268774) (xy 299.40377 -350.268286) (xy 299.429006 -350.268654) (xy 299.479041 -350.275281)
			(xy 299.527762 -350.288463) (xy 299.574312 -350.307967) (xy 299.596302 -350.320356) (xy 299.605954 -350.326198)
			(xy 299.628052 -350.32823) (xy 299.72254 -350.294702) (xy 299.738542 -350.279208) (xy 299.742606 -350.268794)
			(xy 299.753277 -350.242007) (xy 299.781568 -350.191764) (xy 299.817101 -350.146354) (xy 299.859066 -350.106811)
			(xy 299.906507 -350.074039) (xy 299.958342 -350.048783) (xy 300.013389 -350.03162) (xy 300.070392 -350.022941)
			(xy 300.099222 -350.022414) (xy 300.126475 -350.022857) (xy 300.180425 -350.030617) (xy 300.232722 -350.045977)
			(xy 300.282301 -350.068622) (xy 300.328152 -350.098092) (xy 300.369343 -350.133788) (xy 300.405034 -350.174983)
			(xy 300.434499 -350.220838) (xy 300.457139 -350.270419) (xy 300.46986 -350.313752) (xy 302.610774 -350.313752)
			(xy 302.611285 -350.286179) (xy 302.619229 -350.231609) (xy 302.634946 -350.17875) (xy 302.658108 -350.128704)
			(xy 302.688232 -350.082513) (xy 302.724691 -350.04114) (xy 302.745394 -350.022922) (xy 302.753497 -350.015306)
			(xy 302.76286 -349.995165) (xy 302.763428 -349.98406) (xy 302.763428 -349.906844) (xy 302.762875 -349.895732)
			(xy 302.753528 -349.875572) (xy 302.745394 -349.867982) (xy 302.72467 -349.849785) (xy 302.688201 -349.808413)
			(xy 302.65807 -349.76222) (xy 302.634907 -349.71217) (xy 302.619193 -349.659304) (xy 302.611257 -349.604728)
			(xy 302.610774 -349.577152) (xy 302.611233 -349.5499) (xy 302.618996 -349.495953) (xy 302.634356 -349.443659)
			(xy 302.657001 -349.394082) (xy 302.686471 -349.348233) (xy 302.722165 -349.307044) (xy 302.763357 -349.271353)
			(xy 302.809209 -349.241887) (xy 302.858787 -349.219245) (xy 302.911082 -349.203889) (xy 302.96503 -349.196131)
			(xy 302.992282 -349.195644) (xy 303.026572 -349.197168) (xy 303.036732 -349.198184) (xy 303.056036 -349.192088)
			(xy 303.126648 -349.132906) (xy 303.136046 -349.114872) (xy 303.137062 -349.104712) (xy 303.140003 -349.076538)
			(xy 303.153181 -349.021447) (xy 303.174363 -348.968911) (xy 303.203083 -348.920087) (xy 303.238709 -348.876047)
			(xy 303.280457 -348.837761) (xy 303.327409 -348.806072) (xy 303.378531 -348.781676) (xy 303.4327 -348.76511)
			(xy 303.488723 -348.756738) (xy 303.517046 -348.756224) (xy 303.535065 -348.756444) (xy 303.57094 -348.759879)
			(xy 303.588674 -348.763082) (xy 303.598072 -348.76486) (xy 303.617122 -348.76105) (xy 303.692306 -348.713298)
			(xy 303.703736 -348.69755) (xy 303.706022 -348.688152) (xy 303.713412 -348.661106) (xy 303.735043 -348.609379)
			(xy 303.764008 -348.561373) (xy 303.799684 -348.518122) (xy 303.841305 -348.480555) (xy 303.887973 -348.449481)
			(xy 303.938685 -348.425569) (xy 303.99235 -348.409333) (xy 304.047813 -348.401122) (xy 304.075846 -348.400624)
			(xy 304.1031 -348.401035) (xy 304.157052 -348.408799) (xy 304.20935 -348.424161) (xy 304.25893 -348.44681)
			(xy 304.304781 -348.476284) (xy 304.345972 -348.511983) (xy 304.381663 -348.553181) (xy 304.411127 -348.599039)
			(xy 304.433766 -348.648623) (xy 304.449118 -348.700924) (xy 304.45687 -348.754878) (xy 304.457354 -348.782132)
			(xy 304.456858 -348.809706) (xy 304.448914 -348.864278) (xy 304.433196 -348.917138) (xy 304.410032 -348.967184)
			(xy 304.379904 -349.013375) (xy 304.34344 -349.054746) (xy 304.322734 -349.072962) (xy 304.314627 -349.080574)
			(xy 304.305269 -349.100719) (xy 304.3047 -349.111824) (xy 304.3047 -349.18904) (xy 304.30523 -349.200154)
			(xy 304.314596 -349.220313) (xy 304.322734 -349.227902) (xy 304.34347 -349.246084) (xy 304.37993 -349.287461)
			(xy 304.410054 -349.333656) (xy 304.433213 -349.383707) (xy 304.448924 -349.436571) (xy 304.456861 -349.491146)
			(xy 304.456858 -349.546295) (xy 304.448915 -349.60087) (xy 304.448339 -349.602806) (xy 305.58943 -349.602806)
			(xy 305.593501 -349.547184) (xy 305.605627 -349.492747) (xy 305.62555 -349.440656) (xy 305.652846 -349.392021)
			(xy 305.686932 -349.347878) (xy 305.727081 -349.309169) (xy 305.772439 -349.276718) (xy 305.822039 -349.251217)
			(xy 305.874823 -349.23321) (xy 305.929666 -349.22308) (xy 305.9854 -349.221043) (xy 306.040837 -349.227143)
			(xy 306.094794 -349.241249) (xy 306.146123 -349.263061) (xy 306.193729 -349.292115) (xy 306.236597 -349.32779)
			(xy 306.273814 -349.369327) (xy 306.304587 -349.41584) (xy 306.328259 -349.466337) (xy 306.344327 -349.519744)
			(xy 306.352447 -349.57492) (xy 306.352956 -349.602806) (xy 306.352447 -349.630692) (xy 306.344327 -349.685868)
			(xy 306.328259 -349.739275) (xy 306.304587 -349.789772) (xy 306.273814 -349.836285) (xy 306.236597 -349.877822)
			(xy 306.193729 -349.913497) (xy 306.146123 -349.942551) (xy 306.094794 -349.964363) (xy 306.040837 -349.978469)
			(xy 305.9854 -349.984569) (xy 305.929666 -349.982532) (xy 305.874823 -349.972402) (xy 305.822039 -349.954395)
			(xy 305.772439 -349.928894) (xy 305.727081 -349.896443) (xy 305.686932 -349.857734) (xy 305.652846 -349.813591)
			(xy 305.62555 -349.764956) (xy 305.605627 -349.712865) (xy 305.593501 -349.658428) (xy 305.58943 -349.602806)
			(xy 304.448339 -349.602806) (xy 304.433198 -349.653732) (xy 304.410034 -349.70378) (xy 304.379905 -349.749972)
			(xy 304.34344 -349.791345) (xy 304.322734 -349.809562) (xy 304.314627 -349.817174) (xy 304.305269 -349.837319)
			(xy 304.3047 -349.848424) (xy 304.3047 -349.92564) (xy 304.30523 -349.936754) (xy 304.314596 -349.956913)
			(xy 304.322734 -349.964502) (xy 304.343456 -349.982701) (xy 304.379924 -350.024073) (xy 304.410054 -350.070266)
			(xy 304.433218 -350.120316) (xy 304.448932 -350.17318) (xy 304.45687 -350.227757) (xy 304.457354 -350.255332)
			(xy 304.456852 -350.282582) (xy 304.449092 -350.336527) (xy 304.433736 -350.388818) (xy 304.411094 -350.438393)
			(xy 304.381629 -350.484241) (xy 304.369571 -350.498156) (xy 305.01031 -350.498156) (xy 305.014381 -350.442534)
			(xy 305.026507 -350.388097) (xy 305.04643 -350.336006) (xy 305.073726 -350.287371) (xy 305.107812 -350.243228)
			(xy 305.147961 -350.204519) (xy 305.193319 -350.172068) (xy 305.242919 -350.146567) (xy 305.295703 -350.12856)
			(xy 305.350546 -350.11843) (xy 305.40628 -350.116393) (xy 305.461717 -350.122493) (xy 305.515674 -350.136599)
			(xy 305.567003 -350.158411) (xy 305.614609 -350.187465) (xy 305.657477 -350.22314) (xy 305.694694 -350.264677)
			(xy 305.725467 -350.31119) (xy 305.749139 -350.361687) (xy 305.765207 -350.415094) (xy 305.773327 -350.47027)
			(xy 305.773836 -350.498156) (xy 305.773327 -350.526042) (xy 305.765207 -350.581218) (xy 305.749139 -350.634625)
			(xy 305.725467 -350.685122) (xy 305.694694 -350.731635) (xy 305.657477 -350.773172) (xy 305.614609 -350.808847)
			(xy 305.567003 -350.837901) (xy 305.515674 -350.859713) (xy 305.461717 -350.873819) (xy 305.40628 -350.879919)
			(xy 305.350546 -350.877882) (xy 305.295703 -350.867752) (xy 305.242919 -350.849745) (xy 305.193319 -350.824244)
			(xy 305.147961 -350.791793) (xy 305.107812 -350.753084) (xy 305.073726 -350.708941) (xy 305.04643 -350.660306)
			(xy 305.026507 -350.608215) (xy 305.014381 -350.553778) (xy 305.01031 -350.498156) (xy 304.369571 -350.498156)
			(xy 304.345939 -350.525429) (xy 304.304752 -350.56112) (xy 304.258905 -350.590587) (xy 304.209331 -350.613231)
			(xy 304.15704 -350.628589) (xy 304.103096 -350.636351) (xy 304.075846 -350.63684) (xy 304.047993 -350.636246)
			(xy 303.992882 -350.62813) (xy 303.939535 -350.612092) (xy 303.889085 -350.588474) (xy 303.842601 -350.557776)
			(xy 303.801071 -350.52065) (xy 303.765376 -350.477884) (xy 303.736273 -350.430385) (xy 303.714381 -350.379161)
			(xy 303.706784 -350.35236) (xy 303.704498 -350.34347) (xy 303.69383 -350.32823) (xy 303.621948 -350.280478)
			(xy 303.603914 -350.276414) (xy 303.59477 -350.277684) (xy 303.581754 -350.279354) (xy 303.555569 -350.281133)
			(xy 303.542446 -350.28124) (xy 303.528297 -350.281141) (xy 303.500074 -350.27911) (xy 303.486058 -350.277176)
			(xy 303.475898 -350.275652) (xy 303.45634 -350.280478) (xy 303.381918 -350.336358) (xy 303.371758 -350.353884)
			(xy 303.370488 -350.364044) (xy 303.366427 -350.391202) (xy 303.351453 -350.444035) (xy 303.329059 -350.494175)
			(xy 303.299709 -350.540587) (xy 303.264009 -350.582312) (xy 303.222695 -350.618488) (xy 303.176623 -350.648368)
			(xy 303.126743 -350.671335) (xy 303.074086 -350.686914) (xy 303.019739 -350.694784) (xy 302.992282 -350.69526)
			(xy 302.965026 -350.694862) (xy 302.911071 -350.687101) (xy 302.858769 -350.67174) (xy 302.809185 -350.649092)
			(xy 302.76333 -350.619618) (xy 302.722136 -350.583917) (xy 302.686443 -350.542717) (xy 302.656976 -350.496857)
			(xy 302.634337 -350.447269) (xy 302.618985 -350.394965) (xy 302.611234 -350.341008) (xy 302.610774 -350.313752)
			(xy 300.46986 -350.313752) (xy 300.472492 -350.322718) (xy 300.480246 -350.376669) (xy 300.48073 -350.403922)
			(xy 300.48006 -350.435484) (xy 300.469676 -350.497749) (xy 300.449195 -350.557459) (xy 300.434756 -350.585532)
			(xy 300.42993 -350.594422) (xy 300.427898 -350.61398) (xy 300.453552 -350.702118) (xy 300.465998 -350.717612)
			(xy 300.474888 -350.722692) (xy 300.500011 -350.737205) (xy 300.545894 -350.772714) (xy 300.585868 -350.814763)
			(xy 300.619012 -350.862383) (xy 300.644559 -350.914474) (xy 300.66192 -350.969834) (xy 300.670695 -351.027185)
			(xy 300.67123 -351.056194) (xy 300.671112 -351.071114) (xy 300.668821 -351.100867) (xy 300.666658 -351.11563)
			(xy 300.664626 -351.127822) (xy 300.671992 -351.150682) (xy 300.695111 -351.173796) (xy 306.349146 -351.173796)
			(xy 306.349619 -351.146321) (xy 306.357512 -351.09194) (xy 306.373135 -351.039257) (xy 306.396163 -350.989365)
			(xy 306.426118 -350.943297) (xy 306.443888 -350.922336) (xy 306.449984 -350.915224) (xy 306.456334 -350.898206)
			(xy 306.456334 -350.812354) (xy 306.449984 -350.795336) (xy 306.443888 -350.788224) (xy 306.426152 -350.767239)
			(xy 306.396224 -350.721163) (xy 306.373206 -350.671275) (xy 306.357573 -350.618603) (xy 306.349649 -350.564235)
			(xy 306.349146 -350.536764) (xy 306.349632 -350.509513) (xy 306.357388 -350.455565) (xy 306.372743 -350.40327)
			(xy 306.395385 -350.353693) (xy 306.424851 -350.307843) (xy 306.460542 -350.266652) (xy 306.501733 -350.230961)
			(xy 306.547583 -350.201495) (xy 306.59716 -350.178853) (xy 306.649455 -350.163498) (xy 306.703403 -350.155742)
			(xy 306.757905 -350.155742) (xy 306.811853 -350.163498) (xy 306.864148 -350.178853) (xy 306.913725 -350.201495)
			(xy 306.959575 -350.230961) (xy 307.000766 -350.266652) (xy 307.036457 -350.307843) (xy 307.065923 -350.353693)
			(xy 307.088565 -350.40327) (xy 307.10392 -350.455565) (xy 307.111676 -350.509513) (xy 307.112162 -350.536764)
			(xy 307.111664 -350.564238) (xy 307.103776 -350.618618) (xy 307.088159 -350.6713) (xy 307.065137 -350.721193)
			(xy 307.035187 -350.767262) (xy 307.01742 -350.788224) (xy 307.011324 -350.795336) (xy 307.004974 -350.812354)
			(xy 307.004974 -350.898206) (xy 307.011324 -350.915224) (xy 307.01742 -350.922336) (xy 307.035185 -350.943297)
			(xy 307.065109 -350.98938) (xy 307.088121 -351.039274) (xy 307.103747 -351.091951) (xy 307.111663 -351.146324)
			(xy 307.112162 -351.173796) (xy 307.111676 -351.201047) (xy 307.10392 -351.254995) (xy 307.088565 -351.30729)
			(xy 307.065923 -351.356867) (xy 307.036457 -351.402717) (xy 307.000766 -351.443908) (xy 306.959575 -351.479599)
			(xy 306.913725 -351.509065) (xy 306.864148 -351.531707) (xy 306.811853 -351.547062) (xy 306.757905 -351.554818)
			(xy 306.703403 -351.554818) (xy 306.649455 -351.547062) (xy 306.59716 -351.531707) (xy 306.547583 -351.509065)
			(xy 306.501733 -351.479599) (xy 306.460542 -351.443908) (xy 306.424851 -351.402717) (xy 306.395385 -351.356867)
			(xy 306.372743 -351.30729) (xy 306.357388 -351.254995) (xy 306.349632 -351.201047) (xy 306.349146 -351.173796)
			(xy 300.695111 -351.173796) (xy 301.743618 -352.222054) (xy 301.757475 -352.236508) (xy 301.779727 -352.269793)
			(xy 301.795051 -352.306783) (xy 301.802856 -352.346053) (xy 301.803308 -352.366072) (xy 301.803308 -354.711)
			(xy 302.969166 -354.711) (xy 302.973237 -354.655378) (xy 302.985363 -354.600941) (xy 303.005286 -354.54885)
			(xy 303.032582 -354.500215) (xy 303.066668 -354.456072) (xy 303.106817 -354.417363) (xy 303.152175 -354.384912)
			(xy 303.201775 -354.359411) (xy 303.254559 -354.341404) (xy 303.309402 -354.331274) (xy 303.365136 -354.329237)
			(xy 303.420573 -354.335337) (xy 303.47453 -354.349443) (xy 303.525859 -354.371255) (xy 303.573465 -354.400309)
			(xy 303.616333 -354.435984) (xy 303.65355 -354.477521) (xy 303.684323 -354.524034) (xy 303.707995 -354.574531)
			(xy 303.724063 -354.627938) (xy 303.732183 -354.683114) (xy 303.732692 -354.711) (xy 303.732183 -354.738886)
			(xy 303.724063 -354.794062) (xy 303.707995 -354.847469) (xy 303.684323 -354.897966) (xy 303.65355 -354.944479)
			(xy 303.616333 -354.986016) (xy 303.573465 -355.021691) (xy 303.525859 -355.050745) (xy 303.47453 -355.072557)
			(xy 303.420573 -355.086663) (xy 303.365136 -355.092763) (xy 303.309402 -355.090726) (xy 303.254559 -355.080596)
			(xy 303.201775 -355.062589) (xy 303.152175 -355.037088) (xy 303.106817 -355.004637) (xy 303.066668 -354.965928)
			(xy 303.032582 -354.921785) (xy 303.005286 -354.87315) (xy 302.985363 -354.821059) (xy 302.973237 -354.766622)
			(xy 302.969166 -354.711) (xy 301.803308 -354.711) (xy 301.803308 -358.7496) (xy 301.802786 -358.769611)
			(xy 301.794967 -358.808862) (xy 301.779648 -358.845837) (xy 301.757418 -358.879118) (xy 301.743618 -358.893618)
			(xy 301.38624 -359.250742) (xy 301.379538 -359.258216) (xy 301.371953 -359.276781) (xy 301.371508 -359.28681)
			(xy 301.371508 -360.234738) (xy 301.371876 -360.244035) (xy 301.378516 -360.261405) (xy 301.390882 -360.275293)
			(xy 301.39894 -360.27995) (xy 301.49165 -360.327956) (xy 301.519844 -360.326178) (xy 301.531528 -360.317796)
			(xy 301.555841 -360.301263) (xy 301.608476 -360.275066) (xy 301.664505 -360.257249) (xy 301.722603 -360.248234)
			(xy 301.752 -360.247692) (xy 301.779251 -360.248178) (xy 301.833199 -360.255934) (xy 301.885494 -360.271289)
			(xy 301.935071 -360.293931) (xy 301.980921 -360.323397) (xy 302.022112 -360.359088) (xy 302.057803 -360.400279)
			(xy 302.087269 -360.446129) (xy 302.109911 -360.495706) (xy 302.125266 -360.548001) (xy 302.133022 -360.601949)
			(xy 302.133022 -360.656451) (xy 302.125266 -360.710399) (xy 302.109911 -360.762694) (xy 302.087269 -360.812271)
			(xy 302.057803 -360.858121) (xy 302.022112 -360.899312) (xy 301.980921 -360.935003) (xy 301.935071 -360.964469)
			(xy 301.885494 -360.987111) (xy 301.833199 -361.002466) (xy 301.779251 -361.010222) (xy 301.752 -361.010708)
			(xy 301.722604 -361.010154) (xy 301.664506 -361.001141) (xy 301.608477 -360.983329) (xy 301.55584 -360.957137)
			(xy 301.531528 -360.940604) (xy 301.519844 -360.932222) (xy 301.49165 -360.930444) (xy 301.39894 -360.97845)
			(xy 301.390845 -360.98306) (xy 301.37844 -360.996939) (xy 301.371864 -361.014352) (xy 301.371508 -361.023662)
			(xy 301.371508 -361.66679) (xy 301.371854 -361.676838) (xy 301.37946 -361.695434) (xy 301.38624 -361.702858)
			(xy 301.862219 -362.1786) (xy 302.131982 -362.1786) (xy 302.136053 -362.122978) (xy 302.148179 -362.068541)
			(xy 302.168102 -362.01645) (xy 302.195398 -361.967815) (xy 302.229484 -361.923672) (xy 302.269633 -361.884963)
			(xy 302.314991 -361.852512) (xy 302.364591 -361.827011) (xy 302.417375 -361.809004) (xy 302.472218 -361.798874)
			(xy 302.527952 -361.796837) (xy 302.583389 -361.802937) (xy 302.637346 -361.817043) (xy 302.688675 -361.838855)
			(xy 302.736281 -361.867909) (xy 302.779149 -361.903584) (xy 302.816366 -361.945121) (xy 302.847139 -361.991634)
			(xy 302.870811 -362.042131) (xy 302.886879 -362.095538) (xy 302.894999 -362.150714) (xy 302.895508 -362.1786)
			(xy 302.894999 -362.206486) (xy 302.886879 -362.261662) (xy 302.870811 -362.315069) (xy 302.847139 -362.365566)
			(xy 302.816366 -362.412079) (xy 302.779149 -362.453616) (xy 302.736281 -362.489291) (xy 302.688675 -362.518345)
			(xy 302.637346 -362.540157) (xy 302.583389 -362.554263) (xy 302.527952 -362.560363) (xy 302.472218 -362.558326)
			(xy 302.417375 -362.548196) (xy 302.364591 -362.530189) (xy 302.314991 -362.504688) (xy 302.269633 -362.472237)
			(xy 302.229484 -362.433528) (xy 302.195398 -362.389385) (xy 302.168102 -362.34075) (xy 302.148179 -362.288659)
			(xy 302.136053 -362.234222) (xy 302.131982 -362.1786) (xy 301.862219 -362.1786) (xy 301.896018 -362.212382)
			(xy 301.909841 -362.226867) (xy 301.932099 -362.260141) (xy 301.947432 -362.297121) (xy 301.955249 -362.336384)
			(xy 301.955708 -362.3564) (xy 301.955708 -363.39399) (xy 301.956054 -363.404038) (xy 301.96366 -363.422634)
			(xy 301.97044 -363.430058) (xy 302.761142 -364.22076) (xy 302.768616 -364.227462) (xy 302.787181 -364.235047)
			(xy 302.79721 -364.235492) (xy 303.4284 -364.235492) (xy 303.448411 -364.236014) (xy 303.487662 -364.243833)
			(xy 303.524637 -364.259152) (xy 303.557918 -364.281382) (xy 303.572418 -364.295182) (xy 303.631854 -364.354618)
			(xy 303.661572 -364.360714) (xy 303.67605 -364.354618) (xy 303.685159 -364.350403) (xy 303.699332 -364.336215)
			(xy 303.706933 -364.317658) (xy 303.707292 -364.307628) (xy 303.707292 -362.04906) (xy 303.70684 -362.039185)
			(xy 303.699427 -362.020881) (xy 303.685668 -362.006714) (xy 303.676812 -362.002324) (xy 303.577244 -361.959144)
			(xy 303.547526 -361.964224) (xy 303.53635 -361.974638) (xy 303.515029 -361.993823) (xy 303.467752 -362.026293)
			(xy 303.416147 -362.051319) (xy 303.361377 -362.068339) (xy 303.304676 -362.076969) (xy 303.276 -362.077508)
			(xy 303.248749 -362.077022) (xy 303.194801 -362.069266) (xy 303.142506 -362.053911) (xy 303.092929 -362.031269)
			(xy 303.047079 -362.001803) (xy 303.005888 -361.966112) (xy 302.970197 -361.924921) (xy 302.940731 -361.879071)
			(xy 302.918089 -361.829494) (xy 302.902734 -361.777199) (xy 302.894978 -361.723251) (xy 302.894978 -361.668749)
			(xy 302.902734 -361.614801) (xy 302.918089 -361.562506) (xy 302.940731 -361.512929) (xy 302.970197 -361.467079)
			(xy 303.005888 -361.425888) (xy 303.047079 -361.390197) (xy 303.092929 -361.360731) (xy 303.142506 -361.338089)
			(xy 303.194801 -361.322734) (xy 303.248749 -361.314978) (xy 303.276 -361.314492) (xy 303.304677 -361.315053)
			(xy 303.36138 -361.323669) (xy 303.416155 -361.340677) (xy 303.467766 -361.365692) (xy 303.515051 -361.398153)
			(xy 303.53635 -361.417362) (xy 303.547526 -361.427776) (xy 303.577244 -361.432856) (xy 303.676812 -361.389676)
			(xy 303.685714 -361.38535) (xy 303.699511 -361.37118) (xy 303.706892 -361.352832) (xy 303.707292 -361.34294)
			(xy 303.707292 -359.63606) (xy 303.70684 -359.626185) (xy 303.699427 -359.607881) (xy 303.685668 -359.593714)
			(xy 303.676812 -359.589324) (xy 303.577244 -359.546144) (xy 303.547526 -359.551224) (xy 303.53635 -359.561638)
			(xy 303.515029 -359.580823) (xy 303.467752 -359.613293) (xy 303.416147 -359.638319) (xy 303.361377 -359.655339)
			(xy 303.304676 -359.663969) (xy 303.276 -359.664508) (xy 303.248749 -359.664022) (xy 303.194801 -359.656266)
			(xy 303.142506 -359.640911) (xy 303.092929 -359.618269) (xy 303.047079 -359.588803) (xy 303.005888 -359.553112)
			(xy 302.970197 -359.511921) (xy 302.940731 -359.466071) (xy 302.918089 -359.416494) (xy 302.902734 -359.364199)
			(xy 302.894978 -359.310251) (xy 302.894978 -359.255749) (xy 302.902734 -359.201801) (xy 302.918089 -359.149506)
			(xy 302.940731 -359.099929) (xy 302.970197 -359.054079) (xy 303.005888 -359.012888) (xy 303.047079 -358.977197)
			(xy 303.092929 -358.947731) (xy 303.142506 -358.925089) (xy 303.194801 -358.909734) (xy 303.248749 -358.901978)
			(xy 303.276 -358.901492) (xy 303.304677 -358.902053) (xy 303.36138 -358.910669) (xy 303.416155 -358.927677)
			(xy 303.467766 -358.952692) (xy 303.515051 -358.985153) (xy 303.53635 -359.004362) (xy 303.547526 -359.014776)
			(xy 303.577244 -359.019856) (xy 303.676812 -358.976676) (xy 303.685714 -358.97235) (xy 303.699511 -358.95818)
			(xy 303.706892 -358.939832) (xy 303.707292 -358.92994) (xy 303.707292 -358.47528) (xy 303.706896 -358.465165)
			(xy 303.699112 -358.446494) (xy 303.684748 -358.432249) (xy 303.675542 -358.428036) (xy 303.573688 -358.386888)
			(xy 303.543716 -358.393492) (xy 303.532794 -358.404668) (xy 303.51474 -358.422795) (xy 303.474644 -358.454569)
			(xy 303.430661 -358.4807) (xy 303.383581 -358.500719) (xy 303.334247 -358.514266) (xy 303.283546 -358.521098)
			(xy 303.257966 -358.521508) (xy 303.230716 -358.52102) (xy 303.176772 -358.513259) (xy 303.124482 -358.497901)
			(xy 303.074909 -358.475258) (xy 303.029063 -358.445791) (xy 302.987876 -358.4101) (xy 302.952189 -358.36891)
			(xy 302.922725 -358.323061) (xy 302.900087 -358.273486) (xy 302.884733 -358.221194) (xy 302.876978 -358.16725)
			(xy 302.876978 -358.11275) (xy 302.884733 -358.058806) (xy 302.900087 -358.006514) (xy 302.922725 -357.956939)
			(xy 302.952189 -357.91109) (xy 302.987876 -357.8699) (xy 303.029063 -357.834209) (xy 303.074909 -357.804742)
			(xy 303.124482 -357.782099) (xy 303.176772 -357.766741) (xy 303.230716 -357.75898) (xy 303.257966 -357.758492)
			(xy 303.283546 -357.758876) (xy 303.334245 -357.765727) (xy 303.383576 -357.779285) (xy 303.430656 -357.799307)
			(xy 303.474642 -357.825434) (xy 303.514746 -357.8572) (xy 303.532794 -357.875332) (xy 303.543716 -357.886508)
			(xy 303.573688 -357.893112) (xy 303.675542 -357.851964) (xy 303.684784 -357.847805) (xy 303.699185 -357.833566)
			(xy 303.706918 -357.814849) (xy 303.707292 -357.80472) (xy 303.707292 -357.418132) (xy 303.706927 -357.40928)
			(xy 303.700889 -357.392635) (xy 303.689581 -357.37901) (xy 303.682146 -357.37419) (xy 303.59477 -357.323136)
			(xy 303.567846 -357.322882) (xy 303.555908 -357.329486) (xy 303.534417 -357.341113) (xy 303.489118 -357.35943)
			(xy 303.441853 -357.371825) (xy 303.393395 -357.378098) (xy 303.368964 -357.378508) (xy 303.341714 -357.37802)
			(xy 303.287771 -357.370259) (xy 303.23548 -357.354901) (xy 303.185907 -357.332258) (xy 303.140062 -357.30279)
			(xy 303.098876 -357.267099) (xy 303.063188 -357.22591) (xy 303.033725 -357.180061) (xy 303.011087 -357.130486)
			(xy 302.995733 -357.078194) (xy 302.987978 -357.02425) (xy 302.987978 -356.96975) (xy 302.995733 -356.915806)
			(xy 303.011087 -356.863514) (xy 303.033725 -356.813939) (xy 303.063188 -356.76809) (xy 303.098876 -356.726901)
			(xy 303.140062 -356.69121) (xy 303.185907 -356.661742) (xy 303.23548 -356.639099) (xy 303.287771 -356.623741)
			(xy 303.341714 -356.61598) (xy 303.368964 -356.615492) (xy 303.393399 -356.61585) (xy 303.441869 -356.622099)
			(xy 303.48914 -356.634499) (xy 303.534436 -356.652845) (xy 303.555908 -356.664514) (xy 303.567846 -356.671118)
			(xy 303.59477 -356.670864) (xy 303.682146 -356.61981) (xy 303.689678 -356.615102) (xy 303.701047 -356.601466)
			(xy 303.707021 -356.584748) (xy 303.707292 -356.575868) (xy 303.707292 -356.20706) (xy 303.70684 -356.197185)
			(xy 303.699427 -356.178881) (xy 303.685668 -356.164714) (xy 303.676812 -356.160324) (xy 303.577244 -356.117144)
			(xy 303.547526 -356.122224) (xy 303.53635 -356.132638) (xy 303.515029 -356.151823) (xy 303.467752 -356.184293)
			(xy 303.416147 -356.209319) (xy 303.361377 -356.226339) (xy 303.304676 -356.234969) (xy 303.276 -356.235508)
			(xy 303.248749 -356.235022) (xy 303.194801 -356.227266) (xy 303.142506 -356.211911) (xy 303.092929 -356.189269)
			(xy 303.047079 -356.159803) (xy 303.005888 -356.124112) (xy 302.970197 -356.082921) (xy 302.940731 -356.037071)
			(xy 302.918089 -355.987494) (xy 302.902734 -355.935199) (xy 302.894978 -355.881251) (xy 302.894978 -355.826749)
			(xy 302.902734 -355.772801) (xy 302.918089 -355.720506) (xy 302.940731 -355.670929) (xy 302.970197 -355.625079)
			(xy 303.005888 -355.583888) (xy 303.047079 -355.548197) (xy 303.092929 -355.518731) (xy 303.142506 -355.496089)
			(xy 303.194801 -355.480734) (xy 303.248749 -355.472978) (xy 303.276 -355.472492) (xy 303.304677 -355.473053)
			(xy 303.36138 -355.481669) (xy 303.416155 -355.498677) (xy 303.467766 -355.523692) (xy 303.515051 -355.556153)
			(xy 303.53635 -355.575362) (xy 303.547526 -355.585776) (xy 303.577244 -355.590856) (xy 303.676812 -355.547676)
			(xy 303.685714 -355.54335) (xy 303.699511 -355.52918) (xy 303.706892 -355.510832) (xy 303.707292 -355.50094)
			(xy 303.707292 -355.3714) (xy 303.707814 -355.351389) (xy 303.715633 -355.312138) (xy 303.730952 -355.275163)
			(xy 303.753182 -355.241882) (xy 303.766982 -355.227382) (xy 307.803042 -351.191322) (xy 307.817509 -351.177535)
			(xy 307.850778 -351.155402) (xy 307.869082 -351.14738) (xy 308.23154 -350.997266) (xy 308.247034 -350.978978)
			(xy 308.250082 -350.966786) (xy 308.256249 -350.942802) (xy 308.27396 -350.896554) (xy 308.285388 -350.874584)
			(xy 308.290214 -350.865694) (xy 308.292246 -350.846136) (xy 308.266592 -350.757998) (xy 308.254146 -350.742504)
			(xy 308.245256 -350.737424) (xy 308.23789 -350.73336) (xy 308.228238 -350.727518) (xy 308.20614 -350.725486)
			(xy 308.111652 -350.759014) (xy 308.09565 -350.774508) (xy 308.091586 -350.784922) (xy 308.08093 -350.811715)
			(xy 308.052637 -350.861958) (xy 308.017101 -350.907368) (xy 307.975133 -350.94691) (xy 307.92769 -350.979681)
			(xy 307.875854 -351.004936) (xy 307.820805 -351.022098) (xy 307.763801 -351.030775) (xy 307.73497 -351.031302)
			(xy 307.70772 -351.030826) (xy 307.653774 -351.023066) (xy 307.601482 -351.007708) (xy 307.551908 -350.985065)
			(xy 307.506061 -350.955597) (xy 307.464874 -350.919905) (xy 307.429185 -350.878715) (xy 307.399721 -350.832865)
			(xy 307.377081 -350.783289) (xy 307.361728 -350.730996) (xy 307.353972 -350.67705) (xy 307.353972 -350.62255)
			(xy 307.361728 -350.568604) (xy 307.377081 -350.516311) (xy 307.399721 -350.466735) (xy 307.429185 -350.420885)
			(xy 307.464874 -350.379695) (xy 307.506061 -350.344003) (xy 307.551908 -350.314535) (xy 307.601482 -350.291892)
			(xy 307.653774 -350.276534) (xy 307.70772 -350.268774) (xy 307.73497 -350.268286) (xy 307.760206 -350.268654)
			(xy 307.810241 -350.275281) (xy 307.858962 -350.288463) (xy 307.905512 -350.307967) (xy 307.927502 -350.320356)
			(xy 307.937154 -350.326198) (xy 307.959252 -350.32823) (xy 308.05374 -350.294702) (xy 308.069742 -350.279208)
			(xy 308.073806 -350.268794) (xy 308.084477 -350.242007) (xy 308.112768 -350.191764) (xy 308.148301 -350.146354)
			(xy 308.190266 -350.106811) (xy 308.237707 -350.074039) (xy 308.289542 -350.048783) (xy 308.344589 -350.03162)
			(xy 308.401592 -350.022941) (xy 308.430422 -350.022414) (xy 308.457675 -350.022857) (xy 308.511625 -350.030617)
			(xy 308.563922 -350.045977) (xy 308.613501 -350.068622) (xy 308.659352 -350.098092) (xy 308.700543 -350.133788)
			(xy 308.736234 -350.174983) (xy 308.765699 -350.220838) (xy 308.788339 -350.270419) (xy 308.80106 -350.313752)
			(xy 310.941974 -350.313752) (xy 310.942485 -350.286179) (xy 310.950429 -350.231609) (xy 310.966146 -350.17875)
			(xy 310.989308 -350.128704) (xy 311.019432 -350.082513) (xy 311.055891 -350.04114) (xy 311.076594 -350.022922)
			(xy 311.084697 -350.015306) (xy 311.09406 -349.995165) (xy 311.094628 -349.98406) (xy 311.094628 -349.906844)
			(xy 311.094075 -349.895732) (xy 311.084728 -349.875572) (xy 311.076594 -349.867982) (xy 311.05587 -349.849785)
			(xy 311.019401 -349.808413) (xy 310.98927 -349.76222) (xy 310.966107 -349.71217) (xy 310.950393 -349.659304)
			(xy 310.942457 -349.604728) (xy 310.941974 -349.577152) (xy 310.942433 -349.5499) (xy 310.950196 -349.495953)
			(xy 310.965556 -349.443659) (xy 310.988201 -349.394082) (xy 311.017671 -349.348233) (xy 311.053365 -349.307044)
			(xy 311.094557 -349.271353) (xy 311.140409 -349.241887) (xy 311.189987 -349.219245) (xy 311.242282 -349.203889)
			(xy 311.29623 -349.196131) (xy 311.323482 -349.195644) (xy 311.357772 -349.197168) (xy 311.367932 -349.198184)
			(xy 311.387236 -349.192088) (xy 311.457848 -349.132906) (xy 311.467246 -349.114872) (xy 311.468262 -349.104712)
			(xy 311.471203 -349.076538) (xy 311.484381 -349.021447) (xy 311.505563 -348.968911) (xy 311.534283 -348.920087)
			(xy 311.569909 -348.876047) (xy 311.611657 -348.837761) (xy 311.658609 -348.806072) (xy 311.709731 -348.781676)
			(xy 311.7639 -348.76511) (xy 311.819923 -348.756738) (xy 311.848246 -348.756224) (xy 311.866265 -348.756444)
			(xy 311.90214 -348.759879) (xy 311.919874 -348.763082) (xy 311.929272 -348.76486) (xy 311.948322 -348.76105)
			(xy 312.023506 -348.713298) (xy 312.034936 -348.69755) (xy 312.037222 -348.688152) (xy 312.044612 -348.661106)
			(xy 312.066243 -348.609379) (xy 312.095208 -348.561373) (xy 312.130884 -348.518122) (xy 312.172505 -348.480555)
			(xy 312.219173 -348.449481) (xy 312.269885 -348.425569) (xy 312.32355 -348.409333) (xy 312.379013 -348.401122)
			(xy 312.407046 -348.400624) (xy 312.4343 -348.401035) (xy 312.488252 -348.408799) (xy 312.54055 -348.424161)
			(xy 312.59013 -348.44681) (xy 312.635981 -348.476284) (xy 312.677172 -348.511983) (xy 312.712863 -348.553181)
			(xy 312.742327 -348.599039) (xy 312.764966 -348.648623) (xy 312.780318 -348.700924) (xy 312.78807 -348.754878)
			(xy 312.788554 -348.782132) (xy 312.788058 -348.809706) (xy 312.780114 -348.864278) (xy 312.764396 -348.917138)
			(xy 312.741232 -348.967184) (xy 312.711104 -349.013375) (xy 312.67464 -349.054746) (xy 312.653934 -349.072962)
			(xy 312.645827 -349.080574) (xy 312.636469 -349.100719) (xy 312.6359 -349.111824) (xy 312.6359 -349.18904)
			(xy 312.63643 -349.200154) (xy 312.645796 -349.220313) (xy 312.653934 -349.227902) (xy 312.67467 -349.246084)
			(xy 312.71113 -349.287461) (xy 312.741254 -349.333656) (xy 312.764413 -349.383707) (xy 312.780124 -349.436571)
			(xy 312.788061 -349.491146) (xy 312.788058 -349.546295) (xy 312.780115 -349.60087) (xy 312.764398 -349.653732)
			(xy 312.741234 -349.70378) (xy 312.711105 -349.749972) (xy 312.67464 -349.791345) (xy 312.653934 -349.809562)
			(xy 312.645827 -349.817174) (xy 312.636469 -349.837319) (xy 312.6359 -349.848424) (xy 312.6359 -349.92564)
			(xy 312.63643 -349.936754) (xy 312.645796 -349.956913) (xy 312.653934 -349.964502) (xy 312.674656 -349.982701)
			(xy 312.711124 -350.024073) (xy 312.741254 -350.070266) (xy 312.764418 -350.120316) (xy 312.780132 -350.17318)
			(xy 312.78807 -350.227757) (xy 312.788554 -350.255332) (xy 312.788052 -350.282582) (xy 312.780292 -350.336527)
			(xy 312.764936 -350.388818) (xy 312.742294 -350.438393) (xy 312.712829 -350.484241) (xy 312.677139 -350.525429)
			(xy 312.635952 -350.56112) (xy 312.590105 -350.590587) (xy 312.540531 -350.613231) (xy 312.48824 -350.628589)
			(xy 312.434296 -350.636351) (xy 312.407046 -350.63684) (xy 312.379193 -350.636246) (xy 312.324082 -350.62813)
			(xy 312.270735 -350.612092) (xy 312.220285 -350.588474) (xy 312.173801 -350.557776) (xy 312.132271 -350.52065)
			(xy 312.096576 -350.477884) (xy 312.067473 -350.430385) (xy 312.045581 -350.379161) (xy 312.037984 -350.35236)
			(xy 312.035698 -350.34347) (xy 312.02503 -350.32823) (xy 311.953148 -350.280478) (xy 311.935114 -350.276414)
			(xy 311.92597 -350.277684) (xy 311.912954 -350.279354) (xy 311.886769 -350.281133) (xy 311.873646 -350.28124)
			(xy 311.859497 -350.281141) (xy 311.831274 -350.27911) (xy 311.817258 -350.277176) (xy 311.807098 -350.275652)
			(xy 311.78754 -350.280478) (xy 311.713118 -350.336358) (xy 311.702958 -350.353884) (xy 311.701688 -350.364044)
			(xy 311.697627 -350.391202) (xy 311.682653 -350.444035) (xy 311.660259 -350.494175) (xy 311.630909 -350.540587)
			(xy 311.595209 -350.582312) (xy 311.553895 -350.618488) (xy 311.507823 -350.648368) (xy 311.457943 -350.671335)
			(xy 311.405286 -350.686914) (xy 311.350939 -350.694784) (xy 311.323482 -350.69526) (xy 311.296226 -350.694862)
			(xy 311.242271 -350.687101) (xy 311.189969 -350.67174) (xy 311.140385 -350.649092) (xy 311.09453 -350.619618)
			(xy 311.053336 -350.583917) (xy 311.017643 -350.542717) (xy 310.988176 -350.496857) (xy 310.965537 -350.447269)
			(xy 310.950185 -350.394965) (xy 310.942434 -350.341008) (xy 310.941974 -350.313752) (xy 308.80106 -350.313752)
			(xy 308.803692 -350.322718) (xy 308.811446 -350.376669) (xy 308.81193 -350.403922) (xy 308.81126 -350.435484)
			(xy 308.800876 -350.497749) (xy 308.780395 -350.557459) (xy 308.765956 -350.585532) (xy 308.76113 -350.594422)
			(xy 308.759098 -350.61398) (xy 308.784752 -350.702118) (xy 308.797198 -350.717612) (xy 308.806088 -350.722692)
			(xy 308.831211 -350.737205) (xy 308.877094 -350.772714) (xy 308.917068 -350.814763) (xy 308.950212 -350.862383)
			(xy 308.975759 -350.914474) (xy 308.99312 -350.969834) (xy 309.001895 -351.027185) (xy 309.00243 -351.056194)
			(xy 309.001917 -351.083444) (xy 308.994162 -351.13739) (xy 308.978808 -351.189683) (xy 308.956169 -351.239258)
			(xy 308.926706 -351.285108) (xy 308.891017 -351.326297) (xy 308.84983 -351.361989) (xy 308.803983 -351.391456)
			(xy 308.754409 -351.414099) (xy 308.702117 -351.429456) (xy 308.648172 -351.437215) (xy 308.620922 -351.437702)
			(xy 308.59472 -351.437269) (xy 308.54281 -351.430094) (xy 308.492372 -351.415876) (xy 308.444357 -351.394883)
			(xy 308.421786 -351.381568) (xy 308.411372 -351.375218) (xy 308.387242 -351.373186) (xy 308.071774 -351.503996)
			(xy 308.067186 -351.506041) (xy 308.058872 -351.511677) (xy 308.055264 -351.515172) (xy 306.637344 -352.933)
			(xy 314.527182 -352.933) (xy 314.531253 -352.877378) (xy 314.543379 -352.822941) (xy 314.563302 -352.77085)
			(xy 314.590598 -352.722215) (xy 314.624684 -352.678072) (xy 314.664833 -352.639363) (xy 314.710191 -352.606912)
			(xy 314.759791 -352.581411) (xy 314.812575 -352.563404) (xy 314.867418 -352.553274) (xy 314.923152 -352.551237)
			(xy 314.978589 -352.557337) (xy 315.032546 -352.571443) (xy 315.083875 -352.593255) (xy 315.131481 -352.622309)
			(xy 315.174349 -352.657984) (xy 315.211566 -352.699521) (xy 315.242339 -352.746034) (xy 315.266011 -352.796531)
			(xy 315.282079 -352.849938) (xy 315.290199 -352.905114) (xy 315.290708 -352.933) (xy 315.290199 -352.960886)
			(xy 315.282079 -353.016062) (xy 315.266011 -353.069469) (xy 315.242339 -353.119966) (xy 315.211566 -353.166479)
			(xy 315.174349 -353.208016) (xy 315.131481 -353.243691) (xy 315.083875 -353.272745) (xy 315.032546 -353.294557)
			(xy 314.978589 -353.308663) (xy 314.923152 -353.314763) (xy 314.867418 -353.312726) (xy 314.812575 -353.302596)
			(xy 314.759791 -353.284589) (xy 314.710191 -353.259088) (xy 314.664833 -353.226637) (xy 314.624684 -353.187928)
			(xy 314.590598 -353.143785) (xy 314.563302 -353.09515) (xy 314.543379 -353.043059) (xy 314.531253 -352.988622)
			(xy 314.527182 -352.933) (xy 306.637344 -352.933) (xy 305.970551 -353.59975) (xy 307.212492 -353.59975)
			(xy 307.212978 -353.572499) (xy 307.220734 -353.518551) (xy 307.236089 -353.466256) (xy 307.258731 -353.416679)
			(xy 307.288197 -353.370829) (xy 307.323888 -353.329638) (xy 307.365079 -353.293947) (xy 307.410929 -353.264481)
			(xy 307.460506 -353.241839) (xy 307.512801 -353.226484) (xy 307.566749 -353.218728) (xy 307.621251 -353.218728)
			(xy 307.675199 -353.226484) (xy 307.727494 -353.241839) (xy 307.777071 -353.264481) (xy 307.822921 -353.293947)
			(xy 307.864112 -353.329638) (xy 307.899803 -353.370829) (xy 307.929269 -353.416679) (xy 307.951911 -353.466256)
			(xy 307.967266 -353.518551) (xy 307.975022 -353.572499) (xy 307.975168 -353.5807) (xy 309.409082 -353.5807)
			(xy 309.413153 -353.525078) (xy 309.425279 -353.470641) (xy 309.445202 -353.41855) (xy 309.472498 -353.369915)
			(xy 309.506584 -353.325772) (xy 309.546733 -353.287063) (xy 309.592091 -353.254612) (xy 309.641691 -353.229111)
			(xy 309.694475 -353.211104) (xy 309.749318 -353.200974) (xy 309.805052 -353.198937) (xy 309.860489 -353.205037)
			(xy 309.914446 -353.219143) (xy 309.965775 -353.240955) (xy 310.013381 -353.270009) (xy 310.056249 -353.305684)
			(xy 310.093466 -353.347221) (xy 310.121901 -353.3902) (xy 311.733182 -353.3902) (xy 311.737253 -353.334578)
			(xy 311.749379 -353.280141) (xy 311.769302 -353.22805) (xy 311.796598 -353.179415) (xy 311.830684 -353.135272)
			(xy 311.870833 -353.096563) (xy 311.916191 -353.064112) (xy 311.965791 -353.038611) (xy 312.018575 -353.020604)
			(xy 312.073418 -353.010474) (xy 312.129152 -353.008437) (xy 312.184589 -353.014537) (xy 312.238546 -353.028643)
			(xy 312.289875 -353.050455) (xy 312.337481 -353.079509) (xy 312.380349 -353.115184) (xy 312.417566 -353.156721)
			(xy 312.448339 -353.203234) (xy 312.472011 -353.253731) (xy 312.488079 -353.307138) (xy 312.496199 -353.362314)
			(xy 312.496244 -353.3648) (xy 313.409582 -353.3648) (xy 313.413653 -353.309178) (xy 313.425779 -353.254741)
			(xy 313.445702 -353.20265) (xy 313.472998 -353.154015) (xy 313.507084 -353.109872) (xy 313.547233 -353.071163)
			(xy 313.592591 -353.038712) (xy 313.642191 -353.013211) (xy 313.694975 -352.995204) (xy 313.749818 -352.985074)
			(xy 313.805552 -352.983037) (xy 313.860989 -352.989137) (xy 313.914946 -353.003243) (xy 313.966275 -353.025055)
			(xy 314.013881 -353.054109) (xy 314.056749 -353.089784) (xy 314.093966 -353.131321) (xy 314.124739 -353.177834)
			(xy 314.148411 -353.228331) (xy 314.164479 -353.281738) (xy 314.172599 -353.336914) (xy 314.173108 -353.3648)
			(xy 314.172599 -353.392686) (xy 314.164479 -353.447862) (xy 314.148411 -353.501269) (xy 314.124739 -353.551766)
			(xy 314.093966 -353.598279) (xy 314.056749 -353.639816) (xy 314.013881 -353.675491) (xy 313.966275 -353.704545)
			(xy 313.914946 -353.726357) (xy 313.860989 -353.740463) (xy 313.805552 -353.746563) (xy 313.749818 -353.744526)
			(xy 313.694975 -353.734396) (xy 313.642191 -353.716389) (xy 313.592591 -353.690888) (xy 313.547233 -353.658437)
			(xy 313.507084 -353.619728) (xy 313.472998 -353.575585) (xy 313.445702 -353.52695) (xy 313.425779 -353.474859)
			(xy 313.413653 -353.420422) (xy 313.409582 -353.3648) (xy 312.496244 -353.3648) (xy 312.496708 -353.3902)
			(xy 312.496199 -353.418086) (xy 312.488079 -353.473262) (xy 312.472011 -353.526669) (xy 312.448339 -353.577166)
			(xy 312.417566 -353.623679) (xy 312.380349 -353.665216) (xy 312.337481 -353.700891) (xy 312.289875 -353.729945)
			(xy 312.238546 -353.751757) (xy 312.184589 -353.765863) (xy 312.129152 -353.771963) (xy 312.073418 -353.769926)
			(xy 312.018575 -353.759796) (xy 311.965791 -353.741789) (xy 311.916191 -353.716288) (xy 311.870833 -353.683837)
			(xy 311.830684 -353.645128) (xy 311.796598 -353.600985) (xy 311.769302 -353.55235) (xy 311.749379 -353.500259)
			(xy 311.737253 -353.445822) (xy 311.733182 -353.3902) (xy 310.121901 -353.3902) (xy 310.124239 -353.393734)
			(xy 310.147911 -353.444231) (xy 310.163979 -353.497638) (xy 310.172099 -353.552814) (xy 310.172608 -353.5807)
			(xy 310.172099 -353.608586) (xy 310.163979 -353.663762) (xy 310.147911 -353.717169) (xy 310.124239 -353.767666)
			(xy 310.093466 -353.814179) (xy 310.056249 -353.855716) (xy 310.013381 -353.891391) (xy 309.965775 -353.920445)
			(xy 309.914446 -353.942257) (xy 309.888653 -353.949) (xy 310.564782 -353.949) (xy 310.568853 -353.893378)
			(xy 310.580979 -353.838941) (xy 310.600902 -353.78685) (xy 310.628198 -353.738215) (xy 310.662284 -353.694072)
			(xy 310.702433 -353.655363) (xy 310.747791 -353.622912) (xy 310.797391 -353.597411) (xy 310.850175 -353.579404)
			(xy 310.905018 -353.569274) (xy 310.960752 -353.567237) (xy 311.016189 -353.573337) (xy 311.070146 -353.587443)
			(xy 311.121475 -353.609255) (xy 311.169081 -353.638309) (xy 311.211949 -353.673984) (xy 311.249166 -353.715521)
			(xy 311.279939 -353.762034) (xy 311.303611 -353.812531) (xy 311.319679 -353.865938) (xy 311.327799 -353.921114)
			(xy 311.328308 -353.949) (xy 311.327799 -353.976886) (xy 311.319679 -354.032062) (xy 311.303611 -354.085469)
			(xy 311.279939 -354.135966) (xy 311.249166 -354.182479) (xy 311.211949 -354.224016) (xy 311.169081 -354.259691)
			(xy 311.121475 -354.288745) (xy 311.070146 -354.310557) (xy 311.016189 -354.324663) (xy 310.960752 -354.330763)
			(xy 310.905018 -354.328726) (xy 310.850175 -354.318596) (xy 310.797391 -354.300589) (xy 310.747791 -354.275088)
			(xy 310.702433 -354.242637) (xy 310.662284 -354.203928) (xy 310.628198 -354.159785) (xy 310.600902 -354.11115)
			(xy 310.580979 -354.059059) (xy 310.568853 -354.004622) (xy 310.564782 -353.949) (xy 309.888653 -353.949)
			(xy 309.860489 -353.956363) (xy 309.805052 -353.962463) (xy 309.749318 -353.960426) (xy 309.694475 -353.950296)
			(xy 309.641691 -353.932289) (xy 309.592091 -353.906788) (xy 309.546733 -353.874337) (xy 309.506584 -353.835628)
			(xy 309.472498 -353.791485) (xy 309.445202 -353.74285) (xy 309.425279 -353.690759) (xy 309.413153 -353.636322)
			(xy 309.409082 -353.5807) (xy 307.975168 -353.5807) (xy 307.975508 -353.59975) (xy 307.974903 -353.628935)
			(xy 307.966012 -353.686624) (xy 307.948445 -353.742289) (xy 307.922611 -353.794631) (xy 307.889112 -353.842432)
			(xy 307.848729 -353.884578) (xy 307.825902 -353.902772) (xy 307.815264 -353.911392) (xy 307.798733 -353.933209)
			(xy 307.788603 -353.958638) (xy 307.785606 -353.985847) (xy 307.789959 -354.012871) (xy 307.801346 -354.037763)
			(xy 307.818946 -354.058727) (xy 307.829966 -354.066856) (xy 307.851369 -354.082218) (xy 307.89017 -354.117855)
			(xy 307.923701 -354.158491) (xy 307.951324 -354.203352) (xy 307.972514 -354.251586) (xy 307.986869 -354.302276)
			(xy 307.994115 -354.354458) (xy 307.994558 -354.3808) (xy 307.994072 -354.408051) (xy 307.986316 -354.461999)
			(xy 307.980326 -354.4824) (xy 312.977782 -354.4824) (xy 312.981853 -354.426778) (xy 312.993979 -354.372341)
			(xy 313.013902 -354.32025) (xy 313.041198 -354.271615) (xy 313.075284 -354.227472) (xy 313.115433 -354.188763)
			(xy 313.160791 -354.156312) (xy 313.210391 -354.130811) (xy 313.263175 -354.112804) (xy 313.318018 -354.102674)
			(xy 313.373752 -354.100637) (xy 313.429189 -354.106737) (xy 313.483146 -354.120843) (xy 313.534475 -354.142655)
			(xy 313.582081 -354.171709) (xy 313.624949 -354.207384) (xy 313.662166 -354.248921) (xy 313.692939 -354.295434)
			(xy 313.716611 -354.345931) (xy 313.732679 -354.399338) (xy 313.740799 -354.454514) (xy 313.740844 -354.457)
			(xy 314.120782 -354.457) (xy 314.124853 -354.401378) (xy 314.136979 -354.346941) (xy 314.156902 -354.29485)
			(xy 314.184198 -354.246215) (xy 314.218284 -354.202072) (xy 314.258433 -354.163363) (xy 314.303791 -354.130912)
			(xy 314.353391 -354.105411) (xy 314.406175 -354.087404) (xy 314.461018 -354.077274) (xy 314.516752 -354.075237)
			(xy 314.572189 -354.081337) (xy 314.626146 -354.095443) (xy 314.677475 -354.117255) (xy 314.725081 -354.146309)
			(xy 314.767949 -354.181984) (xy 314.805166 -354.223521) (xy 314.835939 -354.270034) (xy 314.859611 -354.320531)
			(xy 314.875679 -354.373938) (xy 314.883799 -354.429114) (xy 314.884308 -354.457) (xy 314.883799 -354.484886)
			(xy 314.875679 -354.540062) (xy 314.859611 -354.593469) (xy 314.835939 -354.643966) (xy 314.805166 -354.690479)
			(xy 314.767949 -354.732016) (xy 314.725081 -354.767691) (xy 314.677475 -354.796745) (xy 314.626146 -354.818557)
			(xy 314.572189 -354.832663) (xy 314.516752 -354.838763) (xy 314.461018 -354.836726) (xy 314.406175 -354.826596)
			(xy 314.353391 -354.808589) (xy 314.303791 -354.783088) (xy 314.258433 -354.750637) (xy 314.218284 -354.711928)
			(xy 314.184198 -354.667785) (xy 314.156902 -354.61915) (xy 314.136979 -354.567059) (xy 314.124853 -354.512622)
			(xy 314.120782 -354.457) (xy 313.740844 -354.457) (xy 313.741308 -354.4824) (xy 313.740799 -354.510286)
			(xy 313.732679 -354.565462) (xy 313.716611 -354.618869) (xy 313.692939 -354.669366) (xy 313.662166 -354.715879)
			(xy 313.624949 -354.757416) (xy 313.582081 -354.793091) (xy 313.534475 -354.822145) (xy 313.483146 -354.843957)
			(xy 313.429189 -354.858063) (xy 313.373752 -354.864163) (xy 313.318018 -354.862126) (xy 313.263175 -354.851996)
			(xy 313.210391 -354.833989) (xy 313.160791 -354.808488) (xy 313.115433 -354.776037) (xy 313.075284 -354.737328)
			(xy 313.041198 -354.693185) (xy 313.013902 -354.64455) (xy 312.993979 -354.592459) (xy 312.981853 -354.538022)
			(xy 312.977782 -354.4824) (xy 307.980326 -354.4824) (xy 307.970961 -354.514294) (xy 307.948319 -354.563871)
			(xy 307.918853 -354.609721) (xy 307.883162 -354.650912) (xy 307.841971 -354.686603) (xy 307.796121 -354.716069)
			(xy 307.746544 -354.738711) (xy 307.694249 -354.754066) (xy 307.640301 -354.761822) (xy 307.585799 -354.761822)
			(xy 307.531851 -354.754066) (xy 307.479556 -354.738711) (xy 307.429979 -354.716069) (xy 307.384129 -354.686603)
			(xy 307.342938 -354.650912) (xy 307.307247 -354.609721) (xy 307.277781 -354.563871) (xy 307.255139 -354.514294)
			(xy 307.239784 -354.461999) (xy 307.232028 -354.408051) (xy 307.231542 -354.3808) (xy 307.232092 -354.351613)
			(xy 307.240992 -354.29392) (xy 307.258568 -354.238254) (xy 307.284413 -354.185911) (xy 307.317922 -354.138112)
			(xy 307.358316 -354.095969) (xy 307.381148 -354.077778) (xy 307.391729 -354.069096) (xy 307.408252 -354.047292)
			(xy 307.41838 -354.021877) (xy 307.421381 -353.994684) (xy 307.417041 -353.967672) (xy 307.405672 -353.942789)
			(xy 307.388092 -353.921826) (xy 307.377084 -353.913694) (xy 307.355646 -353.898378) (xy 307.316848 -353.862732)
			(xy 307.283322 -353.822087) (xy 307.255704 -353.777219) (xy 307.234519 -353.728978) (xy 307.220171 -353.678281)
			(xy 307.212932 -353.626094) (xy 307.212492 -353.59975) (xy 305.970551 -353.59975) (xy 304.24959 -355.3206)
			(xy 309.370982 -355.3206) (xy 309.375053 -355.264978) (xy 309.387179 -355.210541) (xy 309.407102 -355.15845)
			(xy 309.434398 -355.109815) (xy 309.468484 -355.065672) (xy 309.508633 -355.026963) (xy 309.553991 -354.994512)
			(xy 309.603591 -354.969011) (xy 309.656375 -354.951004) (xy 309.711218 -354.940874) (xy 309.766952 -354.938837)
			(xy 309.822389 -354.944937) (xy 309.876346 -354.959043) (xy 309.927675 -354.980855) (xy 309.975281 -355.009909)
			(xy 310.018149 -355.045584) (xy 310.055366 -355.087121) (xy 310.086139 -355.133634) (xy 310.109811 -355.184131)
			(xy 310.125879 -355.237538) (xy 310.133999 -355.292714) (xy 310.134508 -355.3206) (xy 310.133999 -355.348486)
			(xy 310.125879 -355.403662) (xy 310.109811 -355.457069) (xy 310.086139 -355.507566) (xy 310.055366 -355.554079)
			(xy 310.018149 -355.595616) (xy 309.975281 -355.631291) (xy 309.927675 -355.660345) (xy 309.876346 -355.682157)
			(xy 309.822389 -355.696263) (xy 309.766952 -355.702363) (xy 309.711218 -355.700326) (xy 309.656375 -355.690196)
			(xy 309.603591 -355.672189) (xy 309.553991 -355.646688) (xy 309.508633 -355.614237) (xy 309.468484 -355.575528)
			(xy 309.434398 -355.531385) (xy 309.407102 -355.48275) (xy 309.387179 -355.430659) (xy 309.375053 -355.376222)
			(xy 309.370982 -355.3206) (xy 304.24959 -355.3206) (xy 304.12944 -355.440742) (xy 304.122738 -355.448216)
			(xy 304.115153 -355.466781) (xy 304.114708 -355.47681) (xy 304.114708 -356.743) (xy 311.276492 -356.743)
			(xy 311.276951 -356.715741) (xy 311.284719 -356.66178) (xy 311.300083 -356.609473) (xy 311.32273 -356.559882)
			(xy 311.352201 -356.514016) (xy 311.387896 -356.472809) (xy 311.429088 -356.437097) (xy 311.451752 -356.421944)
			(xy 311.46368 -356.413664) (xy 311.482686 -356.391729) (xy 311.494742 -356.365328) (xy 311.498873 -356.3366)
			(xy 311.494742 -356.307872) (xy 311.482686 -356.281471) (xy 311.46368 -356.259536) (xy 311.451752 -356.251256)
			(xy 311.429108 -356.236075) (xy 311.387909 -356.200374) (xy 311.352211 -356.159174) (xy 311.322739 -356.113312)
			(xy 311.300094 -356.063724) (xy 311.284736 -356.011417) (xy 311.276978 -355.957457) (xy 311.276492 -355.9302)
			(xy 311.276978 -355.902949) (xy 311.284734 -355.849001) (xy 311.300089 -355.796706) (xy 311.322731 -355.747129)
			(xy 311.352197 -355.701279) (xy 311.387888 -355.660088) (xy 311.429079 -355.624397) (xy 311.474929 -355.594931)
			(xy 311.524506 -355.572289) (xy 311.576801 -355.556934) (xy 311.630749 -355.549178) (xy 311.685251 -355.549178)
			(xy 311.739199 -355.556934) (xy 311.791494 -355.572289) (xy 311.841071 -355.594931) (xy 311.886921 -355.624397)
			(xy 311.928112 -355.660088) (xy 311.963803 -355.701279) (xy 311.993269 -355.747129) (xy 312.015911 -355.796706)
			(xy 312.025276 -355.8286) (xy 314.196982 -355.8286) (xy 314.201053 -355.772978) (xy 314.213179 -355.718541)
			(xy 314.233102 -355.66645) (xy 314.260398 -355.617815) (xy 314.294484 -355.573672) (xy 314.334633 -355.534963)
			(xy 314.379991 -355.502512) (xy 314.429591 -355.477011) (xy 314.482375 -355.459004) (xy 314.537218 -355.448874)
			(xy 314.592952 -355.446837) (xy 314.648389 -355.452937) (xy 314.702346 -355.467043) (xy 314.753675 -355.488855)
			(xy 314.801281 -355.517909) (xy 314.844149 -355.553584) (xy 314.881366 -355.595121) (xy 314.912139 -355.641634)
			(xy 314.935811 -355.692131) (xy 314.951879 -355.745538) (xy 314.959999 -355.800714) (xy 314.960508 -355.8286)
			(xy 314.959999 -355.856486) (xy 314.951879 -355.911662) (xy 314.935811 -355.965069) (xy 314.912139 -356.015566)
			(xy 314.881366 -356.062079) (xy 314.844149 -356.103616) (xy 314.801281 -356.139291) (xy 314.753675 -356.168345)
			(xy 314.702346 -356.190157) (xy 314.648389 -356.204263) (xy 314.592952 -356.210363) (xy 314.537218 -356.208326)
			(xy 314.482375 -356.198196) (xy 314.429591 -356.180189) (xy 314.379991 -356.154688) (xy 314.334633 -356.122237)
			(xy 314.294484 -356.083528) (xy 314.260398 -356.039385) (xy 314.233102 -355.99075) (xy 314.213179 -355.938659)
			(xy 314.201053 -355.884222) (xy 314.196982 -355.8286) (xy 312.025276 -355.8286) (xy 312.031266 -355.849001)
			(xy 312.039022 -355.902949) (xy 312.039508 -355.9302) (xy 312.039049 -355.957459) (xy 312.031281 -356.01142)
			(xy 312.015917 -356.063727) (xy 311.99327 -356.113318) (xy 311.963799 -356.159184) (xy 311.928104 -356.200391)
			(xy 311.886912 -356.236103) (xy 311.864248 -356.251256) (xy 311.85232 -356.259536) (xy 311.833314 -356.281471)
			(xy 311.821258 -356.307872) (xy 311.817127 -356.3366) (xy 311.821258 -356.365328) (xy 311.833314 -356.391729)
			(xy 311.85232 -356.413664) (xy 311.864248 -356.421944) (xy 311.886892 -356.437125) (xy 311.928091 -356.472826)
			(xy 311.963789 -356.514026) (xy 311.993261 -356.559888) (xy 312.015906 -356.609476) (xy 312.031264 -356.661783)
			(xy 312.039022 -356.715743) (xy 312.039055 -356.7176) (xy 313.282582 -356.7176) (xy 313.286653 -356.661978)
			(xy 313.298779 -356.607541) (xy 313.318702 -356.55545) (xy 313.345998 -356.506815) (xy 313.380084 -356.462672)
			(xy 313.420233 -356.423963) (xy 313.465591 -356.391512) (xy 313.515191 -356.366011) (xy 313.567975 -356.348004)
			(xy 313.622818 -356.337874) (xy 313.678552 -356.335837) (xy 313.733989 -356.341937) (xy 313.787946 -356.356043)
			(xy 313.839275 -356.377855) (xy 313.886881 -356.406909) (xy 313.929749 -356.442584) (xy 313.966966 -356.484121)
			(xy 313.970194 -356.489) (xy 315.670182 -356.489) (xy 315.674253 -356.433378) (xy 315.686379 -356.378941)
			(xy 315.706302 -356.32685) (xy 315.733598 -356.278215) (xy 315.767684 -356.234072) (xy 315.807833 -356.195363)
			(xy 315.853191 -356.162912) (xy 315.902791 -356.137411) (xy 315.955575 -356.119404) (xy 316.010418 -356.109274)
			(xy 316.066152 -356.107237) (xy 316.121589 -356.113337) (xy 316.175546 -356.127443) (xy 316.226875 -356.149255)
			(xy 316.274481 -356.178309) (xy 316.317349 -356.213984) (xy 316.354566 -356.255521) (xy 316.385339 -356.302034)
			(xy 316.409011 -356.352531) (xy 316.425079 -356.405938) (xy 316.433199 -356.461114) (xy 316.43336 -356.46995)
			(xy 317.016382 -356.46995) (xy 317.020453 -356.414328) (xy 317.032579 -356.359891) (xy 317.052502 -356.3078)
			(xy 317.079798 -356.259165) (xy 317.113884 -356.215022) (xy 317.154033 -356.176313) (xy 317.199391 -356.143862)
			(xy 317.248991 -356.118361) (xy 317.301775 -356.100354) (xy 317.356618 -356.090224) (xy 317.412352 -356.088187)
			(xy 317.467789 -356.094287) (xy 317.521746 -356.108393) (xy 317.573075 -356.130205) (xy 317.620681 -356.159259)
			(xy 317.663549 -356.194934) (xy 317.700766 -356.236471) (xy 317.731539 -356.282984) (xy 317.755211 -356.333481)
			(xy 317.771279 -356.386888) (xy 317.779399 -356.442064) (xy 317.779908 -356.46995) (xy 317.779399 -356.497836)
			(xy 317.771279 -356.553012) (xy 317.755211 -356.606419) (xy 317.731539 -356.656916) (xy 317.700766 -356.703429)
			(xy 317.663549 -356.744966) (xy 317.620681 -356.780641) (xy 317.573075 -356.809695) (xy 317.521746 -356.831507)
			(xy 317.467789 -356.845613) (xy 317.412352 -356.851713) (xy 317.356618 -356.849676) (xy 317.301775 -356.839546)
			(xy 317.248991 -356.821539) (xy 317.199391 -356.796038) (xy 317.154033 -356.763587) (xy 317.113884 -356.724878)
			(xy 317.079798 -356.680735) (xy 317.052502 -356.6321) (xy 317.032579 -356.580009) (xy 317.020453 -356.525572)
			(xy 317.016382 -356.46995) (xy 316.43336 -356.46995) (xy 316.433708 -356.489) (xy 316.433199 -356.516886)
			(xy 316.425079 -356.572062) (xy 316.409011 -356.625469) (xy 316.385339 -356.675966) (xy 316.354566 -356.722479)
			(xy 316.317349 -356.764016) (xy 316.274481 -356.799691) (xy 316.226875 -356.828745) (xy 316.175546 -356.850557)
			(xy 316.121589 -356.864663) (xy 316.066152 -356.870763) (xy 316.010418 -356.868726) (xy 315.955575 -356.858596)
			(xy 315.902791 -356.840589) (xy 315.853191 -356.815088) (xy 315.807833 -356.782637) (xy 315.767684 -356.743928)
			(xy 315.733598 -356.699785) (xy 315.706302 -356.65115) (xy 315.686379 -356.599059) (xy 315.674253 -356.544622)
			(xy 315.670182 -356.489) (xy 313.970194 -356.489) (xy 313.997739 -356.530634) (xy 314.021411 -356.581131)
			(xy 314.037479 -356.634538) (xy 314.045599 -356.689714) (xy 314.046108 -356.7176) (xy 314.045599 -356.745486)
			(xy 314.037479 -356.800662) (xy 314.021411 -356.854069) (xy 313.997739 -356.904566) (xy 313.966966 -356.951079)
			(xy 313.929749 -356.992616) (xy 313.886881 -357.028291) (xy 313.839275 -357.057345) (xy 313.787946 -357.079157)
			(xy 313.733989 -357.093263) (xy 313.678552 -357.099363) (xy 313.622818 -357.097326) (xy 313.567975 -357.087196)
			(xy 313.515191 -357.069189) (xy 313.465591 -357.043688) (xy 313.420233 -357.011237) (xy 313.380084 -356.972528)
			(xy 313.345998 -356.928385) (xy 313.318702 -356.87975) (xy 313.298779 -356.827659) (xy 313.286653 -356.773222)
			(xy 313.282582 -356.7176) (xy 312.039055 -356.7176) (xy 312.039508 -356.743) (xy 312.039022 -356.770251)
			(xy 312.031266 -356.824199) (xy 312.015911 -356.876494) (xy 311.993269 -356.926071) (xy 311.963803 -356.971921)
			(xy 311.928112 -357.013112) (xy 311.886921 -357.048803) (xy 311.841071 -357.078269) (xy 311.791494 -357.100911)
			(xy 311.739199 -357.116266) (xy 311.685251 -357.124022) (xy 311.630749 -357.124022) (xy 311.576801 -357.116266)
			(xy 311.524506 -357.100911) (xy 311.474929 -357.078269) (xy 311.429079 -357.048803) (xy 311.387888 -357.013112)
			(xy 311.352197 -356.971921) (xy 311.322731 -356.926071) (xy 311.300089 -356.876494) (xy 311.284734 -356.824199)
			(xy 311.276978 -356.770251) (xy 311.276492 -356.743) (xy 304.114708 -356.743) (xy 304.114708 -357.493062)
			(xy 305.065174 -357.493062) (xy 305.069245 -357.43744) (xy 305.081371 -357.383003) (xy 305.101294 -357.330912)
			(xy 305.12859 -357.282277) (xy 305.162676 -357.238134) (xy 305.202825 -357.199425) (xy 305.248183 -357.166974)
			(xy 305.297783 -357.141473) (xy 305.350567 -357.123466) (xy 305.40541 -357.113336) (xy 305.461144 -357.111299)
			(xy 305.516581 -357.117399) (xy 305.570538 -357.131505) (xy 305.621867 -357.153317) (xy 305.669473 -357.182371)
			(xy 305.712341 -357.218046) (xy 305.749558 -357.259583) (xy 305.780331 -357.306096) (xy 305.804003 -357.356593)
			(xy 305.820071 -357.41) (xy 305.828191 -357.465176) (xy 305.8287 -357.493062) (xy 305.828191 -357.520948)
			(xy 305.820071 -357.576124) (xy 305.804003 -357.629531) (xy 305.780331 -357.680028) (xy 305.749558 -357.726541)
			(xy 305.712341 -357.768078) (xy 305.669473 -357.803753) (xy 305.621867 -357.832807) (xy 305.570538 -357.854619)
			(xy 305.516581 -357.868725) (xy 305.461144 -357.874825) (xy 305.40541 -357.872788) (xy 305.350567 -357.862658)
			(xy 305.297783 -357.844651) (xy 305.248183 -357.81915) (xy 305.202825 -357.786699) (xy 305.162676 -357.74799)
			(xy 305.12859 -357.703847) (xy 305.101294 -357.655212) (xy 305.081371 -357.603121) (xy 305.069245 -357.548684)
			(xy 305.065174 -357.493062) (xy 304.114708 -357.493062) (xy 304.114708 -358.763316) (xy 305.14366 -358.763316)
			(xy 305.147731 -358.707694) (xy 305.159857 -358.653257) (xy 305.17978 -358.601166) (xy 305.207076 -358.552531)
			(xy 305.241162 -358.508388) (xy 305.281311 -358.469679) (xy 305.326669 -358.437228) (xy 305.376269 -358.411727)
			(xy 305.429053 -358.39372) (xy 305.483896 -358.38359) (xy 305.53963 -358.381553) (xy 305.595067 -358.387653)
			(xy 305.649024 -358.401759) (xy 305.700353 -358.423571) (xy 305.747959 -358.452625) (xy 305.790827 -358.4883)
			(xy 305.828044 -358.529837) (xy 305.858817 -358.57635) (xy 305.882489 -358.626847) (xy 305.898557 -358.680254)
			(xy 305.906677 -358.73543) (xy 305.907186 -358.763316) (xy 305.906677 -358.791202) (xy 305.898557 -358.846378)
			(xy 305.882489 -358.899785) (xy 305.858817 -358.950282) (xy 305.828044 -358.996795) (xy 305.790827 -359.038332)
			(xy 305.747959 -359.074007) (xy 305.700353 -359.103061) (xy 305.649024 -359.124873) (xy 305.595067 -359.138979)
			(xy 305.53963 -359.145079) (xy 305.483896 -359.143042) (xy 305.429053 -359.132912) (xy 305.376269 -359.114905)
			(xy 305.326669 -359.089404) (xy 305.281311 -359.056953) (xy 305.241162 -359.018244) (xy 305.207076 -358.974101)
			(xy 305.17978 -358.925466) (xy 305.159857 -358.873375) (xy 305.147731 -358.818938) (xy 305.14366 -358.763316)
			(xy 304.114708 -358.763316) (xy 304.114708 -360.666538) (xy 304.115076 -360.675835) (xy 304.121716 -360.693205)
			(xy 304.134082 -360.707093) (xy 304.14214 -360.71175) (xy 304.23485 -360.759756) (xy 304.263044 -360.757978)
			(xy 304.274728 -360.749596) (xy 304.299041 -360.733063) (xy 304.351676 -360.706866) (xy 304.407705 -360.689049)
			(xy 304.465803 -360.680034) (xy 304.4952 -360.679492) (xy 304.522451 -360.679978) (xy 304.576399 -360.687734)
			(xy 304.628694 -360.703089) (xy 304.678271 -360.725731) (xy 304.724121 -360.755197) (xy 304.765312 -360.790888)
			(xy 304.801003 -360.832079) (xy 304.830469 -360.877929) (xy 304.853111 -360.927506) (xy 304.868466 -360.979801)
			(xy 304.876222 -361.033749) (xy 304.876222 -361.088251) (xy 304.868466 -361.142199) (xy 304.853111 -361.194494)
			(xy 304.830469 -361.244071) (xy 304.801003 -361.289921) (xy 304.765312 -361.331112) (xy 304.724121 -361.366803)
			(xy 304.678271 -361.396269) (xy 304.628694 -361.418911) (xy 304.576399 -361.434266) (xy 304.522451 -361.442022)
			(xy 304.4952 -361.442508) (xy 304.465804 -361.441954) (xy 304.407706 -361.432941) (xy 304.351677 -361.415129)
			(xy 304.29904 -361.388937) (xy 304.274728 -361.372404) (xy 304.263044 -361.364022) (xy 304.23485 -361.362244)
			(xy 304.14214 -361.41025) (xy 304.134045 -361.41486) (xy 304.12164 -361.428739) (xy 304.115064 -361.446152)
			(xy 304.114708 -361.455462) (xy 304.114708 -362.56214) (xy 305.030376 -362.56214) (xy 305.034447 -362.506518)
			(xy 305.046573 -362.452081) (xy 305.066496 -362.39999) (xy 305.093792 -362.351355) (xy 305.127878 -362.307212)
			(xy 305.168027 -362.268503) (xy 305.213385 -362.236052) (xy 305.262985 -362.210551) (xy 305.315769 -362.192544)
			(xy 305.370612 -362.182414) (xy 305.426346 -362.180377) (xy 305.481783 -362.186477) (xy 305.53574 -362.200583)
			(xy 305.587069 -362.222395) (xy 305.634675 -362.251449) (xy 305.677543 -362.287124) (xy 305.71476 -362.328661)
			(xy 305.745533 -362.375174) (xy 305.769205 -362.425671) (xy 305.785273 -362.479078) (xy 305.793393 -362.534254)
			(xy 305.793902 -362.56214) (xy 305.793393 -362.590026) (xy 305.785273 -362.645202) (xy 305.769205 -362.698609)
			(xy 305.745533 -362.749106) (xy 305.71476 -362.795619) (xy 305.677543 -362.837156) (xy 305.634675 -362.872831)
			(xy 305.587069 -362.901885) (xy 305.53574 -362.923697) (xy 305.481783 -362.937803) (xy 305.426346 -362.943903)
			(xy 305.370612 -362.941866) (xy 305.315769 -362.931736) (xy 305.262985 -362.913729) (xy 305.213385 -362.888228)
			(xy 305.168027 -362.855777) (xy 305.127878 -362.817068) (xy 305.093792 -362.772925) (xy 305.066496 -362.72429)
			(xy 305.046573 -362.672199) (xy 305.034447 -362.617762) (xy 305.030376 -362.56214) (xy 304.114708 -362.56214)
			(xy 304.114708 -363.846872) (xy 305.046632 -363.846872) (xy 305.050703 -363.79125) (xy 305.062829 -363.736813)
			(xy 305.082752 -363.684722) (xy 305.110048 -363.636087) (xy 305.144134 -363.591944) (xy 305.184283 -363.553235)
			(xy 305.229641 -363.520784) (xy 305.279241 -363.495283) (xy 305.332025 -363.477276) (xy 305.386868 -363.467146)
			(xy 305.442602 -363.465109) (xy 305.498039 -363.471209) (xy 305.551996 -363.485315) (xy 305.603325 -363.507127)
			(xy 305.650931 -363.536181) (xy 305.693799 -363.571856) (xy 305.731016 -363.613393) (xy 305.761789 -363.659906)
			(xy 305.785461 -363.710403) (xy 305.801529 -363.76381) (xy 305.809649 -363.818986) (xy 305.810158 -363.846872)
			(xy 305.809649 -363.874758) (xy 305.801529 -363.929934) (xy 305.785461 -363.983341) (xy 305.761789 -364.033838)
			(xy 305.731016 -364.080351) (xy 305.693799 -364.121888) (xy 305.650931 -364.157563) (xy 305.603325 -364.186617)
			(xy 305.551996 -364.208429) (xy 305.498039 -364.222535) (xy 305.442602 -364.228635) (xy 305.386868 -364.226598)
			(xy 305.332025 -364.216468) (xy 305.279241 -364.198461) (xy 305.229641 -364.17296) (xy 305.184283 -364.140509)
			(xy 305.144134 -364.1018) (xy 305.110048 -364.057657) (xy 305.082752 -364.009022) (xy 305.062829 -363.956931)
			(xy 305.050703 -363.902494) (xy 305.046632 -363.846872) (xy 304.114708 -363.846872) (xy 304.114708 -364.228126)
			(xy 304.115088 -364.23817) (xy 304.12267 -364.256766) (xy 304.12944 -364.264194) (xy 305.019202 -365.153702)
			(xy 305.026266 -365.160219) (xy 305.043903 -365.167829) (xy 305.063101 -365.168471) (xy 305.072288 -365.16564)
			(xy 305.172872 -365.129064) (xy 305.190906 -365.105696) (xy 305.192176 -365.090964) (xy 305.195245 -365.062854)
			(xy 305.208546 -365.007898) (xy 305.229813 -364.955507) (xy 305.258579 -364.906829) (xy 305.294215 -364.862929)
			(xy 305.33594 -364.82477) (xy 305.38284 -364.793187) (xy 305.433888 -364.768873) (xy 305.487966 -364.752359)
			(xy 305.543889 -364.744007) (xy 305.57216 -364.743492) (xy 305.599024 -364.743907) (xy 305.652219 -364.751453)
			(xy 305.703829 -364.766386) (xy 305.752835 -364.788412) (xy 305.798265 -364.817095) (xy 305.839223 -364.851867)
			(xy 305.874898 -364.892041) (xy 305.904584 -364.936823) (xy 305.927695 -364.985326) (xy 305.943772 -365.036591)
			(xy 305.948588 -365.063024) (xy 305.951006 -365.074505) (xy 305.96469 -365.09354) (xy 305.985401 -365.104523)
			(xy 305.997102 -365.105442) (xy 306.043838 -365.10849) (xy 306.060094 -365.110014) (xy 306.08778 -365.094266)
			(xy 306.135532 -364.993174) (xy 306.139509 -364.983504) (xy 306.140161 -364.96263) (xy 306.132429 -364.943229)
			(xy 306.125372 -364.935516) (xy 306.079906 -364.89005) (xy 306.066055 -364.87559) (xy 306.043801 -364.842307)
			(xy 306.028476 -364.805319) (xy 306.020669 -364.766051) (xy 306.020216 -364.746032) (xy 306.020216 -361.658408)
			(xy 306.019768 -361.648597) (xy 306.012426 -361.630402) (xy 305.99878 -361.616304) (xy 305.98999 -361.611926)
			(xy 305.89093 -361.568492) (xy 305.861212 -361.573318) (xy 305.850036 -361.583732) (xy 305.828778 -361.602549)
			(xy 305.781754 -361.634351) (xy 305.730534 -361.658827) (xy 305.67625 -361.675438) (xy 305.620103 -361.683815)
			(xy 305.591718 -361.684316) (xy 305.564465 -361.683838) (xy 305.510513 -361.676083) (xy 305.458214 -361.660729)
			(xy 305.408633 -361.638088) (xy 305.362778 -361.608621) (xy 305.321585 -361.572928) (xy 305.28589 -361.531736)
			(xy 305.256421 -361.485883) (xy 305.233777 -361.436303) (xy 305.218421 -361.384004) (xy 305.210663 -361.330053)
			(xy 305.210663 -361.275547) (xy 305.218421 -361.221596) (xy 305.233777 -361.169297) (xy 305.256421 -361.119717)
			(xy 305.28589 -361.073864) (xy 305.321585 -361.032672) (xy 305.362778 -360.996979) (xy 305.408633 -360.967512)
			(xy 305.458214 -360.944871) (xy 305.510513 -360.929517) (xy 305.564465 -360.921762) (xy 305.591718 -360.9213)
			(xy 305.620101 -360.921817) (xy 305.676242 -360.93021) (xy 305.730522 -360.946823) (xy 305.781744 -360.971289)
			(xy 305.828779 -361.003069) (xy 305.850036 -361.021884) (xy 305.861212 -361.032298) (xy 305.89093 -361.037124)
			(xy 305.98999 -360.99369) (xy 305.998784 -360.989321) (xy 306.012416 -360.975209) (xy 306.019769 -360.957018)
			(xy 306.020216 -360.947208) (xy 306.020216 -360.41203) (xy 306.019801 -360.402611) (xy 306.012973 -360.385051)
			(xy 306.000266 -360.371142) (xy 305.992022 -360.366564) (xy 305.897026 -360.319828) (xy 305.868324 -360.322876)
			(xy 305.85664 -360.331766) (xy 305.836528 -360.346779) (xy 305.79312 -360.371971) (xy 305.746783 -360.391254)
			(xy 305.698319 -360.404296) (xy 305.648562 -360.410872) (xy 305.623468 -360.411268) (xy 305.596215 -360.41086)
			(xy 305.542265 -360.403099) (xy 305.489969 -360.387739) (xy 305.440391 -360.365094) (xy 305.394539 -360.335624)
			(xy 305.353349 -360.299929) (xy 305.317657 -360.258735) (xy 305.288191 -360.212881) (xy 305.265549 -360.163301)
			(xy 305.250194 -360.111003) (xy 305.242438 -360.057053) (xy 305.242438 -360.002547) (xy 305.250194 -359.948597)
			(xy 305.265549 -359.896299) (xy 305.288191 -359.846719) (xy 305.317657 -359.800865) (xy 305.353349 -359.759671)
			(xy 305.39454 -359.723976) (xy 305.440391 -359.694506) (xy 305.489969 -359.671861) (xy 305.542265 -359.656501)
			(xy 305.596215 -359.64874) (xy 305.623468 -359.648252) (xy 305.648562 -359.648645) (xy 305.698317 -359.655229)
			(xy 305.74678 -359.668274) (xy 305.793117 -359.687555) (xy 305.836528 -359.712741) (xy 305.85664 -359.727754)
			(xy 305.868324 -359.736644) (xy 305.897026 -359.739692) (xy 305.992022 -359.692956) (xy 306.000296 -359.688419)
			(xy 306.013018 -359.674499) (xy 306.019839 -359.656919) (xy 306.020216 -359.64749) (xy 306.020216 -358.925876)
			(xy 306.020717 -358.905864) (xy 306.028541 -358.866611) (xy 306.043866 -358.829636) (xy 306.066103 -358.796357)
			(xy 306.079906 -358.781858) (xy 307.399182 -357.462582) (xy 307.413667 -357.448759) (xy 307.446941 -357.426501)
			(xy 307.483921 -357.411168) (xy 307.523184 -357.403351) (xy 307.5432 -357.402892) (xy 317.24219 -357.402892)
			(xy 317.252238 -357.402546) (xy 317.270834 -357.39494) (xy 317.278258 -357.38816) (xy 320.966338 -353.70008)
			(xy 320.973185 -353.692685) (xy 320.980899 -353.674082) (xy 320.981324 -353.664012) (xy 320.981324 -341.386414)
			(xy 320.980911 -341.376343) (xy 320.973184 -341.357744) (xy 320.966338 -341.350346) (xy 319.169542 -339.55355)
			(xy 319.162116 -339.546743) (xy 319.143537 -339.539002) (xy 319.133474 -339.538564) (xy 318.62014 -339.538564)
			(xy 318.608074 -339.539236) (xy 318.5866 -339.550254) (xy 318.578992 -339.559646) (xy 318.560896 -339.58351)
			(xy 318.518522 -339.625827) (xy 318.470056 -339.661002) (xy 318.416687 -339.688171) (xy 318.359728 -339.706665)
			(xy 318.300579 -339.716029) (xy 318.270636 -339.716618) (xy 318.243384 -339.716111) (xy 318.189436 -339.708359)
			(xy 318.137139 -339.693008) (xy 318.08756 -339.670371) (xy 318.041707 -339.640908) (xy 318.000514 -339.605218)
			(xy 317.96482 -339.56403) (xy 317.935351 -339.518181) (xy 317.912708 -339.468604) (xy 317.89735 -339.416309)
			(xy 317.889592 -339.362361) (xy 317.889128 -339.33511) (xy 317.889764 -339.303546) (xy 317.900161 -339.24128)
			(xy 317.920656 -339.181572) (xy 317.935102 -339.1535) (xy 317.939928 -339.14461) (xy 317.94196 -339.125052)
			(xy 317.916306 -339.036914) (xy 317.90386 -339.02142) (xy 317.89497 -339.01634) (xy 317.887604 -339.012276)
			(xy 317.877952 -339.006434) (xy 317.855854 -339.004402) (xy 317.761366 -339.03793) (xy 317.745364 -339.053424)
			(xy 317.7413 -339.063838) (xy 317.730641 -339.09063) (xy 317.702347 -339.140872) (xy 317.666811 -339.186281)
			(xy 317.624844 -339.225822) (xy 317.577401 -339.258593) (xy 317.525566 -339.283849) (xy 317.470518 -339.301011)
			(xy 317.413514 -339.30969) (xy 317.384684 -339.310218) (xy 317.357434 -339.309711) (xy 317.30349 -339.301953)
			(xy 317.251198 -339.286596) (xy 317.201624 -339.263955) (xy 317.155777 -339.234489) (xy 317.11459 -339.198799)
			(xy 317.078901 -339.15761) (xy 317.049437 -339.111761) (xy 317.026798 -339.062187) (xy 317.011444 -339.009895)
			(xy 317.003688 -338.95595) (xy 317.003688 -338.90145) (xy 317.011444 -338.847505) (xy 317.026798 -338.795213)
			(xy 317.049437 -338.745639) (xy 317.078901 -338.69979) (xy 317.11459 -338.658601) (xy 317.155777 -338.622911)
			(xy 317.201624 -338.593445) (xy 317.251198 -338.570804) (xy 317.30349 -338.555447) (xy 317.357434 -338.547689)
			(xy 317.384684 -338.547202) (xy 317.409921 -338.547562) (xy 317.459956 -338.554191) (xy 317.508676 -338.567375)
			(xy 317.555227 -338.586882) (xy 317.577216 -338.599272) (xy 317.586868 -338.605114) (xy 317.608966 -338.607146)
			(xy 317.703454 -338.573618) (xy 317.719456 -338.558124) (xy 317.72352 -338.54771) (xy 317.734188 -338.520921)
			(xy 317.762478 -338.470677) (xy 317.798011 -338.425266) (xy 317.839977 -338.385723) (xy 317.887418 -338.352951)
			(xy 317.939254 -338.327695) (xy 317.994301 -338.310533) (xy 318.051306 -338.301856) (xy 318.080136 -338.30133)
			(xy 318.107392 -338.301722) (xy 318.161347 -338.309484) (xy 318.213649 -338.324847) (xy 318.263231 -338.347496)
			(xy 318.309086 -338.376972) (xy 318.35028 -338.412673) (xy 318.385973 -338.453873) (xy 318.415439 -338.499734)
			(xy 318.438079 -338.549321) (xy 318.450802 -338.592668) (xy 320.591688 -338.592668) (xy 320.592205 -338.565095)
			(xy 320.600147 -338.510525) (xy 320.615863 -338.457666) (xy 320.639023 -338.40762) (xy 320.669146 -338.361429)
			(xy 320.705605 -338.320056) (xy 320.726308 -338.301838) (xy 320.734406 -338.294217) (xy 320.743771 -338.27408)
			(xy 320.744342 -338.262976) (xy 320.744342 -338.18576) (xy 320.743831 -338.174643) (xy 320.734454 -338.154484)
			(xy 320.726308 -338.146898) (xy 320.705594 -338.12869) (xy 320.669124 -338.08732) (xy 320.638992 -338.04113)
			(xy 320.615826 -337.991082) (xy 320.600111 -337.938218) (xy 320.592172 -337.883643) (xy 320.591688 -337.856068)
			(xy 320.592148 -337.828816) (xy 320.599909 -337.774868) (xy 320.615268 -337.722573) (xy 320.637912 -337.672996)
			(xy 320.667382 -337.627146) (xy 320.703076 -337.585956) (xy 320.744268 -337.550265) (xy 320.79012 -337.520799)
			(xy 320.839699 -337.498158) (xy 320.891995 -337.482803) (xy 320.945944 -337.475046) (xy 320.973196 -337.47456)
			(xy 321.007486 -337.476084) (xy 321.017646 -337.4771) (xy 321.03695 -337.471004) (xy 321.107562 -337.411822)
			(xy 321.11696 -337.393788) (xy 321.117976 -337.383628) (xy 321.120916 -337.355454) (xy 321.134093 -337.300362)
			(xy 321.155274 -337.247825) (xy 321.183994 -337.199) (xy 321.21962 -337.154959) (xy 321.261368 -337.116673)
			(xy 321.30832 -337.084984) (xy 321.359444 -337.060588) (xy 321.413613 -337.044023) (xy 321.469637 -337.035653)
			(xy 321.49796 -337.03514) (xy 321.515979 -337.035357) (xy 321.551854 -337.038794) (xy 321.569588 -337.041998)
			(xy 321.578986 -337.043776) (xy 321.598036 -337.039966) (xy 321.67322 -336.992214) (xy 321.68465 -336.976466)
			(xy 321.686936 -336.967068) (xy 321.694324 -336.940021) (xy 321.715954 -336.888293) (xy 321.744918 -336.840287)
			(xy 321.780595 -336.797034) (xy 321.822215 -336.759467) (xy 321.868884 -336.728393) (xy 321.919597 -336.704481)
			(xy 321.973263 -336.688246) (xy 322.028726 -336.680037) (xy 322.05676 -336.67954) (xy 322.084014 -336.679993)
			(xy 322.137968 -336.687745) (xy 322.190269 -336.703099) (xy 322.239852 -336.72574) (xy 322.285708 -336.755208)
			(xy 322.326902 -336.790904) (xy 322.362596 -336.832099) (xy 322.392064 -336.877955) (xy 322.414704 -336.927539)
			(xy 322.430056 -336.97984) (xy 322.437808 -337.033794) (xy 322.438268 -337.061048) (xy 322.437778 -337.088622)
			(xy 322.429832 -337.143194) (xy 322.414112 -337.196054) (xy 322.390947 -337.2461) (xy 322.360818 -337.29229)
			(xy 322.324354 -337.333662) (xy 322.303648 -337.351878) (xy 322.295536 -337.359486) (xy 322.28618 -337.379634)
			(xy 322.285614 -337.39074) (xy 322.285614 -337.467956) (xy 322.286186 -337.479066) (xy 322.295521 -337.499225)
			(xy 322.303648 -337.506818) (xy 322.324404 -337.52498) (xy 322.360872 -337.566356) (xy 322.391002 -337.612553)
			(xy 322.414166 -337.662607) (xy 322.42988 -337.715475) (xy 322.437818 -337.770054) (xy 322.437813 -337.825208)
			(xy 322.430621 -337.87461) (xy 323.594728 -337.87461) (xy 323.598799 -337.818988) (xy 323.610925 -337.764551)
			(xy 323.630848 -337.71246) (xy 323.658144 -337.663825) (xy 323.69223 -337.619682) (xy 323.732379 -337.580973)
			(xy 323.777737 -337.548522) (xy 323.827337 -337.523021) (xy 323.880121 -337.505014) (xy 323.934964 -337.494884)
			(xy 323.990698 -337.492847) (xy 324.046135 -337.498947) (xy 324.100092 -337.513053) (xy 324.151421 -337.534865)
			(xy 324.199027 -337.563919) (xy 324.241895 -337.599594) (xy 324.279112 -337.641131) (xy 324.309885 -337.687644)
			(xy 324.333557 -337.738141) (xy 324.349625 -337.791548) (xy 324.357745 -337.846724) (xy 324.358254 -337.87461)
			(xy 324.357745 -337.902496) (xy 324.349625 -337.957672) (xy 324.333557 -338.011079) (xy 324.309885 -338.061576)
			(xy 324.279112 -338.108089) (xy 324.241895 -338.149626) (xy 324.199027 -338.185301) (xy 324.151421 -338.214355)
			(xy 324.100092 -338.236167) (xy 324.046135 -338.250273) (xy 323.990698 -338.256373) (xy 323.934964 -338.254336)
			(xy 323.880121 -338.244206) (xy 323.827337 -338.226199) (xy 323.777737 -338.200698) (xy 323.732379 -338.168247)
			(xy 323.69223 -338.129538) (xy 323.658144 -338.085395) (xy 323.630848 -338.03676) (xy 323.610925 -337.984669)
			(xy 323.598799 -337.930232) (xy 323.594728 -337.87461) (xy 322.430621 -337.87461) (xy 322.429867 -337.879786)
			(xy 322.414144 -337.932651) (xy 322.390972 -337.982701) (xy 322.360834 -338.028893) (xy 322.324359 -338.070264)
			(xy 322.303648 -338.088478) (xy 322.295536 -338.096086) (xy 322.28618 -338.116234) (xy 322.285614 -338.12734)
			(xy 322.285614 -338.204556) (xy 322.286186 -338.215666) (xy 322.295521 -338.235825) (xy 322.303648 -338.243418)
			(xy 322.324381 -338.261605) (xy 322.360847 -338.30298) (xy 322.390975 -338.349176) (xy 322.414137 -338.399228)
			(xy 322.429849 -338.452094) (xy 322.437785 -338.506672) (xy 322.438268 -338.534248) (xy 322.437867 -338.561502)
			(xy 322.430103 -338.615455) (xy 322.414739 -338.667754) (xy 322.39209 -338.717334) (xy 322.362615 -338.763186)
			(xy 322.356744 -338.76996) (xy 323.015608 -338.76996) (xy 323.019679 -338.714338) (xy 323.031805 -338.659901)
			(xy 323.051728 -338.60781) (xy 323.079024 -338.559175) (xy 323.11311 -338.515032) (xy 323.153259 -338.476323)
			(xy 323.198617 -338.443872) (xy 323.248217 -338.418371) (xy 323.301001 -338.400364) (xy 323.355844 -338.390234)
			(xy 323.411578 -338.388197) (xy 323.467015 -338.394297) (xy 323.520972 -338.408403) (xy 323.572301 -338.430215)
			(xy 323.619907 -338.459269) (xy 323.662775 -338.494944) (xy 323.699992 -338.536481) (xy 323.730765 -338.582994)
			(xy 323.754437 -338.633491) (xy 323.770505 -338.686898) (xy 323.778625 -338.742074) (xy 323.779134 -338.76996)
			(xy 323.778625 -338.797846) (xy 323.770505 -338.853022) (xy 323.754437 -338.906429) (xy 323.730765 -338.956926)
			(xy 323.699992 -339.003439) (xy 323.662775 -339.044976) (xy 323.619907 -339.080651) (xy 323.572301 -339.109705)
			(xy 323.520972 -339.131517) (xy 323.467015 -339.145623) (xy 323.411578 -339.151723) (xy 323.355844 -339.149686)
			(xy 323.301001 -339.139556) (xy 323.248217 -339.121549) (xy 323.198617 -339.096048) (xy 323.153259 -339.063597)
			(xy 323.11311 -339.024888) (xy 323.079024 -338.980745) (xy 323.051728 -338.93211) (xy 323.031805 -338.880019)
			(xy 323.019679 -338.825582) (xy 323.015608 -338.76996) (xy 322.356744 -338.76996) (xy 322.326914 -338.804377)
			(xy 322.285715 -338.840068) (xy 322.239857 -338.869532) (xy 322.190271 -338.89217) (xy 322.137969 -338.907521)
			(xy 322.084014 -338.915273) (xy 322.05676 -338.915756) (xy 322.028902 -338.915302) (xy 321.973782 -338.907171)
			(xy 321.920428 -338.891118) (xy 321.869973 -338.867483) (xy 321.823488 -338.836768) (xy 321.781959 -338.799624)
			(xy 321.746268 -338.75684) (xy 321.717172 -338.709324) (xy 321.695289 -338.658085) (xy 321.687698 -338.631276)
			(xy 321.685412 -338.622386) (xy 321.674744 -338.607146) (xy 321.602862 -338.559394) (xy 321.584828 -338.55533)
			(xy 321.575684 -338.5566) (xy 321.562667 -338.558269) (xy 321.536483 -338.560049) (xy 321.52336 -338.560156)
			(xy 321.509211 -338.560066) (xy 321.480988 -338.558029) (xy 321.466972 -338.556092) (xy 321.456812 -338.554568)
			(xy 321.437254 -338.559394) (xy 321.362832 -338.615274) (xy 321.352672 -338.6328) (xy 321.351402 -338.64296)
			(xy 321.34734 -338.670118) (xy 321.332364 -338.72295) (xy 321.30997 -338.773089) (xy 321.280619 -338.8195)
			(xy 321.244919 -338.861224) (xy 321.203606 -338.8974) (xy 321.157534 -338.92728) (xy 321.107655 -338.950248)
			(xy 321.054999 -338.965828) (xy 321.000653 -338.973699) (xy 320.973196 -338.974176) (xy 320.945942 -338.973748)
			(xy 320.891988 -338.96599) (xy 320.839687 -338.950632) (xy 320.790105 -338.927986) (xy 320.74425 -338.898515)
			(xy 320.703057 -338.862818) (xy 320.667363 -338.821621) (xy 320.637896 -338.775763) (xy 320.615256 -338.726179)
			(xy 320.599902 -338.673877) (xy 320.592149 -338.619922) (xy 320.591688 -338.592668) (xy 318.450802 -338.592668)
			(xy 318.453431 -338.601625) (xy 318.461184 -338.655582) (xy 318.461644 -338.682838) (xy 318.460991 -338.714401)
			(xy 318.450602 -338.776667) (xy 318.430113 -338.836376) (xy 318.41567 -338.864448) (xy 318.410844 -338.873338)
			(xy 318.408812 -338.892896) (xy 318.434466 -338.981034) (xy 318.446912 -338.996528) (xy 318.455802 -339.001608)
			(xy 318.47973 -339.015454) (xy 318.523676 -339.048992) (xy 318.562324 -339.088519) (xy 318.578992 -339.110574)
			(xy 318.58658 -339.119985) (xy 318.608069 -339.130987) (xy 318.62014 -339.131656) (xy 319.238884 -339.131656)
			(xy 319.25889 -339.13209) (xy 319.298145 -339.139829) (xy 319.33513 -339.155089) (xy 319.368421 -339.177282)
			(xy 319.382902 -339.191092) (xy 319.63741 -339.4456) (xy 324.354444 -339.4456) (xy 324.35492 -339.418125)
			(xy 324.362812 -339.363744) (xy 324.378434 -339.311061) (xy 324.401462 -339.261169) (xy 324.431417 -339.215101)
			(xy 324.449186 -339.19414) (xy 324.455282 -339.187028) (xy 324.461632 -339.17001) (xy 324.461632 -339.084158)
			(xy 324.455282 -339.06714) (xy 324.449186 -339.060028) (xy 324.431452 -339.039042) (xy 324.401523 -338.992966)
			(xy 324.378505 -338.943078) (xy 324.362872 -338.890407) (xy 324.354947 -338.836039) (xy 324.354444 -338.808568)
			(xy 324.35493 -338.781317) (xy 324.362686 -338.727369) (xy 324.378041 -338.675074) (xy 324.400683 -338.625497)
			(xy 324.430149 -338.579647) (xy 324.46584 -338.538456) (xy 324.507031 -338.502765) (xy 324.552881 -338.473299)
			(xy 324.602458 -338.450657) (xy 324.654753 -338.435302) (xy 324.708701 -338.427546) (xy 324.763203 -338.427546)
			(xy 324.817151 -338.435302) (xy 324.869446 -338.450657) (xy 324.919023 -338.473299) (xy 324.964873 -338.502765)
			(xy 325.006064 -338.538456) (xy 325.041755 -338.579647) (xy 325.071221 -338.625497) (xy 325.093863 -338.675074)
			(xy 325.109218 -338.727369) (xy 325.116974 -338.781317) (xy 325.11746 -338.808568) (xy 325.116965 -338.836042)
			(xy 325.109076 -338.890422) (xy 325.093459 -338.943105) (xy 325.070436 -338.992998) (xy 325.040485 -339.039066)
			(xy 325.022718 -339.060028) (xy 325.016622 -339.06714) (xy 325.010272 -339.084158) (xy 325.010272 -339.17001)
			(xy 325.016622 -339.187028) (xy 325.022718 -339.19414) (xy 325.040484 -339.2151) (xy 325.070408 -339.261183)
			(xy 325.09342 -339.311077) (xy 325.109046 -339.363755) (xy 325.116961 -339.418127) (xy 325.11746 -339.4456)
			(xy 325.116974 -339.472851) (xy 325.109218 -339.526799) (xy 325.093863 -339.579094) (xy 325.071221 -339.628671)
			(xy 325.041755 -339.674521) (xy 325.006064 -339.715712) (xy 324.964873 -339.751403) (xy 324.919023 -339.780869)
			(xy 324.869446 -339.803511) (xy 324.817151 -339.818866) (xy 324.763203 -339.826622) (xy 324.708701 -339.826622)
			(xy 324.654753 -339.818866) (xy 324.602458 -339.803511) (xy 324.552881 -339.780869) (xy 324.507031 -339.751403)
			(xy 324.46584 -339.715712) (xy 324.430149 -339.674521) (xy 324.400683 -339.628671) (xy 324.378041 -339.579094)
			(xy 324.362686 -339.526799) (xy 324.35493 -339.472851) (xy 324.354444 -339.4456) (xy 319.63741 -339.4456)
			(xy 321.328796 -341.136986) (xy 321.342574 -341.151492) (xy 321.364747 -341.184785) (xy 321.380005 -341.221762)
			(xy 321.387763 -341.261003) (xy 321.388232 -341.281004) (xy 321.388232 -353.769422) (xy 321.387824 -353.789429)
			(xy 321.380078 -353.828685) (xy 321.36481 -353.865671) (xy 321.342609 -353.89896) (xy 321.328796 -353.91344)
			(xy 317.491618 -357.750618) (xy 317.477133 -357.764441) (xy 317.443859 -357.786699) (xy 317.406879 -357.802032)
			(xy 317.367616 -357.809849) (xy 317.3476 -357.810308) (xy 307.64861 -357.810308) (xy 307.638562 -357.810654)
			(xy 307.619966 -357.81826) (xy 307.612542 -357.82504) (xy 306.442364 -358.995218) (xy 306.435675 -359.002703)
			(xy 306.428082 -359.021259) (xy 306.427735 -359.029) (xy 317.905382 -359.029) (xy 317.909453 -358.973378)
			(xy 317.921579 -358.918941) (xy 317.941502 -358.86685) (xy 317.968798 -358.818215) (xy 318.002884 -358.774072)
			(xy 318.043033 -358.735363) (xy 318.088391 -358.702912) (xy 318.137991 -358.677411) (xy 318.190775 -358.659404)
			(xy 318.245618 -358.649274) (xy 318.301352 -358.647237) (xy 318.356789 -358.653337) (xy 318.410746 -358.667443)
			(xy 318.462075 -358.689255) (xy 318.509681 -358.718309) (xy 318.552549 -358.753984) (xy 318.589766 -358.795521)
			(xy 318.620539 -358.842034) (xy 318.644211 -358.892531) (xy 318.660279 -358.945938) (xy 318.668399 -359.001114)
			(xy 318.668908 -359.029) (xy 318.668399 -359.056886) (xy 318.660279 -359.112062) (xy 318.644211 -359.165469)
			(xy 318.620539 -359.215966) (xy 318.589766 -359.262479) (xy 318.552549 -359.304016) (xy 318.509681 -359.339691)
			(xy 318.462075 -359.368745) (xy 318.410746 -359.390557) (xy 318.356789 -359.404663) (xy 318.301352 -359.410763)
			(xy 318.245618 -359.408726) (xy 318.190775 -359.398596) (xy 318.137991 -359.380589) (xy 318.088391 -359.355088)
			(xy 318.043033 -359.322637) (xy 318.002884 -359.283928) (xy 317.968798 -359.239785) (xy 317.941502 -359.19115)
			(xy 317.921579 -359.139059) (xy 317.909453 -359.084622) (xy 317.905382 -359.029) (xy 306.427735 -359.029)
			(xy 306.427632 -359.031286) (xy 306.427632 -360.402632) (xy 313.480448 -360.402632) (xy 313.484519 -360.34701)
			(xy 313.496645 -360.292573) (xy 313.516568 -360.240482) (xy 313.543864 -360.191847) (xy 313.57795 -360.147704)
			(xy 313.618099 -360.108995) (xy 313.663457 -360.076544) (xy 313.713057 -360.051043) (xy 313.765841 -360.033036)
			(xy 313.820684 -360.022906) (xy 313.876418 -360.020869) (xy 313.931855 -360.026969) (xy 313.985812 -360.041075)
			(xy 314.037141 -360.062887) (xy 314.084747 -360.091941) (xy 314.127615 -360.127616) (xy 314.164832 -360.169153)
			(xy 314.195605 -360.215666) (xy 314.219277 -360.266163) (xy 314.226252 -360.289348) (xy 314.38545 -360.289348)
			(xy 314.389521 -360.233726) (xy 314.401647 -360.179289) (xy 314.42157 -360.127198) (xy 314.448866 -360.078563)
			(xy 314.482952 -360.03442) (xy 314.523101 -359.995711) (xy 314.568459 -359.96326) (xy 314.618059 -359.937759)
			(xy 314.670843 -359.919752) (xy 314.725686 -359.909622) (xy 314.78142 -359.907585) (xy 314.836857 -359.913685)
			(xy 314.853362 -359.918) (xy 319.046858 -359.918) (xy 319.050929 -359.862378) (xy 319.063055 -359.807941)
			(xy 319.082978 -359.75585) (xy 319.110274 -359.707215) (xy 319.14436 -359.663072) (xy 319.184509 -359.624363)
			(xy 319.229867 -359.591912) (xy 319.279467 -359.566411) (xy 319.332251 -359.548404) (xy 319.387094 -359.538274)
			(xy 319.442828 -359.536237) (xy 319.498265 -359.542337) (xy 319.552222 -359.556443) (xy 319.603551 -359.578255)
			(xy 319.651157 -359.607309) (xy 319.694025 -359.642984) (xy 319.731242 -359.684521) (xy 319.762015 -359.731034)
			(xy 319.785687 -359.781531) (xy 319.801755 -359.834938) (xy 319.809875 -359.890114) (xy 319.810384 -359.918)
			(xy 319.809875 -359.945886) (xy 319.801755 -360.001062) (xy 319.785687 -360.054469) (xy 319.762015 -360.104966)
			(xy 319.731242 -360.151479) (xy 319.694025 -360.193016) (xy 319.651157 -360.228691) (xy 319.603551 -360.257745)
			(xy 319.552222 -360.279557) (xy 319.498265 -360.293663) (xy 319.442828 -360.299763) (xy 319.387094 -360.297726)
			(xy 319.332251 -360.287596) (xy 319.279467 -360.269589) (xy 319.229867 -360.244088) (xy 319.184509 -360.211637)
			(xy 319.14436 -360.172928) (xy 319.110274 -360.128785) (xy 319.082978 -360.08015) (xy 319.063055 -360.028059)
			(xy 319.050929 -359.973622) (xy 319.046858 -359.918) (xy 314.853362 -359.918) (xy 314.890814 -359.927791)
			(xy 314.942143 -359.949603) (xy 314.989749 -359.978657) (xy 315.032617 -360.014332) (xy 315.069834 -360.055869)
			(xy 315.100607 -360.102382) (xy 315.124279 -360.152879) (xy 315.140347 -360.206286) (xy 315.148467 -360.261462)
			(xy 315.148976 -360.289348) (xy 315.148467 -360.317234) (xy 315.140347 -360.37241) (xy 315.124279 -360.425817)
			(xy 315.100607 -360.476314) (xy 315.069834 -360.522827) (xy 315.032617 -360.564364) (xy 314.989749 -360.600039)
			(xy 314.942143 -360.629093) (xy 314.890814 -360.650905) (xy 314.836857 -360.665011) (xy 314.78142 -360.671111)
			(xy 314.725686 -360.669074) (xy 314.670843 -360.658944) (xy 314.618059 -360.640937) (xy 314.568459 -360.615436)
			(xy 314.523101 -360.582985) (xy 314.482952 -360.544276) (xy 314.448866 -360.500133) (xy 314.42157 -360.451498)
			(xy 314.401647 -360.399407) (xy 314.389521 -360.34497) (xy 314.38545 -360.289348) (xy 314.226252 -360.289348)
			(xy 314.235345 -360.31957) (xy 314.243465 -360.374746) (xy 314.243974 -360.402632) (xy 314.243465 -360.430518)
			(xy 314.235345 -360.485694) (xy 314.219277 -360.539101) (xy 314.195605 -360.589598) (xy 314.164832 -360.636111)
			(xy 314.127615 -360.677648) (xy 314.084747 -360.713323) (xy 314.037141 -360.742377) (xy 313.985812 -360.764189)
			(xy 313.931855 -360.778295) (xy 313.876418 -360.784395) (xy 313.820684 -360.782358) (xy 313.765841 -360.772228)
			(xy 313.713057 -360.754221) (xy 313.663457 -360.72872) (xy 313.618099 -360.696269) (xy 313.57795 -360.65756)
			(xy 313.543864 -360.613417) (xy 313.516568 -360.564782) (xy 313.496645 -360.512691) (xy 313.484519 -360.458254)
			(xy 313.480448 -360.402632) (xy 306.427632 -360.402632) (xy 306.427632 -361.279948) (xy 314.255656 -361.279948)
			(xy 314.259727 -361.224326) (xy 314.271853 -361.169889) (xy 314.291776 -361.117798) (xy 314.319072 -361.069163)
			(xy 314.353158 -361.02502) (xy 314.393307 -360.986311) (xy 314.438665 -360.95386) (xy 314.488265 -360.928359)
			(xy 314.541049 -360.910352) (xy 314.595892 -360.900222) (xy 314.651626 -360.898185) (xy 314.707063 -360.904285)
			(xy 314.76102 -360.918391) (xy 314.812349 -360.940203) (xy 314.859955 -360.969257) (xy 314.902823 -361.004932)
			(xy 314.94004 -361.046469) (xy 314.970813 -361.092982) (xy 314.994485 -361.143479) (xy 315.010553 -361.196886)
			(xy 315.018673 -361.252062) (xy 315.019182 -361.279948) (xy 315.018673 -361.307834) (xy 315.010553 -361.36301)
			(xy 314.994485 -361.416417) (xy 314.970813 -361.466914) (xy 314.94004 -361.513427) (xy 314.902823 -361.554964)
			(xy 314.859955 -361.590639) (xy 314.812349 -361.619693) (xy 314.76102 -361.641505) (xy 314.707063 -361.655611)
			(xy 314.651626 -361.661711) (xy 314.595892 -361.659674) (xy 314.541049 -361.649544) (xy 314.488265 -361.631537)
			(xy 314.438665 -361.606036) (xy 314.393307 -361.573585) (xy 314.353158 -361.534876) (xy 314.319072 -361.490733)
			(xy 314.291776 -361.442098) (xy 314.271853 -361.390007) (xy 314.259727 -361.33557) (xy 314.255656 -361.279948)
			(xy 306.427632 -361.279948) (xy 306.427632 -364.640622) (xy 306.428008 -364.650667) (xy 306.435592 -364.669263)
			(xy 306.442364 -364.67669) (xy 307.200554 -365.434626) (xy 307.234336 -365.439198) (xy 307.249576 -365.430308)
			(xy 307.271525 -365.417999) (xy 307.317966 -365.398618) (xy 307.366552 -365.385507) (xy 307.416438 -365.378894)
			(xy 307.4416 -365.378492) (xy 307.463698 -365.379254) (xy 307.474603 -365.379409) (xy 307.494941 -365.371588)
			(xy 307.510227 -365.35606) (xy 307.517727 -365.335602) (xy 307.516099 -365.313874) (xy 307.505634 -365.294761)
			(xy 307.497226 -365.287814) (xy 307.491472 -365.283466) (xy 307.480541 -365.274057) (xy 307.475382 -365.269018)
			(xy 307.459888 -365.25327) (xy 307.437028 -365.245904) (xy 307.424836 -365.247936) (xy 307.410073 -365.250097)
			(xy 307.38032 -365.252384) (xy 307.3654 -365.252508) (xy 307.338149 -365.252022) (xy 307.284201 -365.244266)
			(xy 307.231906 -365.228911) (xy 307.182329 -365.206269) (xy 307.136479 -365.176803) (xy 307.095288 -365.141112)
			(xy 307.059597 -365.099921) (xy 307.030131 -365.054071) (xy 307.007489 -365.004494) (xy 306.992134 -364.952199)
			(xy 306.984378 -364.898251) (xy 306.984378 -364.843749) (xy 306.992134 -364.789801) (xy 307.007489 -364.737506)
			(xy 307.030131 -364.687929) (xy 307.059597 -364.642079) (xy 307.095288 -364.600888) (xy 307.136479 -364.565197)
			(xy 307.182329 -364.535731) (xy 307.231906 -364.513089) (xy 307.284201 -364.497734) (xy 307.338149 -364.489978)
			(xy 307.3654 -364.489492) (xy 307.391858 -364.489953) (xy 307.444268 -364.497261) (xy 307.495166 -364.511736)
			(xy 307.543578 -364.533102) (xy 307.566314 -364.546642) (xy 307.577744 -364.553754) (xy 307.604414 -364.55477)
			(xy 307.706014 -364.502446) (xy 307.720492 -364.480094) (xy 307.721254 -364.466632) (xy 307.723585 -364.437914)
			(xy 307.735709 -364.381591) (xy 307.756165 -364.327731) (xy 307.78449 -364.277561) (xy 307.820038 -364.232222)
			(xy 307.862001 -364.192745) (xy 307.909424 -364.160029) (xy 307.961228 -364.134817) (xy 308.016235 -364.117684)
			(xy 308.073193 -364.109019) (xy 308.102 -364.108492) (xy 308.11692 -364.108609) (xy 308.146673 -364.1109)
			(xy 308.161436 -364.113064) (xy 308.173628 -364.115096) (xy 308.196488 -364.10773) (xy 309.227982 -363.075982)
			(xy 309.242467 -363.062159) (xy 309.275741 -363.039901) (xy 309.312721 -363.024568) (xy 309.351984 -363.016751)
			(xy 309.372 -363.016292) (xy 312.97499 -363.016292) (xy 312.985038 -363.015946) (xy 313.003634 -363.00834)
			(xy 313.011058 -363.00156) (xy 313.825382 -362.186982) (xy 313.839867 -362.173159) (xy 313.873141 -362.150901)
			(xy 313.910121 -362.135568) (xy 313.949384 -362.127751) (xy 313.9694 -362.127292) (xy 315.64199 -362.127292)
			(xy 315.652038 -362.126946) (xy 315.670634 -362.11934) (xy 315.678058 -362.11256) (xy 316.873382 -360.916982)
			(xy 316.887867 -360.903159) (xy 316.921141 -360.880901) (xy 316.958121 -360.865568) (xy 316.997384 -360.857751)
			(xy 317.0174 -360.857292) (xy 319.57899 -360.857292) (xy 319.589038 -360.856946) (xy 319.607634 -360.84934)
			(xy 319.615058 -360.84256) (xy 322.436744 -358.020874) (xy 322.443437 -358.013393) (xy 322.451028 -357.994834)
			(xy 322.451476 -357.984806) (xy 322.451476 -342.801194) (xy 322.451999 -342.781183) (xy 322.459818 -342.741932)
			(xy 322.475137 -342.704957) (xy 322.497367 -342.671677) (xy 322.511166 -342.657176) (xy 325.714868 -339.453474)
			(xy 325.728722 -339.440233) (xy 325.760412 -339.418689) (xy 325.79558 -339.403472) (xy 325.814182 -339.398864)
			(xy 325.823608 -339.396269) (xy 325.839673 -339.38516) (xy 325.850419 -339.368851) (xy 325.85429 -339.349706)
			(xy 325.850723 -339.330503) (xy 325.840236 -339.314025) (xy 325.824349 -339.302663) (xy 325.805367 -339.298063)
			(xy 325.79564 -339.299042) (xy 325.781875 -339.300934) (xy 325.754162 -339.302969) (xy 325.740268 -339.303106)
			(xy 325.713018 -339.302622) (xy 325.659074 -339.294862) (xy 325.606782 -339.279504) (xy 325.557209 -339.256861)
			(xy 325.511362 -339.227393) (xy 325.470176 -339.191702) (xy 325.434487 -339.150512) (xy 325.405024 -339.104663)
			(xy 325.382385 -339.055088) (xy 325.367031 -339.002795) (xy 325.359276 -338.94885) (xy 325.359276 -338.89435)
			(xy 325.367031 -338.840405) (xy 325.382385 -338.788112) (xy 325.405024 -338.738537) (xy 325.434487 -338.692688)
			(xy 325.470176 -338.651498) (xy 325.511362 -338.615807) (xy 325.557209 -338.586339) (xy 325.606782 -338.563696)
			(xy 325.659074 -338.548338) (xy 325.713018 -338.540578) (xy 325.740268 -338.54009) (xy 325.765504 -338.540458)
			(xy 325.815539 -338.547085) (xy 325.86426 -338.560267) (xy 325.91081 -338.579771) (xy 325.9328 -338.59216)
			(xy 325.942452 -338.598002) (xy 325.96455 -338.600034) (xy 326.059038 -338.566506) (xy 326.07504 -338.551012)
			(xy 326.079104 -338.540598) (xy 326.089779 -338.513812) (xy 326.118069 -338.46357) (xy 326.153601 -338.418159)
			(xy 326.195566 -338.378617) (xy 326.243007 -338.345844) (xy 326.294841 -338.320588) (xy 326.349887 -338.303424)
			(xy 326.40689 -338.294745) (xy 326.43572 -338.294218) (xy 326.462975 -338.294636) (xy 326.516928 -338.302397)
			(xy 326.569229 -338.317757) (xy 326.618811 -338.340403) (xy 326.664665 -338.369876) (xy 326.705858 -338.405574)
			(xy 326.741552 -338.446772) (xy 326.771019 -338.49263) (xy 326.793659 -338.542214) (xy 326.806382 -338.585556)
			(xy 328.947272 -338.585556) (xy 328.947786 -338.557983) (xy 328.95573 -338.503413) (xy 328.971446 -338.450554)
			(xy 328.994607 -338.400509) (xy 329.024731 -338.354318) (xy 329.061189 -338.312944) (xy 329.081892 -338.294726)
			(xy 329.089993 -338.287108) (xy 329.099357 -338.266968) (xy 329.099926 -338.255864) (xy 329.099926 -338.178648)
			(xy 329.099371 -338.167536) (xy 329.090026 -338.147376) (xy 329.081892 -338.139786) (xy 329.061169 -338.121587)
			(xy 329.0247 -338.080216) (xy 328.99457 -338.034023) (xy 328.971406 -337.983973) (xy 328.955692 -337.931108)
			(xy 328.947756 -337.876531) (xy 328.947272 -337.848956) (xy 328.947737 -337.821705) (xy 328.955499 -337.767757)
			(xy 328.970859 -337.715463) (xy 328.993503 -337.665887) (xy 329.022972 -337.620038) (xy 329.058666 -337.578849)
			(xy 329.099857 -337.543158) (xy 329.145708 -337.513692) (xy 329.195286 -337.49105) (xy 329.247581 -337.475694)
			(xy 329.301529 -337.467935) (xy 329.32878 -337.467448) (xy 329.36307 -337.468972) (xy 329.37323 -337.469988)
			(xy 329.392534 -337.463892) (xy 329.463146 -337.40471) (xy 329.472544 -337.386676) (xy 329.47356 -337.376516)
			(xy 329.476506 -337.348343) (xy 329.489684 -337.293252) (xy 329.510865 -337.240716) (xy 329.539585 -337.191892)
			(xy 329.57521 -337.147852) (xy 329.616957 -337.109566) (xy 329.663909 -337.077877) (xy 329.715031 -337.05348)
			(xy 329.769199 -337.036914) (xy 329.825221 -337.028542) (xy 329.853544 -337.028028) (xy 329.871563 -337.028248)
			(xy 329.907438 -337.031683) (xy 329.925172 -337.034886) (xy 329.93457 -337.036664) (xy 329.95362 -337.032854)
			(xy 330.028804 -336.985102) (xy 330.040234 -336.969354) (xy 330.04252 -336.959956) (xy 330.049915 -336.932911)
			(xy 330.071545 -336.881184) (xy 330.100509 -336.833179) (xy 330.136185 -336.789927) (xy 330.177804 -336.75236)
			(xy 330.224472 -336.721286) (xy 330.275184 -336.697373) (xy 330.328848 -336.681137) (xy 330.384311 -336.672927)
			(xy 330.412344 -336.672428) (xy 330.439598 -336.672837) (xy 330.49355 -336.6806) (xy 330.545849 -336.695963)
			(xy 330.595428 -336.718612) (xy 330.64128 -336.748086) (xy 330.682471 -336.783786) (xy 330.718162 -336.824984)
			(xy 330.747627 -336.870842) (xy 330.770265 -336.920426) (xy 330.785617 -336.972728) (xy 330.793369 -337.026682)
			(xy 330.793852 -337.053936) (xy 330.793359 -337.08151) (xy 330.785414 -337.136082) (xy 330.769696 -337.188942)
			(xy 330.746531 -337.238989) (xy 330.716403 -337.285179) (xy 330.679938 -337.32655) (xy 330.659232 -337.344766)
			(xy 330.651122 -337.352376) (xy 330.641766 -337.372522) (xy 330.641198 -337.383628) (xy 330.641198 -337.460844)
			(xy 330.641782 -337.471952) (xy 330.651109 -337.492111) (xy 330.659232 -337.499706) (xy 330.679972 -337.517883)
			(xy 330.716433 -337.559261) (xy 330.746556 -337.605457) (xy 330.769715 -337.655508) (xy 330.785426 -337.708373)
			(xy 330.793363 -337.762948) (xy 330.79336 -337.818098) (xy 330.787241 -337.860132) (xy 331.952344 -337.860132)
			(xy 331.956415 -337.80451) (xy 331.968541 -337.750073) (xy 331.988464 -337.697982) (xy 332.01576 -337.649347)
			(xy 332.049846 -337.605204) (xy 332.089995 -337.566495) (xy 332.135353 -337.534044) (xy 332.184953 -337.508543)
			(xy 332.237737 -337.490536) (xy 332.29258 -337.480406) (xy 332.348314 -337.478369) (xy 332.403751 -337.484469)
			(xy 332.457708 -337.498575) (xy 332.509037 -337.520387) (xy 332.556643 -337.549441) (xy 332.599511 -337.585116)
			(xy 332.636728 -337.626653) (xy 332.667501 -337.673166) (xy 332.691173 -337.723663) (xy 332.707241 -337.77707)
			(xy 332.715361 -337.832246) (xy 332.71587 -337.860132) (xy 332.715361 -337.888018) (xy 332.707241 -337.943194)
			(xy 332.691173 -337.996601) (xy 332.667501 -338.047098) (xy 332.636728 -338.093611) (xy 332.599511 -338.135148)
			(xy 332.556643 -338.170823) (xy 332.509037 -338.199877) (xy 332.457708 -338.221689) (xy 332.403751 -338.235795)
			(xy 332.348314 -338.241895) (xy 332.29258 -338.239858) (xy 332.237737 -338.229728) (xy 332.184953 -338.211721)
			(xy 332.135353 -338.18622) (xy 332.089995 -338.153769) (xy 332.049846 -338.11506) (xy 332.01576 -338.070917)
			(xy 331.988464 -338.022282) (xy 331.968541 -337.970191) (xy 331.956415 -337.915754) (xy 331.952344 -337.860132)
			(xy 330.787241 -337.860132) (xy 330.785416 -337.872673) (xy 330.769699 -337.925535) (xy 330.746534 -337.975584)
			(xy 330.716404 -338.021776) (xy 330.679939 -338.06315) (xy 330.659232 -338.081366) (xy 330.651122 -338.088976)
			(xy 330.641766 -338.109122) (xy 330.641198 -338.120228) (xy 330.641198 -338.197444) (xy 330.641782 -338.208552)
			(xy 330.651109 -338.228711) (xy 330.659232 -338.236306) (xy 330.679956 -338.254503) (xy 330.716424 -338.295876)
			(xy 330.746553 -338.342069) (xy 330.769717 -338.392119) (xy 330.785431 -338.444984) (xy 330.793368 -338.499561)
			(xy 330.793852 -338.527136) (xy 330.793356 -338.554386) (xy 330.785596 -338.608331) (xy 330.770238 -338.660623)
			(xy 330.747596 -338.710197) (xy 330.718492 -338.755482) (xy 331.373224 -338.755482) (xy 331.377295 -338.69986)
			(xy 331.389421 -338.645423) (xy 331.409344 -338.593332) (xy 331.43664 -338.544697) (xy 331.470726 -338.500554)
			(xy 331.510875 -338.461845) (xy 331.556233 -338.429394) (xy 331.605833 -338.403893) (xy 331.658617 -338.385886)
			(xy 331.71346 -338.375756) (xy 331.769194 -338.373719) (xy 331.824631 -338.379819) (xy 331.878588 -338.393925)
			(xy 331.929917 -338.415737) (xy 331.977523 -338.444791) (xy 332.020391 -338.480466) (xy 332.057608 -338.522003)
			(xy 332.088381 -338.568516) (xy 332.112053 -338.619013) (xy 332.128121 -338.67242) (xy 332.136241 -338.727596)
			(xy 332.13675 -338.755482) (xy 332.136241 -338.783368) (xy 332.128121 -338.838544) (xy 332.112053 -338.891951)
			(xy 332.088381 -338.942448) (xy 332.057608 -338.988961) (xy 332.020391 -339.030498) (xy 331.977523 -339.066173)
			(xy 331.929917 -339.095227) (xy 331.878588 -339.117039) (xy 331.824631 -339.131145) (xy 331.769194 -339.137245)
			(xy 331.71346 -339.135208) (xy 331.658617 -339.125078) (xy 331.605833 -339.107071) (xy 331.556233 -339.08157)
			(xy 331.510875 -339.049119) (xy 331.470726 -339.01041) (xy 331.43664 -338.966267) (xy 331.409344 -338.917632)
			(xy 331.389421 -338.865541) (xy 331.377295 -338.811104) (xy 331.373224 -338.755482) (xy 330.718492 -338.755482)
			(xy 330.71813 -338.756046) (xy 330.68244 -338.797234) (xy 330.641252 -338.832925) (xy 330.595405 -338.862392)
			(xy 330.545831 -338.885035) (xy 330.493539 -338.900394) (xy 330.439594 -338.908155) (xy 330.412344 -338.908644)
			(xy 330.384492 -338.908049) (xy 330.329381 -338.899932) (xy 330.276034 -338.883895) (xy 330.225583 -338.860277)
			(xy 330.1791 -338.829579) (xy 330.13757 -338.792453) (xy 330.101875 -338.749687) (xy 330.072772 -338.702188)
			(xy 330.050879 -338.650965) (xy 330.043282 -338.624164) (xy 330.040996 -338.615274) (xy 330.030328 -338.600034)
			(xy 329.958446 -338.552282) (xy 329.940412 -338.548218) (xy 329.931268 -338.549488) (xy 329.918252 -338.551158)
			(xy 329.892067 -338.552937) (xy 329.878944 -338.553044) (xy 329.864795 -338.552945) (xy 329.836572 -338.550914)
			(xy 329.822556 -338.54898) (xy 329.812396 -338.547456) (xy 329.792838 -338.552282) (xy 329.718416 -338.608162)
			(xy 329.708256 -338.625688) (xy 329.706986 -338.635848) (xy 329.70293 -338.663007) (xy 329.687955 -338.71584)
			(xy 329.665561 -338.76598) (xy 329.63621 -338.812392) (xy 329.600509 -338.854117) (xy 329.559195 -338.890293)
			(xy 329.513122 -338.920173) (xy 329.463242 -338.94314) (xy 329.410584 -338.958719) (xy 329.356237 -338.966588)
			(xy 329.32878 -338.967064) (xy 329.301525 -338.966664) (xy 329.247569 -338.958903) (xy 329.195267 -338.943542)
			(xy 329.145684 -338.920894) (xy 329.099829 -338.89142) (xy 329.058635 -338.855719) (xy 329.022942 -338.81452)
			(xy 328.993475 -338.76866) (xy 328.970836 -338.719073) (xy 328.955484 -338.666768) (xy 328.947732 -338.612811)
			(xy 328.947272 -338.585556) (xy 326.806382 -338.585556) (xy 326.809013 -338.594517) (xy 326.816767 -338.648471)
			(xy 326.817228 -338.675726) (xy 326.81656 -338.707288) (xy 326.806176 -338.769553) (xy 326.785693 -338.829263)
			(xy 326.771254 -338.857336) (xy 326.766428 -338.866226) (xy 326.764396 -338.885784) (xy 326.79005 -338.973922)
			(xy 326.802496 -338.989416) (xy 326.811386 -338.994496) (xy 326.83651 -339.009007) (xy 326.882393 -339.044516)
			(xy 326.922368 -339.086566) (xy 326.955511 -339.134186) (xy 326.981058 -339.186277) (xy 326.998419 -339.241637)
			(xy 327.007193 -339.298989) (xy 327.007728 -339.327998) (xy 327.00722 -339.355248) (xy 326.999465 -339.409194)
			(xy 326.993027 -339.431122) (xy 332.71206 -339.431122) (xy 332.712569 -339.403648) (xy 332.720457 -339.34927)
			(xy 332.736072 -339.296588) (xy 332.759092 -339.246695) (xy 332.789037 -339.200625) (xy 332.806802 -339.179662)
			(xy 332.812898 -339.17255) (xy 332.819248 -339.155532) (xy 332.819248 -339.06968) (xy 332.812898 -339.052662)
			(xy 332.806802 -339.04555) (xy 332.789034 -339.024591) (xy 332.75911 -338.978509) (xy 332.736098 -338.928613)
			(xy 332.720473 -338.875936) (xy 332.712558 -338.821563) (xy 332.71206 -338.79409) (xy 332.712546 -338.766839)
			(xy 332.720302 -338.712891) (xy 332.735657 -338.660596) (xy 332.758299 -338.611019) (xy 332.787765 -338.565169)
			(xy 332.823456 -338.523978) (xy 332.864647 -338.488287) (xy 332.910497 -338.458821) (xy 332.960074 -338.436179)
			(xy 333.012369 -338.420824) (xy 333.066317 -338.413068) (xy 333.120819 -338.413068) (xy 333.174767 -338.420824)
			(xy 333.227062 -338.436179) (xy 333.276639 -338.458821) (xy 333.322489 -338.488287) (xy 333.36368 -338.523978)
			(xy 333.399371 -338.565169) (xy 333.428837 -338.611019) (xy 333.451479 -338.660596) (xy 333.466834 -338.712891)
			(xy 333.47459 -338.766839) (xy 333.475076 -338.79409) (xy 333.47459 -338.821565) (xy 333.466699 -338.875945)
			(xy 333.451079 -338.928627) (xy 333.428054 -338.97852) (xy 333.398102 -339.024588) (xy 333.380334 -339.04555)
			(xy 333.374238 -339.052662) (xy 333.367888 -339.06968) (xy 333.367888 -339.155532) (xy 333.374238 -339.17255)
			(xy 333.380334 -339.179662) (xy 333.398066 -339.20065) (xy 333.427995 -339.246725) (xy 333.451013 -339.296613)
			(xy 333.466646 -339.349284) (xy 333.474572 -339.403651) (xy 333.475076 -339.431122) (xy 333.47459 -339.458373)
			(xy 333.466834 -339.512321) (xy 333.451479 -339.564616) (xy 333.428837 -339.614193) (xy 333.399371 -339.660043)
			(xy 333.36368 -339.701234) (xy 333.322489 -339.736925) (xy 333.276639 -339.766391) (xy 333.227062 -339.789033)
			(xy 333.174767 -339.804388) (xy 333.120819 -339.812144) (xy 333.066317 -339.812144) (xy 333.012369 -339.804388)
			(xy 332.960074 -339.789033) (xy 332.910497 -339.766391) (xy 332.864647 -339.736925) (xy 332.823456 -339.701234)
			(xy 332.787765 -339.660043) (xy 332.758299 -339.614193) (xy 332.735657 -339.564616) (xy 332.720302 -339.512321)
			(xy 332.712546 -339.458373) (xy 332.71206 -339.431122) (xy 326.993027 -339.431122) (xy 326.984111 -339.461487)
			(xy 326.961471 -339.511063) (xy 326.932007 -339.556913) (xy 326.896318 -339.598102) (xy 326.85513 -339.633794)
			(xy 326.809283 -339.663261) (xy 326.759708 -339.685903) (xy 326.707416 -339.70126) (xy 326.65347 -339.709019)
			(xy 326.62622 -339.709506) (xy 326.6113 -339.709387) (xy 326.581547 -339.707097) (xy 326.566784 -339.704934)
			(xy 326.554592 -339.702902) (xy 326.531732 -339.710268) (xy 326.500744 -339.74151) (xy 326.486289 -339.755366)
			(xy 326.453004 -339.777619) (xy 326.416015 -339.792942) (xy 326.376745 -339.800747) (xy 326.356726 -339.8012)
			(xy 325.964296 -339.8012) (xy 325.95425 -339.801567) (xy 325.935653 -339.809155) (xy 325.928228 -339.815932)
			(xy 322.873624 -342.870536) (xy 322.866922 -342.87801) (xy 322.859338 -342.896575) (xy 322.858892 -342.906604)
			(xy 322.858892 -358.090216) (xy 322.858384 -358.110228) (xy 322.850562 -358.14948) (xy 322.835239 -358.186455)
			(xy 322.813004 -358.219735) (xy 322.799202 -358.234234) (xy 319.828418 -361.205018) (xy 319.813933 -361.218841)
			(xy 319.780659 -361.241099) (xy 319.743679 -361.256432) (xy 319.704416 -361.264249) (xy 319.6844 -361.264708)
			(xy 317.12281 -361.264708) (xy 317.112762 -361.265054) (xy 317.094166 -361.27266) (xy 317.086742 -361.27944)
			(xy 315.891418 -362.475018) (xy 315.876933 -362.488841) (xy 315.843659 -362.511099) (xy 315.806679 -362.526432)
			(xy 315.767416 -362.534249) (xy 315.7474 -362.534708) (xy 314.07481 -362.534708) (xy 314.064762 -362.535054)
			(xy 314.046166 -362.54266) (xy 314.038742 -362.54944) (xy 313.224418 -363.364018) (xy 313.209933 -363.377841)
			(xy 313.176659 -363.400099) (xy 313.139679 -363.415432) (xy 313.100416 -363.423249) (xy 313.0804 -363.423708)
			(xy 309.47741 -363.423708) (xy 309.467362 -363.424054) (xy 309.448766 -363.43166) (xy 309.441342 -363.43844)
			(xy 308.48427 -364.395512) (xy 308.476904 -364.418372) (xy 308.478936 -364.430564) (xy 308.481097 -364.445327)
			(xy 308.483384 -364.47508) (xy 308.483508 -364.49) (xy 308.483442 -364.500563) (xy 308.482301 -364.521657)
			(xy 308.481222 -364.532164) (xy 308.479444 -364.54842) (xy 308.494938 -364.576614) (xy 308.59603 -364.625128)
			(xy 308.60572 -364.629142) (xy 308.626655 -364.629894) (xy 308.64616 -364.622251) (xy 308.653942 -364.615222)
			(xy 309.304182 -363.964982) (xy 309.318667 -363.951159) (xy 309.351941 -363.928901) (xy 309.388921 -363.913568)
			(xy 309.428184 -363.905751) (xy 309.4482 -363.905292) (xy 315.64199 -363.905292) (xy 315.652038 -363.904946)
			(xy 315.670634 -363.89734) (xy 315.678058 -363.89056) (xy 317.508382 -362.059982) (xy 317.522867 -362.046159)
			(xy 317.556141 -362.023901) (xy 317.593121 -362.008568) (xy 317.632384 -362.000751) (xy 317.6524 -362.000292)
			(xy 319.83299 -362.000292) (xy 319.843038 -361.999946) (xy 319.861634 -361.99234) (xy 319.869058 -361.98556)
			(xy 324.209664 -357.644954) (xy 324.216369 -357.637482) (xy 324.223952 -357.618916) (xy 324.224396 -357.608886)
			(xy 324.224396 -345.109292) (xy 324.224912 -345.089281) (xy 324.232733 -345.050029) (xy 324.248053 -345.013054)
			(xy 324.270286 -344.979774) (xy 324.284086 -344.965274) (xy 326.944736 -342.304624) (xy 326.959266 -342.290873)
			(xy 326.99255 -342.268694) (xy 327.02952 -342.253428) (xy 327.068755 -342.245661) (xy 327.088754 -342.245188)
			(xy 331.194664 -342.245188) (xy 331.204732 -342.244747) (xy 331.22333 -342.237038) (xy 331.230732 -342.230202)
			(xy 334.019906 -339.440774) (xy 334.021176 -339.439504) (xy 334.030828 -339.430106) (xy 334.038194 -339.404706)
			(xy 334.012032 -339.293962) (xy 333.993998 -339.274404) (xy 333.981298 -339.27034) (xy 333.955972 -339.2618)
			(xy 333.907858 -339.238527) (xy 333.863463 -339.208766) (xy 333.823657 -339.173098) (xy 333.789221 -339.132223)
			(xy 333.760829 -339.08694) (xy 333.739036 -339.038137) (xy 333.72427 -338.98677) (xy 333.71682 -338.933844)
			(xy 333.716376 -338.90712) (xy 333.716874 -338.879868) (xy 333.724628 -338.82592) (xy 333.73998 -338.773623)
			(xy 333.762619 -338.724044) (xy 333.792084 -338.678192) (xy 333.827774 -338.636999) (xy 333.868963 -338.601305)
			(xy 333.914813 -338.571837) (xy 333.96439 -338.549193) (xy 334.016684 -338.533835) (xy 334.070632 -338.526076)
			(xy 334.097884 -338.525612) (xy 334.123121 -338.52597) (xy 334.173156 -338.5326) (xy 334.221876 -338.545784)
			(xy 334.268427 -338.565292) (xy 334.290416 -338.577682) (xy 334.300068 -338.583524) (xy 334.322166 -338.585556)
			(xy 334.416654 -338.552028) (xy 334.432656 -338.536534) (xy 334.43672 -338.52612) (xy 334.447394 -338.499334)
			(xy 334.475682 -338.449089) (xy 334.511214 -338.403678) (xy 334.553179 -338.364135) (xy 334.60062 -338.331361)
			(xy 334.652455 -338.306106) (xy 334.707502 -338.288944) (xy 334.764506 -338.280266) (xy 334.793336 -338.27974)
			(xy 334.820592 -338.280122) (xy 334.874548 -338.287885) (xy 334.926851 -338.303248) (xy 334.976434 -338.325898)
			(xy 335.02229 -338.355374) (xy 335.063483 -338.391076) (xy 335.099176 -338.432278) (xy 335.128642 -338.47814)
			(xy 335.151282 -338.527728) (xy 335.164005 -338.571078) (xy 337.304888 -338.571078) (xy 337.305412 -338.543506)
			(xy 337.313353 -338.488935) (xy 337.329067 -338.436077) (xy 337.352226 -338.386031) (xy 337.382348 -338.33984)
			(xy 337.418806 -338.298466) (xy 337.439508 -338.280248) (xy 337.447602 -338.272623) (xy 337.456969 -338.252489)
			(xy 337.457542 -338.241386) (xy 337.457542 -338.16417) (xy 337.457025 -338.153053) (xy 337.447652 -338.132894)
			(xy 337.439508 -338.125308) (xy 337.418799 -338.107094) (xy 337.382328 -338.065726) (xy 337.352196 -338.019537)
			(xy 337.329029 -337.969489) (xy 337.313313 -337.916627) (xy 337.305373 -337.862053) (xy 337.304888 -337.834478)
			(xy 337.305357 -337.807226) (xy 337.313117 -337.753278) (xy 337.328474 -337.700983) (xy 337.351118 -337.651406)
			(xy 337.380586 -337.605556) (xy 337.416279 -337.564366) (xy 337.457471 -337.528675) (xy 337.503322 -337.499209)
			(xy 337.5529 -337.476568) (xy 337.605196 -337.461213) (xy 337.659144 -337.453456) (xy 337.686396 -337.45297)
			(xy 337.720686 -337.454494) (xy 337.730846 -337.45551) (xy 337.75015 -337.449414) (xy 337.820762 -337.390232)
			(xy 337.83016 -337.372198) (xy 337.831176 -337.362038) (xy 337.834125 -337.333865) (xy 337.8473 -337.278773)
			(xy 337.86848 -337.226236) (xy 337.897198 -337.177411) (xy 337.932823 -337.13337) (xy 337.974571 -337.095084)
			(xy 338.021522 -337.063394) (xy 338.072645 -337.038998) (xy 338.126814 -337.022433) (xy 338.182837 -337.014063)
			(xy 338.21116 -337.01355) (xy 338.229179 -337.013767) (xy 338.265054 -337.017204) (xy 338.282788 -337.020408)
			(xy 338.292186 -337.022186) (xy 338.311236 -337.018376) (xy 338.38642 -336.970624) (xy 338.39785 -336.954876)
			(xy 338.400136 -336.945478) (xy 338.407531 -336.918433) (xy 338.429159 -336.866705) (xy 338.458122 -336.818698)
			(xy 338.493798 -336.775445) (xy 338.535417 -336.737878) (xy 338.582086 -336.706803) (xy 338.632798 -336.682891)
			(xy 338.686463 -336.666656) (xy 338.741926 -336.658447) (xy 338.76996 -336.65795) (xy 338.797208 -336.658515)
			(xy 338.851151 -336.666265) (xy 338.895514 -336.679286) (xy 339.325712 -336.679286) (xy 339.326216 -336.651376)
			(xy 339.334351 -336.596151) (xy 339.350445 -336.542701) (xy 339.374154 -336.492167) (xy 339.404974 -336.445625)
			(xy 339.423248 -336.424524) (xy 339.429598 -336.417412) (xy 339.436202 -336.40014) (xy 339.436202 -336.313018)
			(xy 339.429598 -336.295746) (xy 339.423248 -336.288634) (xy 339.404956 -336.267546) (xy 339.374133 -336.221004)
			(xy 339.350421 -336.170466) (xy 339.334327 -336.117012) (xy 339.326196 -336.061784) (xy 339.325712 -336.033872)
			(xy 339.326198 -336.006621) (xy 339.333954 -335.952673) (xy 339.349309 -335.900378) (xy 339.371951 -335.850801)
			(xy 339.401417 -335.804951) (xy 339.437108 -335.76376) (xy 339.478299 -335.728069) (xy 339.524149 -335.698603)
			(xy 339.573726 -335.675961) (xy 339.626021 -335.660606) (xy 339.679969 -335.65285) (xy 339.734471 -335.65285)
			(xy 339.788419 -335.660606) (xy 339.840714 -335.675961) (xy 339.890291 -335.698603) (xy 339.936141 -335.728069)
			(xy 339.977332 -335.76376) (xy 340.013023 -335.804951) (xy 340.042489 -335.850801) (xy 340.065131 -335.900378)
			(xy 340.080486 -335.952673) (xy 340.088242 -336.006621) (xy 340.088728 -336.033872) (xy 340.088274 -336.061784)
			(xy 340.080129 -336.117011) (xy 340.064025 -336.170463) (xy 340.040303 -336.220997) (xy 340.009472 -336.267535)
			(xy 339.991192 -336.288634) (xy 339.984842 -336.295746) (xy 339.978238 -336.313018) (xy 339.978238 -336.40014)
			(xy 339.984842 -336.417412) (xy 339.991192 -336.424524) (xy 340.009454 -336.445637) (xy 340.040284 -336.492171)
			(xy 340.064003 -336.542703) (xy 340.080103 -336.596151) (xy 340.088241 -336.651376) (xy 340.088728 -336.679286)
			(xy 340.088242 -336.706537) (xy 340.080486 -336.760485) (xy 340.065131 -336.81278) (xy 340.042489 -336.862357)
			(xy 340.013023 -336.908207) (xy 339.977332 -336.949398) (xy 339.936141 -336.985089) (xy 339.893022 -337.0128)
			(xy 343.707948 -337.0128) (xy 343.712115 -336.957185) (xy 343.724526 -336.902811) (xy 343.744901 -336.850895)
			(xy 343.772787 -336.802596) (xy 343.80756 -336.758992) (xy 343.848443 -336.721058) (xy 343.894524 -336.68964)
			(xy 343.944772 -336.665442) (xy 343.998066 -336.649003) (xy 344.053214 -336.640691) (xy 344.0811 -336.64017)
			(xy 344.107521 -336.640635) (xy 344.159836 -336.648084) (xy 344.210575 -336.662848) (xy 344.258719 -336.68463)
			(xy 344.303304 -336.712993) (xy 344.32367 -336.729832) (xy 344.330528 -336.735928) (xy 344.347546 -336.742024)
			(xy 344.431874 -336.742024) (xy 344.448892 -336.735928) (xy 344.45575 -336.729832) (xy 344.476116 -336.712993)
			(xy 344.520702 -336.684628) (xy 344.568846 -336.662841) (xy 344.619583 -336.64807) (xy 344.671898 -336.64061)
			(xy 344.724742 -336.64061) (xy 344.777057 -336.64807) (xy 344.827794 -336.662841) (xy 344.875938 -336.684628)
			(xy 344.920524 -336.712993) (xy 344.94089 -336.729832) (xy 344.947748 -336.735928) (xy 344.964766 -336.742024)
			(xy 345.049094 -336.742024) (xy 345.066112 -336.735928) (xy 345.07297 -336.729832) (xy 345.09535 -336.711413)
			(xy 345.144682 -336.680989) (xy 345.198128 -336.658566) (xy 345.226132 -336.651092) (xy 345.237816 -336.648298)
			(xy 345.25585 -336.632804) (xy 345.297506 -336.537046) (xy 345.29649 -336.513424) (xy 345.290648 -336.50301)
			(xy 345.279175 -336.481643) (xy 345.261122 -336.43663) (xy 345.248921 -336.389692) (xy 345.242769 -336.341585)
			(xy 345.242388 -336.317336) (xy 345.242883 -336.289763) (xy 345.25083 -336.235191) (xy 345.266549 -336.182332)
			(xy 345.289714 -336.132286) (xy 345.319841 -336.086096) (xy 345.356303 -336.044723) (xy 345.377008 -336.026506)
			(xy 345.385121 -336.018898) (xy 345.394478 -335.998751) (xy 345.395042 -335.987644) (xy 345.395042 -335.910428)
			(xy 345.394493 -335.899315) (xy 345.385143 -335.879156) (xy 345.377008 -335.871566) (xy 345.356279 -335.853374)
			(xy 345.31981 -335.812002) (xy 345.289679 -335.765808) (xy 345.266517 -335.715756) (xy 345.250804 -335.66289)
			(xy 345.24287 -335.608312) (xy 345.242388 -335.580736) (xy 345.242874 -335.553485) (xy 345.25063 -335.499537)
			(xy 345.265985 -335.447242) (xy 345.288627 -335.397665) (xy 345.318093 -335.351815) (xy 345.353784 -335.310624)
			(xy 345.394975 -335.274933) (xy 345.440825 -335.245467) (xy 345.490402 -335.222825) (xy 345.542697 -335.20747)
			(xy 345.596645 -335.199714) (xy 345.651147 -335.199714) (xy 345.705095 -335.20747) (xy 345.75739 -335.222825)
			(xy 345.806967 -335.245467) (xy 345.852817 -335.274933) (xy 345.894008 -335.310624) (xy 345.929699 -335.351815)
			(xy 345.959165 -335.397665) (xy 345.981807 -335.447242) (xy 345.997162 -335.499537) (xy 346.004918 -335.553485)
			(xy 346.005404 -335.580736) (xy 346.004893 -335.608309) (xy 345.996949 -335.66288) (xy 345.981233 -335.715739)
			(xy 345.958072 -335.765785) (xy 345.927947 -335.811976) (xy 345.891488 -335.853349) (xy 345.870784 -335.871566)
			(xy 345.862683 -335.879184) (xy 345.85332 -335.899324) (xy 345.85275 -335.910428) (xy 345.85275 -335.987644)
			(xy 345.853317 -335.998754) (xy 345.862655 -336.018914) (xy 345.870784 -336.026506) (xy 345.891498 -336.044714)
			(xy 345.927969 -336.086083) (xy 345.958101 -336.132273) (xy 345.981266 -336.182322) (xy 345.996982 -336.235185)
			(xy 346.00492 -336.289761) (xy 346.005404 -336.317336) (xy 346.004864 -336.345812) (xy 345.99638 -336.402129)
			(xy 345.979619 -336.45656) (xy 345.954956 -336.507895) (xy 345.922936 -336.554994) (xy 345.884272 -336.596812)
			(xy 345.839823 -336.632418) (xy 345.790575 -336.661023) (xy 345.737623 -336.681992) (xy 345.710002 -336.688938)
			(xy 345.698572 -336.691732) (xy 345.680284 -336.706718) (xy 345.637104 -336.801968) (xy 345.637866 -336.82559)
			(xy 345.643708 -336.836004) (xy 345.657683 -336.863356) (xy 345.677513 -336.921486) (xy 345.687548 -336.982079)
			(xy 345.688158 -337.012788) (xy 345.687632 -337.039402) (xy 345.680059 -337.092089) (xy 345.665066 -337.143162)
			(xy 345.642956 -337.191581) (xy 345.614182 -337.236361) (xy 345.579327 -337.27659) (xy 345.539103 -337.31145)
			(xy 345.494326 -337.340231) (xy 345.44591 -337.362347) (xy 345.39484 -337.377348) (xy 345.342154 -337.384929)
			(xy 345.31554 -337.385406) (xy 345.289117 -337.384982) (xy 345.2368 -337.377523) (xy 345.186061 -337.362751)
			(xy 345.137918 -337.340959) (xy 345.093334 -337.312587) (xy 345.07297 -337.295744) (xy 345.066112 -337.289648)
			(xy 345.049094 -337.283552) (xy 344.964766 -337.283552) (xy 344.947748 -337.289648) (xy 344.94089 -337.295744)
			(xy 344.920524 -337.312583) (xy 344.875938 -337.340948) (xy 344.827794 -337.362735) (xy 344.777057 -337.377506)
			(xy 344.724742 -337.384966) (xy 344.671898 -337.384966) (xy 344.619583 -337.377506) (xy 344.568846 -337.362735)
			(xy 344.520702 -337.340948) (xy 344.476116 -337.312583) (xy 344.45575 -337.295744) (xy 344.448892 -337.289648)
			(xy 344.431874 -337.283552) (xy 344.347546 -337.283552) (xy 344.330528 -337.289648) (xy 344.32367 -337.295744)
			(xy 344.303309 -337.312587) (xy 344.258718 -337.340944) (xy 344.210573 -337.362723) (xy 344.159835 -337.377489)
			(xy 344.107521 -337.384947) (xy 344.0811 -337.385406) (xy 344.053214 -337.384909) (xy 343.998066 -337.376597)
			(xy 343.944772 -337.360158) (xy 343.894524 -337.33596) (xy 343.848443 -337.304542) (xy 343.80756 -337.266608)
			(xy 343.772787 -337.223004) (xy 343.744901 -337.174705) (xy 343.724526 -337.122789) (xy 343.712115 -337.068415)
			(xy 343.707948 -337.0128) (xy 339.893022 -337.0128) (xy 339.890291 -337.014555) (xy 339.840714 -337.037197)
			(xy 339.788419 -337.052552) (xy 339.734471 -337.060308) (xy 339.679969 -337.060308) (xy 339.626021 -337.052552)
			(xy 339.573726 -337.037197) (xy 339.524149 -337.014555) (xy 339.478299 -336.985089) (xy 339.437108 -336.949398)
			(xy 339.401417 -336.908207) (xy 339.371951 -336.862357) (xy 339.349309 -336.81278) (xy 339.333954 -336.760485)
			(xy 339.326198 -336.706537) (xy 339.325712 -336.679286) (xy 338.895514 -336.679286) (xy 338.903442 -336.681613)
			(xy 338.953016 -336.704247) (xy 338.998864 -336.733705) (xy 339.040054 -336.769388) (xy 339.075746 -336.81057)
			(xy 339.105214 -336.856412) (xy 339.127858 -336.905981) (xy 339.143217 -336.958269) (xy 339.150979 -337.01221)
			(xy 339.151468 -337.039458) (xy 339.150985 -337.067032) (xy 339.143037 -337.121605) (xy 339.127316 -337.174465)
			(xy 339.10415 -337.224511) (xy 339.07402 -337.270701) (xy 339.037554 -337.312072) (xy 339.016848 -337.330288)
			(xy 339.008731 -337.337892) (xy 338.999378 -337.358043) (xy 338.998814 -337.36915) (xy 338.998814 -337.446366)
			(xy 338.999381 -337.457476) (xy 339.00872 -337.477635) (xy 339.016848 -337.485228) (xy 339.037514 -337.503488)
			(xy 339.073982 -337.544852) (xy 339.104114 -337.591035) (xy 339.127281 -337.641077) (xy 339.143001 -337.693932)
			(xy 339.150945 -337.748501) (xy 339.150949 -337.803645) (xy 339.143012 -337.858215) (xy 339.127342 -337.910932)
			(xy 340.283544 -337.910932) (xy 340.287615 -337.85531) (xy 340.299741 -337.800873) (xy 340.319664 -337.748782)
			(xy 340.34696 -337.700147) (xy 340.381046 -337.656004) (xy 340.421195 -337.617295) (xy 340.466553 -337.584844)
			(xy 340.516153 -337.559343) (xy 340.568937 -337.541336) (xy 340.62378 -337.531206) (xy 340.679514 -337.529169)
			(xy 340.734951 -337.535269) (xy 340.788908 -337.549375) (xy 340.840237 -337.571187) (xy 340.887843 -337.600241)
			(xy 340.930711 -337.635916) (xy 340.967928 -337.677453) (xy 340.998701 -337.723966) (xy 341.022373 -337.774463)
			(xy 341.038441 -337.82787) (xy 341.046561 -337.883046) (xy 341.04707 -337.910932) (xy 341.046561 -337.938818)
			(xy 341.038441 -337.993994) (xy 341.022373 -338.047401) (xy 340.998701 -338.097898) (xy 340.967928 -338.144411)
			(xy 340.930711 -338.185948) (xy 340.887843 -338.221623) (xy 340.840237 -338.250677) (xy 340.788908 -338.272489)
			(xy 340.734951 -338.286595) (xy 340.679514 -338.292695) (xy 340.62378 -338.290658) (xy 340.568937 -338.280528)
			(xy 340.516153 -338.262521) (xy 340.466553 -338.23702) (xy 340.421195 -338.204569) (xy 340.381046 -338.16586)
			(xy 340.34696 -338.121717) (xy 340.319664 -338.073082) (xy 340.299741 -338.020991) (xy 340.287615 -337.966554)
			(xy 340.283544 -337.910932) (xy 339.127342 -337.910932) (xy 339.1273 -337.911073) (xy 339.10414 -337.961117)
			(xy 339.074015 -338.007305) (xy 339.037553 -338.048674) (xy 339.016848 -338.066888) (xy 339.008731 -338.074492)
			(xy 338.999378 -338.094643) (xy 338.998814 -338.10575) (xy 338.998814 -338.182966) (xy 338.999381 -338.194076)
			(xy 339.00872 -338.214235) (xy 339.016848 -338.221828) (xy 339.037586 -338.24001) (xy 339.074052 -338.281386)
			(xy 339.104179 -338.327583) (xy 339.12734 -338.377636) (xy 339.143051 -338.430503) (xy 339.150985 -338.485082)
			(xy 339.151468 -338.512658) (xy 339.151006 -338.539912) (xy 339.143253 -338.593865) (xy 339.1279 -338.646165)
			(xy 339.10526 -338.695748) (xy 339.075793 -338.741603) (xy 339.040099 -338.782797) (xy 339.012995 -338.806282)
			(xy 339.704424 -338.806282) (xy 339.708495 -338.75066) (xy 339.720621 -338.696223) (xy 339.740544 -338.644132)
			(xy 339.76784 -338.595497) (xy 339.801926 -338.551354) (xy 339.842075 -338.512645) (xy 339.887433 -338.480194)
			(xy 339.937033 -338.454693) (xy 339.989817 -338.436686) (xy 340.04466 -338.426556) (xy 340.100394 -338.424519)
			(xy 340.155831 -338.430619) (xy 340.209788 -338.444725) (xy 340.261117 -338.466537) (xy 340.308723 -338.495591)
			(xy 340.351591 -338.531266) (xy 340.388808 -338.572803) (xy 340.419581 -338.619316) (xy 340.443253 -338.669813)
			(xy 340.459321 -338.72322) (xy 340.467441 -338.778396) (xy 340.46795 -338.806282) (xy 340.467441 -338.834168)
			(xy 340.459321 -338.889344) (xy 340.443253 -338.942751) (xy 340.419581 -338.993248) (xy 340.388808 -339.039761)
			(xy 340.351591 -339.081298) (xy 340.308723 -339.116973) (xy 340.261117 -339.146027) (xy 340.209788 -339.167839)
			(xy 340.155831 -339.181945) (xy 340.100394 -339.188045) (xy 340.04466 -339.186008) (xy 339.989817 -339.175878)
			(xy 339.937033 -339.157871) (xy 339.887433 -339.13237) (xy 339.842075 -339.099919) (xy 339.801926 -339.06121)
			(xy 339.76784 -339.017067) (xy 339.740544 -338.968432) (xy 339.720621 -338.916341) (xy 339.708495 -338.861904)
			(xy 339.704424 -338.806282) (xy 339.012995 -338.806282) (xy 338.998905 -338.818491) (xy 338.953049 -338.847959)
			(xy 338.903467 -338.8706) (xy 338.851167 -338.885953) (xy 338.797214 -338.893705) (xy 338.76996 -338.894166)
			(xy 338.742102 -338.893704) (xy 338.686983 -338.885574) (xy 338.63363 -338.869521) (xy 338.583175 -338.845887)
			(xy 338.53669 -338.815173) (xy 338.495161 -338.77803) (xy 338.45947 -338.735247) (xy 338.430373 -338.687732)
			(xy 338.40849 -338.636494) (xy 338.400898 -338.609686) (xy 338.398612 -338.600796) (xy 338.387944 -338.585556)
			(xy 338.316062 -338.537804) (xy 338.298028 -338.53374) (xy 338.288884 -338.53501) (xy 338.275867 -338.536679)
			(xy 338.249683 -338.538459) (xy 338.23656 -338.538566) (xy 338.222411 -338.538477) (xy 338.194188 -338.53644)
			(xy 338.180172 -338.534502) (xy 338.170012 -338.532978) (xy 338.150454 -338.537804) (xy 338.076032 -338.593684)
			(xy 338.065872 -338.61121) (xy 338.064602 -338.62137) (xy 338.060548 -338.648529) (xy 338.045571 -338.701361)
			(xy 338.023175 -338.7515) (xy 337.993824 -338.797911) (xy 337.958122 -338.839635) (xy 337.916809 -338.875811)
			(xy 337.870736 -338.905691) (xy 337.820856 -338.928658) (xy 337.768199 -338.944238) (xy 337.713853 -338.952109)
			(xy 337.686396 -338.952586) (xy 337.659142 -338.952148) (xy 337.605189 -338.94439) (xy 337.552889 -338.929033)
			(xy 337.503308 -338.906388) (xy 337.457454 -338.876918) (xy 337.41626 -338.841221) (xy 337.380567 -338.800026)
			(xy 337.3511 -338.754169) (xy 337.328458 -338.704586) (xy 337.313104 -338.652285) (xy 337.30535 -338.598332)
			(xy 337.304888 -338.571078) (xy 335.164005 -338.571078) (xy 335.166633 -338.580034) (xy 335.174384 -338.633992)
			(xy 335.174844 -338.661248) (xy 335.174195 -338.692811) (xy 335.163804 -338.755077) (xy 335.143314 -338.814786)
			(xy 335.12887 -338.842858) (xy 335.124044 -338.851748) (xy 335.122012 -338.871306) (xy 335.147666 -338.959444)
			(xy 335.160112 -338.974938) (xy 335.169002 -338.980018) (xy 335.194096 -338.994578) (xy 335.239978 -339.03008)
			(xy 335.279953 -339.072122) (xy 335.313099 -339.119734) (xy 335.338651 -339.171817) (xy 335.356019 -339.227169)
			(xy 335.364803 -339.284513) (xy 335.365344 -339.31352) (xy 335.364841 -339.34077) (xy 335.357083 -339.394715)
			(xy 335.341727 -339.447008) (xy 335.325781 -339.481922) (xy 341.04326 -339.481922) (xy 341.043769 -339.454448)
			(xy 341.051657 -339.40007) (xy 341.067272 -339.347388) (xy 341.090292 -339.297495) (xy 341.120237 -339.251425)
			(xy 341.138002 -339.230462) (xy 341.144098 -339.22335) (xy 341.150448 -339.206332) (xy 341.150448 -339.12048)
			(xy 341.144098 -339.103462) (xy 341.138002 -339.09635) (xy 341.120234 -339.075391) (xy 341.09031 -339.029309)
			(xy 341.067298 -338.979413) (xy 341.051673 -338.926736) (xy 341.043758 -338.872363) (xy 341.04326 -338.84489)
			(xy 341.043746 -338.817639) (xy 341.051502 -338.763691) (xy 341.066857 -338.711396) (xy 341.089499 -338.661819)
			(xy 341.118965 -338.615969) (xy 341.154656 -338.574778) (xy 341.195847 -338.539087) (xy 341.241697 -338.509621)
			(xy 341.291274 -338.486979) (xy 341.343569 -338.471624) (xy 341.397517 -338.463868) (xy 341.452019 -338.463868)
			(xy 341.505967 -338.471624) (xy 341.558262 -338.486979) (xy 341.607839 -338.509621) (xy 341.653689 -338.539087)
			(xy 341.69488 -338.574778) (xy 341.730571 -338.615969) (xy 341.760037 -338.661819) (xy 341.782679 -338.711396)
			(xy 341.798034 -338.763691) (xy 341.80579 -338.817639) (xy 341.806276 -338.84489) (xy 341.80579 -338.872365)
			(xy 341.797899 -338.926745) (xy 341.782279 -338.979427) (xy 341.759254 -339.02932) (xy 341.729302 -339.075388)
			(xy 341.711534 -339.09635) (xy 341.705438 -339.103462) (xy 341.699088 -339.12048) (xy 341.699088 -339.206332)
			(xy 341.705438 -339.22335) (xy 341.711534 -339.230462) (xy 341.729266 -339.25145) (xy 341.759195 -339.297525)
			(xy 341.782213 -339.347413) (xy 341.797846 -339.400084) (xy 341.805772 -339.454451) (xy 341.806276 -339.481922)
			(xy 341.80579 -339.509173) (xy 341.798034 -339.563121) (xy 341.782679 -339.615416) (xy 341.760037 -339.664993)
			(xy 341.730571 -339.710843) (xy 341.69488 -339.752034) (xy 341.653689 -339.787725) (xy 341.607839 -339.817191)
			(xy 341.558262 -339.839833) (xy 341.505967 -339.855188) (xy 341.452019 -339.862944) (xy 341.397517 -339.862944)
			(xy 341.343569 -339.855188) (xy 341.291274 -339.839833) (xy 341.241697 -339.817191) (xy 341.195847 -339.787725)
			(xy 341.154656 -339.752034) (xy 341.118965 -339.710843) (xy 341.089499 -339.664993) (xy 341.066857 -339.615416)
			(xy 341.051502 -339.563121) (xy 341.043746 -339.509173) (xy 341.04326 -339.481922) (xy 335.325781 -339.481922)
			(xy 335.319086 -339.496582) (xy 335.289621 -339.542431) (xy 335.253931 -339.58362) (xy 335.212744 -339.619311)
			(xy 335.166897 -339.648778) (xy 335.117323 -339.671421) (xy 335.065031 -339.686779) (xy 335.011086 -339.69454)
			(xy 334.983836 -339.695028) (xy 334.968916 -339.694906) (xy 334.939163 -339.692618) (xy 334.9244 -339.690456)
			(xy 334.912208 -339.688424) (xy 334.889348 -339.69579) (xy 334.856582 -339.72881) (xy 334.842111 -339.742648)
			(xy 334.808832 -339.764904) (xy 334.771847 -339.780233) (xy 334.732582 -339.788044) (xy 334.712564 -339.7885)
			(xy 334.269334 -339.7885) (xy 334.259284 -339.788834) (xy 334.240687 -339.796446) (xy 334.233266 -339.803232)
			(xy 331.444092 -342.59266) (xy 331.42959 -342.606442) (xy 331.396296 -342.628616) (xy 331.359318 -342.643874)
			(xy 331.320075 -342.651629) (xy 331.300074 -342.652096) (xy 327.194164 -342.652096) (xy 327.184089 -342.652477)
			(xy 327.16549 -342.660226) (xy 327.158096 -342.667082) (xy 324.646544 -345.178634) (xy 324.639846 -345.186111)
			(xy 324.632258 -345.204674) (xy 324.631812 -345.214702) (xy 324.631812 -349.473958) (xy 327.06208 -349.473958)
			(xy 327.06208 -349.389262) (xy 327.070131 -349.304948) (xy 327.08616 -349.221782) (xy 327.110021 -349.140515)
			(xy 327.1415 -349.061885) (xy 327.180311 -348.986604) (xy 327.226101 -348.915352) (xy 327.278457 -348.848776)
			(xy 327.336905 -348.787478) (xy 327.400915 -348.732013) (xy 327.469907 -348.682884) (xy 327.543257 -348.640535)
			(xy 327.6203 -348.605351) (xy 327.700339 -348.577649) (xy 327.782648 -348.557681) (xy 327.866483 -348.545628)
			(xy 327.951084 -348.541598) (xy 328.035685 -348.545628) (xy 328.11952 -348.557681) (xy 328.201829 -348.577649)
			(xy 328.281868 -348.605351) (xy 328.358911 -348.640535) (xy 328.432261 -348.682884) (xy 328.501253 -348.732013)
			(xy 328.565263 -348.787478) (xy 328.623711 -348.848776) (xy 328.676067 -348.915352) (xy 328.721857 -348.986604)
			(xy 328.760668 -349.061885) (xy 328.792147 -349.140515) (xy 328.816008 -349.221782) (xy 328.832037 -349.304948)
			(xy 328.840088 -349.389262) (xy 328.840592 -349.43161) (xy 328.840088 -349.473958) (xy 328.832037 -349.558272)
			(xy 328.816008 -349.641438) (xy 328.792147 -349.722705) (xy 328.760668 -349.801335) (xy 328.721857 -349.876616)
			(xy 328.676067 -349.947868) (xy 328.623711 -350.014444) (xy 328.565263 -350.075742) (xy 328.501253 -350.131207)
			(xy 328.432261 -350.180336) (xy 328.358911 -350.222685) (xy 328.281868 -350.257869) (xy 328.201829 -350.285571)
			(xy 328.11952 -350.305539) (xy 328.035685 -350.317592) (xy 327.951084 -350.321623) (xy 327.866483 -350.317592)
			(xy 327.782648 -350.305539) (xy 327.700339 -350.285571) (xy 327.6203 -350.257869) (xy 327.543257 -350.222685)
			(xy 327.469907 -350.180336) (xy 327.400915 -350.131207) (xy 327.336905 -350.075742) (xy 327.278457 -350.014444)
			(xy 327.226101 -349.947868) (xy 327.180311 -349.876616) (xy 327.1415 -349.801335) (xy 327.110021 -349.722705)
			(xy 327.08616 -349.641438) (xy 327.070131 -349.558272) (xy 327.06208 -349.473958) (xy 324.631812 -349.473958)
			(xy 324.631812 -351.97408) (xy 327.06208 -351.97408) (xy 327.06208 -351.889384) (xy 327.070131 -351.80507)
			(xy 327.08616 -351.721904) (xy 327.110021 -351.640637) (xy 327.1415 -351.562007) (xy 327.180311 -351.486726)
			(xy 327.226101 -351.415474) (xy 327.278457 -351.348898) (xy 327.336905 -351.2876) (xy 327.400915 -351.232135)
			(xy 327.469907 -351.183006) (xy 327.543257 -351.140657) (xy 327.6203 -351.105473) (xy 327.700339 -351.077771)
			(xy 327.782648 -351.057803) (xy 327.866483 -351.04575) (xy 327.951084 -351.04172) (xy 328.035685 -351.04575)
			(xy 328.11952 -351.057803) (xy 328.201829 -351.077771) (xy 328.281868 -351.105473) (xy 328.358911 -351.140657)
			(xy 328.432261 -351.183006) (xy 328.501253 -351.232135) (xy 328.565263 -351.2876) (xy 328.623711 -351.348898)
			(xy 328.676067 -351.415474) (xy 328.721857 -351.486726) (xy 328.760668 -351.562007) (xy 328.792147 -351.640637)
			(xy 328.816008 -351.721904) (xy 328.832037 -351.80507) (xy 328.840088 -351.889384) (xy 328.840592 -351.931732)
			(xy 328.840088 -351.97408) (xy 328.832037 -352.058394) (xy 328.816008 -352.14156) (xy 328.792147 -352.222827)
			(xy 328.760668 -352.301457) (xy 328.721857 -352.376738) (xy 328.676067 -352.44799) (xy 328.623711 -352.514566)
			(xy 328.565263 -352.575864) (xy 328.501253 -352.631329) (xy 328.432261 -352.680458) (xy 328.358911 -352.722807)
			(xy 328.281868 -352.757991) (xy 328.201829 -352.785693) (xy 328.11952 -352.805661) (xy 328.035685 -352.817714)
			(xy 327.951084 -352.821745) (xy 327.866483 -352.817714) (xy 327.782648 -352.805661) (xy 327.700339 -352.785693)
			(xy 327.6203 -352.757991) (xy 327.543257 -352.722807) (xy 327.469907 -352.680458) (xy 327.400915 -352.631329)
			(xy 327.336905 -352.575864) (xy 327.278457 -352.514566) (xy 327.226101 -352.44799) (xy 327.180311 -352.376738)
			(xy 327.1415 -352.301457) (xy 327.110021 -352.222827) (xy 327.08616 -352.14156) (xy 327.070131 -352.058394)
			(xy 327.06208 -351.97408) (xy 324.631812 -351.97408) (xy 324.631812 -357.714296) (xy 324.631286 -357.734307)
			(xy 324.623468 -357.773558) (xy 324.608151 -357.810533) (xy 324.585921 -357.843813) (xy 324.572122 -357.858314)
			(xy 322.068444 -360.361992) (xy 322.46265 -360.361992) (xy 322.466721 -360.30637) (xy 322.478847 -360.251933)
			(xy 322.49877 -360.199842) (xy 322.526066 -360.151207) (xy 322.560152 -360.107064) (xy 322.600301 -360.068355)
			(xy 322.645659 -360.035904) (xy 322.695259 -360.010403) (xy 322.748043 -359.992396) (xy 322.802886 -359.982266)
			(xy 322.85862 -359.980229) (xy 322.914057 -359.986329) (xy 322.968014 -360.000435) (xy 323.019343 -360.022247)
			(xy 323.066949 -360.051301) (xy 323.109817 -360.086976) (xy 323.147034 -360.128513) (xy 323.177807 -360.175026)
			(xy 323.201479 -360.225523) (xy 323.217547 -360.27893) (xy 323.225667 -360.334106) (xy 323.226176 -360.361992)
			(xy 323.225667 -360.389878) (xy 323.217547 -360.445054) (xy 323.201479 -360.498461) (xy 323.177807 -360.548958)
			(xy 323.147034 -360.595471) (xy 323.109817 -360.637008) (xy 323.066949 -360.672683) (xy 323.019343 -360.701737)
			(xy 322.968014 -360.723549) (xy 322.914057 -360.737655) (xy 322.85862 -360.743755) (xy 322.802886 -360.741718)
			(xy 322.748043 -360.731588) (xy 322.695259 -360.713581) (xy 322.645659 -360.68808) (xy 322.600301 -360.655629)
			(xy 322.560152 -360.61692) (xy 322.526066 -360.572777) (xy 322.49877 -360.524142) (xy 322.478847 -360.472051)
			(xy 322.466721 -360.417614) (xy 322.46265 -360.361992) (xy 322.068444 -360.361992) (xy 320.831718 -361.598718)
			(xy 321.434966 -361.598718) (xy 321.439037 -361.543096) (xy 321.451163 -361.488659) (xy 321.471086 -361.436568)
			(xy 321.498382 -361.387933) (xy 321.532468 -361.34379) (xy 321.572617 -361.305081) (xy 321.617975 -361.27263)
			(xy 321.667575 -361.247129) (xy 321.720359 -361.229122) (xy 321.775202 -361.218992) (xy 321.830936 -361.216955)
			(xy 321.886373 -361.223055) (xy 321.94033 -361.237161) (xy 321.991659 -361.258973) (xy 322.039265 -361.288027)
			(xy 322.082133 -361.323702) (xy 322.11935 -361.365239) (xy 322.150123 -361.411752) (xy 322.173795 -361.462249)
			(xy 322.189863 -361.515656) (xy 322.197983 -361.570832) (xy 322.198492 -361.598718) (xy 322.197983 -361.626604)
			(xy 322.189863 -361.68178) (xy 322.173795 -361.735187) (xy 322.150123 -361.785684) (xy 322.11935 -361.832197)
			(xy 322.082133 -361.873734) (xy 322.039265 -361.909409) (xy 321.991659 -361.938463) (xy 321.94033 -361.960275)
			(xy 321.886373 -361.974381) (xy 321.830936 -361.980481) (xy 321.775202 -361.978444) (xy 321.720359 -361.968314)
			(xy 321.667575 -361.950307) (xy 321.617975 -361.924806) (xy 321.572617 -361.892355) (xy 321.532468 -361.853646)
			(xy 321.498382 -361.809503) (xy 321.471086 -361.760868) (xy 321.451163 -361.708777) (xy 321.439037 -361.65434)
			(xy 321.434966 -361.598718) (xy 320.831718 -361.598718) (xy 320.082418 -362.348018) (xy 320.067933 -362.361841)
			(xy 320.034659 -362.384099) (xy 319.997679 -362.399432) (xy 319.958416 -362.407249) (xy 319.9384 -362.407708)
			(xy 317.75781 -362.407708) (xy 317.747762 -362.408054) (xy 317.729166 -362.41566) (xy 317.721742 -362.42244)
			(xy 317.355271 -362.788962) (xy 320.244722 -362.788962) (xy 320.248793 -362.73334) (xy 320.260919 -362.678903)
			(xy 320.280842 -362.626812) (xy 320.308138 -362.578177) (xy 320.342224 -362.534034) (xy 320.382373 -362.495325)
			(xy 320.427731 -362.462874) (xy 320.477331 -362.437373) (xy 320.530115 -362.419366) (xy 320.584958 -362.409236)
			(xy 320.640692 -362.407199) (xy 320.696129 -362.413299) (xy 320.750086 -362.427405) (xy 320.801415 -362.449217)
			(xy 320.849021 -362.478271) (xy 320.891889 -362.513946) (xy 320.929106 -362.555483) (xy 320.959879 -362.601996)
			(xy 320.983551 -362.652493) (xy 320.999619 -362.7059) (xy 321.007739 -362.761076) (xy 321.008248 -362.788962)
			(xy 321.007739 -362.816848) (xy 320.999619 -362.872024) (xy 320.983551 -362.925431) (xy 320.959879 -362.975928)
			(xy 320.929106 -363.022441) (xy 320.891889 -363.063978) (xy 320.849021 -363.099653) (xy 320.801415 -363.128707)
			(xy 320.750086 -363.150519) (xy 320.696129 -363.164625) (xy 320.640692 -363.170725) (xy 320.584958 -363.168688)
			(xy 320.530115 -363.158558) (xy 320.477331 -363.140551) (xy 320.427731 -363.11505) (xy 320.382373 -363.082599)
			(xy 320.342224 -363.04389) (xy 320.308138 -362.999747) (xy 320.280842 -362.951112) (xy 320.260919 -362.899021)
			(xy 320.248793 -362.844584) (xy 320.244722 -362.788962) (xy 317.355271 -362.788962) (xy 316.905245 -363.23905)
			(xy 318.698878 -363.23905) (xy 318.702949 -363.183428) (xy 318.715075 -363.128991) (xy 318.734998 -363.0769)
			(xy 318.762294 -363.028265) (xy 318.79638 -362.984122) (xy 318.836529 -362.945413) (xy 318.881887 -362.912962)
			(xy 318.931487 -362.887461) (xy 318.984271 -362.869454) (xy 319.039114 -362.859324) (xy 319.094848 -362.857287)
			(xy 319.150285 -362.863387) (xy 319.204242 -362.877493) (xy 319.255571 -362.899305) (xy 319.303177 -362.928359)
			(xy 319.346045 -362.964034) (xy 319.383262 -363.005571) (xy 319.414035 -363.052084) (xy 319.437707 -363.102581)
			(xy 319.453775 -363.155988) (xy 319.461895 -363.211164) (xy 319.462404 -363.23905) (xy 319.461895 -363.266936)
			(xy 319.453775 -363.322112) (xy 319.437707 -363.375519) (xy 319.414035 -363.426016) (xy 319.383262 -363.472529)
			(xy 319.346045 -363.514066) (xy 319.303177 -363.549741) (xy 319.255571 -363.578795) (xy 319.204242 -363.600607)
			(xy 319.150285 -363.614713) (xy 319.094848 -363.620813) (xy 319.039114 -363.618776) (xy 318.984271 -363.608646)
			(xy 318.931487 -363.590639) (xy 318.881887 -363.565138) (xy 318.836529 -363.532687) (xy 318.79638 -363.493978)
			(xy 318.762294 -363.449835) (xy 318.734998 -363.4012) (xy 318.715075 -363.349109) (xy 318.702949 -363.294672)
			(xy 318.698878 -363.23905) (xy 316.905245 -363.23905) (xy 315.891418 -364.253018) (xy 315.876933 -364.266841)
			(xy 315.843659 -364.289099) (xy 315.806679 -364.304432) (xy 315.767416 -364.312249) (xy 315.7474 -364.312708)
			(xy 310.10606 -364.312708) (xy 310.096185 -364.31316) (xy 310.077881 -364.320573) (xy 310.063714 -364.334332)
			(xy 310.059324 -364.343188) (xy 310.050732 -364.363) (xy 318.794382 -364.363) (xy 318.798453 -364.307378)
			(xy 318.810579 -364.252941) (xy 318.830502 -364.20085) (xy 318.857798 -364.152215) (xy 318.891884 -364.108072)
			(xy 318.932033 -364.069363) (xy 318.977391 -364.036912) (xy 319.026991 -364.011411) (xy 319.079775 -363.993404)
			(xy 319.134618 -363.983274) (xy 319.190352 -363.981237) (xy 319.245789 -363.987337) (xy 319.299746 -364.001443)
			(xy 319.351075 -364.023255) (xy 319.398681 -364.052309) (xy 319.441549 -364.087984) (xy 319.478766 -364.129521)
			(xy 319.509539 -364.176034) (xy 319.533211 -364.226531) (xy 319.549279 -364.279938) (xy 319.557399 -364.335114)
			(xy 319.557908 -364.363) (xy 319.557399 -364.390886) (xy 319.549279 -364.446062) (xy 319.533211 -364.499469)
			(xy 319.509539 -364.549966) (xy 319.478766 -364.596479) (xy 319.441549 -364.638016) (xy 319.398681 -364.673691)
			(xy 319.351075 -364.702745) (xy 319.299746 -364.724557) (xy 319.245789 -364.738663) (xy 319.190352 -364.744763)
			(xy 319.134618 -364.742726) (xy 319.079775 -364.732596) (xy 319.026991 -364.714589) (xy 318.977391 -364.689088)
			(xy 318.932033 -364.656637) (xy 318.891884 -364.617928) (xy 318.857798 -364.573785) (xy 318.830502 -364.52515)
			(xy 318.810579 -364.473059) (xy 318.798453 -364.418622) (xy 318.794382 -364.363) (xy 310.050732 -364.363)
			(xy 310.016144 -364.442756) (xy 310.021224 -364.472474) (xy 310.031638 -364.48365) (xy 310.039539 -364.492202)
			(xy 310.054408 -364.510121) (xy 310.061356 -364.519464) (xy 310.068942 -364.528844) (xy 310.090451 -364.539704)
			(xy 310.102504 -364.540292) (xy 313.3852 -364.540292) (xy 313.405211 -364.540814) (xy 313.444462 -364.548633)
			(xy 313.481437 -364.563952) (xy 313.514718 -364.586182) (xy 313.529218 -364.599982) (xy 313.939838 -365.0107)
			(xy 314.463682 -365.0107) (xy 314.467753 -364.955078) (xy 314.479879 -364.900641) (xy 314.499802 -364.84855)
			(xy 314.527098 -364.799915) (xy 314.561184 -364.755772) (xy 314.601333 -364.717063) (xy 314.646691 -364.684612)
			(xy 314.696291 -364.659111) (xy 314.749075 -364.641104) (xy 314.803918 -364.630974) (xy 314.859652 -364.628937)
			(xy 314.915089 -364.635037) (xy 314.969046 -364.649143) (xy 315.020375 -364.670955) (xy 315.067981 -364.700009)
			(xy 315.110849 -364.735684) (xy 315.148066 -364.777221) (xy 315.178839 -364.823734) (xy 315.202511 -364.874231)
			(xy 315.218579 -364.927638) (xy 315.226699 -364.982814) (xy 315.227208 -365.0107) (xy 315.226699 -365.038586)
			(xy 315.218579 -365.093762) (xy 315.202511 -365.147169) (xy 315.178839 -365.197666) (xy 315.148066 -365.244179)
			(xy 315.110849 -365.285716) (xy 315.067981 -365.321391) (xy 315.020375 -365.350445) (xy 314.969046 -365.372257)
			(xy 314.915089 -365.386363) (xy 314.859652 -365.392463) (xy 314.803918 -365.390426) (xy 314.749075 -365.380296)
			(xy 314.696291 -365.362289) (xy 314.646691 -365.336788) (xy 314.601333 -365.304337) (xy 314.561184 -365.265628)
			(xy 314.527098 -365.221485) (xy 314.499802 -365.17285) (xy 314.479879 -365.120759) (xy 314.467753 -365.066322)
			(xy 314.463682 -365.0107) (xy 313.939838 -365.0107) (xy 314.597542 -365.66856) (xy 314.605016 -365.675262)
			(xy 314.623581 -365.682847) (xy 314.63361 -365.683292) (xy 318.63919 -365.683292) (xy 318.649238 -365.682946)
			(xy 318.667834 -365.67534) (xy 318.675258 -365.66856) (xy 330.56957 -353.774248) (xy 330.576377 -353.766822)
			(xy 330.584117 -353.748243) (xy 330.584556 -353.73818) (xy 330.584556 -349.030036) (xy 330.585003 -349.010031)
			(xy 330.592737 -348.970777) (xy 330.607994 -348.933791) (xy 330.630184 -348.9005) (xy 330.643992 -348.886018)
			(xy 333.373222 -346.156788) (xy 333.38771 -346.14299) (xy 333.42101 -346.120822) (xy 333.457992 -346.105569)
			(xy 333.497237 -346.097817) (xy 333.51724 -346.097352) (xy 341.485728 -346.097352) (xy 341.495801 -346.096954)
			(xy 341.514399 -346.089215) (xy 341.521796 -346.082366) (xy 343.480644 -344.123518) (xy 343.487362 -344.116056)
			(xy 343.494938 -344.097482) (xy 343.495376 -344.08745) (xy 343.495376 -339.853778) (xy 343.494999 -339.843733)
			(xy 343.487416 -339.825137) (xy 343.480644 -339.81771) (xy 343.409524 -339.74659) (xy 343.386664 -339.739224)
			(xy 343.374472 -339.741256) (xy 343.359708 -339.743413) (xy 343.329956 -339.745703) (xy 343.315036 -339.745828)
			(xy 343.287785 -339.745311) (xy 343.233837 -339.73756) (xy 343.181541 -339.722209) (xy 343.131963 -339.699572)
			(xy 343.08611 -339.67011) (xy 343.044918 -339.634422) (xy 343.009224 -339.593235) (xy 342.979754 -339.547387)
			(xy 342.95711 -339.497811) (xy 342.941752 -339.445518) (xy 342.933993 -339.391571) (xy 342.933528 -339.36432)
			(xy 342.934168 -339.332756) (xy 342.944563 -339.27049) (xy 342.965057 -339.210782) (xy 342.979502 -339.18271)
			(xy 342.984328 -339.17382) (xy 342.98636 -339.154262) (xy 342.960706 -339.066124) (xy 342.94826 -339.05063)
			(xy 342.93937 -339.04555) (xy 342.932004 -339.041486) (xy 342.922352 -339.035644) (xy 342.900254 -339.033612)
			(xy 342.805766 -339.06714) (xy 342.789764 -339.082634) (xy 342.7857 -339.093048) (xy 342.775046 -339.119842)
			(xy 342.746751 -339.170084) (xy 342.711214 -339.215492) (xy 342.669246 -339.255033) (xy 342.621803 -339.287804)
			(xy 342.569967 -339.313059) (xy 342.514919 -339.330221) (xy 342.457915 -339.3389) (xy 342.429084 -339.339428)
			(xy 342.401835 -339.338901) (xy 342.347892 -339.331143) (xy 342.295602 -339.315787) (xy 342.246029 -339.293146)
			(xy 342.200183 -339.263681) (xy 342.158997 -339.227991) (xy 342.123309 -339.186804) (xy 342.093846 -339.140957)
			(xy 342.071207 -339.091383) (xy 342.055854 -339.039092) (xy 342.048098 -338.985149) (xy 342.048098 -338.930651)
			(xy 342.055854 -338.876708) (xy 342.071207 -338.824417) (xy 342.093846 -338.774843) (xy 342.123309 -338.728996)
			(xy 342.158997 -338.687809) (xy 342.200183 -338.652119) (xy 342.246029 -338.622654) (xy 342.295602 -338.600013)
			(xy 342.347892 -338.584657) (xy 342.401835 -338.576899) (xy 342.429084 -338.576412) (xy 342.454321 -338.57677)
			(xy 342.504356 -338.5834) (xy 342.553076 -338.596584) (xy 342.599627 -338.616092) (xy 342.621616 -338.628482)
			(xy 342.631268 -338.634324) (xy 342.653366 -338.636356) (xy 342.747854 -338.602828) (xy 342.763856 -338.587334)
			(xy 342.76792 -338.57692) (xy 342.778594 -338.550134) (xy 342.806882 -338.499889) (xy 342.842414 -338.454478)
			(xy 342.884379 -338.414935) (xy 342.93182 -338.382161) (xy 342.983655 -338.356906) (xy 343.038702 -338.339744)
			(xy 343.095706 -338.331066) (xy 343.124536 -338.33054) (xy 343.151792 -338.330922) (xy 343.205748 -338.338685)
			(xy 343.258051 -338.354048) (xy 343.307634 -338.376698) (xy 343.35349 -338.406174) (xy 343.394683 -338.441876)
			(xy 343.430376 -338.483078) (xy 343.459842 -338.52894) (xy 343.482482 -338.578528) (xy 343.497833 -338.630834)
			(xy 343.505584 -338.684792) (xy 343.506044 -338.712048) (xy 343.505395 -338.743611) (xy 343.495004 -338.805877)
			(xy 343.474514 -338.865586) (xy 343.46007 -338.893658) (xy 343.455244 -338.902548) (xy 343.453212 -338.922106)
			(xy 343.478866 -339.010244) (xy 343.491312 -339.025738) (xy 343.500202 -339.030818) (xy 343.525296 -339.045378)
			(xy 343.571178 -339.08088) (xy 343.611153 -339.122922) (xy 343.644299 -339.170534) (xy 343.669851 -339.222617)
			(xy 343.687219 -339.277969) (xy 343.696003 -339.335313) (xy 343.696435 -339.358478) (xy 345.636088 -339.358478)
			(xy 345.636612 -339.330906) (xy 345.644553 -339.276335) (xy 345.660267 -339.223477) (xy 345.683426 -339.173431)
			(xy 345.713548 -339.12724) (xy 345.750006 -339.085866) (xy 345.770708 -339.067648) (xy 345.778802 -339.060023)
			(xy 345.788169 -339.039889) (xy 345.788742 -339.028786) (xy 345.788742 -338.95157) (xy 345.788225 -338.940453)
			(xy 345.778852 -338.920294) (xy 345.770708 -338.912708) (xy 345.74998 -338.894516) (xy 345.713516 -338.853142)
			(xy 345.683389 -338.806949) (xy 345.660227 -338.756899) (xy 345.644513 -338.704036) (xy 345.636575 -338.649461)
			(xy 345.636577 -338.594311) (xy 345.644519 -338.539737) (xy 345.660237 -338.486874) (xy 345.683403 -338.436826)
			(xy 345.713533 -338.390635) (xy 345.750001 -338.349264) (xy 345.770708 -338.331048) (xy 345.778802 -338.323423)
			(xy 345.788169 -338.303289) (xy 345.788742 -338.292186) (xy 345.788742 -338.21497) (xy 345.788225 -338.203853)
			(xy 345.778852 -338.183694) (xy 345.770708 -338.176108) (xy 345.749999 -338.157894) (xy 345.713528 -338.116526)
			(xy 345.683396 -338.070337) (xy 345.660229 -338.020289) (xy 345.644513 -337.967427) (xy 345.636573 -337.912853)
			(xy 345.636088 -337.885278) (xy 345.636557 -337.858026) (xy 345.644317 -337.804078) (xy 345.659674 -337.751783)
			(xy 345.682318 -337.702206) (xy 345.711786 -337.656356) (xy 345.747479 -337.615166) (xy 345.788671 -337.579475)
			(xy 345.834522 -337.550009) (xy 345.8841 -337.527368) (xy 345.936396 -337.512013) (xy 345.990344 -337.504256)
			(xy 346.017596 -337.50377) (xy 346.051886 -337.505294) (xy 346.062046 -337.50631) (xy 346.08135 -337.500214)
			(xy 346.151962 -337.441032) (xy 346.16136 -337.422998) (xy 346.162376 -337.412838) (xy 346.165325 -337.384665)
			(xy 346.1785 -337.329573) (xy 346.19968 -337.277036) (xy 346.228398 -337.228211) (xy 346.264023 -337.18417)
			(xy 346.305771 -337.145884) (xy 346.352722 -337.114194) (xy 346.403845 -337.089798) (xy 346.458014 -337.073233)
			(xy 346.514037 -337.064863) (xy 346.54236 -337.06435) (xy 346.569608 -337.064915) (xy 346.623551 -337.072665)
			(xy 346.675842 -337.088013) (xy 346.725416 -337.110647) (xy 346.771264 -337.140105) (xy 346.812454 -337.175788)
			(xy 346.848146 -337.21697) (xy 346.877614 -337.262812) (xy 346.900258 -337.312381) (xy 346.915617 -337.364669)
			(xy 346.923379 -337.41861) (xy 346.923868 -337.445858) (xy 346.923337 -337.473719) (xy 346.915242 -337.528849)
			(xy 346.899218 -337.582216) (xy 346.875606 -337.632687) (xy 346.844907 -337.679189) (xy 346.807773 -337.720733)
			(xy 346.786708 -337.738974) (xy 346.777564 -337.746594) (xy 346.767912 -337.767676) (xy 346.771468 -337.871562)
			(xy 346.78239 -337.892136) (xy 346.792042 -337.899248) (xy 346.8126 -337.914661) (xy 346.849734 -337.950174)
			(xy 346.881765 -337.990351) (xy 346.908113 -338.034465) (xy 346.9283 -338.081715) (xy 346.941963 -338.131248)
			(xy 346.948852 -338.182167) (xy 346.949268 -338.207858) (xy 346.948732 -338.236774) (xy 346.940008 -338.293945)
			(xy 346.922755 -338.349144) (xy 346.897366 -338.401106) (xy 346.864425 -338.448641) (xy 346.824687 -338.490658)
			(xy 346.802202 -338.508848) (xy 346.793423 -338.516394) (xy 346.783249 -338.537165) (xy 346.782644 -338.548726)
			(xy 346.782644 -338.62899) (xy 346.783205 -338.64056) (xy 346.793405 -338.661331) (xy 346.802202 -338.668868)
			(xy 346.822945 -338.68567) (xy 346.860078 -338.724016) (xy 346.891503 -338.767164) (xy 346.916606 -338.814272)
			(xy 346.934896 -338.864419) (xy 346.946016 -338.916626) (xy 346.94975 -338.969874) (xy 346.946024 -339.023123)
			(xy 346.93491 -339.075332) (xy 346.916627 -339.125481) (xy 346.891531 -339.172592) (xy 346.860112 -339.215745)
			(xy 346.822984 -339.254096) (xy 346.802202 -339.270848) (xy 346.793423 -339.278394) (xy 346.783249 -339.299165)
			(xy 346.782644 -339.310726) (xy 346.782644 -339.39099) (xy 346.783205 -339.40256) (xy 346.793405 -339.423331)
			(xy 346.802202 -339.430868) (xy 346.824671 -339.449077) (xy 346.864407 -339.491093) (xy 346.897347 -339.538624)
			(xy 346.922738 -339.590582) (xy 346.939998 -339.645776) (xy 346.948731 -339.702943) (xy 346.949268 -339.731858)
			(xy 346.948806 -339.759112) (xy 346.941053 -339.813065) (xy 346.9257 -339.865365) (xy 346.90306 -339.914948)
			(xy 346.873593 -339.960803) (xy 346.837899 -340.001997) (xy 346.796705 -340.037691) (xy 346.750849 -340.067159)
			(xy 346.701267 -340.0898) (xy 346.648967 -340.105153) (xy 346.595014 -340.112905) (xy 346.56776 -340.113366)
			(xy 346.539022 -340.112852) (xy 346.482198 -340.104211) (xy 346.427313 -340.087145) (xy 346.375608 -340.06204)
			(xy 346.328253 -340.029464) (xy 346.28632 -339.990155) (xy 346.250757 -339.945001) (xy 346.222368 -339.895024)
			(xy 346.201796 -339.841355) (xy 346.195142 -339.813392) (xy 346.192856 -339.80374) (xy 346.182188 -339.787738)
			(xy 346.10802 -339.737446) (xy 346.089224 -339.733382) (xy 346.079318 -339.734906) (xy 346.063998 -339.737279)
			(xy 346.033098 -339.739824) (xy 346.017596 -339.739986) (xy 345.990342 -339.739548) (xy 345.936389 -339.73179)
			(xy 345.884089 -339.716433) (xy 345.834508 -339.693788) (xy 345.788654 -339.664318) (xy 345.74746 -339.628621)
			(xy 345.711767 -339.587426) (xy 345.6823 -339.541569) (xy 345.659658 -339.491986) (xy 345.644304 -339.439685)
			(xy 345.63655 -339.385732) (xy 345.636088 -339.358478) (xy 343.696435 -339.358478) (xy 343.696544 -339.36432)
			(xy 343.696417 -339.37924) (xy 343.694132 -339.408993) (xy 343.691972 -339.423756) (xy 343.68994 -339.435948)
			(xy 343.697306 -339.458808) (xy 343.843102 -339.60435) (xy 343.856954 -339.618809) (xy 343.879208 -339.652092)
			(xy 343.894533 -339.68908) (xy 343.902339 -339.728349) (xy 343.902792 -339.748368) (xy 343.902792 -341.58936)
			(xy 347.60154 -341.58936) (xy 347.602021 -341.561449) (xy 347.610161 -341.506223) (xy 347.626259 -341.452773)
			(xy 347.649974 -341.402238) (xy 347.680799 -341.355698) (xy 347.699076 -341.334598) (xy 347.705426 -341.327486)
			(xy 347.71203 -341.310214) (xy 347.71203 -341.223092) (xy 347.705426 -341.20582) (xy 347.699076 -341.198708)
			(xy 347.680777 -341.177626) (xy 347.649953 -341.131083) (xy 347.626242 -341.080543) (xy 347.610151 -341.027088)
			(xy 347.602022 -340.971858) (xy 347.60154 -340.943946) (xy 347.602026 -340.916695) (xy 347.609782 -340.862747)
			(xy 347.625137 -340.810452) (xy 347.647779 -340.760875) (xy 347.677245 -340.715025) (xy 347.712936 -340.673834)
			(xy 347.754127 -340.638143) (xy 347.799977 -340.608677) (xy 347.849554 -340.586035) (xy 347.901849 -340.57068)
			(xy 347.955797 -340.562924) (xy 348.010299 -340.562924) (xy 348.064247 -340.57068) (xy 348.116542 -340.586035)
			(xy 348.166119 -340.608677) (xy 348.211969 -340.638143) (xy 348.25316 -340.673834) (xy 348.288851 -340.715025)
			(xy 348.318317 -340.760875) (xy 348.340959 -340.810452) (xy 348.356314 -340.862747) (xy 348.36407 -340.916695)
			(xy 348.364556 -340.943946) (xy 348.364079 -340.971857) (xy 348.355939 -341.027083) (xy 348.339839 -341.080534)
			(xy 348.316123 -341.131068) (xy 348.285297 -341.177608) (xy 348.26702 -341.198708) (xy 348.26067 -341.20582)
			(xy 348.254066 -341.223092) (xy 348.254066 -341.310214) (xy 348.26067 -341.327486) (xy 348.26702 -341.334598)
			(xy 348.285274 -341.355717) (xy 348.316105 -341.40225) (xy 348.339824 -341.45278) (xy 348.355926 -341.506227)
			(xy 348.364067 -341.56145) (xy 348.364556 -341.58936) (xy 348.36407 -341.616611) (xy 348.356314 -341.670559)
			(xy 348.340959 -341.722854) (xy 348.318317 -341.772431) (xy 348.288851 -341.818281) (xy 348.25316 -341.859472)
			(xy 348.211969 -341.895163) (xy 348.168809 -341.9229) (xy 351.983695 -341.9229) (xy 351.987864 -341.867274)
			(xy 352.000278 -341.812891) (xy 352.020658 -341.760965) (xy 352.04855 -341.712658) (xy 352.083331 -341.669047)
			(xy 352.124223 -341.631107) (xy 352.170314 -341.599686) (xy 352.220573 -341.575486) (xy 352.273878 -341.559047)
			(xy 352.329037 -341.550737) (xy 352.356928 -341.550244) (xy 352.38335 -341.550699) (xy 352.435665 -341.558151)
			(xy 352.486403 -341.572918) (xy 352.534547 -341.594702) (xy 352.579132 -341.623067) (xy 352.599498 -341.639906)
			(xy 352.606356 -341.646002) (xy 352.623374 -341.652098) (xy 352.707702 -341.652098) (xy 352.72472 -341.646002)
			(xy 352.731578 -341.639906) (xy 352.751944 -341.623067) (xy 352.79653 -341.594702) (xy 352.844674 -341.572915)
			(xy 352.895411 -341.558144) (xy 352.947726 -341.550684) (xy 353.00057 -341.550684) (xy 353.052885 -341.558144)
			(xy 353.103622 -341.572915) (xy 353.151766 -341.594702) (xy 353.196352 -341.623067) (xy 353.216718 -341.639906)
			(xy 353.223576 -341.646002) (xy 353.240594 -341.652098) (xy 353.324922 -341.652098) (xy 353.34194 -341.646002)
			(xy 353.348798 -341.639906) (xy 353.37117 -341.621476) (xy 353.420505 -341.591056) (xy 353.473954 -341.568638)
			(xy 353.50196 -341.561166) (xy 353.513644 -341.558372) (xy 353.531678 -341.542878) (xy 353.573334 -341.44712)
			(xy 353.572318 -341.423498) (xy 353.566476 -341.413084) (xy 353.554996 -341.391721) (xy 353.536944 -341.346707)
			(xy 353.524745 -341.299767) (xy 353.518595 -341.251659) (xy 353.518216 -341.22741) (xy 353.518683 -341.199835)
			(xy 353.526634 -341.145262) (xy 353.542359 -341.092402) (xy 353.565529 -341.042356) (xy 353.595661 -340.996167)
			(xy 353.632129 -340.954796) (xy 353.652836 -340.93658) (xy 353.660965 -340.928987) (xy 353.670312 -340.908828)
			(xy 353.67087 -340.897718) (xy 353.67087 -340.820502) (xy 353.670326 -340.809389) (xy 353.660972 -340.78923)
			(xy 353.652836 -340.78164) (xy 353.632148 -340.763403) (xy 353.595675 -340.722041) (xy 353.565539 -340.675857)
			(xy 353.542368 -340.625813) (xy 353.526647 -340.572955) (xy 353.518703 -340.518383) (xy 353.518216 -340.49081)
			(xy 353.518702 -340.463559) (xy 353.526458 -340.409611) (xy 353.541813 -340.357316) (xy 353.564455 -340.307739)
			(xy 353.593921 -340.261889) (xy 353.629612 -340.220698) (xy 353.670803 -340.185007) (xy 353.716653 -340.155541)
			(xy 353.76623 -340.132899) (xy 353.818525 -340.117544) (xy 353.872473 -340.109788) (xy 353.926975 -340.109788)
			(xy 353.980923 -340.117544) (xy 354.033218 -340.132899) (xy 354.082795 -340.155541) (xy 354.128645 -340.185007)
			(xy 354.169836 -340.220698) (xy 354.205527 -340.261889) (xy 354.234993 -340.307739) (xy 354.257635 -340.357316)
			(xy 354.27299 -340.409611) (xy 354.280746 -340.463559) (xy 354.281232 -340.49081) (xy 354.280693 -340.518382)
			(xy 354.272754 -340.572951) (xy 354.257043 -340.625809) (xy 354.233886 -340.675855) (xy 354.203767 -340.722046)
			(xy 354.167313 -340.763422) (xy 354.146612 -340.78164) (xy 354.138482 -340.789232) (xy 354.129133 -340.809391)
			(xy 354.128578 -340.820502) (xy 354.128578 -340.897718) (xy 354.129095 -340.908835) (xy 354.138467 -340.928995)
			(xy 354.146612 -340.93658) (xy 354.167319 -340.954795) (xy 354.203789 -340.996164) (xy 354.233922 -341.042353)
			(xy 354.257088 -341.0924) (xy 354.272805 -341.145261) (xy 354.280746 -341.199836) (xy 354.281232 -341.22741)
			(xy 354.280647 -341.255884) (xy 354.272167 -341.312198) (xy 354.255412 -341.366627) (xy 354.230754 -341.41796)
			(xy 354.19874 -341.465059) (xy 354.160082 -341.506877) (xy 354.115638 -341.542485) (xy 354.066396 -341.571092)
			(xy 354.013449 -341.592064) (xy 353.98583 -341.599012) (xy 353.9744 -341.601806) (xy 353.956112 -341.616792)
			(xy 353.912932 -341.712042) (xy 353.913694 -341.735664) (xy 353.919536 -341.746078) (xy 353.93354 -341.773417)
			(xy 353.953359 -341.831553) (xy 353.963382 -341.892151) (xy 353.963986 -341.922862) (xy 353.96353 -341.94948)
			(xy 353.955959 -342.002176) (xy 353.940964 -342.053257) (xy 353.918851 -342.101684) (xy 353.89007 -342.14647)
			(xy 353.855208 -342.186704) (xy 353.814975 -342.221567) (xy 353.770189 -342.250348) (xy 353.721762 -342.272461)
			(xy 353.670682 -342.287457) (xy 353.617986 -342.29503) (xy 353.591368 -342.29548) (xy 353.564946 -342.295022)
			(xy 353.512632 -342.287569) (xy 353.461894 -342.272803) (xy 353.41375 -342.25102) (xy 353.369164 -342.222656)
			(xy 353.348798 -342.205818) (xy 353.34194 -342.199722) (xy 353.324922 -342.193626) (xy 353.240594 -342.193626)
			(xy 353.223576 -342.199722) (xy 353.216718 -342.205818) (xy 353.196352 -342.222657) (xy 353.151766 -342.251022)
			(xy 353.103622 -342.272809) (xy 353.052885 -342.28758) (xy 353.00057 -342.29504) (xy 352.947726 -342.29504)
			(xy 352.895411 -342.28758) (xy 352.844674 -342.272809) (xy 352.79653 -342.251022) (xy 352.751944 -342.222657)
			(xy 352.731578 -342.205818) (xy 352.72472 -342.199722) (xy 352.707702 -342.193626) (xy 352.623374 -342.193626)
			(xy 352.606356 -342.199722) (xy 352.599498 -342.205818) (xy 352.579123 -342.222644) (xy 352.534537 -342.251004)
			(xy 352.486395 -342.272787) (xy 352.43566 -342.287557) (xy 352.383348 -342.295019) (xy 352.356928 -342.29548)
			(xy 352.329037 -342.295063) (xy 352.273878 -342.286753) (xy 352.220573 -342.270314) (xy 352.170314 -342.246114)
			(xy 352.124223 -342.214693) (xy 352.083331 -342.176753) (xy 352.04855 -342.133142) (xy 352.020658 -342.084835)
			(xy 352.000278 -342.032909) (xy 351.987864 -341.978526) (xy 351.983695 -341.9229) (xy 348.168809 -341.9229)
			(xy 348.166119 -341.924629) (xy 348.116542 -341.947271) (xy 348.064247 -341.962626) (xy 348.010299 -341.970382)
			(xy 347.955797 -341.970382) (xy 347.901849 -341.962626) (xy 347.849554 -341.947271) (xy 347.799977 -341.924629)
			(xy 347.754127 -341.895163) (xy 347.712936 -341.859472) (xy 347.677245 -341.818281) (xy 347.647779 -341.772431)
			(xy 347.625137 -341.722854) (xy 347.609782 -341.670559) (xy 347.602026 -341.616611) (xy 347.60154 -341.58936)
			(xy 343.902792 -341.58936) (xy 343.902792 -342.821006) (xy 348.559372 -342.821006) (xy 348.563443 -342.765384)
			(xy 348.575569 -342.710947) (xy 348.595492 -342.658856) (xy 348.622788 -342.610221) (xy 348.656874 -342.566078)
			(xy 348.697023 -342.527369) (xy 348.742381 -342.494918) (xy 348.791981 -342.469417) (xy 348.844765 -342.45141)
			(xy 348.899608 -342.44128) (xy 348.955342 -342.439243) (xy 349.010779 -342.445343) (xy 349.064736 -342.459449)
			(xy 349.116065 -342.481261) (xy 349.163671 -342.510315) (xy 349.206539 -342.54599) (xy 349.243756 -342.587527)
			(xy 349.274529 -342.63404) (xy 349.298201 -342.684537) (xy 349.314269 -342.737944) (xy 349.322389 -342.79312)
			(xy 349.322898 -342.821006) (xy 349.322389 -342.848892) (xy 349.314269 -342.904068) (xy 349.298201 -342.957475)
			(xy 349.274529 -343.007972) (xy 349.243756 -343.054485) (xy 349.206539 -343.096022) (xy 349.163671 -343.131697)
			(xy 349.116065 -343.160751) (xy 349.064736 -343.182563) (xy 349.010779 -343.196669) (xy 348.955342 -343.202769)
			(xy 348.899608 -343.200732) (xy 348.844765 -343.190602) (xy 348.791981 -343.172595) (xy 348.742381 -343.147094)
			(xy 348.697023 -343.114643) (xy 348.656874 -343.075934) (xy 348.622788 -343.031791) (xy 348.595492 -342.983156)
			(xy 348.575569 -342.931065) (xy 348.563443 -342.876628) (xy 348.559372 -342.821006) (xy 343.902792 -342.821006)
			(xy 343.902792 -343.716356) (xy 347.980252 -343.716356) (xy 347.984323 -343.660734) (xy 347.996449 -343.606297)
			(xy 348.016372 -343.554206) (xy 348.043668 -343.505571) (xy 348.077754 -343.461428) (xy 348.117903 -343.422719)
			(xy 348.163261 -343.390268) (xy 348.212861 -343.364767) (xy 348.265645 -343.34676) (xy 348.320488 -343.33663)
			(xy 348.376222 -343.334593) (xy 348.431659 -343.340693) (xy 348.485616 -343.354799) (xy 348.536945 -343.376611)
			(xy 348.584551 -343.405665) (xy 348.627419 -343.44134) (xy 348.664636 -343.482877) (xy 348.695409 -343.52939)
			(xy 348.719081 -343.579887) (xy 348.735149 -343.633294) (xy 348.743269 -343.68847) (xy 348.743778 -343.716356)
			(xy 348.743269 -343.744242) (xy 348.735149 -343.799418) (xy 348.719081 -343.852825) (xy 348.695409 -343.903322)
			(xy 348.664636 -343.949835) (xy 348.627419 -343.991372) (xy 348.584551 -344.027047) (xy 348.536945 -344.056101)
			(xy 348.485616 -344.077913) (xy 348.431659 -344.092019) (xy 348.376222 -344.098119) (xy 348.320488 -344.096082)
			(xy 348.265645 -344.085952) (xy 348.212861 -344.067945) (xy 348.163261 -344.042444) (xy 348.117903 -344.009993)
			(xy 348.077754 -343.971284) (xy 348.043668 -343.927141) (xy 348.016372 -343.878506) (xy 347.996449 -343.826415)
			(xy 347.984323 -343.771978) (xy 347.980252 -343.716356) (xy 343.902792 -343.716356) (xy 343.902792 -344.19286)
			(xy 343.902311 -344.212873) (xy 343.89448 -344.252127) (xy 343.879149 -344.289101) (xy 343.856907 -344.32238)
			(xy 343.843102 -344.336878) (xy 343.787984 -344.391996) (xy 349.319088 -344.391996) (xy 349.319575 -344.364521)
			(xy 349.327467 -344.310142) (xy 349.343087 -344.25746) (xy 349.366112 -344.207567) (xy 349.396063 -344.161498)
			(xy 349.41383 -344.140536) (xy 349.419926 -344.133424) (xy 349.426276 -344.116406) (xy 349.426276 -344.030554)
			(xy 349.419926 -344.013536) (xy 349.41383 -344.006424) (xy 349.396085 -343.985446) (xy 349.36616 -343.939368)
			(xy 349.343145 -343.889477) (xy 349.327514 -343.836804) (xy 349.319591 -343.782435) (xy 349.319088 -343.754964)
			(xy 349.319574 -343.727713) (xy 349.32733 -343.673765) (xy 349.342685 -343.62147) (xy 349.365327 -343.571893)
			(xy 349.394793 -343.526043) (xy 349.430484 -343.484852) (xy 349.471675 -343.449161) (xy 349.517525 -343.419695)
			(xy 349.567102 -343.397053) (xy 349.619397 -343.381698) (xy 349.673345 -343.373942) (xy 349.727847 -343.373942)
			(xy 349.781795 -343.381698) (xy 349.83409 -343.397053) (xy 349.883667 -343.419695) (xy 349.929517 -343.449161)
			(xy 349.970708 -343.484852) (xy 350.006399 -343.526043) (xy 350.035865 -343.571893) (xy 350.058507 -343.62147)
			(xy 350.073862 -343.673765) (xy 350.081618 -343.727713) (xy 350.082104 -343.754964) (xy 350.081596 -343.782438)
			(xy 350.073709 -343.836816) (xy 350.058094 -343.889498) (xy 350.035074 -343.939392) (xy 350.005127 -343.985461)
			(xy 349.987362 -344.006424) (xy 349.981266 -344.013536) (xy 349.974916 -344.030554) (xy 349.974916 -344.116406)
			(xy 349.981266 -344.133424) (xy 349.987362 -344.140536) (xy 350.005133 -344.161492) (xy 350.035055 -344.207576)
			(xy 350.058065 -344.257472) (xy 350.07369 -344.31015) (xy 350.081605 -344.364523) (xy 350.082104 -344.391996)
			(xy 350.081618 -344.419247) (xy 350.073862 -344.473195) (xy 350.058507 -344.52549) (xy 350.035865 -344.575067)
			(xy 350.006399 -344.620917) (xy 349.970708 -344.662108) (xy 349.929517 -344.697799) (xy 349.883667 -344.727265)
			(xy 349.83409 -344.749907) (xy 349.781795 -344.765262) (xy 349.727847 -344.773018) (xy 349.673345 -344.773018)
			(xy 349.619397 -344.765262) (xy 349.567102 -344.749907) (xy 349.517525 -344.727265) (xy 349.471675 -344.697799)
			(xy 349.430484 -344.662108) (xy 349.394793 -344.620917) (xy 349.365327 -344.575067) (xy 349.342685 -344.52549)
			(xy 349.32733 -344.473195) (xy 349.319574 -344.419247) (xy 349.319088 -344.391996) (xy 343.787984 -344.391996)
			(xy 341.735156 -346.444824) (xy 341.720621 -346.45857) (xy 341.687339 -346.480752) (xy 341.650372 -346.49602)
			(xy 341.611137 -346.503787) (xy 341.591138 -346.50426) (xy 333.62265 -346.50426) (xy 333.612582 -346.504695)
			(xy 333.593983 -346.512407) (xy 333.586582 -346.519246) (xy 331.00645 -349.099378) (xy 330.999634 -349.106797)
			(xy 330.991899 -349.125382) (xy 330.991464 -349.135446) (xy 330.991464 -353.84359) (xy 330.991028 -353.863596)
			(xy 330.983289 -353.90285) (xy 330.968029 -353.939835) (xy 330.945837 -353.973126) (xy 330.932028 -353.987608)
			(xy 318.888618 -366.031018) (xy 318.874133 -366.044841) (xy 318.840859 -366.067099) (xy 318.803879 -366.082432)
			(xy 318.764616 -366.090249) (xy 318.7446 -366.090708) (xy 314.5282 -366.090708) (xy 314.508189 -366.090186)
			(xy 314.468938 -366.082367) (xy 314.431963 -366.067048) (xy 314.398682 -366.044818) (xy 314.384182 -366.031018)
			(xy 313.315858 -364.96244) (xy 313.308384 -364.955738) (xy 313.289819 -364.948153) (xy 313.27979 -364.947708)
			(xy 310.102504 -364.947708) (xy 310.090473 -364.948352) (xy 310.069009 -364.959229) (xy 310.061356 -364.968536)
			(xy 310.045934 -364.989053) (xy 310.010436 -365.026126) (xy 309.970287 -365.058104) (xy 309.926213 -365.084408)
			(xy 309.879008 -365.104564) (xy 309.829527 -365.118206) (xy 309.778664 -365.12509) (xy 309.753 -365.125508)
			(xy 309.725749 -365.125022) (xy 309.671801 -365.117266) (xy 309.619506 -365.101911) (xy 309.569929 -365.079269)
			(xy 309.524079 -365.049803) (xy 309.482888 -365.014112) (xy 309.447197 -364.972921) (xy 309.417731 -364.927071)
			(xy 309.395089 -364.877494) (xy 309.379734 -364.825199) (xy 309.371978 -364.771251) (xy 309.371492 -364.744)
			(xy 309.372 -364.72368) (xy 309.372762 -364.707678) (xy 309.356506 -364.681008) (xy 309.255414 -364.635796)
			(xy 309.245831 -364.632115) (xy 309.225327 -364.631797) (xy 309.206333 -364.639523) (xy 309.198772 -364.646464)
			(xy 308.695852 -365.149384) (xy 308.681386 -365.163173) (xy 308.648117 -365.185305) (xy 308.629812 -365.193326)
			(xy 308.539896 -365.230664) (xy 308.530847 -365.235001) (xy 308.5167 -365.249199) (xy 308.509055 -365.267726)
			(xy 308.509074 -365.287769) (xy 308.512464 -365.297212) (xy 308.51856 -365.312198) (xy 308.545992 -365.329216)
			(xy 308.562248 -365.328454) (xy 308.5846 -365.327692) (xy 308.611851 -365.328178) (xy 308.665799 -365.335934)
			(xy 308.718094 -365.351289) (xy 308.767671 -365.373931) (xy 308.813521 -365.403397) (xy 308.854712 -365.439088)
			(xy 308.890403 -365.480279) (xy 308.919869 -365.526129) (xy 308.942511 -365.575706) (xy 308.957866 -365.628001)
			(xy 308.965622 -365.681949) (xy 308.965622 -365.736451) (xy 308.957866 -365.790399) (xy 308.942511 -365.842694)
			(xy 308.919869 -365.892271) (xy 308.890403 -365.938121) (xy 308.854712 -365.979312) (xy 308.813521 -366.015003)
			(xy 308.767671 -366.044469) (xy 308.718094 -366.067111) (xy 308.665799 -366.082466) (xy 308.611851 -366.090222)
			(xy 308.5846 -366.090708) (xy 308.56968 -366.090591) (xy 308.539927 -366.0883) (xy 308.525164 -366.086136)
			(xy 308.512972 -366.084104) (xy 308.490112 -366.09147) (xy 308.093618 -366.488218) (xy 308.079133 -366.502041)
			(xy 308.045859 -366.524299) (xy 308.008879 -366.539632) (xy 307.969616 -366.547449) (xy 307.9496 -366.547908)
			(xy 305.931824 -366.547908) (xy 305.906424 -366.564672) (xy 305.900582 -366.57915) (xy 305.897217 -366.588579)
			(xy 305.897208 -366.608579) (xy 305.90481 -366.627078) (xy 305.911504 -366.634522) (xy 305.986942 -366.70996)
			(xy 305.994416 -366.716662) (xy 306.012981 -366.724247) (xy 306.02301 -366.724692) (xy 308.27599 -366.724692)
			(xy 308.286038 -366.724346) (xy 308.304634 -366.71674) (xy 308.312058 -366.70996) (xy 309.075582 -365.946182)
			(xy 309.090067 -365.932359) (xy 309.123341 -365.910101) (xy 309.160321 -365.894768) (xy 309.199584 -365.886951)
			(xy 309.2196 -365.886492) (xy 309.993538 -365.886492) (xy 310.003413 -365.886038) (xy 310.021717 -365.878626)
			(xy 310.035884 -365.864868) (xy 310.040274 -365.856012) (xy 310.083454 -365.756444) (xy 310.078374 -365.726726)
			(xy 310.06796 -365.71555) (xy 310.048774 -365.694229) (xy 310.016305 -365.646952) (xy 309.991278 -365.595347)
			(xy 309.974258 -365.540577) (xy 309.965629 -365.483876) (xy 309.96509 -365.4552) (xy 309.965578 -365.427949)
			(xy 309.973334 -365.374001) (xy 309.988689 -365.321707) (xy 310.01133 -365.27213) (xy 310.040796 -365.226279)
			(xy 310.076488 -365.185089) (xy 310.117678 -365.149398) (xy 310.163528 -365.119931) (xy 310.213105 -365.09729)
			(xy 310.265399 -365.081935) (xy 310.319347 -365.074178) (xy 310.346598 -365.073692) (xy 310.372263 -365.074085)
			(xy 310.423131 -365.080961) (xy 310.472615 -365.094602) (xy 310.519821 -365.114761) (xy 310.563894 -365.141074)
			(xy 310.604036 -365.173064) (xy 310.639522 -365.210152) (xy 310.654954 -365.230664) (xy 310.662541 -365.240043)
			(xy 310.68405 -365.250903) (xy 310.696102 -365.251492) (xy 312.5216 -365.251492) (xy 312.541611 -365.252014)
			(xy 312.580862 -365.259833) (xy 312.617837 -365.275152) (xy 312.651118 -365.297382) (xy 312.665618 -365.311182)
			(xy 314.038742 -366.68456) (xy 314.046216 -366.691262) (xy 314.064781 -366.698847) (xy 314.07481 -366.699292)
			(xy 319.35039 -366.699292) (xy 319.360438 -366.698946) (xy 319.379034 -366.69134) (xy 319.386458 -366.68456)
			(xy 331.99197 -354.079048) (xy 331.998777 -354.071622) (xy 332.006517 -354.053043) (xy 332.006956 -354.04298)
			(xy 332.006956 -349.62338) (xy 332.007368 -349.603373) (xy 332.015114 -349.564117) (xy 332.03038 -349.527132)
			(xy 332.05258 -349.493842) (xy 332.066392 -349.479362) (xy 334.112362 -347.433392) (xy 334.126876 -347.419624)
			(xy 334.160167 -347.397449) (xy 334.197141 -347.382188) (xy 334.23638 -347.374427) (xy 334.25638 -347.373956)
			(xy 340.9188 -347.373956) (xy 349.981774 -347.373956) (xy 349.991822 -347.373611) (xy 350.010418 -347.366006)
			(xy 350.017842 -347.359224) (xy 350.275144 -347.101922) (xy 350.28186 -347.094459) (xy 350.289437 -347.075886)
			(xy 350.289876 -347.065854) (xy 350.289876 -345.053666) (xy 350.290382 -345.033654) (xy 350.298207 -344.994403)
			(xy 350.31353 -344.957428) (xy 350.335765 -344.924148) (xy 350.349566 -344.909648) (xy 351.128838 -344.130376)
			(xy 351.144765 -344.115297) (xy 351.181671 -344.091617) (xy 351.22278 -344.076359) (xy 351.244408 -344.072718)
			(xy 351.253762 -344.070958) (xy 351.270327 -344.061618) (xy 351.282349 -344.046884) (xy 351.288174 -344.028782)
			(xy 351.287001 -344.009801) (xy 351.278991 -343.992554) (xy 351.265246 -343.979413) (xy 351.2566 -343.975436)
			(xy 351.244047 -343.970233) (xy 351.21964 -343.958284) (xy 351.207832 -343.95156) (xy 351.19818 -343.945718)
			(xy 351.176082 -343.943686) (xy 351.081594 -343.977214) (xy 351.065592 -343.992708) (xy 351.061528 -344.003122)
			(xy 351.050837 -344.0299) (xy 351.022548 -344.080142) (xy 350.987017 -344.125551) (xy 350.945054 -344.165093)
			(xy 350.897616 -344.197866) (xy 350.845785 -344.223124) (xy 350.790741 -344.24029) (xy 350.733741 -344.248972)
			(xy 350.704912 -344.249502) (xy 350.677658 -344.249051) (xy 350.623705 -344.241296) (xy 350.571405 -344.225941)
			(xy 350.521823 -344.203298) (xy 350.475967 -344.17383) (xy 350.434772 -344.138136) (xy 350.399077 -344.096942)
			(xy 350.369607 -344.051088) (xy 350.346964 -344.001506) (xy 350.331607 -343.949207) (xy 350.323849 -343.895254)
			(xy 350.323849 -343.840746) (xy 350.331607 -343.786793) (xy 350.346964 -343.734494) (xy 350.369607 -343.684912)
			(xy 350.399077 -343.639058) (xy 350.434772 -343.597864) (xy 350.475967 -343.56217) (xy 350.521823 -343.532702)
			(xy 350.571405 -343.510059) (xy 350.623705 -343.494704) (xy 350.677658 -343.486949) (xy 350.704912 -343.486486)
			(xy 350.730147 -343.48688) (xy 350.780181 -343.493499) (xy 350.828902 -343.506673) (xy 350.875454 -343.526171)
			(xy 350.897444 -343.538556) (xy 350.907096 -343.544398) (xy 350.929194 -343.54643) (xy 351.023682 -343.512902)
			(xy 351.039684 -343.497408) (xy 351.043748 -343.486994) (xy 351.054468 -343.460228) (xy 351.082752 -343.409987)
			(xy 351.118279 -343.364577) (xy 351.160237 -343.325035) (xy 351.207671 -343.29226) (xy 351.259499 -343.267)
			(xy 351.314539 -343.249831) (xy 351.371536 -343.241145) (xy 351.400364 -343.240614) (xy 351.427617 -343.241089)
			(xy 351.481569 -343.248842) (xy 351.533868 -343.264194) (xy 351.583449 -343.286834) (xy 351.629303 -343.3163)
			(xy 351.670497 -343.351993) (xy 351.706191 -343.393185) (xy 351.735659 -343.439039) (xy 351.758301 -343.488619)
			(xy 351.771024 -343.531952) (xy 353.911916 -343.531952) (xy 353.912412 -343.504378) (xy 353.920357 -343.449807)
			(xy 353.936076 -343.396947) (xy 353.95924 -343.346901) (xy 353.989368 -343.300711) (xy 354.025831 -343.259338)
			(xy 354.046536 -343.241122) (xy 354.054646 -343.233512) (xy 354.064004 -343.213366) (xy 354.06457 -343.20226)
			(xy 354.06457 -343.125044) (xy 354.064003 -343.113934) (xy 354.054665 -343.093775) (xy 354.046536 -343.086182)
			(xy 354.02582 -343.067976) (xy 353.989349 -343.026607) (xy 353.959216 -342.980416) (xy 353.936051 -342.930367)
			(xy 353.920336 -342.877503) (xy 353.912399 -342.822927) (xy 353.911916 -342.795352) (xy 353.912333 -342.768098)
			(xy 353.920097 -342.714147) (xy 353.935459 -342.66185) (xy 353.958108 -342.612271) (xy 353.987581 -342.566419)
			(xy 354.02328 -342.525229) (xy 354.064477 -342.489538) (xy 354.110334 -342.460073) (xy 354.159917 -342.437434)
			(xy 354.212217 -342.422082) (xy 354.26617 -342.414328) (xy 354.293424 -342.413844) (xy 354.327714 -342.415368)
			(xy 354.337874 -342.416384) (xy 354.357178 -342.410288) (xy 354.42779 -342.351106) (xy 354.437188 -342.333072)
			(xy 354.438204 -342.322912) (xy 354.441103 -342.294733) (xy 354.454284 -342.239638) (xy 354.475469 -342.1871)
			(xy 354.504193 -342.138273) (xy 354.539824 -342.094232) (xy 354.581577 -342.055946) (xy 354.628534 -342.024258)
			(xy 354.679662 -341.999864) (xy 354.733836 -341.983302) (xy 354.789863 -341.974935) (xy 354.818188 -341.974424)
			(xy 354.836208 -341.974638) (xy 354.872082 -341.978077) (xy 354.889816 -341.981282) (xy 354.899214 -341.98306)
			(xy 354.918264 -341.97925) (xy 354.993448 -341.931498) (xy 355.004878 -341.91575) (xy 355.007164 -341.906352)
			(xy 355.014516 -341.879294) (xy 355.03615 -341.827565) (xy 355.065119 -341.779558) (xy 355.1008 -341.736305)
			(xy 355.142425 -341.698739) (xy 355.189099 -341.667666) (xy 355.239816 -341.643757) (xy 355.293486 -341.627525)
			(xy 355.348953 -341.619319) (xy 355.376988 -341.618824) (xy 355.404242 -341.619267) (xy 355.458195 -341.627023)
			(xy 355.510496 -341.642379) (xy 355.560078 -341.665022) (xy 355.605932 -341.694492) (xy 355.647126 -341.730188)
			(xy 355.68282 -341.771384) (xy 355.712287 -341.81724) (xy 355.734928 -341.866823) (xy 355.750282 -341.919124)
			(xy 355.758035 -341.973078) (xy 355.758496 -342.000332) (xy 355.757985 -342.027905) (xy 355.750042 -342.082476)
			(xy 355.734326 -342.135335) (xy 355.711164 -342.185381) (xy 355.68104 -342.231572) (xy 355.64458 -342.272945)
			(xy 355.623876 -342.291162) (xy 355.615776 -342.298781) (xy 355.606412 -342.31892) (xy 355.605842 -342.330024)
			(xy 355.605842 -342.40724) (xy 355.606358 -342.418356) (xy 355.615732 -342.438515) (xy 355.623876 -342.446102)
			(xy 355.644614 -342.464282) (xy 355.68108 -342.505657) (xy 355.711208 -342.551852) (xy 355.734371 -342.601903)
			(xy 355.750085 -342.654768) (xy 355.758023 -342.709345) (xy 355.75802 -342.764496) (xy 355.750076 -342.819072)
			(xy 355.734356 -342.871935) (xy 355.711188 -342.921984) (xy 355.681055 -342.968176) (xy 355.644585 -343.009547)
			(xy 355.623876 -343.027762) (xy 355.615776 -343.035381) (xy 355.606412 -343.05552) (xy 355.605842 -343.066624)
			(xy 355.605842 -343.14384) (xy 355.606358 -343.154956) (xy 355.615732 -343.175115) (xy 355.623876 -343.182702)
			(xy 355.644587 -343.200914) (xy 355.681058 -343.242282) (xy 355.711191 -343.288471) (xy 355.734357 -343.338519)
			(xy 355.750073 -343.391382) (xy 355.758012 -343.445957) (xy 355.758496 -343.473532) (xy 355.758052 -343.500785)
			(xy 355.750291 -343.554734) (xy 355.734931 -343.607031) (xy 355.712285 -343.656609) (xy 355.682814 -343.70246)
			(xy 355.647119 -343.74365) (xy 355.605924 -343.779341) (xy 355.56007 -343.808806) (xy 355.510489 -343.831446)
			(xy 355.458191 -343.8468) (xy 355.404241 -343.854555) (xy 355.376988 -343.85504) (xy 355.349134 -343.854498)
			(xy 355.29402 -343.846374) (xy 355.240672 -343.830329) (xy 355.190221 -343.806703) (xy 355.143738 -343.775999)
			(xy 355.102208 -343.738867) (xy 355.066514 -343.696095) (xy 355.037413 -343.648591) (xy 355.015522 -343.597363)
			(xy 355.007926 -343.57056) (xy 355.00564 -343.56167) (xy 354.994972 -343.54643) (xy 354.92309 -343.498678)
			(xy 354.905056 -343.494614) (xy 354.895912 -343.495884) (xy 354.882895 -343.49755) (xy 354.856711 -343.499332)
			(xy 354.843588 -343.49944) (xy 354.829439 -343.499347) (xy 354.801216 -343.497312) (xy 354.7872 -343.495376)
			(xy 354.77704 -343.493852) (xy 354.757482 -343.498678) (xy 354.68306 -343.554558) (xy 354.6729 -343.572084)
			(xy 354.67163 -343.582244) (xy 354.667529 -343.609395) (xy 354.652557 -343.662224) (xy 354.630166 -343.712362)
			(xy 354.60082 -343.758772) (xy 354.565124 -343.800496) (xy 354.523816 -343.836673) (xy 354.477749 -343.866554)
			(xy 354.427874 -343.889524) (xy 354.375221 -343.905107) (xy 354.320879 -343.912981) (xy 354.293424 -343.91346)
			(xy 354.26617 -343.913022) (xy 354.212215 -343.905267) (xy 354.159914 -343.889912) (xy 354.110331 -343.867269)
			(xy 354.064475 -343.837799) (xy 354.023281 -343.802102) (xy 353.987587 -343.760906) (xy 353.95812 -343.715048)
			(xy 353.93548 -343.665464) (xy 353.920128 -343.613161) (xy 353.912376 -343.559206) (xy 353.911916 -343.531952)
			(xy 351.771024 -343.531952) (xy 351.773656 -343.540918) (xy 351.78141 -343.594869) (xy 351.781872 -343.622122)
			(xy 351.781209 -343.653685) (xy 351.770824 -343.71595) (xy 351.750339 -343.775659) (xy 351.735898 -343.803732)
			(xy 351.731072 -343.812622) (xy 351.72904 -343.83218) (xy 351.754694 -343.920318) (xy 351.76714 -343.935812)
			(xy 351.77603 -343.940892) (xy 351.801163 -343.955389) (xy 351.847044 -343.990902) (xy 351.887016 -344.032955)
			(xy 351.920157 -344.080578) (xy 351.945703 -344.132671) (xy 351.963063 -344.188032) (xy 351.971837 -344.245384)
			(xy 351.972372 -344.274394) (xy 351.971939 -344.301648) (xy 351.964182 -344.355602) (xy 351.948825 -344.407903)
			(xy 351.92618 -344.457485) (xy 351.89671 -344.50334) (xy 351.861013 -344.544534) (xy 351.819816 -344.580228)
			(xy 351.773959 -344.609695) (xy 351.724375 -344.632335) (xy 351.672073 -344.647688) (xy 351.618118 -344.655441)
			(xy 351.590864 -344.655902) (xy 351.565315 -344.655526) (xy 351.514674 -344.648711) (xy 351.465397 -344.635195)
			(xy 351.418366 -344.615218) (xy 351.374424 -344.58914) (xy 351.354136 -344.573606) (xy 351.346899 -344.568292)
			(xy 351.329842 -344.562712) (xy 351.320862 -344.562684) (xy 351.29089 -344.5637) (xy 351.281316 -344.564395)
			(xy 351.263693 -344.571964) (xy 351.2566 -344.578432) (xy 350.712024 -345.123008) (xy 350.705334 -345.130492)
			(xy 350.697743 -345.149049) (xy 350.697292 -345.159076) (xy 350.697292 -347.171264) (xy 350.696814 -347.191277)
			(xy 350.688982 -347.230531) (xy 350.67365 -347.267506) (xy 350.651407 -347.300784) (xy 350.637602 -347.315282)
			(xy 350.231202 -347.721682) (xy 350.216718 -347.735506) (xy 350.183444 -347.757766) (xy 350.146463 -347.773098)
			(xy 350.107201 -347.780914) (xy 350.087184 -347.781372) (xy 340.90991 -347.781372) (xy 340.900766 -347.781118)
			(xy 340.89975 -347.780864) (xy 334.36179 -347.780864) (xy 334.351718 -347.781267) (xy 334.333119 -347.789001)
			(xy 334.325722 -347.79585) (xy 332.647614 -349.473958) (xy 334.52206 -349.473958) (xy 334.52206 -349.389262)
			(xy 334.530111 -349.304948) (xy 334.54614 -349.221782) (xy 334.570001 -349.140515) (xy 334.60148 -349.061885)
			(xy 334.640291 -348.986604) (xy 334.686081 -348.915352) (xy 334.738437 -348.848776) (xy 334.796885 -348.787478)
			(xy 334.860895 -348.732013) (xy 334.929887 -348.682884) (xy 335.003237 -348.640535) (xy 335.08028 -348.605351)
			(xy 335.160319 -348.577649) (xy 335.242628 -348.557681) (xy 335.326463 -348.545628) (xy 335.411064 -348.541598)
			(xy 335.495665 -348.545628) (xy 335.5795 -348.557681) (xy 335.661809 -348.577649) (xy 335.741848 -348.605351)
			(xy 335.818891 -348.640535) (xy 335.892241 -348.682884) (xy 335.961233 -348.732013) (xy 336.025243 -348.787478)
			(xy 336.083691 -348.848776) (xy 336.136047 -348.915352) (xy 336.181837 -348.986604) (xy 336.220648 -349.061885)
			(xy 336.252127 -349.140515) (xy 336.275988 -349.221782) (xy 336.292017 -349.304948) (xy 336.300068 -349.389262)
			(xy 336.300572 -349.43161) (xy 336.300068 -349.473958) (xy 336.292017 -349.558272) (xy 336.275988 -349.641438)
			(xy 336.252127 -349.722705) (xy 336.220648 -349.801335) (xy 336.181837 -349.876616) (xy 336.136047 -349.947868)
			(xy 336.083691 -350.014444) (xy 336.025243 -350.075742) (xy 335.961233 -350.131207) (xy 335.892241 -350.180336)
			(xy 335.818891 -350.222685) (xy 335.741848 -350.257869) (xy 335.661809 -350.285571) (xy 335.5795 -350.305539)
			(xy 335.495665 -350.317592) (xy 335.411064 -350.321623) (xy 335.326463 -350.317592) (xy 335.242628 -350.305539)
			(xy 335.160319 -350.285571) (xy 335.08028 -350.257869) (xy 335.003237 -350.222685) (xy 334.929887 -350.180336)
			(xy 334.860895 -350.131207) (xy 334.796885 -350.075742) (xy 334.738437 -350.014444) (xy 334.686081 -349.947868)
			(xy 334.640291 -349.876616) (xy 334.60148 -349.801335) (xy 334.570001 -349.722705) (xy 334.54614 -349.641438)
			(xy 334.530111 -349.558272) (xy 334.52206 -349.473958) (xy 332.647614 -349.473958) (xy 332.42885 -349.692722)
			(xy 332.422015 -349.700126) (xy 332.414291 -349.718722) (xy 332.413864 -349.72879) (xy 332.413864 -351.97408)
			(xy 334.52206 -351.97408) (xy 334.52206 -351.889384) (xy 334.530111 -351.80507) (xy 334.54614 -351.721904)
			(xy 334.570001 -351.640637) (xy 334.60148 -351.562007) (xy 334.640291 -351.486726) (xy 334.686081 -351.415474)
			(xy 334.738437 -351.348898) (xy 334.796885 -351.2876) (xy 334.860895 -351.232135) (xy 334.929887 -351.183006)
			(xy 335.003237 -351.140657) (xy 335.08028 -351.105473) (xy 335.160319 -351.077771) (xy 335.242628 -351.057803)
			(xy 335.326463 -351.04575) (xy 335.411064 -351.04172) (xy 335.495665 -351.04575) (xy 335.5795 -351.057803)
			(xy 335.661809 -351.077771) (xy 335.741848 -351.105473) (xy 335.818891 -351.140657) (xy 335.892241 -351.183006)
			(xy 335.961233 -351.232135) (xy 336.025243 -351.2876) (xy 336.083691 -351.348898) (xy 336.136047 -351.415474)
			(xy 336.181837 -351.486726) (xy 336.220648 -351.562007) (xy 336.252127 -351.640637) (xy 336.275988 -351.721904)
			(xy 336.292017 -351.80507) (xy 336.300068 -351.889384) (xy 336.300572 -351.931732) (xy 336.300068 -351.97408)
			(xy 336.292017 -352.058394) (xy 336.275988 -352.14156) (xy 336.252127 -352.222827) (xy 336.220648 -352.301457)
			(xy 336.181837 -352.376738) (xy 336.136047 -352.44799) (xy 336.083691 -352.514566) (xy 336.025243 -352.575864)
			(xy 335.961233 -352.631329) (xy 335.892241 -352.680458) (xy 335.818891 -352.722807) (xy 335.741848 -352.757991)
			(xy 335.661809 -352.785693) (xy 335.5795 -352.805661) (xy 335.495665 -352.817714) (xy 335.411064 -352.821745)
			(xy 335.326463 -352.817714) (xy 335.242628 -352.805661) (xy 335.160319 -352.785693) (xy 335.08028 -352.757991)
			(xy 335.003237 -352.722807) (xy 334.929887 -352.680458) (xy 334.860895 -352.631329) (xy 334.796885 -352.575864)
			(xy 334.738437 -352.514566) (xy 334.686081 -352.44799) (xy 334.640291 -352.376738) (xy 334.60148 -352.301457)
			(xy 334.570001 -352.222827) (xy 334.54614 -352.14156) (xy 334.530111 -352.058394) (xy 334.52206 -351.97408)
			(xy 332.413864 -351.97408) (xy 332.413864 -352.973132) (xy 339.357462 -352.973132) (xy 339.357989 -352.944427)
			(xy 339.366594 -352.887665) (xy 339.3836 -352.832831) (xy 339.408623 -352.781161) (xy 339.4411 -352.73382)
			(xy 339.480298 -352.691874) (xy 339.502496 -352.673666) (xy 339.511894 -352.6663) (xy 339.5218 -352.645726)
			(xy 339.5218 -352.542348) (xy 339.511894 -352.521774) (xy 339.502496 -352.514408) (xy 339.480306 -352.496237)
			(xy 339.441174 -352.454308) (xy 339.408755 -352.406996) (xy 339.383781 -352.355366) (xy 339.366812 -352.30058)
			(xy 339.358231 -352.243873) (xy 339.357716 -352.215196) (xy 339.358226 -352.186279) (xy 339.366956 -352.129107)
			(xy 339.384215 -352.073908) (xy 339.409608 -352.021946) (xy 339.442553 -351.974412) (xy 339.482296 -351.932396)
			(xy 339.504782 -351.914206) (xy 339.513551 -351.906651) (xy 339.523727 -351.885887) (xy 339.52434 -351.874328)
			(xy 339.52434 -351.794064) (xy 339.523754 -351.782498) (xy 339.513572 -351.761725) (xy 339.504782 -351.754186)
			(xy 339.482288 -351.736007) (xy 339.442554 -351.693985) (xy 339.409617 -351.646447) (xy 339.384231 -351.594483)
			(xy 339.366977 -351.539284) (xy 339.35825 -351.482113) (xy 339.357716 -351.453196) (xy 339.358152 -351.425942)
			(xy 339.36591 -351.371989) (xy 339.381268 -351.319689) (xy 339.403912 -351.270107) (xy 339.433383 -351.224253)
			(xy 339.46908 -351.18306) (xy 339.510275 -351.147366) (xy 339.556132 -351.117899) (xy 339.605715 -351.095258)
			(xy 339.658016 -351.079904) (xy 339.71197 -351.07215) (xy 339.739224 -351.071688) (xy 339.768141 -351.072228)
			(xy 339.825312 -351.080948) (xy 339.880512 -351.098199) (xy 339.932475 -351.123587) (xy 339.980009 -351.156528)
			(xy 340.022025 -351.196269) (xy 340.040214 -351.218754) (xy 340.047765 -351.227527) (xy 340.068532 -351.237702)
			(xy 340.080092 -351.238312) (xy 340.160356 -351.238312) (xy 340.17192 -351.237712) (xy 340.192691 -351.227538)
			(xy 340.200234 -351.218754) (xy 340.216987 -351.197971) (xy 340.255341 -351.160841) (xy 340.298495 -351.129419)
			(xy 340.345609 -351.10432) (xy 340.395761 -351.086034) (xy 340.447972 -351.074917) (xy 340.501224 -351.071187)
			(xy 340.554476 -351.074917) (xy 340.606687 -351.086034) (xy 340.656839 -351.10432) (xy 340.703953 -351.129419)
			(xy 340.747107 -351.160841) (xy 340.785461 -351.197971) (xy 340.802214 -351.218754) (xy 340.809765 -351.227527)
			(xy 340.830532 -351.237702) (xy 340.842092 -351.238312) (xy 340.922356 -351.238312) (xy 340.93392 -351.237712)
			(xy 340.954691 -351.227538) (xy 340.962234 -351.218754) (xy 340.978987 -351.197971) (xy 341.017341 -351.160841)
			(xy 341.060495 -351.129419) (xy 341.107609 -351.10432) (xy 341.157761 -351.086034) (xy 341.209972 -351.074917)
			(xy 341.263224 -351.071187) (xy 341.316476 -351.074917) (xy 341.368687 -351.086034) (xy 341.418839 -351.10432)
			(xy 341.465953 -351.129419) (xy 341.509107 -351.160841) (xy 341.547461 -351.197971) (xy 341.564214 -351.218754)
			(xy 341.571765 -351.227527) (xy 341.592532 -351.237702) (xy 341.604092 -351.238312) (xy 341.684356 -351.238312)
			(xy 341.69592 -351.237712) (xy 341.716691 -351.227538) (xy 341.724234 -351.218754) (xy 341.740987 -351.197971)
			(xy 341.779341 -351.160841) (xy 341.822495 -351.129419) (xy 341.869609 -351.10432) (xy 341.919761 -351.086034)
			(xy 341.971972 -351.074917) (xy 342.025224 -351.071187) (xy 342.078476 -351.074917) (xy 342.130687 -351.086034)
			(xy 342.180839 -351.10432) (xy 342.227953 -351.129419) (xy 342.271107 -351.160841) (xy 342.309461 -351.197971)
			(xy 342.326214 -351.218754) (xy 342.333765 -351.227527) (xy 342.354532 -351.237702) (xy 342.366092 -351.238312)
			(xy 342.446356 -351.238312) (xy 342.45792 -351.237712) (xy 342.478691 -351.227538) (xy 342.486234 -351.218754)
			(xy 342.504394 -351.196245) (xy 342.546422 -351.156513) (xy 342.593963 -351.123579) (xy 342.645931 -351.098195)
			(xy 342.701133 -351.080944) (xy 342.758306 -351.07222) (xy 342.787224 -351.071688) (xy 342.813553 -351.072133)
			(xy 342.865711 -351.07936) (xy 342.916378 -351.093701) (xy 342.964587 -351.114883) (xy 343.009419 -351.142502)
			(xy 343.050021 -351.176032) (xy 343.068148 -351.195132) (xy 343.075006 -351.202752) (xy 343.09304 -351.211134)
			(xy 343.184734 -351.215452) (xy 343.203276 -351.208848) (xy 343.210896 -351.20199) (xy 343.231996 -351.183769)
			(xy 343.278502 -351.153026) (xy 343.328986 -351.129378) (xy 343.382374 -351.113327) (xy 343.43753 -351.105215)
			(xy 343.465404 -351.104708) (xy 343.492658 -351.105152) (xy 343.54661 -351.11291) (xy 343.598909 -351.128267)
			(xy 343.648491 -351.150911) (xy 343.694344 -351.180381) (xy 343.735537 -351.216077) (xy 343.771231 -351.257272)
			(xy 343.800699 -351.303127) (xy 343.82334 -351.352709) (xy 343.838695 -351.405009) (xy 343.84645 -351.458962)
			(xy 343.846912 -351.486216) (xy 343.846367 -351.515132) (xy 343.837648 -351.572304) (xy 343.820398 -351.627503)
			(xy 343.795011 -351.679466) (xy 343.762071 -351.727) (xy 343.722331 -351.769016) (xy 343.699846 -351.787206)
			(xy 343.691077 -351.79476) (xy 343.680899 -351.815525) (xy 343.680288 -351.827084) (xy 343.680288 -351.907348)
			(xy 343.680892 -351.918911) (xy 343.691063 -351.939683) (xy 343.699846 -351.947226) (xy 343.722352 -351.965391)
			(xy 343.762083 -352.007417) (xy 343.795018 -352.054958) (xy 343.820402 -352.106924) (xy 343.837654 -352.162126)
			(xy 343.846379 -352.219299) (xy 343.846912 -352.248216) (xy 343.846392 -352.276921) (xy 343.837781 -352.333682)
			(xy 343.820772 -352.388515) (xy 343.795747 -352.440184) (xy 343.763271 -352.487526) (xy 343.724074 -352.529473)
			(xy 343.701878 -352.547682) (xy 343.69248 -352.555048) (xy 343.682574 -352.575622) (xy 343.682574 -352.679)
			(xy 343.69248 -352.699574) (xy 343.701878 -352.70694) (xy 343.724038 -352.725146) (xy 343.763173 -352.767067)
			(xy 343.795596 -352.814372) (xy 343.820576 -352.865995) (xy 343.837551 -352.920775) (xy 343.846139 -352.977477)
			(xy 343.846658 -353.006152) (xy 343.846172 -353.033403) (xy 343.838416 -353.087351) (xy 343.823061 -353.139646)
			(xy 343.800419 -353.189223) (xy 343.770953 -353.235073) (xy 343.735262 -353.276264) (xy 343.694071 -353.311955)
			(xy 343.648221 -353.341421) (xy 343.598644 -353.364063) (xy 343.546349 -353.379418) (xy 343.492401 -353.387174)
			(xy 343.437899 -353.387174) (xy 343.383951 -353.379418) (xy 343.331656 -353.364063) (xy 343.282079 -353.341421)
			(xy 343.236229 -353.311955) (xy 343.195038 -353.276264) (xy 343.159347 -353.235073) (xy 343.129881 -353.189223)
			(xy 343.107239 -353.139646) (xy 343.091884 -353.087351) (xy 343.084128 -353.033403) (xy 343.083642 -353.006152)
			(xy 343.08419 -352.977448) (xy 343.092792 -352.920687) (xy 343.109794 -352.865854) (xy 343.134813 -352.814184)
			(xy 343.167286 -352.766842) (xy 343.20648 -352.724895) (xy 343.228676 -352.706686) (xy 343.238074 -352.69932)
			(xy 343.24798 -352.678746) (xy 343.24798 -352.575368) (xy 343.238074 -352.554794) (xy 343.228676 -352.547428)
			(xy 343.216925 -352.537922) (xy 343.194803 -352.517321) (xy 343.18448 -352.50628) (xy 343.177622 -352.49866)
			(xy 343.159588 -352.490278) (xy 343.067894 -352.48596) (xy 343.049352 -352.492564) (xy 343.041732 -352.499422)
			(xy 343.020373 -352.517836) (xy 342.973249 -352.548808) (xy 342.92208 -352.572511) (xy 342.895174 -352.580956)
			(xy 342.882474 -352.584766) (xy 342.864186 -352.603562) (xy 342.834722 -352.713036) (xy 342.841072 -352.738436)
			(xy 342.850216 -352.748342) (xy 342.869675 -352.769691) (xy 342.902554 -352.817185) (xy 342.927894 -352.869094)
			(xy 342.945115 -352.924231) (xy 342.953825 -352.981334) (xy 342.954356 -353.010216) (xy 342.953837 -353.037465)
			(xy 342.94608 -353.09141) (xy 342.930725 -353.143701) (xy 342.908086 -353.193275) (xy 342.878622 -353.239123)
			(xy 342.842934 -353.280312) (xy 342.801748 -353.316003) (xy 342.755903 -353.34547) (xy 342.706331 -353.368114)
			(xy 342.654041 -353.383473) (xy 342.600097 -353.391235) (xy 342.572848 -353.391724) (xy 342.545478 -353.391248)
			(xy 342.491298 -353.383436) (xy 342.438795 -353.36795) (xy 342.389048 -353.34511) (xy 342.343081 -353.315386)
			(xy 342.32215 -353.297744) (xy 342.315038 -353.291648) (xy 342.29802 -353.285298) (xy 342.212676 -353.285298)
			(xy 342.195658 -353.291648) (xy 342.188546 -353.297744) (xy 342.167613 -353.315385) (xy 342.121645 -353.345109)
			(xy 342.071899 -353.367955) (xy 342.019397 -353.383451) (xy 341.965219 -353.39128) (xy 341.910477 -353.39128)
			(xy 341.856299 -353.383451) (xy 341.803797 -353.367955) (xy 341.754051 -353.345109) (xy 341.708083 -353.315385)
			(xy 341.68715 -353.297744) (xy 341.680038 -353.291648) (xy 341.66302 -353.285298) (xy 341.577676 -353.285298)
			(xy 341.560658 -353.291648) (xy 341.553546 -353.297744) (xy 341.532613 -353.315385) (xy 341.486645 -353.345109)
			(xy 341.436899 -353.367955) (xy 341.384397 -353.383451) (xy 341.330219 -353.39128) (xy 341.275477 -353.39128)
			(xy 341.221299 -353.383451) (xy 341.168797 -353.367955) (xy 341.119051 -353.345109) (xy 341.073083 -353.315385)
			(xy 341.05215 -353.297744) (xy 341.045038 -353.291648) (xy 341.02802 -353.285298) (xy 340.942676 -353.285298)
			(xy 340.925658 -353.291648) (xy 340.918546 -353.297744) (xy 340.897613 -353.315382) (xy 340.85164 -353.345093)
			(xy 340.801893 -353.367928) (xy 340.749392 -353.38342) (xy 340.695217 -353.391249) (xy 340.667848 -353.391724)
			(xy 340.640597 -353.3912) (xy 340.586649 -353.38345) (xy 340.534353 -353.368101) (xy 340.484774 -353.345465)
			(xy 340.438922 -353.316004) (xy 340.397729 -353.280316) (xy 340.362035 -353.239129) (xy 340.332566 -353.193282)
			(xy 340.309921 -353.143707) (xy 340.294564 -353.091413) (xy 340.286804 -353.037467) (xy 340.28634 -353.010216)
			(xy 340.286927 -352.979985) (xy 340.296473 -352.920281) (xy 340.315313 -352.86283) (xy 340.342975 -352.809067)
			(xy 340.378769 -352.760338) (xy 340.399878 -352.73869) (xy 340.409022 -352.729546) (xy 340.416642 -352.704908)
			(xy 340.393782 -352.595688) (xy 340.377018 -352.57613) (xy 340.364826 -352.571558) (xy 340.340772 -352.561862)
			(xy 340.295307 -352.536913) (xy 340.253633 -352.506045) (xy 340.216515 -352.469825) (xy 340.200234 -352.449638)
			(xy 340.192664 -352.440885) (xy 340.171911 -352.430699) (xy 340.160356 -352.43008) (xy 340.080092 -352.43008)
			(xy 340.068525 -352.430653) (xy 340.047754 -352.440847) (xy 340.040214 -352.449638) (xy 340.025838 -352.467546)
			(xy 339.993492 -352.500146) (xy 339.975698 -352.514662) (xy 339.9663 -352.522028) (xy 339.956394 -352.542602)
			(xy 339.956394 -352.64598) (xy 339.9663 -352.666554) (xy 339.975698 -352.67392) (xy 339.997852 -352.692132)
			(xy 340.036987 -352.734053) (xy 340.06941 -352.781356) (xy 340.094391 -352.832978) (xy 340.111367 -352.887756)
			(xy 340.119957 -352.944458) (xy 340.120478 -352.973132) (xy 340.119992 -353.000383) (xy 340.112236 -353.054331)
			(xy 340.096881 -353.106626) (xy 340.074239 -353.156203) (xy 340.044773 -353.202053) (xy 340.009082 -353.243244)
			(xy 339.967891 -353.278935) (xy 339.922041 -353.308401) (xy 339.872464 -353.331043) (xy 339.820169 -353.346398)
			(xy 339.766221 -353.354154) (xy 339.711719 -353.354154) (xy 339.657771 -353.346398) (xy 339.605476 -353.331043)
			(xy 339.555899 -353.308401) (xy 339.510049 -353.278935) (xy 339.468858 -353.243244) (xy 339.433167 -353.202053)
			(xy 339.403701 -353.156203) (xy 339.381059 -353.106626) (xy 339.365704 -353.054331) (xy 339.357948 -353.000383)
			(xy 339.357462 -352.973132) (xy 332.413864 -352.973132) (xy 332.413864 -354.14839) (xy 332.413428 -354.168396)
			(xy 332.405689 -354.20765) (xy 332.390429 -354.244635) (xy 332.368237 -354.277926) (xy 332.354428 -354.292408)
			(xy 327.544684 -359.102152) (xy 335.533238 -359.102152) (xy 335.533763 -359.074042) (xy 335.542002 -359.018429)
			(xy 335.558308 -358.964625) (xy 335.582329 -358.913795) (xy 335.613546 -358.867038) (xy 335.632044 -358.845866)
			(xy 335.638648 -358.838754) (xy 335.645252 -358.82199) (xy 335.646522 -358.736138) (xy 335.640426 -358.71912)
			(xy 335.63433 -358.711754) (xy 335.61724 -358.690976) (xy 335.58848 -358.645509) (xy 335.566395 -358.596451)
			(xy 335.551422 -358.544777) (xy 335.54386 -358.491512) (xy 335.543398 -358.464612) (xy 335.543867 -358.437359)
			(xy 335.551622 -358.383408) (xy 335.566977 -358.33111) (xy 335.589618 -358.28153) (xy 335.619086 -358.235676)
			(xy 335.654779 -358.194483) (xy 335.695971 -358.158789) (xy 335.741824 -358.129321) (xy 335.791404 -358.106679)
			(xy 335.843702 -358.091323) (xy 335.897653 -358.083567) (xy 335.924906 -358.083104) (xy 335.953823 -358.083617)
			(xy 336.010995 -358.092347) (xy 336.066194 -358.109606) (xy 336.118155 -358.134998) (xy 336.165689 -358.167943)
			(xy 336.207706 -358.207684) (xy 336.225896 -358.23017) (xy 336.233452 -358.238937) (xy 336.254216 -358.249115)
			(xy 336.265774 -358.249728) (xy 336.346038 -358.249728) (xy 336.357605 -358.249147) (xy 336.378378 -358.238962)
			(xy 336.385916 -358.23017) (xy 336.402669 -358.209387) (xy 336.441023 -358.172257) (xy 336.484177 -358.140835)
			(xy 336.531291 -358.115736) (xy 336.581443 -358.09745) (xy 336.633654 -358.086333) (xy 336.686906 -358.082603)
			(xy 336.740158 -358.086333) (xy 336.792369 -358.09745) (xy 336.842521 -358.115736) (xy 336.889635 -358.140835)
			(xy 336.932789 -358.172257) (xy 336.971143 -358.209387) (xy 336.987896 -358.23017) (xy 336.995452 -358.238937)
			(xy 337.016216 -358.249115) (xy 337.027774 -358.249728) (xy 337.108038 -358.249728) (xy 337.119605 -358.249147)
			(xy 337.140378 -358.238962) (xy 337.147916 -358.23017) (xy 337.16609 -358.207673) (xy 337.208115 -358.16794)
			(xy 337.255653 -358.135003) (xy 337.307618 -358.109617) (xy 337.362818 -358.092364) (xy 337.419989 -358.083638)
			(xy 337.448906 -358.083104) (xy 337.477834 -358.083626) (xy 337.535025 -358.092383) (xy 337.590236 -358.109678)
			(xy 337.642201 -358.135116) (xy 337.689727 -358.168113) (xy 337.731722 -358.207911) (xy 337.749896 -358.230424)
			(xy 337.757262 -358.239568) (xy 337.777582 -358.249728) (xy 337.880452 -358.251252) (xy 337.90128 -358.2416)
			(xy 337.908646 -358.232456) (xy 337.915758 -358.224074) (xy 337.921854 -358.216962) (xy 337.928204 -358.199944)
			(xy 337.928204 -358.1146) (xy 337.921854 -358.097582) (xy 337.915758 -358.09047) (xy 337.898131 -358.069528)
			(xy 337.868419 -358.023557) (xy 337.845581 -357.973812) (xy 337.830087 -357.921314) (xy 337.822254 -357.86714)
			(xy 337.821778 -357.839772) (xy 337.822252 -357.812521) (xy 337.830012 -357.758573) (xy 337.84537 -357.706279)
			(xy 337.868013 -357.656703) (xy 337.897481 -357.610853) (xy 337.933174 -357.569664) (xy 337.974364 -357.533973)
			(xy 338.020215 -357.504506) (xy 338.069792 -357.481865) (xy 338.122087 -357.466509) (xy 338.176035 -357.458751)
			(xy 338.203286 -357.458264) (xy 338.232204 -357.458768) (xy 338.289377 -357.467497) (xy 338.344577 -357.484756)
			(xy 338.396539 -357.51015) (xy 338.444072 -357.543097) (xy 338.486087 -357.582842) (xy 338.504276 -357.60533)
			(xy 338.511847 -357.614082) (xy 338.532599 -357.62427) (xy 338.544154 -357.624888) (xy 338.624418 -357.624888)
			(xy 338.635988 -357.624332) (xy 338.656759 -357.614128) (xy 338.664296 -357.60533) (xy 338.681049 -357.584547)
			(xy 338.719403 -357.547417) (xy 338.762557 -357.515995) (xy 338.809671 -357.490896) (xy 338.859823 -357.47261)
			(xy 338.912034 -357.461493) (xy 338.965286 -357.457763) (xy 339.018538 -357.461493) (xy 339.070749 -357.47261)
			(xy 339.120901 -357.490896) (xy 339.168015 -357.515995) (xy 339.211169 -357.547417) (xy 339.249523 -357.584547)
			(xy 339.266276 -357.60533) (xy 339.273847 -357.614082) (xy 339.294599 -357.62427) (xy 339.306154 -357.624888)
			(xy 339.386418 -357.624888) (xy 339.397988 -357.624332) (xy 339.418759 -357.614128) (xy 339.426296 -357.60533)
			(xy 339.444497 -357.582855) (xy 339.486514 -357.543118) (xy 339.534046 -357.510177) (xy 339.586006 -357.484787)
			(xy 339.641202 -357.467529) (xy 339.69837 -357.458799) (xy 339.727286 -357.458264) (xy 339.754536 -357.458791)
			(xy 339.80848 -357.466545) (xy 339.860773 -357.481897) (xy 339.910348 -357.504534) (xy 339.956197 -357.533997)
			(xy 339.997386 -357.569684) (xy 340.033078 -357.610869) (xy 340.062545 -357.656715) (xy 340.085188 -357.706288)
			(xy 340.100546 -357.758579) (xy 340.108306 -357.812522) (xy 340.108794 -357.839772) (xy 340.108313 -357.867142)
			(xy 340.100499 -357.92132) (xy 340.085013 -357.973823) (xy 340.062175 -358.02357) (xy 340.032454 -358.069538)
			(xy 340.030165 -358.072254) (xy 340.314959 -358.072254) (xy 340.314959 -358.017746) (xy 340.322717 -357.963791)
			(xy 340.338075 -357.911491) (xy 340.360721 -357.861908) (xy 340.390192 -357.816054) (xy 340.42589 -357.77486)
			(xy 340.467087 -357.739167) (xy 340.512945 -357.709701) (xy 340.56253 -357.687061) (xy 340.614833 -357.671708)
			(xy 340.668787 -357.663956) (xy 340.696042 -357.663496) (xy 340.723411 -357.663997) (xy 340.777589 -357.671807)
			(xy 340.830091 -357.687288) (xy 340.879839 -357.710121) (xy 340.925807 -357.739838) (xy 340.94674 -357.757476)
			(xy 340.953852 -357.763572) (xy 340.97087 -357.769922) (xy 341.056214 -357.769922) (xy 341.073232 -357.763572)
			(xy 341.080344 -357.757476) (xy 341.101277 -357.739835) (xy 341.147245 -357.710111) (xy 341.196991 -357.687265)
			(xy 341.249493 -357.671769) (xy 341.303671 -357.66394) (xy 341.358413 -357.66394) (xy 341.412591 -357.671769)
			(xy 341.465093 -357.687265) (xy 341.514839 -357.710111) (xy 341.560807 -357.739835) (xy 341.58174 -357.757476)
			(xy 341.588852 -357.763572) (xy 341.60587 -357.769922) (xy 341.691214 -357.769922) (xy 341.708232 -357.763572)
			(xy 341.715344 -357.757476) (xy 341.736277 -357.739835) (xy 341.782245 -357.710111) (xy 341.831991 -357.687265)
			(xy 341.884493 -357.671769) (xy 341.938671 -357.66394) (xy 341.993413 -357.66394) (xy 342.047591 -357.671769)
			(xy 342.100093 -357.687265) (xy 342.149839 -357.710111) (xy 342.195807 -357.739835) (xy 342.21674 -357.757476)
			(xy 342.223852 -357.763572) (xy 342.24087 -357.769922) (xy 342.326214 -357.769922) (xy 342.343232 -357.763572)
			(xy 342.350344 -357.757476) (xy 342.371283 -357.739846) (xy 342.417254 -357.710134) (xy 342.467 -357.687296)
			(xy 342.519499 -357.671803) (xy 342.573673 -357.663972) (xy 342.601042 -357.663496) (xy 342.628292 -357.663977)
			(xy 342.682235 -357.671738) (xy 342.734526 -357.687097) (xy 342.784098 -357.709741) (xy 342.829944 -357.739209)
			(xy 342.871129 -357.7749) (xy 342.906817 -357.81609) (xy 342.936279 -357.861939) (xy 342.958918 -357.911514)
			(xy 342.974271 -357.963806) (xy 342.982026 -358.01775) (xy 342.982026 -358.07225) (xy 342.974271 -358.126194)
			(xy 342.958918 -358.178486) (xy 342.936279 -358.228061) (xy 342.906817 -358.27391) (xy 342.871129 -358.3151)
			(xy 342.829944 -358.350791) (xy 342.784098 -358.380259) (xy 342.734526 -358.402903) (xy 342.682235 -358.418262)
			(xy 342.628292 -358.426023) (xy 342.601042 -358.426512) (xy 342.573673 -358.426018) (xy 342.519495 -358.418207)
			(xy 342.466992 -358.402724) (xy 342.417245 -358.379888) (xy 342.371277 -358.35017) (xy 342.350344 -358.332532)
			(xy 342.343232 -358.326436) (xy 342.326214 -358.320086) (xy 342.24087 -358.320086) (xy 342.223852 -358.326436)
			(xy 342.21674 -358.332532) (xy 342.195807 -358.350173) (xy 342.149839 -358.379897) (xy 342.100093 -358.402743)
			(xy 342.047591 -358.418239) (xy 341.993413 -358.426068) (xy 341.938671 -358.426068) (xy 341.884493 -358.418239)
			(xy 341.831991 -358.402743) (xy 341.782245 -358.379897) (xy 341.736277 -358.350173) (xy 341.715344 -358.332532)
			(xy 341.708232 -358.326436) (xy 341.691214 -358.320086) (xy 341.60587 -358.320086) (xy 341.588852 -358.326436)
			(xy 341.58174 -358.332532) (xy 341.560807 -358.350173) (xy 341.514839 -358.379897) (xy 341.465093 -358.402743)
			(xy 341.412591 -358.418239) (xy 341.358413 -358.426068) (xy 341.303671 -358.426068) (xy 341.249493 -358.418239)
			(xy 341.196991 -358.402743) (xy 341.147245 -358.379897) (xy 341.101277 -358.350173) (xy 341.080344 -358.332532)
			(xy 341.073232 -358.326436) (xy 341.056214 -358.320086) (xy 340.97087 -358.320086) (xy 340.953852 -358.326436)
			(xy 340.94674 -358.332532) (xy 340.925808 -358.350171) (xy 340.879835 -358.379882) (xy 340.830087 -358.402717)
			(xy 340.777587 -358.418208) (xy 340.723411 -358.426037) (xy 340.696042 -358.426512) (xy 340.668787 -358.426044)
			(xy 340.614833 -358.418292) (xy 340.56253 -358.402939) (xy 340.512945 -358.380299) (xy 340.467087 -358.350833)
			(xy 340.42589 -358.31514) (xy 340.390192 -358.273946) (xy 340.360721 -358.228092) (xy 340.338075 -358.178509)
			(xy 340.322717 -358.126209) (xy 340.314959 -358.072254) (xy 340.030165 -358.072254) (xy 340.014814 -358.09047)
			(xy 340.008718 -358.097582) (xy 340.002368 -358.1146) (xy 340.002368 -358.199944) (xy 340.008718 -358.216962)
			(xy 340.014814 -358.224074) (xy 340.032457 -358.245003) (xy 340.062167 -358.290977) (xy 340.085002 -358.340725)
			(xy 340.100493 -358.393227) (xy 340.10832 -358.447403) (xy 340.108794 -358.474772) (xy 340.1083 -358.502884)
			(xy 340.100057 -358.558499) (xy 340.083744 -358.612304) (xy 340.059716 -358.663133) (xy 340.02849 -358.709888)
			(xy 340.009988 -358.731058) (xy 340.003384 -358.73817) (xy 339.99678 -358.754934) (xy 339.99551 -358.840786)
			(xy 340.001606 -358.857804) (xy 340.007702 -358.86517) (xy 340.024793 -358.885948) (xy 340.053555 -358.931414)
			(xy 340.075641 -358.980471) (xy 340.090613 -359.032146) (xy 340.098173 -359.085412) (xy 340.098634 -359.112312)
			(xy 340.098109 -359.141265) (xy 340.089351 -359.198505) (xy 340.072036 -359.253762) (xy 340.046565 -359.305765)
			(xy 340.013522 -359.353319) (xy 339.993986 -359.374694) (xy 339.987128 -359.38206) (xy 339.980016 -359.400348)
			(xy 339.981286 -359.491534) (xy 339.988906 -359.509568) (xy 339.996018 -359.51668) (xy 340.004582 -359.525305)
			(xy 340.020722 -359.543481) (xy 340.028276 -359.553002) (xy 340.035852 -359.561749) (xy 340.0566 -359.57194)
			(xy 340.068154 -359.57256) (xy 340.148418 -359.57256) (xy 340.159989 -359.572014) (xy 340.180761 -359.561803)
			(xy 340.188296 -359.553002) (xy 340.206705 -359.530327) (xy 340.249229 -359.490296) (xy 340.29736 -359.457215)
			(xy 340.323424 -359.444036) (xy 340.332822 -359.439464) (xy 340.346284 -359.423716) (xy 340.37524 -359.3338)
			(xy 340.373462 -359.313226) (xy 340.368382 -359.304082) (xy 340.353844 -359.27595) (xy 340.333234 -359.216076)
			(xy 340.322781 -359.153624) (xy 340.322154 -359.121964) (xy 340.322644 -359.094714) (xy 340.330405 -359.040768)
			(xy 340.345762 -358.988476) (xy 340.368405 -358.938901) (xy 340.397871 -358.893052) (xy 340.433562 -358.851864)
			(xy 340.474751 -358.816173) (xy 340.520599 -358.786706) (xy 340.570174 -358.764063) (xy 340.622466 -358.748705)
			(xy 340.676412 -358.740944) (xy 340.703662 -358.740456) (xy 340.731032 -358.740931) (xy 340.785211 -358.748744)
			(xy 340.837715 -358.764231) (xy 340.887462 -358.787071) (xy 340.933429 -358.816795) (xy 340.95436 -358.834436)
			(xy 340.961472 -358.840532) (xy 340.97849 -358.846882) (xy 341.063834 -358.846882) (xy 341.080852 -358.840532)
			(xy 341.087964 -358.834436) (xy 341.108897 -358.816795) (xy 341.154865 -358.787071) (xy 341.204611 -358.764225)
			(xy 341.257113 -358.748729) (xy 341.311291 -358.7409) (xy 341.366033 -358.7409) (xy 341.420211 -358.748729)
			(xy 341.472713 -358.764225) (xy 341.522459 -358.787071) (xy 341.568427 -358.816795) (xy 341.58936 -358.834436)
			(xy 341.596472 -358.840532) (xy 341.61349 -358.846882) (xy 341.698834 -358.846882) (xy 341.715852 -358.840532)
			(xy 341.722964 -358.834436) (xy 341.743897 -358.816795) (xy 341.789865 -358.787071) (xy 341.839611 -358.764225)
			(xy 341.892113 -358.748729) (xy 341.946291 -358.7409) (xy 342.001033 -358.7409) (xy 342.055211 -358.748729)
			(xy 342.107713 -358.764225) (xy 342.157459 -358.787071) (xy 342.203427 -358.816795) (xy 342.22436 -358.834436)
			(xy 342.231472 -358.840532) (xy 342.24849 -358.846882) (xy 342.333834 -358.846882) (xy 342.350852 -358.840532)
			(xy 342.357964 -358.834436) (xy 342.378903 -358.816806) (xy 342.424874 -358.787091) (xy 342.474619 -358.764253)
			(xy 342.527118 -358.74876) (xy 342.581293 -358.740931) (xy 342.608662 -358.740456) (xy 342.635912 -358.740991)
			(xy 342.689859 -358.748741) (xy 342.742153 -358.764091) (xy 342.791731 -358.786726) (xy 342.837582 -358.816187)
			(xy 342.878774 -358.851873) (xy 342.914469 -358.893058) (xy 342.943938 -358.938904) (xy 342.966583 -358.988477)
			(xy 342.981943 -359.040769) (xy 342.989704 -359.094714) (xy 342.99017 -359.121964) (xy 342.989735 -359.147938)
			(xy 342.982694 -359.199406) (xy 342.968738 -359.249444) (xy 342.948123 -359.297126) (xy 342.935052 -359.319576)
			(xy 342.929718 -359.328212) (xy 342.92667 -359.348278) (xy 342.949276 -359.43794) (xy 342.961214 -359.454196)
			(xy 342.970104 -359.45953) (xy 342.990317 -359.47195) (xy 343.027799 -359.501031) (xy 343.061396 -359.534525)
			(xy 343.076276 -359.553002) (xy 343.083852 -359.561749) (xy 343.1046 -359.57194) (xy 343.116154 -359.57256)
			(xy 343.196418 -359.57256) (xy 343.207989 -359.572014) (xy 343.228761 -359.561803) (xy 343.236296 -359.553002)
			(xy 343.243109 -359.544383) (xy 343.257596 -359.527862) (xy 343.265252 -359.519982) (xy 343.272364 -359.512616)
			(xy 343.279984 -359.494328) (xy 343.279984 -359.402888) (xy 343.272364 -359.3846) (xy 343.265252 -359.377234)
			(xy 343.244854 -359.3557) (xy 343.210314 -359.307482) (xy 343.183653 -359.254498) (xy 343.165516 -359.198027)
			(xy 343.156339 -359.139428) (xy 343.155778 -359.109772) (xy 343.156209 -359.0824) (xy 343.164032 -359.028219)
			(xy 343.179528 -358.975715) (xy 343.202379 -358.925968) (xy 343.232112 -358.880004) (xy 343.249758 -358.859074)
			(xy 343.255854 -358.851962) (xy 343.262204 -358.834944) (xy 343.262204 -358.7496) (xy 343.255854 -358.732582)
			(xy 343.249758 -358.72547) (xy 343.232089 -358.70456) (xy 343.202363 -358.658589) (xy 343.179517 -358.608839)
			(xy 343.164022 -358.556333) (xy 343.156195 -358.502151) (xy 343.156198 -358.447407) (xy 343.164031 -358.393225)
			(xy 343.179532 -358.340721) (xy 343.202383 -358.290974) (xy 343.232114 -358.245006) (xy 343.249758 -358.224074)
			(xy 343.255854 -358.216962) (xy 343.262204 -358.199944) (xy 343.262204 -358.1146) (xy 343.255854 -358.097582)
			(xy 343.249758 -358.09047) (xy 343.232131 -358.069528) (xy 343.202419 -358.023557) (xy 343.179581 -357.973812)
			(xy 343.164087 -357.921314) (xy 343.156254 -357.86714) (xy 343.155778 -357.839772) (xy 343.156252 -357.812521)
			(xy 343.164012 -357.758573) (xy 343.17937 -357.706279) (xy 343.202013 -357.656703) (xy 343.231481 -357.610853)
			(xy 343.267174 -357.569664) (xy 343.308364 -357.533973) (xy 343.354215 -357.504506) (xy 343.403792 -357.481865)
			(xy 343.456087 -357.466509) (xy 343.510035 -357.458751) (xy 343.537286 -357.458264) (xy 343.566204 -357.458768)
			(xy 343.623377 -357.467497) (xy 343.678577 -357.484756) (xy 343.730539 -357.51015) (xy 343.778072 -357.543097)
			(xy 343.820087 -357.582842) (xy 343.838276 -357.60533) (xy 343.845847 -357.614082) (xy 343.866599 -357.62427)
			(xy 343.878154 -357.624888) (xy 343.958418 -357.624888) (xy 343.969988 -357.624332) (xy 343.990759 -357.614128)
			(xy 343.998296 -357.60533) (xy 344.015049 -357.584547) (xy 344.053403 -357.547417) (xy 344.096557 -357.515995)
			(xy 344.143671 -357.490896) (xy 344.193823 -357.47261) (xy 344.246034 -357.461493) (xy 344.299286 -357.457763)
			(xy 344.352538 -357.461493) (xy 344.404749 -357.47261) (xy 344.454901 -357.490896) (xy 344.502015 -357.515995)
			(xy 344.545169 -357.547417) (xy 344.583523 -357.584547) (xy 344.600276 -357.60533) (xy 344.607847 -357.614082)
			(xy 344.628599 -357.62427) (xy 344.640154 -357.624888) (xy 344.720418 -357.624888) (xy 344.731988 -357.624332)
			(xy 344.752759 -357.614128) (xy 344.760296 -357.60533) (xy 344.778497 -357.582855) (xy 344.820514 -357.543118)
			(xy 344.868046 -357.510177) (xy 344.920006 -357.484787) (xy 344.975202 -357.467529) (xy 345.03237 -357.458799)
			(xy 345.061286 -357.458264) (xy 345.088536 -357.458791) (xy 345.14248 -357.466545) (xy 345.194773 -357.481897)
			(xy 345.244348 -357.504534) (xy 345.290197 -357.533997) (xy 345.331386 -357.569684) (xy 345.367078 -357.610869)
			(xy 345.396545 -357.656715) (xy 345.419188 -357.706288) (xy 345.434546 -357.758579) (xy 345.442306 -357.812522)
			(xy 345.442794 -357.839772) (xy 345.442313 -357.867142) (xy 345.434499 -357.92132) (xy 345.419013 -357.973823)
			(xy 345.396175 -358.02357) (xy 345.366454 -358.069538) (xy 345.348814 -358.09047) (xy 345.342718 -358.097582)
			(xy 345.336368 -358.1146) (xy 345.336368 -358.199944) (xy 345.342718 -358.216962) (xy 345.348814 -358.224074)
			(xy 345.366426 -358.24503) (xy 345.396148 -358.290995) (xy 345.418993 -358.340737) (xy 345.43449 -358.393235)
			(xy 345.44232 -358.44741) (xy 345.442323 -358.502148) (xy 345.434499 -358.556323) (xy 345.419008 -358.608823)
			(xy 345.396169 -358.658568) (xy 345.366451 -358.704536) (xy 345.348814 -358.72547) (xy 345.342718 -358.732582)
			(xy 345.336368 -358.7496) (xy 345.336368 -358.834944) (xy 345.342718 -358.851962) (xy 345.348814 -358.859074)
			(xy 345.366457 -358.880003) (xy 345.396167 -358.925977) (xy 345.419002 -358.975725) (xy 345.434493 -359.028227)
			(xy 345.44232 -359.082403) (xy 345.442794 -359.109772) (xy 345.442239 -359.139428) (xy 345.433051 -359.198023)
			(xy 345.414908 -359.254492) (xy 345.388247 -359.307474) (xy 345.35371 -359.355693) (xy 345.33332 -359.377234)
			(xy 345.326208 -359.3846) (xy 345.318588 -359.402888) (xy 345.318588 -359.494328) (xy 345.326208 -359.512616)
			(xy 345.33332 -359.519982) (xy 345.353721 -359.541514) (xy 345.388262 -359.589732) (xy 345.414922 -359.642716)
			(xy 345.433059 -359.699188) (xy 345.442234 -359.757787) (xy 345.442794 -359.787444) (xy 345.442363 -359.814697)
			(xy 345.4346 -359.868647) (xy 345.419239 -359.920944) (xy 345.396592 -359.970522) (xy 345.367119 -360.016373)
			(xy 345.331422 -360.057563) (xy 345.290227 -360.093254) (xy 345.244371 -360.122719) (xy 345.19479 -360.145359)
			(xy 345.142491 -360.160713) (xy 345.088539 -360.168467) (xy 345.061286 -360.168952) (xy 345.03237 -360.16839)
			(xy 344.975201 -360.159673) (xy 344.920002 -360.142424) (xy 344.86804 -360.117041) (xy 344.820505 -360.084104)
			(xy 344.778487 -360.044369) (xy 344.760296 -360.021886) (xy 344.752734 -360.013125) (xy 344.731975 -360.002942)
			(xy 344.720418 -360.002328) (xy 344.640154 -360.002328) (xy 344.628589 -360.00292) (xy 344.607817 -360.013098)
			(xy 344.600276 -360.021886) (xy 344.588084 -360.036618) (xy 344.581988 -360.04373) (xy 344.575638 -360.061256)
			(xy 344.576908 -360.147616) (xy 344.583766 -360.164888) (xy 344.59037 -360.171746) (xy 344.609168 -360.19302)
			(xy 344.640975 -360.240039) (xy 344.665456 -360.291255) (xy 344.682071 -360.345536) (xy 344.690451 -360.40168)
			(xy 344.690954 -360.430064) (xy 344.690388 -360.457312) (xy 344.682638 -360.511255) (xy 344.66729 -360.563545)
			(xy 344.644656 -360.613119) (xy 344.615198 -360.658967) (xy 344.579515 -360.700157) (xy 344.538333 -360.735849)
			(xy 344.492491 -360.765317) (xy 344.442922 -360.787961) (xy 344.390635 -360.803321) (xy 344.336694 -360.811083)
			(xy 344.309446 -360.811572) (xy 344.28053 -360.811031) (xy 344.223359 -360.802308) (xy 344.16816 -360.785056)
			(xy 344.116198 -360.759668) (xy 344.068664 -360.726728) (xy 344.026646 -360.68699) (xy 344.008456 -360.664506)
			(xy 344.000908 -360.65573) (xy 343.980139 -360.645554) (xy 343.968578 -360.644948) (xy 343.888314 -360.644948)
			(xy 343.876745 -360.64551) (xy 343.855973 -360.655709) (xy 343.848436 -360.664506) (xy 343.836244 -360.679492)
			(xy 343.830148 -360.68635) (xy 343.823798 -360.703876) (xy 343.824814 -360.789728) (xy 343.831418 -360.807)
			(xy 343.837768 -360.814112) (xy 343.856251 -360.835263) (xy 343.887441 -360.881978) (xy 343.911455 -360.932756)
			(xy 343.927775 -360.986503) (xy 343.936051 -361.04206) (xy 343.936574 -361.070144) (xy 343.936163 -361.097398)
			(xy 343.9284 -361.15135) (xy 343.913037 -361.203648) (xy 343.890388 -361.253228) (xy 343.860914 -361.29908)
			(xy 343.825215 -361.34027) (xy 343.784017 -361.375961) (xy 343.738159 -361.405426) (xy 343.688575 -361.428064)
			(xy 343.636274 -361.443416) (xy 343.58232 -361.451169) (xy 343.555066 -361.451652) (xy 343.52615 -361.451104)
			(xy 343.468979 -361.442384) (xy 343.41378 -361.425133) (xy 343.361818 -361.399747) (xy 343.314284 -361.366807)
			(xy 343.272267 -361.32707) (xy 343.254076 -361.304586) (xy 343.246522 -361.295816) (xy 343.225757 -361.285637)
			(xy 343.214198 -361.285028) (xy 343.133934 -361.285028) (xy 343.122367 -361.285608) (xy 343.101596 -361.295795)
			(xy 343.094056 -361.304586) (xy 343.077303 -361.325369) (xy 343.038949 -361.362499) (xy 342.995795 -361.393921)
			(xy 342.948681 -361.41902) (xy 342.898529 -361.437306) (xy 342.846318 -361.448423) (xy 342.793066 -361.452153)
			(xy 342.739814 -361.448423) (xy 342.687603 -361.437306) (xy 342.637451 -361.41902) (xy 342.590337 -361.393921)
			(xy 342.547183 -361.362499) (xy 342.508829 -361.325369) (xy 342.492076 -361.304586) (xy 342.484522 -361.295816)
			(xy 342.463757 -361.285637) (xy 342.452198 -361.285028) (xy 342.371934 -361.285028) (xy 342.360367 -361.285608)
			(xy 342.339596 -361.295795) (xy 342.332056 -361.304586) (xy 342.315303 -361.325369) (xy 342.276949 -361.362499)
			(xy 342.233795 -361.393921) (xy 342.186681 -361.41902) (xy 342.136529 -361.437306) (xy 342.084318 -361.448423)
			(xy 342.031066 -361.452153) (xy 341.977814 -361.448423) (xy 341.925603 -361.437306) (xy 341.875451 -361.41902)
			(xy 341.828337 -361.393921) (xy 341.785183 -361.362499) (xy 341.746829 -361.325369) (xy 341.730076 -361.304586)
			(xy 341.722522 -361.295816) (xy 341.701757 -361.285637) (xy 341.690198 -361.285028) (xy 341.609934 -361.285028)
			(xy 341.598367 -361.285608) (xy 341.577596 -361.295795) (xy 341.570056 -361.304586) (xy 341.553303 -361.325369)
			(xy 341.514949 -361.362499) (xy 341.471795 -361.393921) (xy 341.424681 -361.41902) (xy 341.374529 -361.437306)
			(xy 341.322318 -361.448423) (xy 341.269066 -361.452153) (xy 341.215814 -361.448423) (xy 341.163603 -361.437306)
			(xy 341.113451 -361.41902) (xy 341.066337 -361.393921) (xy 341.023183 -361.362499) (xy 340.984829 -361.325369)
			(xy 340.968076 -361.304586) (xy 340.960522 -361.295816) (xy 340.939757 -361.285637) (xy 340.928198 -361.285028)
			(xy 340.847934 -361.285028) (xy 340.836367 -361.285608) (xy 340.815596 -361.295795) (xy 340.808056 -361.304586)
			(xy 340.791303 -361.325369) (xy 340.752949 -361.362499) (xy 340.709795 -361.393921) (xy 340.662681 -361.41902)
			(xy 340.612529 -361.437306) (xy 340.560318 -361.448423) (xy 340.507066 -361.452153) (xy 340.453814 -361.448423)
			(xy 340.401603 -361.437306) (xy 340.351451 -361.41902) (xy 340.304337 -361.393921) (xy 340.261183 -361.362499)
			(xy 340.222829 -361.325369) (xy 340.206076 -361.304586) (xy 340.198522 -361.295816) (xy 340.177757 -361.285637)
			(xy 340.166198 -361.285028) (xy 340.085934 -361.285028) (xy 340.074367 -361.285608) (xy 340.053596 -361.295795)
			(xy 340.046056 -361.304586) (xy 340.029303 -361.325369) (xy 339.990949 -361.362499) (xy 339.947795 -361.393921)
			(xy 339.900681 -361.41902) (xy 339.850529 -361.437306) (xy 339.798318 -361.448423) (xy 339.745066 -361.452153)
			(xy 339.691814 -361.448423) (xy 339.639603 -361.437306) (xy 339.589451 -361.41902) (xy 339.542337 -361.393921)
			(xy 339.499183 -361.362499) (xy 339.460829 -361.325369) (xy 339.444076 -361.304586) (xy 339.436522 -361.295816)
			(xy 339.415757 -361.285637) (xy 339.404198 -361.285028) (xy 339.323934 -361.285028) (xy 339.312367 -361.285608)
			(xy 339.291596 -361.295795) (xy 339.284056 -361.304586) (xy 339.267303 -361.325369) (xy 339.228949 -361.362499)
			(xy 339.185795 -361.393921) (xy 339.138681 -361.41902) (xy 339.088529 -361.437306) (xy 339.036318 -361.448423)
			(xy 338.983066 -361.452153) (xy 338.929814 -361.448423) (xy 338.877603 -361.437306) (xy 338.827451 -361.41902)
			(xy 338.780337 -361.393921) (xy 338.737183 -361.362499) (xy 338.698829 -361.325369) (xy 338.682076 -361.304586)
			(xy 338.674522 -361.295816) (xy 338.653757 -361.285637) (xy 338.642198 -361.285028) (xy 338.561934 -361.285028)
			(xy 338.550367 -361.285608) (xy 338.529596 -361.295795) (xy 338.522056 -361.304586) (xy 338.503886 -361.327088)
			(xy 338.461863 -361.366822) (xy 338.414323 -361.39976) (xy 338.362358 -361.425145) (xy 338.307156 -361.442397)
			(xy 338.249983 -361.45112) (xy 338.221066 -361.451652) (xy 338.192139 -361.451095) (xy 338.134949 -361.442348)
			(xy 338.079737 -361.425061) (xy 338.027772 -361.399629) (xy 337.980246 -361.366638) (xy 337.93825 -361.326844)
			(xy 337.920076 -361.304332) (xy 337.91271 -361.295188) (xy 337.89239 -361.285028) (xy 337.78952 -361.283504)
			(xy 337.768692 -361.293156) (xy 337.761326 -361.3023) (xy 337.743109 -361.323664) (xy 337.701484 -361.361338)
			(xy 337.654786 -361.392503) (xy 337.604023 -361.416485) (xy 337.550294 -361.432766) (xy 337.494757 -361.440995)
			(xy 337.466686 -361.441492) (xy 337.437771 -361.440915) (xy 337.380603 -361.432199) (xy 337.325405 -361.414953)
			(xy 337.273443 -361.389572) (xy 337.225907 -361.356639) (xy 337.183888 -361.316907) (xy 337.165696 -361.294426)
			(xy 337.158144 -361.285654) (xy 337.137377 -361.275479) (xy 337.125818 -361.274868) (xy 337.045554 -361.274868)
			(xy 337.033987 -361.275446) (xy 337.013214 -361.285633) (xy 337.005676 -361.294426) (xy 336.988923 -361.315209)
			(xy 336.950569 -361.352339) (xy 336.907415 -361.383761) (xy 336.860301 -361.40886) (xy 336.810149 -361.427146)
			(xy 336.757938 -361.438263) (xy 336.704686 -361.441993) (xy 336.651434 -361.438263) (xy 336.599223 -361.427146)
			(xy 336.549071 -361.40886) (xy 336.501957 -361.383761) (xy 336.458803 -361.352339) (xy 336.420449 -361.315209)
			(xy 336.403696 -361.294426) (xy 336.396144 -361.285654) (xy 336.375377 -361.275479) (xy 336.363818 -361.274868)
			(xy 336.283554 -361.274868) (xy 336.271987 -361.275446) (xy 336.251214 -361.285633) (xy 336.243676 -361.294426)
			(xy 336.225505 -361.316926) (xy 336.18348 -361.356659) (xy 336.135941 -361.389596) (xy 336.083976 -361.414981)
			(xy 336.028775 -361.432234) (xy 335.971603 -361.440959) (xy 335.942686 -361.441492) (xy 335.915432 -361.441058)
			(xy 335.861479 -361.433299) (xy 335.80918 -361.41794) (xy 335.759598 -361.395295) (xy 335.713745 -361.365824)
			(xy 335.672552 -361.330127) (xy 335.636858 -361.288931) (xy 335.607391 -361.243075) (xy 335.584749 -361.193492)
			(xy 335.569395 -361.141191) (xy 335.56164 -361.087238) (xy 335.561178 -361.059984) (xy 335.561627 -361.032788)
			(xy 335.569312 -360.978943) (xy 335.584579 -360.926739) (xy 335.607118 -360.877238) (xy 335.63647 -360.831447)
			(xy 335.653888 -360.810556) (xy 335.659984 -360.803698) (xy 335.666334 -360.786172) (xy 335.665318 -360.70032)
			(xy 335.658714 -360.683048) (xy 335.652364 -360.675936) (xy 335.633861 -360.654801) (xy 335.602673 -360.608082)
			(xy 335.578663 -360.5573) (xy 335.562347 -360.50355) (xy 335.554077 -360.44799) (xy 335.553558 -360.419904)
			(xy 335.554016 -360.392735) (xy 335.561743 -360.338949) (xy 335.577025 -360.286804) (xy 335.599554 -360.237356)
			(xy 335.628874 -360.191607) (xy 335.646268 -360.17073) (xy 335.652364 -360.163618) (xy 335.658714 -360.146092)
			(xy 335.657444 -360.059732) (xy 335.650586 -360.04246) (xy 335.643982 -360.035602) (xy 335.625151 -360.014356)
			(xy 335.593351 -359.967329) (xy 335.568877 -359.916105) (xy 335.552269 -359.861819) (xy 335.543897 -359.805669)
			(xy 335.543398 -359.777284) (xy 335.543939 -359.748332) (xy 335.552696 -359.691093) (xy 335.570008 -359.635837)
			(xy 335.595475 -359.583834) (xy 335.628512 -359.536279) (xy 335.648046 -359.514902) (xy 335.654904 -359.507536)
			(xy 335.662016 -359.489248) (xy 335.660746 -359.398062) (xy 335.653126 -359.380028) (xy 335.646014 -359.372916)
			(xy 335.625019 -359.351305) (xy 335.589452 -359.302673) (xy 335.561974 -359.249053) (xy 335.54327 -359.191779)
			(xy 335.533803 -359.132277) (xy 335.533238 -359.102152) (xy 327.544684 -359.102152) (xy 325.179436 -361.4674)
			(xy 326.668382 -361.4674) (xy 326.672453 -361.411778) (xy 326.684579 -361.357341) (xy 326.704502 -361.30525)
			(xy 326.731798 -361.256615) (xy 326.765884 -361.212472) (xy 326.806033 -361.173763) (xy 326.851391 -361.141312)
			(xy 326.900991 -361.115811) (xy 326.953775 -361.097804) (xy 327.008618 -361.087674) (xy 327.064352 -361.085637)
			(xy 327.119789 -361.091737) (xy 327.173746 -361.105843) (xy 327.225075 -361.127655) (xy 327.240715 -361.1372)
			(xy 328.725782 -361.1372) (xy 328.729853 -361.081578) (xy 328.741979 -361.027141) (xy 328.761902 -360.97505)
			(xy 328.789198 -360.926415) (xy 328.823284 -360.882272) (xy 328.863433 -360.843563) (xy 328.908791 -360.811112)
			(xy 328.958391 -360.785611) (xy 329.011175 -360.767604) (xy 329.066018 -360.757474) (xy 329.121752 -360.755437)
			(xy 329.177189 -360.761537) (xy 329.231146 -360.775643) (xy 329.282475 -360.797455) (xy 329.330081 -360.826509)
			(xy 329.372949 -360.862184) (xy 329.410166 -360.903721) (xy 329.440939 -360.950234) (xy 329.464611 -361.000731)
			(xy 329.480679 -361.054138) (xy 329.488799 -361.109314) (xy 329.489308 -361.1372) (xy 330.021182 -361.1372)
			(xy 330.025253 -361.081578) (xy 330.037379 -361.027141) (xy 330.057302 -360.97505) (xy 330.084598 -360.926415)
			(xy 330.118684 -360.882272) (xy 330.158833 -360.843563) (xy 330.204191 -360.811112) (xy 330.253791 -360.785611)
			(xy 330.306575 -360.767604) (xy 330.361418 -360.757474) (xy 330.417152 -360.755437) (xy 330.472589 -360.761537)
			(xy 330.526546 -360.775643) (xy 330.577875 -360.797455) (xy 330.625481 -360.826509) (xy 330.668349 -360.862184)
			(xy 330.705566 -360.903721) (xy 330.736339 -360.950234) (xy 330.760011 -361.000731) (xy 330.776079 -361.054138)
			(xy 330.784199 -361.109314) (xy 330.784708 -361.1372) (xy 330.784199 -361.165086) (xy 330.776079 -361.220262)
			(xy 330.760011 -361.273669) (xy 330.736339 -361.324166) (xy 330.705566 -361.370679) (xy 330.668349 -361.412216)
			(xy 330.625481 -361.447891) (xy 330.577875 -361.476945) (xy 330.526546 -361.498757) (xy 330.472589 -361.512863)
			(xy 330.417152 -361.518963) (xy 330.361418 -361.516926) (xy 330.306575 -361.506796) (xy 330.253791 -361.488789)
			(xy 330.204191 -361.463288) (xy 330.158833 -361.430837) (xy 330.118684 -361.392128) (xy 330.084598 -361.347985)
			(xy 330.057302 -361.29935) (xy 330.037379 -361.247259) (xy 330.025253 -361.192822) (xy 330.021182 -361.1372)
			(xy 329.489308 -361.1372) (xy 329.488799 -361.165086) (xy 329.480679 -361.220262) (xy 329.464611 -361.273669)
			(xy 329.440939 -361.324166) (xy 329.410166 -361.370679) (xy 329.372949 -361.412216) (xy 329.330081 -361.447891)
			(xy 329.282475 -361.476945) (xy 329.231146 -361.498757) (xy 329.177189 -361.512863) (xy 329.121752 -361.518963)
			(xy 329.066018 -361.516926) (xy 329.011175 -361.506796) (xy 328.958391 -361.488789) (xy 328.908791 -361.463288)
			(xy 328.863433 -361.430837) (xy 328.823284 -361.392128) (xy 328.789198 -361.347985) (xy 328.761902 -361.29935)
			(xy 328.741979 -361.247259) (xy 328.729853 -361.192822) (xy 328.725782 -361.1372) (xy 327.240715 -361.1372)
			(xy 327.272681 -361.156709) (xy 327.315549 -361.192384) (xy 327.352766 -361.233921) (xy 327.383539 -361.280434)
			(xy 327.407211 -361.330931) (xy 327.423279 -361.384338) (xy 327.431399 -361.439514) (xy 327.431908 -361.4674)
			(xy 327.431399 -361.495286) (xy 327.423279 -361.550462) (xy 327.407211 -361.603869) (xy 327.383539 -361.654366)
			(xy 327.352766 -361.700879) (xy 327.315549 -361.742416) (xy 327.272681 -361.778091) (xy 327.225075 -361.807145)
			(xy 327.173746 -361.828957) (xy 327.119789 -361.843063) (xy 327.064352 -361.849163) (xy 327.008618 -361.847126)
			(xy 326.953775 -361.836996) (xy 326.900991 -361.818989) (xy 326.851391 -361.793488) (xy 326.806033 -361.761037)
			(xy 326.765884 -361.722328) (xy 326.731798 -361.678185) (xy 326.704502 -361.62955) (xy 326.684579 -361.577459)
			(xy 326.672453 -361.523022) (xy 326.668382 -361.4674) (xy 325.179436 -361.4674) (xy 324.036436 -362.6104)
			(xy 326.668382 -362.6104) (xy 326.672453 -362.554778) (xy 326.684579 -362.500341) (xy 326.704502 -362.44825)
			(xy 326.731798 -362.399615) (xy 326.765884 -362.355472) (xy 326.806033 -362.316763) (xy 326.851391 -362.284312)
			(xy 326.900991 -362.258811) (xy 326.953775 -362.240804) (xy 327.008618 -362.230674) (xy 327.064352 -362.228637)
			(xy 327.119789 -362.234737) (xy 327.173746 -362.248843) (xy 327.225075 -362.270655) (xy 327.272681 -362.299709)
			(xy 327.315549 -362.335384) (xy 327.352766 -362.376921) (xy 327.383539 -362.423434) (xy 327.407211 -362.473931)
			(xy 327.423279 -362.527338) (xy 327.431399 -362.582514) (xy 327.431908 -362.6104) (xy 327.431444 -362.6358)
			(xy 328.801982 -362.6358) (xy 328.806053 -362.580178) (xy 328.818179 -362.525741) (xy 328.838102 -362.47365)
			(xy 328.865398 -362.425015) (xy 328.899484 -362.380872) (xy 328.939633 -362.342163) (xy 328.984991 -362.309712)
			(xy 329.034591 -362.284211) (xy 329.087375 -362.266204) (xy 329.142218 -362.256074) (xy 329.197952 -362.254037)
			(xy 329.253389 -362.260137) (xy 329.307346 -362.274243) (xy 329.358675 -362.296055) (xy 329.406281 -362.325109)
			(xy 329.449149 -362.360784) (xy 329.486366 -362.402321) (xy 329.517139 -362.448834) (xy 329.540811 -362.499331)
			(xy 329.556879 -362.552738) (xy 329.564999 -362.607914) (xy 329.565508 -362.6358) (xy 330.300582 -362.6358)
			(xy 330.304653 -362.580178) (xy 330.316779 -362.525741) (xy 330.336702 -362.47365) (xy 330.363998 -362.425015)
			(xy 330.398084 -362.380872) (xy 330.438233 -362.342163) (xy 330.483591 -362.309712) (xy 330.533191 -362.284211)
			(xy 330.585975 -362.266204) (xy 330.640818 -362.256074) (xy 330.696552 -362.254037) (xy 330.751989 -362.260137)
			(xy 330.805946 -362.274243) (xy 330.857275 -362.296055) (xy 330.904881 -362.325109) (xy 330.947749 -362.360784)
			(xy 330.984966 -362.402321) (xy 331.015739 -362.448834) (xy 331.039411 -362.499331) (xy 331.055479 -362.552738)
			(xy 331.063599 -362.607914) (xy 331.064108 -362.6358) (xy 331.063599 -362.663686) (xy 331.055479 -362.718862)
			(xy 331.039411 -362.772269) (xy 331.015739 -362.822766) (xy 330.984966 -362.869279) (xy 330.947749 -362.910816)
			(xy 330.904881 -362.946491) (xy 330.857275 -362.975545) (xy 330.805946 -362.997357) (xy 330.751989 -363.011463)
			(xy 330.696552 -363.017563) (xy 330.640818 -363.015526) (xy 330.585975 -363.005396) (xy 330.533191 -362.987389)
			(xy 330.483591 -362.961888) (xy 330.438233 -362.929437) (xy 330.398084 -362.890728) (xy 330.363998 -362.846585)
			(xy 330.336702 -362.79795) (xy 330.316779 -362.745859) (xy 330.304653 -362.691422) (xy 330.300582 -362.6358)
			(xy 329.565508 -362.6358) (xy 329.564999 -362.663686) (xy 329.556879 -362.718862) (xy 329.540811 -362.772269)
			(xy 329.517139 -362.822766) (xy 329.486366 -362.869279) (xy 329.449149 -362.910816) (xy 329.406281 -362.946491)
			(xy 329.358675 -362.975545) (xy 329.307346 -362.997357) (xy 329.253389 -363.011463) (xy 329.197952 -363.017563)
			(xy 329.142218 -363.015526) (xy 329.087375 -363.005396) (xy 329.034591 -362.987389) (xy 328.984991 -362.961888)
			(xy 328.939633 -362.929437) (xy 328.899484 -362.890728) (xy 328.865398 -362.846585) (xy 328.838102 -362.79795)
			(xy 328.818179 -362.745859) (xy 328.806053 -362.691422) (xy 328.801982 -362.6358) (xy 327.431444 -362.6358)
			(xy 327.431399 -362.638286) (xy 327.423279 -362.693462) (xy 327.407211 -362.746869) (xy 327.383539 -362.797366)
			(xy 327.352766 -362.843879) (xy 327.315549 -362.885416) (xy 327.272681 -362.921091) (xy 327.225075 -362.950145)
			(xy 327.173746 -362.971957) (xy 327.119789 -362.986063) (xy 327.064352 -362.992163) (xy 327.008618 -362.990126)
			(xy 326.953775 -362.979996) (xy 326.900991 -362.961989) (xy 326.851391 -362.936488) (xy 326.806033 -362.904037)
			(xy 326.765884 -362.865328) (xy 326.731798 -362.821185) (xy 326.704502 -362.77255) (xy 326.684579 -362.720459)
			(xy 326.672453 -362.666022) (xy 326.668382 -362.6104) (xy 324.036436 -362.6104) (xy 322.891585 -363.755251)
			(xy 323.849978 -363.755251) (xy 323.849978 -363.700749) (xy 323.857734 -363.646801) (xy 323.873089 -363.594506)
			(xy 323.895731 -363.544929) (xy 323.925197 -363.499079) (xy 323.960888 -363.457888) (xy 324.002079 -363.422197)
			(xy 324.047929 -363.392731) (xy 324.097506 -363.370089) (xy 324.149801 -363.354734) (xy 324.203749 -363.346978)
			(xy 324.231 -363.346492) (xy 324.260231 -363.347055) (xy 324.318006 -363.355987) (xy 324.373743 -363.373627)
			(xy 324.426137 -363.399561) (xy 324.473962 -363.433183) (xy 324.5161 -363.473706) (xy 324.534276 -363.496606)
			(xy 324.542714 -363.507003) (xy 324.563918 -363.52334) (xy 324.588637 -363.533613) (xy 324.615175 -363.537118)
			(xy 324.641713 -363.533613) (xy 324.666432 -363.52334) (xy 324.687636 -363.507003) (xy 324.696074 -363.496606)
			(xy 324.714223 -363.473681) (xy 324.756356 -363.433141) (xy 324.804183 -363.399509) (xy 324.856584 -363.373571)
			(xy 324.912331 -363.355937) (xy 324.970115 -363.347019) (xy 324.99935 -363.346492) (xy 325.026605 -363.346952)
			(xy 325.080562 -363.354703) (xy 325.132865 -363.370055) (xy 325.182452 -363.392694) (xy 325.228311 -363.422161)
			(xy 325.26951 -363.457855) (xy 325.305209 -363.499049) (xy 325.334682 -363.544904) (xy 325.357328 -363.594488)
			(xy 325.372686 -363.64679) (xy 325.373406 -363.6518) (xy 326.693782 -363.6518) (xy 326.697853 -363.596178)
			(xy 326.709979 -363.541741) (xy 326.729902 -363.48965) (xy 326.757198 -363.441015) (xy 326.791284 -363.396872)
			(xy 326.831433 -363.358163) (xy 326.876791 -363.325712) (xy 326.926391 -363.300211) (xy 326.979175 -363.282204)
			(xy 327.034018 -363.272074) (xy 327.089752 -363.270037) (xy 327.145189 -363.276137) (xy 327.199146 -363.290243)
			(xy 327.250475 -363.312055) (xy 327.298081 -363.341109) (xy 327.340949 -363.376784) (xy 327.378166 -363.418321)
			(xy 327.408939 -363.464834) (xy 327.432611 -363.515331) (xy 327.448679 -363.568738) (xy 327.456799 -363.623914)
			(xy 327.457308 -363.6518) (xy 327.709782 -363.6518) (xy 327.713853 -363.596178) (xy 327.725979 -363.541741)
			(xy 327.745902 -363.48965) (xy 327.773198 -363.441015) (xy 327.807284 -363.396872) (xy 327.847433 -363.358163)
			(xy 327.892791 -363.325712) (xy 327.942391 -363.300211) (xy 327.995175 -363.282204) (xy 328.050018 -363.272074)
			(xy 328.105752 -363.270037) (xy 328.161189 -363.276137) (xy 328.215146 -363.290243) (xy 328.266475 -363.312055)
			(xy 328.314081 -363.341109) (xy 328.356949 -363.376784) (xy 328.394166 -363.418321) (xy 328.424939 -363.464834)
			(xy 328.448611 -363.515331) (xy 328.464679 -363.568738) (xy 328.472799 -363.623914) (xy 328.473308 -363.6518)
			(xy 328.472799 -363.679686) (xy 328.464679 -363.734862) (xy 328.448611 -363.788269) (xy 328.424939 -363.838766)
			(xy 328.394166 -363.885279) (xy 328.356949 -363.926816) (xy 328.314081 -363.962491) (xy 328.266475 -363.991545)
			(xy 328.215146 -364.013357) (xy 328.161189 -364.027463) (xy 328.105752 -364.033563) (xy 328.050018 -364.031526)
			(xy 327.995175 -364.021396) (xy 327.942391 -364.003389) (xy 327.892791 -363.977888) (xy 327.847433 -363.945437)
			(xy 327.807284 -363.906728) (xy 327.773198 -363.862585) (xy 327.745902 -363.81395) (xy 327.725979 -363.761859)
			(xy 327.713853 -363.707422) (xy 327.709782 -363.6518) (xy 327.457308 -363.6518) (xy 327.456799 -363.679686)
			(xy 327.448679 -363.734862) (xy 327.432611 -363.788269) (xy 327.408939 -363.838766) (xy 327.378166 -363.885279)
			(xy 327.340949 -363.926816) (xy 327.298081 -363.962491) (xy 327.250475 -363.991545) (xy 327.199146 -364.013357)
			(xy 327.145189 -364.027463) (xy 327.089752 -364.033563) (xy 327.034018 -364.031526) (xy 326.979175 -364.021396)
			(xy 326.926391 -364.003389) (xy 326.876791 -363.977888) (xy 326.831433 -363.945437) (xy 326.791284 -363.906728)
			(xy 326.757198 -363.862585) (xy 326.729902 -363.81395) (xy 326.709979 -363.761859) (xy 326.697853 -363.707422)
			(xy 326.693782 -363.6518) (xy 325.373406 -363.6518) (xy 325.380445 -363.700745) (xy 325.380445 -363.755255)
			(xy 325.372686 -363.80921) (xy 325.357328 -363.861512) (xy 325.334682 -363.911096) (xy 325.305209 -363.956951)
			(xy 325.26951 -363.998145) (xy 325.228311 -364.033839) (xy 325.182452 -364.063306) (xy 325.132865 -364.085945)
			(xy 325.080562 -364.101297) (xy 325.026605 -364.109048) (xy 324.99935 -364.109508) (xy 324.970118 -364.108981)
			(xy 324.912341 -364.100041) (xy 324.856604 -364.082395) (xy 324.80421 -364.056454) (xy 324.756385 -364.022825)
			(xy 324.714249 -363.982296) (xy 324.696074 -363.959394) (xy 324.687663 -363.948953) (xy 324.666477 -363.932535)
			(xy 324.641745 -363.922206) (xy 324.615175 -363.918682) (xy 324.588605 -363.922206) (xy 324.563873 -363.932535)
			(xy 324.542687 -363.948953) (xy 324.534276 -363.959394) (xy 324.516077 -363.982276) (xy 324.473954 -364.022814)
			(xy 324.426136 -364.056447) (xy 324.373744 -364.082387) (xy 324.318007 -364.100025) (xy 324.260231 -364.108949)
			(xy 324.231 -364.109508) (xy 324.203749 -364.109022) (xy 324.149801 -364.101266) (xy 324.097506 -364.085911)
			(xy 324.047929 -364.063269) (xy 324.002079 -364.033803) (xy 323.960888 -363.998112) (xy 323.925197 -363.956921)
			(xy 323.895731 -363.911071) (xy 323.873089 -363.861494) (xy 323.857734 -363.809199) (xy 323.849978 -363.755251)
			(xy 322.891585 -363.755251) (xy 319.599818 -367.047018) (xy 319.585333 -367.060841) (xy 319.552059 -367.083099)
			(xy 319.515079 -367.098432) (xy 319.475816 -367.106249) (xy 319.4558 -367.106708) (xy 313.9694 -367.106708)
			(xy 313.949389 -367.106186) (xy 313.910138 -367.098367) (xy 313.873163 -367.083048) (xy 313.839882 -367.060818)
			(xy 313.825382 -367.047018) (xy 312.452258 -365.67364) (xy 312.444784 -365.666938) (xy 312.426219 -365.659353)
			(xy 312.41619 -365.658908) (xy 310.696102 -365.658908) (xy 310.684071 -365.659551) (xy 310.662607 -365.670429)
			(xy 310.654954 -365.679736) (xy 310.648013 -365.689084) (xy 310.633142 -365.707003) (xy 310.625236 -365.71555)
			(xy 310.614822 -365.726726) (xy 310.609742 -365.756444) (xy 310.652922 -365.856012) (xy 310.657249 -365.864914)
			(xy 310.671419 -365.87871) (xy 310.689767 -365.886091) (xy 310.699658 -365.886492) (xy 311.904634 -365.886492)
			(xy 311.924664 -365.887053) (xy 311.963936 -365.894979) (xy 311.982612 -365.90224) (xy 312.100214 -365.951008)
			(xy 312.124344 -365.948976) (xy 312.134758 -365.942626) (xy 312.157329 -365.929312) (xy 312.205345 -365.908322)
			(xy 312.255783 -365.894104) (xy 312.307692 -365.886927) (xy 312.333894 -365.886492) (xy 312.361147 -365.886955)
			(xy 312.415099 -365.894711) (xy 312.467397 -365.910067) (xy 312.516978 -365.932709) (xy 312.562832 -365.962177)
			(xy 312.604025 -365.99787) (xy 312.63972 -366.039063) (xy 312.669188 -366.084917) (xy 312.691831 -366.134497)
			(xy 312.707188 -366.186795) (xy 312.714945 -366.240747) (xy 312.714945 -366.295253) (xy 312.707188 -366.349205)
			(xy 312.691831 -366.401503) (xy 312.669188 -366.451083) (xy 312.63972 -366.496937) (xy 312.604025 -366.53813)
			(xy 312.562832 -366.573823) (xy 312.516978 -366.603291) (xy 312.467397 -366.625933) (xy 312.415099 -366.641289)
			(xy 312.361147 -366.649045) (xy 312.333894 -366.649508) (xy 312.305606 -366.648971) (xy 312.249651 -366.640602)
			(xy 312.195545 -366.624062) (xy 312.144474 -366.599715) (xy 312.097558 -366.568094) (xy 312.055826 -366.529893)
			(xy 312.020191 -366.485948) (xy 311.991435 -366.437223) (xy 311.970189 -366.384787) (xy 311.963054 -366.357408)
			(xy 311.960006 -366.345216) (xy 311.944512 -366.327182) (xy 311.873392 -366.297718) (xy 311.868765 -366.295943)
			(xy 311.859043 -366.294025) (xy 311.854088 -366.293908) (xy 309.32501 -366.293908) (xy 309.314962 -366.294254)
			(xy 309.296366 -366.30186) (xy 309.288942 -366.30864) (xy 308.525418 -367.072418) (xy 308.510933 -367.086241)
			(xy 308.477659 -367.108499) (xy 308.440679 -367.123832) (xy 308.401416 -367.131649) (xy 308.3814 -367.132108)
			(xy 305.9176 -367.132108) (xy 305.897589 -367.131586) (xy 305.858338 -367.123767) (xy 305.821363 -367.108448)
			(xy 305.788082 -367.086218) (xy 305.773582 -367.072418) (xy 303.825656 -365.124492) (xy 303.818731 -365.118159)
			(xy 303.801607 -365.110528) (xy 303.782884 -365.109547) (xy 303.77384 -365.112046) (xy 303.673764 -365.145066)
			(xy 303.655476 -365.16691) (xy 303.653444 -365.181134) (xy 303.648947 -365.207923) (xy 303.633396 -365.259967)
			(xy 303.610624 -365.309282) (xy 303.581091 -365.35487) (xy 303.545393 -365.395811) (xy 303.504252 -365.431278)
			(xy 303.458499 -365.460554) (xy 303.409058 -365.483049) (xy 303.356927 -365.498308) (xy 303.303159 -365.506022)
			(xy 303.276 -365.506508) (xy 303.248749 -365.506022) (xy 303.194801 -365.498266) (xy 303.142506 -365.482911)
			(xy 303.092929 -365.460269) (xy 303.047079 -365.430803) (xy 303.005888 -365.395112) (xy 302.970197 -365.353921)
			(xy 302.940731 -365.308071) (xy 302.918089 -365.258494) (xy 302.902734 -365.206199) (xy 302.894978 -365.152251)
			(xy 302.894492 -365.125) (xy 302.895054 -365.096146) (xy 302.903738 -365.039096) (xy 302.920923 -364.984007)
			(xy 302.946215 -364.932137) (xy 302.979037 -364.884673) (xy 303.018639 -364.842699) (xy 303.04105 -364.824518)
			(xy 303.054004 -364.814358) (xy 303.063148 -364.78337) (xy 303.026572 -364.676944) (xy 303.022569 -364.667227)
			(xy 303.008292 -364.65184) (xy 302.98906 -364.643435) (xy 302.978566 -364.642908) (xy 302.6918 -364.642908)
			(xy 302.671789 -364.642386) (xy 302.632538 -364.634567) (xy 302.595563 -364.619248) (xy 302.562282 -364.597018)
			(xy 302.547782 -364.583218) (xy 301.607982 -363.643418) (xy 301.594159 -363.628933) (xy 301.571901 -363.595659)
			(xy 301.556568 -363.558679) (xy 301.548751 -363.519416) (xy 301.548292 -363.4994) (xy 301.548292 -362.46181)
			(xy 301.547946 -362.451762) (xy 301.54034 -362.433166) (xy 301.53356 -362.425742) (xy 301.023782 -361.916218)
			(xy 301.009959 -361.901733) (xy 300.987701 -361.868459) (xy 300.972368 -361.831479) (xy 300.964551 -361.792216)
			(xy 300.964092 -361.7722) (xy 300.964092 -361.714034) (xy 300.963592 -361.703527) (xy 300.955213 -361.68426)
			(xy 300.939806 -361.669973) (xy 300.930056 -361.666028) (xy 300.82363 -361.629452) (xy 300.792642 -361.638596)
			(xy 300.782482 -361.65155) (xy 300.764324 -361.673981) (xy 300.722341 -361.713578) (xy 300.674871 -361.746399)
			(xy 300.622998 -361.771693) (xy 300.567907 -361.788883) (xy 300.510855 -361.797578) (xy 300.482 -361.798108)
			(xy 300.453323 -361.797547) (xy 300.39662 -361.788931) (xy 300.341845 -361.771923) (xy 300.290234 -361.746908)
			(xy 300.242949 -361.714447) (xy 300.22165 -361.695238) (xy 300.210474 -361.684824) (xy 300.180756 -361.679744)
			(xy 300.081188 -361.722924) (xy 300.072286 -361.72725) (xy 300.058489 -361.74142) (xy 300.051108 -361.759768)
			(xy 300.050708 -361.76966) (xy 300.050708 -362.839) (xy 300.582582 -362.839) (xy 300.586653 -362.783378)
			(xy 300.598779 -362.728941) (xy 300.618702 -362.67685) (xy 300.645998 -362.628215) (xy 300.680084 -362.584072)
			(xy 300.720233 -362.545363) (xy 300.765591 -362.512912) (xy 300.815191 -362.487411) (xy 300.867975 -362.469404)
			(xy 300.922818 -362.459274) (xy 300.978552 -362.457237) (xy 301.033989 -362.463337) (xy 301.087946 -362.477443)
			(xy 301.139275 -362.499255) (xy 301.186881 -362.528309) (xy 301.229749 -362.563984) (xy 301.266966 -362.605521)
			(xy 301.297739 -362.652034) (xy 301.321411 -362.702531) (xy 301.337479 -362.755938) (xy 301.345599 -362.811114)
			(xy 301.346108 -362.839) (xy 301.345599 -362.866886) (xy 301.337479 -362.922062) (xy 301.321411 -362.975469)
			(xy 301.297739 -363.025966) (xy 301.266966 -363.072479) (xy 301.229749 -363.114016) (xy 301.186881 -363.149691)
			(xy 301.139275 -363.178745) (xy 301.087946 -363.200557) (xy 301.033989 -363.214663) (xy 300.978552 -363.220763)
			(xy 300.922818 -363.218726) (xy 300.867975 -363.208596) (xy 300.815191 -363.190589) (xy 300.765591 -363.165088)
			(xy 300.720233 -363.132637) (xy 300.680084 -363.093928) (xy 300.645998 -363.049785) (xy 300.618702 -363.00115)
			(xy 300.598779 -362.949059) (xy 300.586653 -362.894622) (xy 300.582582 -362.839) (xy 300.050708 -362.839)
			(xy 300.050708 -364.6424) (xy 300.398432 -364.6424) (xy 300.402503 -364.586778) (xy 300.414629 -364.532341)
			(xy 300.434552 -364.48025) (xy 300.461848 -364.431615) (xy 300.495934 -364.387472) (xy 300.536083 -364.348763)
			(xy 300.581441 -364.316312) (xy 300.631041 -364.290811) (xy 300.683825 -364.272804) (xy 300.738668 -364.262674)
			(xy 300.794402 -364.260637) (xy 300.849839 -364.266737) (xy 300.903796 -364.280843) (xy 300.955125 -364.302655)
			(xy 301.002731 -364.331709) (xy 301.045599 -364.367384) (xy 301.082816 -364.408921) (xy 301.113589 -364.455434)
			(xy 301.137261 -364.505931) (xy 301.153329 -364.559338) (xy 301.161449 -364.614514) (xy 301.161958 -364.6424)
			(xy 301.161449 -364.670286) (xy 301.153329 -364.725462) (xy 301.137261 -364.778869) (xy 301.113589 -364.829366)
			(xy 301.082816 -364.875879) (xy 301.045599 -364.917416) (xy 301.002731 -364.953091) (xy 300.955125 -364.982145)
			(xy 300.903796 -365.003957) (xy 300.849839 -365.018063) (xy 300.794402 -365.024163) (xy 300.738668 -365.022126)
			(xy 300.683825 -365.011996) (xy 300.631041 -364.993989) (xy 300.581441 -364.968488) (xy 300.536083 -364.936037)
			(xy 300.495934 -364.897328) (xy 300.461848 -364.853185) (xy 300.434552 -364.80455) (xy 300.414629 -364.752459)
			(xy 300.402503 -364.698022) (xy 300.398432 -364.6424) (xy 300.050708 -364.6424) (xy 300.050708 -365.29899)
			(xy 300.051054 -365.309038) (xy 300.05866 -365.327634) (xy 300.06544 -365.335058) (xy 301.125382 -366.395)
			(xy 302.893982 -366.395) (xy 302.898053 -366.339378) (xy 302.910179 -366.284941) (xy 302.930102 -366.23285)
			(xy 302.957398 -366.184215) (xy 302.991484 -366.140072) (xy 303.031633 -366.101363) (xy 303.076991 -366.068912)
			(xy 303.126591 -366.043411) (xy 303.179375 -366.025404) (xy 303.234218 -366.015274) (xy 303.289952 -366.013237)
			(xy 303.345389 -366.019337) (xy 303.399346 -366.033443) (xy 303.450675 -366.055255) (xy 303.498281 -366.084309)
			(xy 303.541149 -366.119984) (xy 303.578366 -366.161521) (xy 303.609139 -366.208034) (xy 303.632811 -366.258531)
			(xy 303.648879 -366.311938) (xy 303.656999 -366.367114) (xy 303.657508 -366.395) (xy 303.656999 -366.422886)
			(xy 303.648879 -366.478062) (xy 303.632811 -366.531469) (xy 303.609139 -366.581966) (xy 303.578366 -366.628479)
			(xy 303.541149 -366.670016) (xy 303.498281 -366.705691) (xy 303.450675 -366.734745) (xy 303.399346 -366.756557)
			(xy 303.345389 -366.770663) (xy 303.289952 -366.776763) (xy 303.234218 -366.774726) (xy 303.179375 -366.764596)
			(xy 303.126591 -366.746589) (xy 303.076991 -366.721088) (xy 303.031633 -366.688637) (xy 302.991484 -366.649928)
			(xy 302.957398 -366.605785) (xy 302.930102 -366.55715) (xy 302.910179 -366.505059) (xy 302.898053 -366.450622)
			(xy 302.893982 -366.395) (xy 301.125382 -366.395) (xy 302.395382 -367.665) (xy 302.893982 -367.665)
			(xy 302.898053 -367.609378) (xy 302.910179 -367.554941) (xy 302.930102 -367.50285) (xy 302.957398 -367.454215)
			(xy 302.991484 -367.410072) (xy 303.031633 -367.371363) (xy 303.076991 -367.338912) (xy 303.126591 -367.313411)
			(xy 303.179375 -367.295404) (xy 303.234218 -367.285274) (xy 303.289952 -367.283237) (xy 303.345389 -367.289337)
			(xy 303.399346 -367.303443) (xy 303.450675 -367.325255) (xy 303.498281 -367.354309) (xy 303.541149 -367.389984)
			(xy 303.578366 -367.431521) (xy 303.609139 -367.478034) (xy 303.632811 -367.528531) (xy 303.648879 -367.581938)
			(xy 303.656999 -367.637114) (xy 303.657508 -367.665) (xy 303.656999 -367.692886) (xy 303.648879 -367.748062)
			(xy 303.632811 -367.801469) (xy 303.609139 -367.851966) (xy 303.578366 -367.898479) (xy 303.541149 -367.940016)
			(xy 303.498281 -367.975691) (xy 303.450675 -368.004745) (xy 303.399346 -368.026557) (xy 303.345389 -368.040663)
			(xy 303.289952 -368.046763) (xy 303.234218 -368.044726) (xy 303.179375 -368.034596) (xy 303.126591 -368.016589)
			(xy 303.076991 -367.991088) (xy 303.031633 -367.958637) (xy 302.991484 -367.919928) (xy 302.957398 -367.875785)
			(xy 302.930102 -367.82715) (xy 302.910179 -367.775059) (xy 302.898053 -367.720622) (xy 302.893982 -367.665)
			(xy 302.395382 -367.665) (xy 302.888142 -368.15776) (xy 302.895616 -368.164462) (xy 302.914181 -368.172047)
			(xy 302.92421 -368.172492) (xy 303.72939 -368.172492) (xy 303.739438 -368.172146) (xy 303.758034 -368.16454)
			(xy 303.765458 -368.15776) (xy 304.528982 -367.393982) (xy 304.543467 -367.380159) (xy 304.576741 -367.357901)
			(xy 304.613721 -367.342568) (xy 304.652984 -367.334751) (xy 304.673 -367.334292) (xy 308.52999 -367.334292)
			(xy 308.540038 -367.333946) (xy 308.558634 -367.32634) (xy 308.566058 -367.31956) (xy 309.380382 -366.504982)
			(xy 309.394867 -366.491159) (xy 309.428141 -366.468901) (xy 309.465121 -366.453568) (xy 309.504384 -366.445751)
			(xy 309.5244 -366.445292) (xy 310.964326 -366.445292) (xy 310.984356 -366.445856) (xy 311.023628 -366.45378)
			(xy 311.042304 -366.46104) (xy 311.22112 -366.534954) (xy 311.24525 -366.533176) (xy 311.255664 -366.526826)
			(xy 311.278234 -366.51351) (xy 311.32625 -366.49252) (xy 311.376688 -366.478303) (xy 311.428598 -366.471127)
			(xy 311.4548 -366.470692) (xy 311.482051 -366.471178) (xy 311.535999 -366.478934) (xy 311.588294 -366.494289)
			(xy 311.637871 -366.516931) (xy 311.683721 -366.546397) (xy 311.724912 -366.582088) (xy 311.760603 -366.623279)
			(xy 311.790069 -366.669129) (xy 311.812711 -366.718706) (xy 311.828066 -366.771001) (xy 311.835822 -366.824949)
			(xy 311.835822 -366.879451) (xy 311.828066 -366.933399) (xy 311.812711 -366.985694) (xy 311.790069 -367.035271)
			(xy 311.760603 -367.081121) (xy 311.724912 -367.122312) (xy 311.683721 -367.158003) (xy 311.637871 -367.187469)
			(xy 311.588294 -367.210111) (xy 311.535999 -367.225466) (xy 311.482051 -367.233222) (xy 311.4548 -367.233708)
			(xy 311.426512 -367.233165) (xy 311.370557 -367.224797) (xy 311.316452 -367.208258) (xy 311.265381 -367.183912)
			(xy 311.218465 -367.152292) (xy 311.176732 -367.114091) (xy 311.141097 -367.070147) (xy 311.112341 -367.021423)
			(xy 311.091095 -366.968987) (xy 311.08396 -366.941608) (xy 311.080912 -366.929416) (xy 311.065418 -366.911128)
			(xy 310.933084 -366.856518) (xy 310.928458 -366.85474) (xy 310.918735 -366.852825) (xy 310.91378 -366.852708)
			(xy 309.62981 -366.852708) (xy 309.619762 -366.853054) (xy 309.601166 -366.86066) (xy 309.593742 -366.86744)
			(xy 308.779418 -367.682018) (xy 308.764933 -367.695841) (xy 308.731659 -367.718099) (xy 308.694679 -367.733432)
			(xy 308.655416 -367.741249) (xy 308.6354 -367.741708) (xy 304.77841 -367.741708) (xy 304.768362 -367.742054)
			(xy 304.749766 -367.74966) (xy 304.742342 -367.75644) (xy 303.978818 -368.520218) (xy 303.964333 -368.534041)
			(xy 303.931059 -368.556299) (xy 303.894079 -368.571632) (xy 303.854816 -368.579449) (xy 303.8348 -368.579908)
			(xy 302.8188 -368.579908) (xy 302.798789 -368.579386) (xy 302.759538 -368.571567) (xy 302.722563 -368.556248)
			(xy 302.689282 -368.534018) (xy 302.674782 -368.520218) (xy 299.702982 -365.548418) (xy 299.689159 -365.533933)
			(xy 299.666901 -365.500659) (xy 299.651568 -365.463679) (xy 299.643751 -365.424416) (xy 299.643292 -365.4044)
			(xy 299.643292 -359.075482) (xy 299.642908 -359.065438) (xy 299.635329 -359.046842) (xy 299.62856 -359.039414)
			(xy 292.02761 -351.438464) (xy 292.00475 -351.431098) (xy 291.992558 -351.43313) (xy 291.977794 -351.435288)
			(xy 291.948042 -351.437577) (xy 291.933122 -351.437702) (xy 291.905869 -351.437224) (xy 291.851919 -351.42947)
			(xy 291.799621 -351.414117) (xy 291.75004 -351.391476) (xy 291.704187 -351.36201) (xy 291.662994 -351.326318)
			(xy 291.6273 -351.285126) (xy 291.597832 -351.239274) (xy 291.575189 -351.189694) (xy 291.559833 -351.137397)
			(xy 291.552077 -351.083447) (xy 291.551614 -351.056194) (xy 291.552285 -351.024632) (xy 291.562667 -350.962367)
			(xy 291.583149 -350.902657) (xy 291.597588 -350.874584) (xy 291.602414 -350.865694) (xy 291.604446 -350.846136)
			(xy 291.578792 -350.757998) (xy 291.566346 -350.742504) (xy 291.557456 -350.737424) (xy 291.55009 -350.73336)
			(xy 291.540438 -350.727518) (xy 291.51834 -350.725486) (xy 291.423852 -350.759014) (xy 291.40785 -350.774508)
			(xy 291.403786 -350.784922) (xy 291.39313 -350.811715) (xy 291.364837 -350.861958) (xy 291.329301 -350.907368)
			(xy 291.287333 -350.94691) (xy 291.23989 -350.979681) (xy 291.188054 -351.004936) (xy 291.133005 -351.022098)
			(xy 291.076001 -351.030775) (xy 291.04717 -351.031302) (xy 291.01992 -351.030826) (xy 290.965974 -351.023066)
			(xy 290.913682 -351.007708) (xy 290.864108 -350.985065) (xy 290.818261 -350.955597) (xy 290.777074 -350.919905)
			(xy 290.741385 -350.878715) (xy 290.711921 -350.832865) (xy 290.689281 -350.783289) (xy 290.673928 -350.730996)
			(xy 290.666172 -350.67705) (xy 290.397706 -350.67705) (xy 290.377337 -350.721193) (xy 290.347387 -350.767262)
			(xy 290.32962 -350.788224) (xy 290.323524 -350.795336) (xy 290.317174 -350.812354) (xy 290.317174 -350.898206)
			(xy 290.323524 -350.915224) (xy 290.32962 -350.922336) (xy 290.347385 -350.943297) (xy 290.377309 -350.98938)
			(xy 290.400321 -351.039274) (xy 290.415947 -351.091951) (xy 290.423863 -351.146324) (xy 290.424362 -351.173796)
			(xy 290.423876 -351.201047) (xy 290.41612 -351.254995) (xy 290.400765 -351.30729) (xy 290.378123 -351.356867)
			(xy 290.348657 -351.402717) (xy 290.312966 -351.443908) (xy 290.271775 -351.479599) (xy 290.225925 -351.509065)
			(xy 290.176348 -351.531707) (xy 290.124053 -351.547062) (xy 290.070105 -351.554818) (xy 290.015603 -351.554818)
			(xy 289.961655 -351.547062) (xy 289.90936 -351.531707) (xy 289.859783 -351.509065) (xy 289.813933 -351.479599)
			(xy 289.772742 -351.443908) (xy 289.737051 -351.402717) (xy 289.707585 -351.356867) (xy 289.684943 -351.30729)
			(xy 289.669588 -351.254995) (xy 289.661832 -351.201047) (xy 289.661346 -351.173796) (xy 284.032732 -351.173796)
			(xy 284.239208 -351.380044) (xy 284.252968 -351.394566) (xy 284.275144 -351.427854) (xy 284.290407 -351.464825)
			(xy 284.298171 -351.504063) (xy 284.298644 -351.524062) (xy 284.298644 -355.279198) (xy 285.984442 -355.279198)
			(xy 285.984854 -355.251943) (xy 285.992612 -355.197987) (xy 286.007971 -355.145686) (xy 286.030617 -355.096102)
			(xy 286.06009 -355.050247) (xy 286.095789 -355.009053) (xy 286.136988 -354.973359) (xy 286.182848 -354.943892)
			(xy 286.232434 -354.921253) (xy 286.284738 -354.905901) (xy 286.338695 -354.89815) (xy 286.36595 -354.89769)
			(xy 286.393319 -354.898188) (xy 286.447497 -354.905998) (xy 286.499999 -354.92148) (xy 286.549747 -354.944315)
			(xy 286.595715 -354.974032) (xy 286.616648 -354.99167) (xy 286.62376 -354.997766) (xy 286.640778 -355.004116)
			(xy 286.726122 -355.004116) (xy 286.74314 -354.997766) (xy 286.750252 -354.99167) (xy 286.771185 -354.974029)
			(xy 286.817153 -354.944305) (xy 286.866899 -354.921459) (xy 286.919401 -354.905963) (xy 286.973579 -354.898134)
			(xy 287.028321 -354.898134) (xy 287.082499 -354.905963) (xy 287.135001 -354.921459) (xy 287.184747 -354.944305)
			(xy 287.230715 -354.974029) (xy 287.251648 -354.99167) (xy 287.25876 -354.997766) (xy 287.275778 -355.004116)
			(xy 287.361122 -355.004116) (xy 287.37814 -354.997766) (xy 287.385252 -354.99167) (xy 287.406185 -354.974029)
			(xy 287.452153 -354.944305) (xy 287.501899 -354.921459) (xy 287.554401 -354.905963) (xy 287.608579 -354.898134)
			(xy 287.663321 -354.898134) (xy 287.717499 -354.905963) (xy 287.770001 -354.921459) (xy 287.819747 -354.944305)
			(xy 287.865715 -354.974029) (xy 287.886648 -354.99167) (xy 287.89376 -354.997766) (xy 287.910778 -355.004116)
			(xy 287.996122 -355.004116) (xy 288.01314 -354.997766) (xy 288.020252 -354.99167) (xy 288.041185 -354.974029)
			(xy 288.087153 -354.944305) (xy 288.136899 -354.921459) (xy 288.189401 -354.905963) (xy 288.243579 -354.898134)
			(xy 288.298321 -354.898134) (xy 288.352499 -354.905963) (xy 288.405001 -354.921459) (xy 288.454747 -354.944305)
			(xy 288.500715 -354.974029) (xy 288.521648 -354.99167) (xy 288.52876 -354.997766) (xy 288.545778 -355.004116)
			(xy 288.631122 -355.004116) (xy 288.64814 -354.997766) (xy 288.655252 -354.99167) (xy 288.676187 -354.974035)
			(xy 288.72216 -354.944324) (xy 288.771907 -354.921488) (xy 288.824406 -354.905995) (xy 288.878581 -354.898165)
			(xy 288.90595 -354.89769) (xy 288.933202 -354.898202) (xy 288.987151 -354.905952) (xy 289.039447 -354.921302)
			(xy 289.089027 -354.943938) (xy 289.134881 -354.973401) (xy 289.176074 -355.009089) (xy 289.211768 -355.050278)
			(xy 289.241237 -355.096127) (xy 289.26388 -355.145704) (xy 289.279237 -355.197999) (xy 289.286994 -355.251947)
			(xy 289.287458 -355.279198) (xy 289.286959 -355.307902) (xy 289.278357 -355.364663) (xy 289.261346 -355.419494)
			(xy 289.236312 -355.471157) (xy 289.203819 -355.518485) (xy 289.184588 -355.539802) (xy 289.17773 -355.547168)
			(xy 289.170618 -355.565202) (xy 289.172142 -355.65588) (xy 289.179508 -355.67366) (xy 289.18662 -355.680772)
			(xy 289.207284 -355.702351) (xy 289.242299 -355.750757) (xy 289.269336 -355.804033) (xy 289.287734 -355.860873)
			(xy 289.297042 -355.919886) (xy 289.297618 -355.949758) (xy 289.297147 -355.977128) (xy 289.289334 -356.031308)
			(xy 289.273847 -356.083812) (xy 289.251006 -356.133559) (xy 289.22128 -356.179525) (xy 289.203638 -356.200456)
			(xy 289.197542 -356.207568) (xy 289.191192 -356.224586) (xy 289.191192 -356.30993) (xy 289.197542 -356.326948)
			(xy 289.203638 -356.33406) (xy 289.221278 -356.354991) (xy 289.250989 -356.400965) (xy 289.273824 -356.450713)
			(xy 289.289315 -356.503213) (xy 289.297144 -356.557389) (xy 289.297618 -356.584758) (xy 289.297106 -356.612009)
			(xy 289.289355 -356.665958) (xy 289.274004 -356.718254) (xy 289.251368 -356.767834) (xy 289.221905 -356.813687)
			(xy 289.186216 -356.854879) (xy 289.145028 -356.890574) (xy 289.099179 -356.920043) (xy 289.049603 -356.942686)
			(xy 288.997309 -356.958044) (xy 288.943361 -356.965802) (xy 288.91611 -356.966266) (xy 288.88874 -356.965802)
			(xy 288.83456 -356.957985) (xy 288.782057 -356.942496) (xy 288.73231 -356.919654) (xy 288.686343 -356.889928)
			(xy 288.665412 -356.872286) (xy 288.6583 -356.86619) (xy 288.641282 -356.85984) (xy 288.555938 -356.85984)
			(xy 288.53892 -356.86619) (xy 288.531808 -356.872286) (xy 288.510875 -356.889927) (xy 288.464907 -356.919651)
			(xy 288.415161 -356.942497) (xy 288.362659 -356.957993) (xy 288.308481 -356.965822) (xy 288.253739 -356.965822)
			(xy 288.199561 -356.957993) (xy 288.147059 -356.942497) (xy 288.097313 -356.919651) (xy 288.051345 -356.889927)
			(xy 288.030412 -356.872286) (xy 288.0233 -356.86619) (xy 288.006282 -356.85984) (xy 287.920938 -356.85984)
			(xy 287.90392 -356.86619) (xy 287.896808 -356.872286) (xy 287.875875 -356.889927) (xy 287.829907 -356.919651)
			(xy 287.780161 -356.942497) (xy 287.727659 -356.957993) (xy 287.673481 -356.965822) (xy 287.618739 -356.965822)
			(xy 287.564561 -356.957993) (xy 287.512059 -356.942497) (xy 287.462313 -356.919651) (xy 287.416345 -356.889927)
			(xy 287.395412 -356.872286) (xy 287.3883 -356.86619) (xy 287.371282 -356.85984) (xy 287.285938 -356.85984)
			(xy 287.26892 -356.86619) (xy 287.261808 -356.872286) (xy 287.240875 -356.889927) (xy 287.194907 -356.919651)
			(xy 287.145161 -356.942497) (xy 287.092659 -356.957993) (xy 287.038481 -356.965822) (xy 286.983739 -356.965822)
			(xy 286.929561 -356.957993) (xy 286.877059 -356.942497) (xy 286.827313 -356.919651) (xy 286.781345 -356.889927)
			(xy 286.760412 -356.872286) (xy 286.7533 -356.86619) (xy 286.736282 -356.85984) (xy 286.650938 -356.85984)
			(xy 286.63392 -356.86619) (xy 286.626808 -356.872286) (xy 286.605882 -356.889933) (xy 286.559908 -356.919644)
			(xy 286.510159 -356.942479) (xy 286.457657 -356.957968) (xy 286.40348 -356.965793) (xy 286.37611 -356.966266)
			(xy 286.348855 -356.965835) (xy 286.294901 -356.958079) (xy 286.2426 -356.942722) (xy 286.193017 -356.920077)
			(xy 286.147162 -356.890606) (xy 286.105968 -356.854909) (xy 286.070274 -356.813712) (xy 286.040807 -356.767855)
			(xy 286.018167 -356.71827) (xy 286.002815 -356.665967) (xy 285.995062 -356.612013) (xy 285.994602 -356.584758)
			(xy 285.995102 -356.557389) (xy 286.002911 -356.503211) (xy 286.018392 -356.450709) (xy 286.041227 -356.400961)
			(xy 286.070944 -356.354993) (xy 286.088582 -356.33406) (xy 286.094678 -356.326948) (xy 286.101028 -356.30993)
			(xy 286.101028 -356.224586) (xy 286.094678 -356.207568) (xy 286.088582 -356.200456) (xy 286.070953 -356.179516)
			(xy 286.04124 -356.133545) (xy 286.018403 -356.0838) (xy 286.002909 -356.031301) (xy 285.995078 -355.977127)
			(xy 285.994602 -355.949758) (xy 285.995146 -355.921055) (xy 286.003739 -355.864297) (xy 286.020739 -355.809467)
			(xy 286.045764 -355.757803) (xy 286.078246 -355.710473) (xy 286.097472 -355.689154) (xy 286.10433 -355.681788)
			(xy 286.111442 -355.663754) (xy 286.109918 -355.573076) (xy 286.102552 -355.555296) (xy 286.09544 -355.548184)
			(xy 286.074796 -355.526587) (xy 286.03978 -355.478185) (xy 286.01274 -355.424914) (xy 285.994337 -355.368078)
			(xy 285.985022 -355.309068) (xy 285.984442 -355.279198) (xy 284.298644 -355.279198) (xy 284.298644 -358.812014)
			(xy 295.410886 -358.812014) (xy 295.410886 -358.727318) (xy 295.418937 -358.643004) (xy 295.434966 -358.559838)
			(xy 295.458827 -358.478571) (xy 295.490306 -358.399941) (xy 295.529117 -358.32466) (xy 295.574907 -358.253408)
			(xy 295.627263 -358.186832) (xy 295.685711 -358.125534) (xy 295.749721 -358.070069) (xy 295.818713 -358.02094)
			(xy 295.892063 -357.978591) (xy 295.969106 -357.943407) (xy 296.049145 -357.915705) (xy 296.131454 -357.895737)
			(xy 296.215289 -357.883684) (xy 296.29989 -357.879654) (xy 296.384491 -357.883684) (xy 296.468326 -357.895737)
			(xy 296.550635 -357.915705) (xy 296.630674 -357.943407) (xy 296.707717 -357.978591) (xy 296.781067 -358.02094)
			(xy 296.850059 -358.070069) (xy 296.914069 -358.125534) (xy 296.972517 -358.186832) (xy 297.024873 -358.253408)
			(xy 297.070663 -358.32466) (xy 297.109474 -358.399941) (xy 297.140953 -358.478571) (xy 297.164814 -358.559838)
			(xy 297.180843 -358.643004) (xy 297.188894 -358.727318) (xy 297.189398 -358.769666) (xy 297.188894 -358.812014)
			(xy 297.180843 -358.896328) (xy 297.164814 -358.979494) (xy 297.140953 -359.060761) (xy 297.109474 -359.139391)
			(xy 297.070663 -359.214672) (xy 297.024873 -359.285924) (xy 296.972517 -359.3525) (xy 296.914069 -359.413798)
			(xy 296.850059 -359.469263) (xy 296.781067 -359.518392) (xy 296.707717 -359.560741) (xy 296.630674 -359.595925)
			(xy 296.550635 -359.623627) (xy 296.468326 -359.643595) (xy 296.384491 -359.655648) (xy 296.29989 -359.659679)
			(xy 296.215289 -359.655648) (xy 296.131454 -359.643595) (xy 296.049145 -359.623627) (xy 295.969106 -359.595925)
			(xy 295.892063 -359.560741) (xy 295.818713 -359.518392) (xy 295.749721 -359.469263) (xy 295.685711 -359.413798)
			(xy 295.627263 -359.3525) (xy 295.574907 -359.285924) (xy 295.529117 -359.214672) (xy 295.490306 -359.139391)
			(xy 295.458827 -359.060761) (xy 295.434966 -358.979494) (xy 295.418937 -358.896328) (xy 295.410886 -358.812014)
			(xy 284.298644 -358.812014) (xy 284.298644 -361.565952) (xy 285.209742 -361.565952) (xy 285.21011 -361.538696)
			(xy 285.217875 -361.484739) (xy 285.23324 -361.432436) (xy 285.255892 -361.382852) (xy 285.285369 -361.336997)
			(xy 285.321073 -361.295803) (xy 285.362276 -361.26011) (xy 285.408138 -361.230645) (xy 285.457728 -361.208006)
			(xy 285.510035 -361.192654) (xy 285.563994 -361.184903) (xy 285.59125 -361.184444) (xy 285.61862 -361.184929)
			(xy 285.672798 -361.19274) (xy 285.725302 -361.208224) (xy 285.775049 -361.231062) (xy 285.821016 -361.260784)
			(xy 285.841948 -361.278424) (xy 285.84906 -361.28452) (xy 285.866078 -361.29087) (xy 285.951422 -361.29087)
			(xy 285.96844 -361.28452) (xy 285.975552 -361.278424) (xy 285.996494 -361.260798) (xy 286.042464 -361.231083)
			(xy 286.092209 -361.208244) (xy 286.144707 -361.19275) (xy 286.198881 -361.184919) (xy 286.22625 -361.184444)
			(xy 286.252898 -361.184913) (xy 286.305674 -361.192349) (xy 286.356902 -361.207056) (xy 286.405586 -361.228747)
			(xy 286.450777 -361.257001) (xy 286.491599 -361.291268) (xy 286.527255 -361.330882) (xy 286.557053 -361.375071)
			(xy 286.56915 -361.39882) (xy 286.57423 -361.409234) (xy 286.592264 -361.423458) (xy 286.692594 -361.446064)
			(xy 286.714946 -361.44073) (xy 286.72409 -361.433618) (xy 286.744487 -361.417796) (xy 286.788733 -361.391204)
			(xy 286.836157 -361.370812) (xy 286.885894 -361.356991) (xy 286.937039 -361.349993) (xy 286.96285 -361.349544)
			(xy 286.99022 -361.350029) (xy 287.044398 -361.35784) (xy 287.096902 -361.373324) (xy 287.146649 -361.396162)
			(xy 287.192616 -361.425884) (xy 287.213548 -361.443524) (xy 287.22066 -361.44962) (xy 287.237678 -361.45597)
			(xy 287.323022 -361.45597) (xy 287.34004 -361.44962) (xy 287.347152 -361.443524) (xy 287.368085 -361.425883)
			(xy 287.414053 -361.396159) (xy 287.463799 -361.373313) (xy 287.516301 -361.357817) (xy 287.570479 -361.349988)
			(xy 287.625221 -361.349988) (xy 287.679399 -361.357817) (xy 287.731901 -361.373313) (xy 287.781647 -361.396159)
			(xy 287.827615 -361.425883) (xy 287.848548 -361.443524) (xy 287.85566 -361.44962) (xy 287.872678 -361.45597)
			(xy 287.958022 -361.45597) (xy 287.97504 -361.44962) (xy 287.982152 -361.443524) (xy 288.003085 -361.425883)
			(xy 288.049053 -361.396159) (xy 288.098799 -361.373313) (xy 288.151301 -361.357817) (xy 288.205479 -361.349988)
			(xy 288.260221 -361.349988) (xy 288.314399 -361.357817) (xy 288.366901 -361.373313) (xy 288.416647 -361.396159)
			(xy 288.462615 -361.425883) (xy 288.483548 -361.443524) (xy 288.49066 -361.44962) (xy 288.507678 -361.45597)
			(xy 288.593022 -361.45597) (xy 288.61004 -361.44962) (xy 288.617152 -361.443524) (xy 288.638094 -361.425898)
			(xy 288.684064 -361.396183) (xy 288.733809 -361.373344) (xy 288.786307 -361.35785) (xy 288.840481 -361.350019)
			(xy 288.86785 -361.349544) (xy 288.893663 -361.35) (xy 288.944816 -361.356964) (xy 288.994561 -361.370771)
			(xy 289.041985 -361.391168) (xy 289.086222 -361.417781) (xy 289.10661 -361.433618) (xy 289.115754 -361.44073)
			(xy 289.138106 -361.446064) (xy 289.238436 -361.423458) (xy 289.25647 -361.409234) (xy 289.26155 -361.39882)
			(xy 289.273615 -361.375051) (xy 289.303402 -361.330844) (xy 289.339054 -361.291217) (xy 289.379878 -361.256941)
			(xy 289.425077 -361.228684) (xy 289.473771 -361.206996) (xy 289.525011 -361.192301) (xy 289.577797 -361.184885)
			(xy 289.60445 -361.184444) (xy 289.63182 -361.184929) (xy 289.685998 -361.19274) (xy 289.738502 -361.208224)
			(xy 289.788249 -361.231062) (xy 289.834216 -361.260784) (xy 289.855148 -361.278424) (xy 289.86226 -361.28452)
			(xy 289.879278 -361.29087) (xy 289.964622 -361.29087) (xy 289.98164 -361.28452) (xy 289.988752 -361.278424)
			(xy 290.009694 -361.260798) (xy 290.055664 -361.231083) (xy 290.105409 -361.208244) (xy 290.157907 -361.19275)
			(xy 290.212081 -361.184919) (xy 290.23945 -361.184444) (xy 290.265295 -361.184875) (xy 290.316511 -361.19186)
			(xy 290.366315 -361.205696) (xy 290.413795 -361.226128) (xy 290.458082 -361.252783) (xy 290.498365 -361.285173)
			(xy 290.533907 -361.322705) (xy 290.54933 -361.343448) (xy 290.556442 -361.353354) (xy 290.57727 -361.364276)
			(xy 290.682934 -361.366816) (xy 290.70427 -361.356656) (xy 290.71189 -361.347004) (xy 290.73011 -361.324759)
			(xy 290.772036 -361.285413) (xy 290.819395 -361.25281) (xy 290.871113 -361.227688) (xy 290.926017 -361.210617)
			(xy 290.982862 -361.201984) (xy 291.01161 -361.201462) (xy 291.03886 -361.201968) (xy 291.092806 -361.209725)
			(xy 291.145098 -361.22508) (xy 291.194673 -361.24772) (xy 291.240522 -361.277185) (xy 291.28086 -361.312136)
			(xy 295.410886 -361.312136) (xy 295.410886 -361.22744) (xy 295.418937 -361.143126) (xy 295.434966 -361.05996)
			(xy 295.458827 -360.978693) (xy 295.490306 -360.900063) (xy 295.529117 -360.824782) (xy 295.574907 -360.75353)
			(xy 295.627263 -360.686954) (xy 295.685711 -360.625656) (xy 295.749721 -360.570191) (xy 295.818713 -360.521062)
			(xy 295.892063 -360.478713) (xy 295.969106 -360.443529) (xy 296.049145 -360.415827) (xy 296.131454 -360.395859)
			(xy 296.215289 -360.383806) (xy 296.29989 -360.379776) (xy 296.384491 -360.383806) (xy 296.468326 -360.395859)
			(xy 296.550635 -360.415827) (xy 296.630674 -360.443529) (xy 296.707717 -360.478713) (xy 296.781067 -360.521062)
			(xy 296.850059 -360.570191) (xy 296.914069 -360.625656) (xy 296.972517 -360.686954) (xy 297.024873 -360.75353)
			(xy 297.070663 -360.824782) (xy 297.109474 -360.900063) (xy 297.140953 -360.978693) (xy 297.164814 -361.05996)
			(xy 297.180843 -361.143126) (xy 297.188894 -361.22744) (xy 297.189398 -361.269788) (xy 297.188894 -361.312136)
			(xy 297.180843 -361.39645) (xy 297.164814 -361.479616) (xy 297.140953 -361.560883) (xy 297.109474 -361.639513)
			(xy 297.070663 -361.714794) (xy 297.024873 -361.786046) (xy 296.972517 -361.852622) (xy 296.914069 -361.91392)
			(xy 296.850059 -361.969385) (xy 296.781067 -362.018514) (xy 296.707717 -362.060863) (xy 296.630674 -362.096047)
			(xy 296.550635 -362.123749) (xy 296.468326 -362.143717) (xy 296.384491 -362.15577) (xy 296.29989 -362.159801)
			(xy 296.215289 -362.15577) (xy 296.131454 -362.143717) (xy 296.049145 -362.123749) (xy 295.969106 -362.096047)
			(xy 295.892063 -362.060863) (xy 295.818713 -362.018514) (xy 295.749721 -361.969385) (xy 295.685711 -361.91392)
			(xy 295.627263 -361.852622) (xy 295.574907 -361.786046) (xy 295.529117 -361.714794) (xy 295.490306 -361.639513)
			(xy 295.458827 -361.560883) (xy 295.434966 -361.479616) (xy 295.418937 -361.39645) (xy 295.410886 -361.312136)
			(xy 291.28086 -361.312136) (xy 291.281712 -361.312874) (xy 291.317403 -361.354062) (xy 291.34687 -361.399909)
			(xy 291.369513 -361.449483) (xy 291.38487 -361.501775) (xy 291.39263 -361.55572) (xy 291.393118 -361.58297)
			(xy 291.3926 -361.612245) (xy 291.383625 -361.670104) (xy 291.365911 -361.725911) (xy 291.339876 -361.778355)
			(xy 291.306131 -361.826203) (xy 291.286184 -361.847638) (xy 291.279072 -361.855004) (xy 291.27196 -361.873546)
			(xy 291.27323 -361.965494) (xy 291.281104 -361.983782) (xy 291.28847 -361.990894) (xy 291.30629 -362.008912)
			(xy 291.33752 -362.048822) (xy 291.36319 -362.092515) (xy 291.38285 -362.139223) (xy 291.396152 -362.188122)
			(xy 291.402863 -362.238352) (xy 291.403278 -362.26369) (xy 291.402811 -362.29106) (xy 291.394995 -362.34524)
			(xy 291.379506 -362.397743) (xy 291.356664 -362.44749) (xy 291.326939 -362.493456) (xy 291.309298 -362.514388)
			(xy 291.303202 -362.5215) (xy 291.296852 -362.538518) (xy 291.296852 -362.623862) (xy 291.303202 -362.64088)
			(xy 291.309298 -362.647992) (xy 291.326928 -362.668933) (xy 291.356651 -362.7149) (xy 291.379496 -362.764645)
			(xy 291.394992 -362.817146) (xy 291.402821 -362.871323) (xy 291.402822 -362.926062) (xy 291.394995 -362.98024)
			(xy 291.379501 -363.032741) (xy 291.356658 -363.082487) (xy 291.326937 -363.128455) (xy 291.309298 -363.149388)
			(xy 291.303202 -363.1565) (xy 291.296852 -363.173518) (xy 291.296852 -363.258862) (xy 291.303202 -363.27588)
			(xy 291.309298 -363.282992) (xy 291.326928 -363.303933) (xy 291.356651 -363.3499) (xy 291.379496 -363.399645)
			(xy 291.394992 -363.452146) (xy 291.402821 -363.506323) (xy 291.402822 -363.561062) (xy 291.394995 -363.61524)
			(xy 291.379501 -363.667741) (xy 291.356658 -363.717487) (xy 291.326937 -363.763455) (xy 291.309298 -363.784388)
			(xy 291.303202 -363.7915) (xy 291.296852 -363.808518) (xy 291.296852 -363.893862) (xy 291.303202 -363.91088)
			(xy 291.309298 -363.917992) (xy 291.326946 -363.938917) (xy 291.356657 -363.984891) (xy 291.379491 -364.034641)
			(xy 291.39498 -364.087143) (xy 291.402805 -364.14132) (xy 291.403278 -364.16869) (xy 291.402835 -364.195944)
			(xy 291.395079 -364.249897) (xy 291.379723 -364.302197) (xy 291.357079 -364.351779) (xy 291.327609 -364.397634)
			(xy 291.291913 -364.438828) (xy 291.250718 -364.474521) (xy 291.204862 -364.503989) (xy 291.155278 -364.52663)
			(xy 291.102978 -364.541983) (xy 291.049024 -364.549737) (xy 291.02177 -364.550198) (xy 290.995926 -364.549734)
			(xy 290.944713 -364.542753) (xy 290.89491 -364.528922) (xy 290.847431 -364.508494) (xy 290.803143 -364.481845)
			(xy 290.762859 -364.44946) (xy 290.727315 -364.411934) (xy 290.71189 -364.391194) (xy 290.704778 -364.381288)
			(xy 290.68395 -364.370366) (xy 290.578286 -364.367826) (xy 290.55695 -364.377986) (xy 290.54933 -364.387638)
			(xy 290.531166 -364.40993) (xy 290.489227 -364.449271) (xy 290.441856 -364.481868) (xy 290.390127 -364.506981)
			(xy 290.335214 -364.524042) (xy 290.278361 -364.532664) (xy 290.24961 -364.53318) (xy 290.22224 -364.532713)
			(xy 290.168061 -364.524896) (xy 290.115557 -364.509408) (xy 290.06581 -364.486566) (xy 290.019844 -364.456841)
			(xy 289.998912 -364.4392) (xy 289.9918 -364.433104) (xy 289.974782 -364.426754) (xy 289.889438 -364.426754)
			(xy 289.87242 -364.433104) (xy 289.865308 -364.4392) (xy 289.844384 -364.456849) (xy 289.798409 -364.486559)
			(xy 289.748659 -364.509393) (xy 289.696157 -364.524882) (xy 289.64198 -364.532707) (xy 289.61461 -364.53318)
			(xy 289.587035 -364.532714) (xy 289.532462 -364.524763) (xy 289.479602 -364.509038) (xy 289.429556 -364.485868)
			(xy 289.383366 -364.455735) (xy 289.341996 -364.419267) (xy 289.32378 -364.39856) (xy 289.316188 -364.390431)
			(xy 289.296028 -364.381084) (xy 289.284918 -364.380526) (xy 289.207702 -364.380526) (xy 289.196589 -364.381071)
			(xy 289.17643 -364.390425) (xy 289.16884 -364.39856) (xy 289.150602 -364.419247) (xy 289.10924 -364.455721)
			(xy 289.063056 -364.485857) (xy 289.013013 -364.509027) (xy 288.960155 -364.524748) (xy 288.905583 -364.532693)
			(xy 288.87801 -364.53318) (xy 288.85064 -364.532713) (xy 288.796461 -364.524896) (xy 288.743957 -364.509408)
			(xy 288.69421 -364.486566) (xy 288.648244 -364.456841) (xy 288.627312 -364.4392) (xy 288.6202 -364.433104)
			(xy 288.603182 -364.426754) (xy 288.517838 -364.426754) (xy 288.50082 -364.433104) (xy 288.493708 -364.4392)
			(xy 288.472775 -364.456841) (xy 288.426807 -364.486565) (xy 288.377061 -364.509411) (xy 288.324559 -364.524907)
			(xy 288.270381 -364.532736) (xy 288.215639 -364.532736) (xy 288.161461 -364.524907) (xy 288.108959 -364.509411)
			(xy 288.059213 -364.486565) (xy 288.013245 -364.456841) (xy 287.992312 -364.4392) (xy 287.9852 -364.433104)
			(xy 287.968182 -364.426754) (xy 287.882838 -364.426754) (xy 287.86582 -364.433104) (xy 287.858708 -364.4392)
			(xy 287.837775 -364.456841) (xy 287.791807 -364.486565) (xy 287.742061 -364.509411) (xy 287.689559 -364.524907)
			(xy 287.635381 -364.532736) (xy 287.580639 -364.532736) (xy 287.526461 -364.524907) (xy 287.473959 -364.509411)
			(xy 287.424213 -364.486565) (xy 287.378245 -364.456841) (xy 287.357312 -364.4392) (xy 287.3502 -364.433104)
			(xy 287.333182 -364.426754) (xy 287.247838 -364.426754) (xy 287.23082 -364.433104) (xy 287.223708 -364.4392)
			(xy 287.202784 -364.456849) (xy 287.156809 -364.486559) (xy 287.107059 -364.509393) (xy 287.054557 -364.524882)
			(xy 287.00038 -364.532707) (xy 286.97301 -364.53318) (xy 286.945435 -364.532714) (xy 286.890862 -364.524763)
			(xy 286.838002 -364.509038) (xy 286.787956 -364.485868) (xy 286.741766 -364.455735) (xy 286.700396 -364.419267)
			(xy 286.68218 -364.39856) (xy 286.674588 -364.390431) (xy 286.654428 -364.381084) (xy 286.643318 -364.380526)
			(xy 286.566102 -364.380526) (xy 286.554989 -364.381071) (xy 286.53483 -364.390425) (xy 286.52724 -364.39856)
			(xy 286.509002 -364.419247) (xy 286.46764 -364.455721) (xy 286.421456 -364.485857) (xy 286.371413 -364.509027)
			(xy 286.318555 -364.524748) (xy 286.263983 -364.532693) (xy 286.23641 -364.53318) (xy 286.20904 -364.532713)
			(xy 286.154861 -364.524896) (xy 286.102357 -364.509408) (xy 286.05261 -364.486566) (xy 286.006644 -364.456841)
			(xy 285.985712 -364.4392) (xy 285.9786 -364.433104) (xy 285.961582 -364.426754) (xy 285.876238 -364.426754)
			(xy 285.85922 -364.433104) (xy 285.852108 -364.4392) (xy 285.831184 -364.456849) (xy 285.785209 -364.486559)
			(xy 285.735459 -364.509393) (xy 285.682957 -364.524882) (xy 285.62878 -364.532707) (xy 285.60141 -364.53318)
			(xy 285.574156 -364.532735) (xy 285.520203 -364.524979) (xy 285.467903 -364.509623) (xy 285.418321 -364.486979)
			(xy 285.372467 -364.45751) (xy 285.331273 -364.421814) (xy 285.295579 -364.380619) (xy 285.266112 -364.334763)
			(xy 285.243471 -364.28518) (xy 285.228117 -364.232879) (xy 285.220363 -364.178926) (xy 285.219902 -364.151672)
			(xy 285.220351 -364.124301) (xy 285.228173 -364.070121) (xy 285.243666 -364.017618) (xy 285.266511 -363.967871)
			(xy 285.296239 -363.921905) (xy 285.313882 -363.900974) (xy 285.319978 -363.893862) (xy 285.326328 -363.876844)
			(xy 285.326328 -363.7915) (xy 285.319978 -363.774482) (xy 285.313882 -363.76737) (xy 285.296216 -363.746459)
			(xy 285.266496 -363.700486) (xy 285.243655 -363.650736) (xy 285.228162 -363.598231) (xy 285.220337 -363.54405)
			(xy 285.22034 -363.489308) (xy 285.228171 -363.435128) (xy 285.243669 -363.382625) (xy 285.266516 -363.332877)
			(xy 285.296241 -363.286908) (xy 285.313882 -363.265974) (xy 285.319978 -363.258862) (xy 285.326328 -363.241844)
			(xy 285.326328 -363.1565) (xy 285.319978 -363.139482) (xy 285.313882 -363.13237) (xy 285.296216 -363.111459)
			(xy 285.266496 -363.065486) (xy 285.243655 -363.015736) (xy 285.228162 -362.963231) (xy 285.220337 -362.90905)
			(xy 285.22034 -362.854308) (xy 285.228171 -362.800128) (xy 285.243669 -362.747625) (xy 285.266516 -362.697877)
			(xy 285.296241 -362.651908) (xy 285.313882 -362.630974) (xy 285.319978 -362.623862) (xy 285.326328 -362.606844)
			(xy 285.326328 -362.5215) (xy 285.319978 -362.504482) (xy 285.313882 -362.49737) (xy 285.296259 -362.476425)
			(xy 285.266546 -362.430455) (xy 285.243707 -362.380711) (xy 285.228212 -362.328213) (xy 285.220379 -362.27404)
			(xy 285.219902 -362.246672) (xy 285.22044 -362.217398) (xy 285.22941 -362.159539) (xy 285.247118 -362.103732)
			(xy 285.273149 -362.051288) (xy 285.306891 -362.003439) (xy 285.326836 -361.982004) (xy 285.333948 -361.974638)
			(xy 285.34106 -361.956096) (xy 285.33979 -361.864148) (xy 285.331916 -361.84586) (xy 285.32455 -361.838748)
			(xy 285.306706 -361.820753) (xy 285.275478 -361.780839) (xy 285.24981 -361.73714) (xy 285.230155 -361.690428)
			(xy 285.216858 -361.641525) (xy 285.210153 -361.591291) (xy 285.209742 -361.565952) (xy 284.298644 -361.565952)
			(xy 284.298644 -364.183422) (xy 284.299046 -364.193494) (xy 284.306782 -364.212092) (xy 284.31363 -364.21949)
			(xy 285.274512 -365.180372) (xy 285.281995 -365.187063) (xy 285.300553 -365.194654) (xy 285.31058 -365.195104)
			(xy 298.419012 -365.195104) (xy 298.439024 -365.195615) (xy 298.478276 -365.203437) (xy 298.51525 -365.218759)
			(xy 298.54853 -365.240993) (xy 298.56303 -365.254794) (xy 302.278542 -368.97056) (xy 302.286016 -368.977262)
			(xy 302.304581 -368.984847) (xy 302.31461 -368.985292) (xy 303.93259 -368.985292) (xy 303.942638 -368.984946)
			(xy 303.961234 -368.97734) (xy 303.968658 -368.97056) (xy 304.986182 -367.952782) (xy 305.000667 -367.938959)
			(xy 305.033941 -367.916701) (xy 305.070921 -367.901368) (xy 305.110184 -367.893551) (xy 305.1302 -367.893092)
			(xy 308.80939 -367.893092) (xy 308.819438 -367.892746) (xy 308.838034 -367.88514) (xy 308.845458 -367.87836)
			(xy 309.507382 -367.216182) (xy 309.521867 -367.202359) (xy 309.555141 -367.180101) (xy 309.592121 -367.164768)
			(xy 309.631384 -367.156951) (xy 309.6514 -367.156492) (xy 310.216296 -367.156492) (xy 310.228327 -367.155848)
			(xy 310.249791 -367.144971) (xy 310.257444 -367.135664) (xy 310.272866 -367.115147) (xy 310.308364 -367.078074)
			(xy 310.348513 -367.046096) (xy 310.392587 -367.019792) (xy 310.439792 -366.999636) (xy 310.489273 -366.985994)
			(xy 310.540136 -366.97911) (xy 310.5658 -366.978692) (xy 310.593051 -366.979178) (xy 310.646999 -366.986934)
			(xy 310.699294 -367.002289) (xy 310.748871 -367.024931) (xy 310.794721 -367.054397) (xy 310.835912 -367.090088)
			(xy 310.871603 -367.131279) (xy 310.901069 -367.177129) (xy 310.923711 -367.226706) (xy 310.939066 -367.279001)
			(xy 310.946822 -367.332949) (xy 310.946822 -367.387451) (xy 310.939066 -367.441399) (xy 310.923711 -367.493694)
			(xy 310.901069 -367.543271) (xy 310.871603 -367.589121) (xy 310.835912 -367.630312) (xy 310.794721 -367.666003)
			(xy 310.748871 -367.695469) (xy 310.699294 -367.718111) (xy 310.646999 -367.733466) (xy 310.593051 -367.741222)
			(xy 310.5658 -367.741708) (xy 310.540135 -367.741316) (xy 310.489267 -367.73444) (xy 310.439783 -367.720799)
			(xy 310.392577 -367.70064) (xy 310.348504 -367.674327) (xy 310.308361 -367.642336) (xy 310.272876 -367.605248)
			(xy 310.257444 -367.584736) (xy 310.249858 -367.575356) (xy 310.228349 -367.564496) (xy 310.216296 -367.563908)
			(xy 309.75681 -367.563908) (xy 309.746762 -367.564254) (xy 309.728166 -367.57186) (xy 309.720742 -367.57864)
			(xy 309.058818 -368.240818) (xy 309.044333 -368.254641) (xy 309.011059 -368.276899) (xy 308.974079 -368.292232)
			(xy 308.934816 -368.300049) (xy 308.9148 -368.300508) (xy 305.23561 -368.300508) (xy 305.225562 -368.300854)
			(xy 305.206966 -368.30846) (xy 305.199542 -368.31524) (xy 304.182018 -369.333018) (xy 304.167533 -369.346841)
			(xy 304.134259 -369.369099) (xy 304.097279 -369.384432) (xy 304.058016 -369.392249) (xy 304.038 -369.392708)
			(xy 302.2092 -369.392708) (xy 302.189189 -369.392186) (xy 302.149938 -369.384367) (xy 302.112963 -369.369048)
			(xy 302.079682 -369.346818) (xy 302.065182 -369.333018) (xy 298.34967 -365.617252) (xy 298.342191 -365.610556)
			(xy 298.32363 -365.602967) (xy 298.313602 -365.60252) (xy 285.20517 -365.60252) (xy 285.185158 -365.602013)
			(xy 285.145907 -365.594189) (xy 285.108932 -365.578865) (xy 285.075652 -365.556631) (xy 285.061152 -365.54283)
			(xy 283.951172 -364.43285) (xy 283.937423 -364.418318) (xy 283.915241 -364.385035) (xy 283.899975 -364.348067)
			(xy 283.892209 -364.308831) (xy 283.891736 -364.288832) (xy 283.891736 -351.629472) (xy 283.891342 -351.619399)
			(xy 283.883601 -351.6008) (xy 283.87675 -351.593404) (xy 283.72181 -351.438464) (xy 283.69895 -351.431098)
			(xy 283.686758 -351.43313) (xy 283.671994 -351.435288) (xy 283.642242 -351.437577) (xy 283.627322 -351.437702)
			(xy 283.600069 -351.437224) (xy 283.546119 -351.42947) (xy 283.493821 -351.414117) (xy 283.44424 -351.391476)
			(xy 283.398387 -351.36201) (xy 283.357194 -351.326318) (xy 283.3215 -351.285126) (xy 283.292032 -351.239274)
			(xy 283.269389 -351.189694) (xy 283.254033 -351.137397) (xy 283.246277 -351.083447) (xy 283.245814 -351.056194)
			(xy 283.246485 -351.024632) (xy 283.256867 -350.962367) (xy 283.277349 -350.902657) (xy 283.291788 -350.874584)
			(xy 283.296614 -350.865694) (xy 283.298646 -350.846136) (xy 283.272992 -350.757998) (xy 283.260546 -350.742504)
			(xy 283.251656 -350.737424) (xy 283.24429 -350.73336) (xy 283.234638 -350.727518) (xy 283.21254 -350.725486)
			(xy 283.118052 -350.759014) (xy 283.10205 -350.774508) (xy 283.097986 -350.784922) (xy 283.08733 -350.811715)
			(xy 283.059037 -350.861958) (xy 283.023501 -350.907368) (xy 282.981533 -350.94691) (xy 282.93409 -350.979681)
			(xy 282.882254 -351.004936) (xy 282.827205 -351.022098) (xy 282.770201 -351.030775) (xy 282.74137 -351.031302)
			(xy 282.71412 -351.030826) (xy 282.660174 -351.023066) (xy 282.607882 -351.007708) (xy 282.558308 -350.985065)
			(xy 282.512461 -350.955597) (xy 282.471274 -350.919905) (xy 282.435585 -350.878715) (xy 282.406121 -350.832865)
			(xy 282.383481 -350.783289) (xy 282.368128 -350.730996) (xy 282.360372 -350.67705) (xy 282.091906 -350.67705)
			(xy 282.071537 -350.721193) (xy 282.041587 -350.767262) (xy 282.02382 -350.788224) (xy 282.017724 -350.795336)
			(xy 282.011374 -350.812354) (xy 282.011374 -350.898206) (xy 282.017724 -350.915224) (xy 282.02382 -350.922336)
			(xy 282.041585 -350.943297) (xy 282.071509 -350.98938) (xy 282.094521 -351.039274) (xy 282.110147 -351.091951)
			(xy 282.118063 -351.146324) (xy 282.118562 -351.173796) (xy 282.118076 -351.201047) (xy 282.11032 -351.254995)
			(xy 282.094965 -351.30729) (xy 282.072323 -351.356867) (xy 282.042857 -351.402717) (xy 282.007166 -351.443908)
			(xy 281.965975 -351.479599) (xy 281.920125 -351.509065) (xy 281.870548 -351.531707) (xy 281.818253 -351.547062)
			(xy 281.764305 -351.554818) (xy 281.709803 -351.554818) (xy 281.655855 -351.547062) (xy 281.60356 -351.531707)
			(xy 281.553983 -351.509065) (xy 281.508133 -351.479599) (xy 281.466942 -351.443908) (xy 281.431251 -351.402717)
			(xy 281.401785 -351.356867) (xy 281.379143 -351.30729) (xy 281.363788 -351.254995) (xy 281.356032 -351.201047)
			(xy 281.355546 -351.173796) (xy 275.752317 -351.173796) (xy 276.255988 -351.677224) (xy 276.269782 -351.691715)
			(xy 276.291953 -351.725013) (xy 276.307207 -351.761994) (xy 276.314959 -351.80124) (xy 276.315424 -351.821242)
			(xy 276.315424 -358.163622) (xy 276.315832 -358.173693) (xy 276.323564 -358.192291) (xy 276.33041 -358.19969)
			(xy 284.431232 -366.300512) (xy 284.438715 -366.307204) (xy 284.457273 -366.314796) (xy 284.4673 -366.315244)
			(xy 297.939206 -366.315244) (xy 297.959218 -366.315748) (xy 297.998471 -366.32357) (xy 298.035446 -366.338894)
			(xy 298.068725 -366.361131) (xy 298.083224 -366.374934) (xy 301.440596 -369.73256) (xy 301.448052 -369.739286)
			(xy 301.466631 -369.746857) (xy 301.476664 -369.747292) (xy 304.21199 -369.747292) (xy 304.222038 -369.746946)
			(xy 304.240634 -369.73934) (xy 304.248058 -369.73256) (xy 305.392582 -368.587782) (xy 305.407067 -368.573959)
			(xy 305.440341 -368.551701) (xy 305.477321 -368.536368) (xy 305.516584 -368.528551) (xy 305.5366 -368.528092)
			(xy 309.16499 -368.528092) (xy 309.175038 -368.527746) (xy 309.193634 -368.52014) (xy 309.201058 -368.51336)
			(xy 309.54853 -368.165888) (xy 309.555896 -368.143028) (xy 309.553864 -368.130836) (xy 309.551703 -368.116073)
			(xy 309.549416 -368.08632) (xy 309.549292 -368.0714) (xy 309.549778 -368.044149) (xy 309.557534 -367.990201)
			(xy 309.572889 -367.937906) (xy 309.595531 -367.888329) (xy 309.624997 -367.842479) (xy 309.660688 -367.801288)
			(xy 309.701879 -367.765597) (xy 309.747729 -367.736131) (xy 309.797306 -367.713489) (xy 309.849601 -367.698134)
			(xy 309.903549 -367.690378) (xy 309.958051 -367.690378) (xy 310.011999 -367.698134) (xy 310.064294 -367.713489)
			(xy 310.113871 -367.736131) (xy 310.159721 -367.765597) (xy 310.200912 -367.801288) (xy 310.236603 -367.842479)
			(xy 310.266069 -367.888329) (xy 310.288711 -367.937906) (xy 310.304066 -367.990201) (xy 310.311822 -368.044149)
			(xy 310.311822 -368.098651) (xy 310.304066 -368.152599) (xy 310.288711 -368.204894) (xy 310.266069 -368.254471)
			(xy 310.236603 -368.300321) (xy 310.200912 -368.341512) (xy 310.159721 -368.377203) (xy 310.113871 -368.406669)
			(xy 310.064294 -368.429311) (xy 310.011999 -368.444666) (xy 309.958051 -368.452422) (xy 309.9308 -368.452908)
			(xy 309.91588 -368.452791) (xy 309.886127 -368.4505) (xy 309.871364 -368.448336) (xy 309.859172 -368.446304)
			(xy 309.836312 -368.45367) (xy 309.414418 -368.875818) (xy 309.399933 -368.889641) (xy 309.366659 -368.911899)
			(xy 309.329679 -368.927232) (xy 309.290416 -368.935049) (xy 309.2704 -368.935508) (xy 305.64201 -368.935508)
			(xy 305.631962 -368.935854) (xy 305.613366 -368.94346) (xy 305.605942 -368.95024) (xy 304.461418 -370.095018)
			(xy 304.446933 -370.108841) (xy 304.413659 -370.131099) (xy 304.376679 -370.146432) (xy 304.337416 -370.154249)
			(xy 304.3174 -370.154708) (xy 301.371254 -370.154708) (xy 301.351242 -370.154214) (xy 301.311989 -370.146386)
			(xy 301.275014 -370.131059) (xy 301.241735 -370.108821) (xy 301.227236 -370.095018) (xy 297.869864 -366.737392)
			(xy 297.862382 -366.730699) (xy 297.843824 -366.723107) (xy 297.833796 -366.72266) (xy 295.946322 -366.72266)
			(xy 295.9378 -366.722959) (xy 295.92169 -366.72852) (xy 295.908281 -366.739038) (xy 295.903396 -366.746028)
			(xy 295.85031 -366.829594) (xy 295.848786 -366.855502) (xy 295.854374 -366.86744) (xy 295.865843 -366.892988)
			(xy 295.882018 -366.946601) (xy 295.8902 -367.002) (xy 295.890696 -367.03) (xy 295.890245 -367.057253)
			(xy 295.882487 -367.111205) (xy 295.867131 -367.163504) (xy 295.844487 -367.213085) (xy 295.815018 -367.258939)
			(xy 295.779323 -367.300132) (xy 295.738129 -367.335825) (xy 295.692275 -367.365293) (xy 295.642693 -367.387935)
			(xy 295.590394 -367.40329) (xy 295.536441 -367.411045) (xy 295.509188 -367.411508) (xy 295.481511 -367.411002)
			(xy 295.426738 -367.402996) (xy 295.373698 -367.387154) (xy 295.323507 -367.363809) (xy 295.277219 -367.333452)
			(xy 295.235807 -367.29672) (xy 295.217596 -367.275872) (xy 295.208452 -367.265204) (xy 295.182798 -367.25606)
			(xy 295.068244 -367.278158) (xy 295.047924 -367.296192) (xy 295.043606 -367.3094) (xy 295.034848 -367.334436)
			(xy 295.011327 -367.381976) (xy 294.981448 -367.4258) (xy 294.945787 -367.465064) (xy 294.905032 -367.49901)
			(xy 294.859968 -367.526984) (xy 294.811463 -367.548446) (xy 294.760454 -367.562984) (xy 294.707922 -367.570317)
			(xy 294.681402 -367.570766) (xy 294.654147 -367.570343) (xy 294.600193 -367.562585) (xy 294.547892 -367.547227)
			(xy 294.498309 -367.524582) (xy 294.452454 -367.49511) (xy 294.41126 -367.459412) (xy 294.375566 -367.418214)
			(xy 294.346099 -367.372356) (xy 294.323459 -367.322771) (xy 294.308107 -367.270468) (xy 294.300354 -367.216513)
			(xy 294.299894 -367.189258) (xy 294.300351 -367.162001) (xy 294.308123 -367.108042) (xy 294.323501 -367.055741)
			(xy 294.346173 -367.006164) (xy 294.375676 -366.960322) (xy 294.411408 -366.91915) (xy 294.43172 -366.900968)
			(xy 294.443658 -366.890554) (xy 294.451532 -366.85982) (xy 294.41267 -366.75568) (xy 294.408592 -366.746204)
			(xy 294.394406 -366.731264) (xy 294.375474 -366.723139) (xy 294.365172 -366.72266) (xy 284.36189 -366.72266)
			(xy 284.341878 -366.722157) (xy 284.302625 -366.714334) (xy 284.26565 -366.69901) (xy 284.232371 -366.676773)
			(xy 284.217872 -366.66297) (xy 275.967952 -358.41305) (xy 275.954199 -358.398521) (xy 275.932019 -358.365237)
			(xy 275.916754 -358.328268) (xy 275.908988 -358.289031) (xy 275.908516 -358.269032) (xy 275.908516 -351.926652)
			(xy 275.908086 -351.916583) (xy 275.900371 -351.897984) (xy 275.89353 -351.890584) (xy 275.44141 -351.438464)
			(xy 275.41855 -351.431098) (xy 275.406358 -351.43313) (xy 275.391594 -351.435288) (xy 275.361842 -351.437577)
			(xy 275.346922 -351.437702) (xy 275.319669 -351.437224) (xy 275.265719 -351.42947) (xy 275.213421 -351.414117)
			(xy 275.16384 -351.391476) (xy 275.117987 -351.36201) (xy 275.076794 -351.326318) (xy 275.0411 -351.285126)
			(xy 275.011632 -351.239274) (xy 274.988989 -351.189694) (xy 274.973633 -351.137397) (xy 274.965877 -351.083447)
			(xy 274.965414 -351.056194) (xy 274.966085 -351.024632) (xy 274.976467 -350.962367) (xy 274.996949 -350.902657)
			(xy 275.011388 -350.874584) (xy 275.016214 -350.865694) (xy 275.018246 -350.846136) (xy 274.992592 -350.757998)
			(xy 274.980146 -350.742504) (xy 274.971256 -350.737424) (xy 274.96389 -350.73336) (xy 274.954238 -350.727518)
			(xy 274.93214 -350.725486) (xy 274.837652 -350.759014) (xy 274.82165 -350.774508) (xy 274.817586 -350.784922)
			(xy 274.80693 -350.811715) (xy 274.778637 -350.861958) (xy 274.743101 -350.907368) (xy 274.701133 -350.94691)
			(xy 274.65369 -350.979681) (xy 274.601854 -351.004936) (xy 274.546805 -351.022098) (xy 274.489801 -351.030775)
			(xy 274.46097 -351.031302) (xy 274.43372 -351.030826) (xy 274.379774 -351.023066) (xy 274.327482 -351.007708)
			(xy 274.277908 -350.985065) (xy 274.232061 -350.955597) (xy 274.190874 -350.919905) (xy 274.155185 -350.878715)
			(xy 274.125721 -350.832865) (xy 274.103081 -350.783289) (xy 274.087728 -350.730996) (xy 274.079972 -350.67705)
			(xy 273.811506 -350.67705) (xy 273.791137 -350.721193) (xy 273.761187 -350.767262) (xy 273.74342 -350.788224)
			(xy 273.737324 -350.795336) (xy 273.730974 -350.812354) (xy 273.730974 -350.898206) (xy 273.737324 -350.915224)
			(xy 273.74342 -350.922336) (xy 273.761185 -350.943297) (xy 273.791109 -350.98938) (xy 273.814121 -351.039274)
			(xy 273.829747 -351.091951) (xy 273.837663 -351.146324) (xy 273.838162 -351.173796) (xy 273.837676 -351.201047)
			(xy 273.82992 -351.254995) (xy 273.814565 -351.30729) (xy 273.791923 -351.356867) (xy 273.762457 -351.402717)
			(xy 273.726766 -351.443908) (xy 273.685575 -351.479599) (xy 273.639725 -351.509065) (xy 273.590148 -351.531707)
			(xy 273.537853 -351.547062) (xy 273.483905 -351.554818) (xy 273.429403 -351.554818) (xy 273.375455 -351.547062)
			(xy 273.32316 -351.531707) (xy 273.273583 -351.509065) (xy 273.227733 -351.479599) (xy 273.186542 -351.443908)
			(xy 273.150851 -351.402717) (xy 273.121385 -351.356867) (xy 273.098743 -351.30729) (xy 273.083388 -351.254995)
			(xy 273.075632 -351.201047) (xy 273.075146 -351.173796) (xy 260.312662 -351.173796) (xy 260.312662 -351.223326)
			(xy 260.313092 -351.233393) (xy 260.320819 -351.251984) (xy 260.327648 -351.259394) (xy 269.538958 -360.470704)
			(xy 271.604498 -360.470704) (xy 271.608464 -360.386173) (xy 271.620329 -360.302386) (xy 271.639987 -360.220077)
			(xy 271.667267 -360.139971) (xy 271.701928 -360.062772) (xy 271.743666 -359.989157) (xy 271.792113 -359.919774)
			(xy 271.846845 -359.855233) (xy 271.907381 -359.796101) (xy 271.973187 -359.742897) (xy 272.043687 -359.696089)
			(xy 272.118259 -359.656088) (xy 272.19625 -359.623246) (xy 272.276974 -359.597852) (xy 272.359721 -359.580129)
			(xy 272.443763 -359.570231) (xy 272.528364 -359.568248) (xy 272.612778 -359.574195) (xy 272.696265 -359.58802)
			(xy 272.77809 -359.609603) (xy 272.857534 -359.638753) (xy 272.9339 -359.675214) (xy 273.006516 -359.718666)
			(xy 273.074744 -359.768727) (xy 273.137984 -359.824957) (xy 273.195681 -359.886862) (xy 273.247328 -359.953898)
			(xy 273.29247 -360.025475) (xy 273.330712 -360.100965) (xy 273.361716 -360.179704) (xy 273.385211 -360.261001)
			(xy 273.40099 -360.34414) (xy 273.408914 -360.428392) (xy 273.40941 -360.470704) (xy 273.408914 -360.513016)
			(xy 273.40099 -360.597268) (xy 273.385211 -360.680407) (xy 273.361716 -360.761704) (xy 273.330712 -360.840443)
			(xy 273.29247 -360.915933) (xy 273.247328 -360.98751) (xy 273.195681 -361.054546) (xy 273.137984 -361.116451)
			(xy 273.074744 -361.172681) (xy 273.006516 -361.222742) (xy 272.9339 -361.266194) (xy 272.857534 -361.302655)
			(xy 272.77809 -361.331805) (xy 272.696265 -361.353388) (xy 272.612778 -361.367213) (xy 272.528364 -361.37316)
			(xy 272.443763 -361.371177) (xy 272.359721 -361.361279) (xy 272.276974 -361.343556) (xy 272.19625 -361.318162)
			(xy 272.118259 -361.28532) (xy 272.043687 -361.245319) (xy 271.973187 -361.198511) (xy 271.907381 -361.145307)
			(xy 271.846845 -361.086175) (xy 271.792113 -361.021634) (xy 271.743666 -360.952251) (xy 271.701928 -360.878636)
			(xy 271.667267 -360.801437) (xy 271.639987 -360.721331) (xy 271.620329 -360.639022) (xy 271.608464 -360.555235)
			(xy 271.604498 -360.470704) (xy 269.538958 -360.470704) (xy 271.134586 -362.066332) (xy 274.193252 -362.066332)
			(xy 274.197323 -362.01071) (xy 274.209449 -361.956273) (xy 274.229372 -361.904182) (xy 274.256668 -361.855547)
			(xy 274.290754 -361.811404) (xy 274.330903 -361.772695) (xy 274.376261 -361.740244) (xy 274.425861 -361.714743)
			(xy 274.478645 -361.696736) (xy 274.533488 -361.686606) (xy 274.589222 -361.684569) (xy 274.644659 -361.690669)
			(xy 274.698616 -361.704775) (xy 274.749945 -361.726587) (xy 274.797551 -361.755641) (xy 274.840419 -361.791316)
			(xy 274.877636 -361.832853) (xy 274.908409 -361.879366) (xy 274.932081 -361.929863) (xy 274.948149 -361.98327)
			(xy 274.956269 -362.038446) (xy 274.956778 -362.066332) (xy 274.956269 -362.094218) (xy 274.948149 -362.149394)
			(xy 274.932081 -362.202801) (xy 274.908409 -362.253298) (xy 274.877636 -362.299811) (xy 274.840419 -362.341348)
			(xy 274.797551 -362.377023) (xy 274.749945 -362.406077) (xy 274.698616 -362.427889) (xy 274.644659 -362.441995)
			(xy 274.589222 -362.448095) (xy 274.533488 -362.446058) (xy 274.478645 -362.435928) (xy 274.425861 -362.417921)
			(xy 274.376261 -362.39242) (xy 274.330903 -362.359969) (xy 274.290754 -362.32126) (xy 274.256668 -362.277117)
			(xy 274.229372 -362.228482) (xy 274.209449 -362.176391) (xy 274.197323 -362.121954) (xy 274.193252 -362.066332)
			(xy 271.134586 -362.066332) (xy 271.597628 -362.529374) (xy 271.606057 -362.536995) (xy 271.627424 -362.54464)
			(xy 271.638776 -362.544106) (xy 271.728692 -362.534962) (xy 271.747996 -362.523278) (xy 271.754346 -362.513626)
			(xy 271.77934 -362.476752) (xy 271.835516 -362.407611) (xy 271.898231 -362.344342) (xy 271.966876 -362.287561)
			(xy 272.040782 -362.23782) (xy 272.119229 -362.195603) (xy 272.201454 -362.161322) (xy 272.286658 -362.13531)
			(xy 272.374009 -362.11782) (xy 272.462659 -362.109022) (xy 272.507202 -362.108496) (xy 272.548892 -362.108963)
			(xy 272.631916 -362.116656) (xy 272.713876 -362.131978) (xy 272.794073 -362.154796) (xy 272.871822 -362.184916)
			(xy 272.94646 -362.222082) (xy 273.017351 -362.265976) (xy 273.08389 -362.316224) (xy 273.145508 -362.372396)
			(xy 273.20168 -362.434015) (xy 273.251927 -362.500554) (xy 273.295821 -362.571445) (xy 273.332986 -362.646083)
			(xy 273.363106 -362.723833) (xy 273.385924 -362.80403) (xy 273.401245 -362.88599) (xy 273.408937 -362.969014)
			(xy 273.40941 -363.010704) (xy 273.408936 -363.052564) (xy 273.401182 -363.135923) (xy 273.385741 -363.218207)
			(xy 273.362746 -363.298707) (xy 273.332395 -363.376731) (xy 273.294948 -363.451609) (xy 273.250728 -363.522697)
			(xy 273.200114 -363.589384) (xy 273.172174 -363.620558) (xy 273.162014 -363.631734) (xy 273.156934 -363.661452)
			(xy 273.200622 -363.760512) (xy 273.205003 -363.7693) (xy 273.219101 -363.782941) (xy 273.237294 -363.79028)
			(xy 273.247104 -363.790738) (xy 273.728434 -363.790738) (xy 273.738501 -363.791168) (xy 273.757093 -363.798895)
			(xy 273.764502 -363.805724) (xy 277.623016 -367.664238) (xy 277.630413 -367.671088) (xy 277.649011 -367.678827)
			(xy 277.659084 -367.679224) (xy 285.22168 -367.679224) (xy 285.231743 -367.679662) (xy 285.250324 -367.6874)
			(xy 285.257748 -367.69421) (xy 286.938974 -369.375436) (xy 295.870882 -369.375436) (xy 295.874953 -369.319814)
			(xy 295.887079 -369.265377) (xy 295.907002 -369.213286) (xy 295.934298 -369.164651) (xy 295.968384 -369.120508)
			(xy 296.008533 -369.081799) (xy 296.053891 -369.049348) (xy 296.103491 -369.023847) (xy 296.156275 -369.00584)
			(xy 296.211118 -368.99571) (xy 296.266852 -368.993673) (xy 296.322289 -368.999773) (xy 296.376246 -369.013879)
			(xy 296.427575 -369.035691) (xy 296.475181 -369.064745) (xy 296.518049 -369.10042) (xy 296.555266 -369.141957)
			(xy 296.586039 -369.18847) (xy 296.609711 -369.238967) (xy 296.625779 -369.292374) (xy 296.633899 -369.34755)
			(xy 296.634408 -369.375436) (xy 296.633899 -369.403322) (xy 296.625779 -369.458498) (xy 296.609711 -369.511905)
			(xy 296.586039 -369.562402) (xy 296.555266 -369.608915) (xy 296.518049 -369.650452) (xy 296.475181 -369.686127)
			(xy 296.427575 -369.715181) (xy 296.376246 -369.736993) (xy 296.322289 -369.751099) (xy 296.266852 -369.757199)
			(xy 296.211118 -369.755162) (xy 296.156275 -369.745032) (xy 296.103491 -369.727025) (xy 296.053891 -369.701524)
			(xy 296.008533 -369.669073) (xy 295.968384 -369.630364) (xy 295.934298 -369.586221) (xy 295.907002 -369.537586)
			(xy 295.887079 -369.485495) (xy 295.874953 -369.431058) (xy 295.870882 -369.375436) (xy 286.938974 -369.375436)
			(xy 287.659572 -370.096034) (xy 298.448982 -370.096034) (xy 298.453053 -370.040412) (xy 298.465179 -369.985975)
			(xy 298.485102 -369.933884) (xy 298.512398 -369.885249) (xy 298.546484 -369.841106) (xy 298.586633 -369.802397)
			(xy 298.631991 -369.769946) (xy 298.681591 -369.744445) (xy 298.734375 -369.726438) (xy 298.789218 -369.716308)
			(xy 298.844952 -369.714271) (xy 298.900389 -369.720371) (xy 298.954346 -369.734477) (xy 299.005675 -369.756289)
			(xy 299.053281 -369.785343) (xy 299.096149 -369.821018) (xy 299.133366 -369.862555) (xy 299.164139 -369.909068)
			(xy 299.187811 -369.959565) (xy 299.203879 -370.012972) (xy 299.211999 -370.068148) (xy 299.212508 -370.096034)
			(xy 299.212374 -370.1034) (xy 299.388782 -370.1034) (xy 299.392853 -370.047778) (xy 299.404979 -369.993341)
			(xy 299.424902 -369.94125) (xy 299.452198 -369.892615) (xy 299.486284 -369.848472) (xy 299.526433 -369.809763)
			(xy 299.571791 -369.777312) (xy 299.621391 -369.751811) (xy 299.674175 -369.733804) (xy 299.729018 -369.723674)
			(xy 299.784752 -369.721637) (xy 299.840189 -369.727737) (xy 299.894146 -369.741843) (xy 299.945475 -369.763655)
			(xy 299.993081 -369.792709) (xy 300.035949 -369.828384) (xy 300.073166 -369.869921) (xy 300.103939 -369.916434)
			(xy 300.127611 -369.966931) (xy 300.143679 -370.020338) (xy 300.151799 -370.075514) (xy 300.152308 -370.1034)
			(xy 300.151799 -370.131286) (xy 300.143679 -370.186462) (xy 300.127611 -370.239869) (xy 300.103939 -370.290366)
			(xy 300.073166 -370.336879) (xy 300.035949 -370.378416) (xy 299.993081 -370.414091) (xy 299.945475 -370.443145)
			(xy 299.894146 -370.464957) (xy 299.840189 -370.479063) (xy 299.784752 -370.485163) (xy 299.729018 -370.483126)
			(xy 299.674175 -370.472996) (xy 299.621391 -370.454989) (xy 299.571791 -370.429488) (xy 299.526433 -370.397037)
			(xy 299.486284 -370.358328) (xy 299.452198 -370.314185) (xy 299.424902 -370.26555) (xy 299.404979 -370.213459)
			(xy 299.392853 -370.159022) (xy 299.388782 -370.1034) (xy 299.212374 -370.1034) (xy 299.211999 -370.12392)
			(xy 299.203879 -370.179096) (xy 299.187811 -370.232503) (xy 299.164139 -370.283) (xy 299.133366 -370.329513)
			(xy 299.096149 -370.37105) (xy 299.053281 -370.406725) (xy 299.005675 -370.435779) (xy 298.954346 -370.457591)
			(xy 298.900389 -370.471697) (xy 298.844952 -370.477797) (xy 298.789218 -370.47576) (xy 298.734375 -370.46563)
			(xy 298.681591 -370.447623) (xy 298.631991 -370.422122) (xy 298.586633 -370.389671) (xy 298.546484 -370.350962)
			(xy 298.512398 -370.306819) (xy 298.485102 -370.258184) (xy 298.465179 -370.206093) (xy 298.453053 -370.151656)
			(xy 298.448982 -370.096034) (xy 287.659572 -370.096034) (xy 288.154364 -370.590826) (xy 288.161763 -370.59767)
			(xy 288.180362 -370.605393) (xy 288.190432 -370.605812) (xy 288.234882 -370.605812) (xy 288.244945 -370.60625)
			(xy 288.263527 -370.613987) (xy 288.27095 -370.620798) (xy 292.211252 -374.5611) (xy 292.218615 -374.567931)
			(xy 292.237127 -374.575682) (xy 292.257197 -374.575737) (xy 292.266624 -374.572276) (xy 292.281102 -374.56618)
			(xy 292.29812 -374.54078) (xy 292.29812 -373.842788) (xy 292.297581 -373.832801) (xy 292.289867 -373.81437)
			(xy 292.283134 -373.806974) (xy 292.061138 -373.584978) (xy 292.044061 -373.567277) (xy 292.01513 -373.527502)
			(xy 291.992786 -373.483687) (xy 291.977579 -373.436914) (xy 291.969885 -373.388336) (xy 291.969444 -373.363744)
			(xy 291.969444 -371.783102) (xy 291.969278 -371.775788) (xy 291.965277 -371.761723) (xy 291.96157 -371.755416)
			(xy 291.947206 -371.732247) (xy 291.924525 -371.682675) (xy 291.909135 -371.630379) (xy 291.901348 -371.576425)
			(xy 291.900864 -371.549168) (xy 291.901352 -371.521918) (xy 291.909112 -371.467972) (xy 291.92447 -371.415679)
			(xy 291.947112 -371.366104) (xy 291.976579 -371.320256) (xy 292.01227 -371.279067) (xy 292.053459 -371.243377)
			(xy 292.099308 -371.21391) (xy 292.148883 -371.191268) (xy 292.201176 -371.175911) (xy 292.255122 -371.168152)
			(xy 292.282372 -371.16766) (xy 292.310351 -371.168151) (xy 292.365708 -371.176331) (xy 292.419274 -371.19252)
			(xy 292.469896 -371.216369) (xy 292.516485 -371.247365) (xy 292.55804 -371.284842) (xy 292.57625 -371.30609)
			(xy 292.58387 -371.315234) (xy 292.605206 -371.324632) (xy 292.709346 -371.32133) (xy 292.72992 -371.310408)
			(xy 292.736778 -371.300756) (xy 292.752227 -371.28016) (xy 292.78777 -371.242911) (xy 292.827996 -371.210776)
			(xy 292.872176 -371.18434) (xy 292.919509 -371.164081) (xy 292.969135 -371.150367) (xy 293.020153 -371.143447)
			(xy 293.045896 -371.143022) (xy 293.074668 -371.143552) (xy 293.131558 -371.152205) (xy 293.186504 -371.1693)
			(xy 293.238262 -371.194449) (xy 293.285657 -371.227084) (xy 293.327617 -371.266463) (xy 293.363189 -371.311695)
			(xy 293.391569 -371.361755) (xy 293.412111 -371.415507) (xy 293.418768 -371.443504) (xy 293.420292 -371.45087)
			(xy 293.42715 -371.463316) (xy 293.629334 -371.6655) (xy 294.448482 -371.6655) (xy 294.452553 -371.609878)
			(xy 294.464679 -371.555441) (xy 294.484602 -371.50335) (xy 294.511898 -371.454715) (xy 294.545984 -371.410572)
			(xy 294.586133 -371.371863) (xy 294.631491 -371.339412) (xy 294.681091 -371.313911) (xy 294.733875 -371.295904)
			(xy 294.788718 -371.285774) (xy 294.844452 -371.283737) (xy 294.899889 -371.289837) (xy 294.953846 -371.303943)
			(xy 295.005175 -371.325755) (xy 295.052781 -371.354809) (xy 295.095649 -371.390484) (xy 295.132866 -371.432021)
			(xy 295.163639 -371.478534) (xy 295.187311 -371.529031) (xy 295.203379 -371.582438) (xy 295.211499 -371.637614)
			(xy 295.212008 -371.6655) (xy 295.211776 -371.6782) (xy 295.350182 -371.6782) (xy 295.354253 -371.622578)
			(xy 295.366379 -371.568141) (xy 295.386302 -371.51605) (xy 295.413598 -371.467415) (xy 295.447684 -371.423272)
			(xy 295.487833 -371.384563) (xy 295.533191 -371.352112) (xy 295.582791 -371.326611) (xy 295.635575 -371.308604)
			(xy 295.690418 -371.298474) (xy 295.746152 -371.296437) (xy 295.801589 -371.302537) (xy 295.855546 -371.316643)
			(xy 295.906875 -371.338455) (xy 295.954481 -371.367509) (xy 295.997349 -371.403184) (xy 296.034566 -371.444721)
			(xy 296.065339 -371.491234) (xy 296.089011 -371.541731) (xy 296.105079 -371.595138) (xy 296.113199 -371.650314)
			(xy 296.113708 -371.6782) (xy 296.113199 -371.706086) (xy 296.105079 -371.761262) (xy 296.089011 -371.814669)
			(xy 296.065339 -371.865166) (xy 296.034566 -371.911679) (xy 295.997349 -371.953216) (xy 295.954481 -371.988891)
			(xy 295.906875 -372.017945) (xy 295.855546 -372.039757) (xy 295.801589 -372.053863) (xy 295.746152 -372.059963)
			(xy 295.690418 -372.057926) (xy 295.635575 -372.047796) (xy 295.582791 -372.029789) (xy 295.533191 -372.004288)
			(xy 295.487833 -371.971837) (xy 295.447684 -371.933128) (xy 295.413598 -371.888985) (xy 295.386302 -371.84035)
			(xy 295.366379 -371.788259) (xy 295.354253 -371.733822) (xy 295.350182 -371.6782) (xy 295.211776 -371.6782)
			(xy 295.211499 -371.693386) (xy 295.203379 -371.748562) (xy 295.187311 -371.801969) (xy 295.163639 -371.852466)
			(xy 295.132866 -371.898979) (xy 295.095649 -371.940516) (xy 295.052781 -371.976191) (xy 295.005175 -372.005245)
			(xy 294.953846 -372.027057) (xy 294.899889 -372.041163) (xy 294.844452 -372.047263) (xy 294.788718 -372.045226)
			(xy 294.733875 -372.035096) (xy 294.681091 -372.017089) (xy 294.631491 -371.991588) (xy 294.586133 -371.959137)
			(xy 294.545984 -371.920428) (xy 294.511898 -371.876285) (xy 294.484602 -371.82765) (xy 294.464679 -371.775559)
			(xy 294.452553 -371.721122) (xy 294.448482 -371.6655) (xy 293.629334 -371.6655) (xy 294.1574 -372.193566)
			(xy 294.174451 -372.211278) (xy 294.203329 -372.251066) (xy 294.225622 -372.294885) (xy 294.240781 -372.341653)
			(xy 294.248431 -372.390218) (xy 294.24884 -372.4148) (xy 294.24884 -373.196612) (xy 294.249543 -373.20805)
			(xy 294.259582 -373.228616) (xy 294.268144 -373.236236) (xy 294.339264 -373.293132) (xy 294.361616 -373.298212)
			(xy 294.373046 -373.295672) (xy 294.393965 -373.291164) (xy 294.436485 -373.286323) (xy 294.457882 -373.28602)
			(xy 294.485136 -373.286526) (xy 294.539086 -373.294321) (xy 294.591378 -373.309712) (xy 294.640948 -373.332386)
			(xy 294.66413 -373.346726) (xy 294.670434 -373.350441) (xy 294.684501 -373.354449) (xy 294.691816 -373.3546)
			(xy 296.327068 -373.3546) (xy 296.351657 -373.355063) (xy 296.400227 -373.362769) (xy 296.446994 -373.37798)
			(xy 296.490804 -373.400322) (xy 296.530578 -373.429244) (xy 296.548302 -373.446294) (xy 297.310556 -374.208548)
			(xy 297.327606 -374.226261) (xy 297.356481 -374.266051) (xy 297.378772 -374.309869) (xy 297.393931 -374.356637)
			(xy 297.401582 -374.4052) (xy 297.401996 -374.429782) (xy 297.401996 -374.574816) (xy 297.402487 -374.584822)
			(xy 297.410149 -374.603309) (xy 297.424301 -374.617458) (xy 297.44279 -374.625115) (xy 297.452796 -374.625616)
		)
		(stroke
			(width 0)
			(type solid)
		)
		(fill yes)
		(layer "In4.Cu")
		(net "GND")
	)
	(gr_poly
		(pts
			(xy 47.426118 -394.189966) (xy 47.434712 -394.189681) (xy 47.450962 -394.184091) (xy 47.464452 -394.173445)
			(xy 47.469298 -394.166344) (xy 47.52213 -394.082524) (xy 47.523654 -394.056616) (xy 47.518066 -394.044678)
			(xy 47.507902 -394.022357) (xy 47.493541 -393.975462) (xy 47.486271 -393.92696) (xy 47.485808 -393.902438)
			(xy 47.486357 -393.874949) (xy 47.495454 -393.820729) (xy 47.513387 -393.768759) (xy 47.539663 -393.720467)
			(xy 47.556166 -393.698476) (xy 47.562008 -393.69111) (xy 47.567342 -393.67333) (xy 47.562008 -393.587224)
			(xy 47.554388 -393.57046) (xy 47.547784 -393.563856) (xy 47.526791 -393.542211) (xy 47.491214 -393.493529)
			(xy 47.463733 -393.439859) (xy 47.445033 -393.382536) (xy 47.435578 -393.322986) (xy 47.435008 -393.292838)
			(xy 47.435008 -392.429238) (xy 47.43543 -392.402887) (xy 47.442641 -392.350683) (xy 47.456973 -392.299969)
			(xy 47.478153 -392.251711) (xy 47.505777 -392.206831) (xy 47.539319 -392.166183) (xy 47.558452 -392.14806)
			(xy 47.565564 -392.14171) (xy 47.573692 -392.124946) (xy 47.582074 -392.038332) (xy 47.576994 -392.020552)
			(xy 47.571406 -392.012678) (xy 47.557247 -391.992834) (xy 47.534756 -391.949587) (xy 47.519435 -391.903311)
			(xy 47.511675 -391.855187) (xy 47.511208 -391.830814) (xy 47.51173 -391.805559) (xy 47.520043 -391.755737)
			(xy 47.536444 -391.707963) (xy 47.560485 -391.66354) (xy 47.591509 -391.62368) (xy 47.628671 -391.58947)
			(xy 47.670957 -391.561844) (xy 47.717213 -391.541554) (xy 47.766178 -391.529154) (xy 47.816516 -391.524983)
			(xy 47.866854 -391.529154) (xy 47.915819 -391.541554) (xy 47.962075 -391.561844) (xy 48.004361 -391.58947)
			(xy 48.041523 -391.62368) (xy 48.072547 -391.66354) (xy 48.096588 -391.707963) (xy 48.112989 -391.755737)
			(xy 48.121302 -391.805559) (xy 48.121824 -391.830814) (xy 48.121326 -391.855184) (xy 48.113545 -391.903299)
			(xy 48.098232 -391.949572) (xy 48.075773 -391.992829) (xy 48.061626 -392.012678) (xy 48.056038 -392.020552)
			(xy 48.050958 -392.038332) (xy 48.05934 -392.124946) (xy 48.067468 -392.14171) (xy 48.07458 -392.14806)
			(xy 48.093679 -392.166214) (xy 48.127202 -392.206867) (xy 48.154816 -392.251744) (xy 48.175994 -392.299994)
			(xy 48.190333 -392.350697) (xy 48.197563 -392.402892) (xy 48.198024 -392.429238) (xy 48.198024 -393.292838)
			(xy 48.197473 -393.322987) (xy 48.188025 -393.382541) (xy 48.169321 -393.439865) (xy 48.141829 -393.493531)
			(xy 48.106234 -393.542202) (xy 48.085248 -393.563856) (xy 48.078644 -393.57046) (xy 48.071024 -393.587224)
			(xy 48.06569 -393.67333) (xy 48.071024 -393.69111) (xy 48.076866 -393.698476) (xy 48.09339 -393.720452)
			(xy 48.119667 -393.768746) (xy 48.137591 -393.820722) (xy 48.146666 -393.874948) (xy 48.147224 -393.902438)
			(xy 48.146762 -393.92696) (xy 48.139488 -393.975462) (xy 48.125136 -394.02236) (xy 48.114966 -394.044678)
			(xy 48.109378 -394.056616) (xy 48.110902 -394.082524) (xy 48.163734 -394.166344) (xy 48.168611 -394.17342)
			(xy 48.182085 -394.184068) (xy 48.198325 -394.189655) (xy 48.206914 -394.189966) (xy 48.626014 -394.189966)
			(xy 48.634608 -394.189681) (xy 48.65086 -394.184093) (xy 48.66435 -394.173447) (xy 48.669194 -394.166344)
			(xy 48.722026 -394.082524) (xy 48.72355 -394.056616) (xy 48.717962 -394.044678) (xy 48.707798 -394.022357)
			(xy 48.693437 -393.975462) (xy 48.686167 -393.92696) (xy 48.685704 -393.902438) (xy 48.686253 -393.874949)
			(xy 48.69535 -393.820729) (xy 48.713282 -393.768759) (xy 48.739558 -393.720467) (xy 48.756062 -393.698476)
			(xy 48.761904 -393.69111) (xy 48.767238 -393.67333) (xy 48.761904 -393.587224) (xy 48.754284 -393.57046)
			(xy 48.74768 -393.563856) (xy 48.726683 -393.542213) (xy 48.691097 -393.493534) (xy 48.663609 -393.439865)
			(xy 48.644904 -393.38254) (xy 48.635446 -393.322988) (xy 48.634904 -393.292838) (xy 48.634904 -392.429238)
			(xy 48.635326 -392.402887) (xy 48.642537 -392.350683) (xy 48.656869 -392.299968) (xy 48.678049 -392.251711)
			(xy 48.705673 -392.206831) (xy 48.739214 -392.166182) (xy 48.758348 -392.14806) (xy 48.76546 -392.141456)
			(xy 48.773842 -392.124946) (xy 48.78197 -392.038078) (xy 48.777144 -392.020298) (xy 48.771302 -392.012678)
			(xy 48.757199 -391.992812) (xy 48.73481 -391.949545) (xy 48.719566 -391.903275) (xy 48.711854 -391.855172)
			(xy 48.711358 -391.830814) (xy 48.71188 -391.805559) (xy 48.720193 -391.755737) (xy 48.736594 -391.707963)
			(xy 48.760635 -391.66354) (xy 48.791659 -391.62368) (xy 48.828821 -391.58947) (xy 48.871107 -391.561844)
			(xy 48.917363 -391.541554) (xy 48.966328 -391.529154) (xy 49.016666 -391.524983) (xy 49.067004 -391.529154)
			(xy 49.115969 -391.541554) (xy 49.162225 -391.561844) (xy 49.204511 -391.58947) (xy 49.241673 -391.62368)
			(xy 49.272697 -391.66354) (xy 49.296738 -391.707963) (xy 49.313139 -391.755737) (xy 49.321452 -391.805559)
			(xy 49.321974 -391.830814) (xy 49.321496 -391.855216) (xy 49.313736 -391.903398) (xy 49.298418 -391.949735)
			(xy 49.275929 -391.993048) (xy 49.261776 -392.012932) (xy 49.256188 -392.020552) (xy 49.251108 -392.038332)
			(xy 49.259236 -392.1252) (xy 49.267618 -392.14171) (xy 49.27473 -392.148314) (xy 49.293791 -392.166464)
			(xy 49.327246 -392.207096) (xy 49.354804 -392.251937) (xy 49.375941 -392.300139) (xy 49.390258 -392.350787)
			(xy 49.397482 -392.402922) (xy 49.39792 -392.429238) (xy 49.39792 -393.292838) (xy 49.397369 -393.322987)
			(xy 49.387921 -393.382541) (xy 49.369217 -393.439865) (xy 49.341725 -393.493531) (xy 49.306129 -393.542201)
			(xy 49.285144 -393.563856) (xy 49.27854 -393.57046) (xy 49.27092 -393.587224) (xy 49.265586 -393.67333)
			(xy 49.27092 -393.69111) (xy 49.276762 -393.698476) (xy 49.293286 -393.720452) (xy 49.319564 -393.768746)
			(xy 49.337488 -393.820722) (xy 49.346563 -393.874948) (xy 49.34712 -393.902438) (xy 49.346658 -393.92696)
			(xy 49.339387 -393.975463) (xy 49.325038 -394.022362) (xy 49.314862 -394.044678) (xy 49.309274 -394.056616)
			(xy 49.310798 -394.082524) (xy 49.36363 -394.166344) (xy 49.368507 -394.17342) (xy 49.381981 -394.18407)
			(xy 49.398221 -394.189658) (xy 49.40681 -394.189966) (xy 49.815242 -394.189966) (xy 49.827681 -394.189271)
			(xy 49.849637 -394.177552) (xy 49.857152 -394.167614) (xy 49.911508 -394.08735) (xy 49.914302 -394.062458)
			(xy 49.909476 -394.050774) (xy 49.898483 -394.021235) (xy 49.88659 -393.959348) (xy 49.885854 -393.927838)
			(xy 49.886256 -393.90444) (xy 49.892843 -393.85811) (xy 49.90589 -393.81317) (xy 49.925138 -393.770516)
			(xy 49.950202 -393.730999) (xy 49.965102 -393.712954) (xy 49.971706 -393.705334) (xy 49.977802 -393.687046)
			(xy 49.972468 -393.596876) (xy 49.96434 -393.57935) (xy 49.956974 -393.572492) (xy 49.938074 -393.554379)
			(xy 49.90491 -393.513874) (xy 49.87759 -393.469218) (xy 49.856626 -393.421249) (xy 49.842413 -393.370865)
			(xy 49.835215 -393.319013) (xy 49.8348 -393.292838) (xy 49.8348 -392.429238) (xy 49.835243 -392.40288)
			(xy 49.842499 -392.350667) (xy 49.856879 -392.29995) (xy 49.878109 -392.251698) (xy 49.905783 -392.206831)
			(xy 49.939373 -392.166203) (xy 49.958498 -392.14806) (xy 49.96561 -392.14171) (xy 49.973738 -392.124946)
			(xy 49.98212 -392.038332) (xy 49.97704 -392.020552) (xy 49.971452 -392.012678) (xy 49.957295 -391.992833)
			(xy 49.934808 -391.949585) (xy 49.91949 -391.90331) (xy 49.911731 -391.855186) (xy 49.911254 -391.830814)
			(xy 49.911776 -391.805559) (xy 49.920089 -391.755737) (xy 49.93649 -391.707963) (xy 49.960531 -391.66354)
			(xy 49.991555 -391.62368) (xy 50.028717 -391.58947) (xy 50.071003 -391.561844) (xy 50.117259 -391.541554)
			(xy 50.166224 -391.529154) (xy 50.216562 -391.524983) (xy 50.2669 -391.529154) (xy 50.315865 -391.541554)
			(xy 50.362121 -391.561844) (xy 50.404407 -391.58947) (xy 50.441569 -391.62368) (xy 50.472593 -391.66354)
			(xy 50.496634 -391.707963) (xy 50.513035 -391.755737) (xy 50.521348 -391.805559) (xy 50.52187 -391.830814)
			(xy 50.521372 -391.855184) (xy 50.513592 -391.9033) (xy 50.498281 -391.949574) (xy 50.475825 -391.992833)
			(xy 50.461672 -392.012678) (xy 50.456084 -392.020552) (xy 50.451004 -392.038332) (xy 50.459386 -392.124946)
			(xy 50.467514 -392.14171) (xy 50.474626 -392.14806) (xy 50.49375 -392.166201) (xy 50.527325 -392.206838)
			(xy 50.554988 -392.251708) (xy 50.576212 -392.299959) (xy 50.590592 -392.350672) (xy 50.597856 -392.402882)
			(xy 50.598324 -392.429238) (xy 50.598324 -393.292838) (xy 50.597876 -393.319012) (xy 50.590691 -393.370865)
			(xy 50.576487 -393.42125) (xy 50.555531 -393.469221) (xy 50.528216 -393.513879) (xy 50.495056 -393.554385)
			(xy 50.47615 -393.572492) (xy 50.468784 -393.57935) (xy 50.460656 -393.596876) (xy 50.455322 -393.687046)
			(xy 50.461418 -393.705334) (xy 50.468022 -393.712954) (xy 50.482903 -393.731012) (xy 50.507964 -393.770527)
			(xy 50.527209 -393.813179) (xy 50.540255 -393.858115) (xy 50.54684 -393.904442) (xy 50.54727 -393.927838)
			(xy 50.546589 -393.959353) (xy 50.534686 -394.021247) (xy 50.523648 -394.050774) (xy 50.518822 -394.062458)
			(xy 50.521616 -394.08735) (xy 50.575972 -394.167614) (xy 50.583453 -394.177587) (xy 50.605431 -394.189294)
			(xy 50.617882 -394.189966) (xy 51.039268 -394.189966) (xy 51.048119 -394.189581) (xy 51.064767 -394.18356)
			(xy 51.078388 -394.172253) (xy 51.08321 -394.16482) (xy 51.134264 -394.077444) (xy 51.134518 -394.05052)
			(xy 51.127914 -394.038836) (xy 51.114645 -394.013957) (xy 51.095847 -393.960801) (xy 51.086324 -393.905229)
			(xy 51.08575 -393.877038) (xy 51.086249 -393.851257) (xy 51.094265 -393.800322) (xy 51.110092 -393.75125)
			(xy 51.133347 -393.70523) (xy 51.14798 -393.683998) (xy 51.15306 -393.676886) (xy 51.157886 -393.659868)
			(xy 51.152298 -393.577572) (xy 51.145186 -393.56157) (xy 51.13909 -393.554966) (xy 51.119606 -393.533594)
			(xy 51.086659 -393.486068) (xy 51.061263 -393.434113) (xy 51.044 -393.378919) (xy 51.035265 -393.321753)
			(xy 51.034696 -393.292838) (xy 51.034696 -392.429238) (xy 51.035139 -392.40288) (xy 51.042395 -392.350666)
			(xy 51.056775 -392.29995) (xy 51.078004 -392.251698) (xy 51.105678 -392.20683) (xy 51.139268 -392.166203)
			(xy 51.158394 -392.14806) (xy 51.165506 -392.14171) (xy 51.173634 -392.124946) (xy 51.182016 -392.038332)
			(xy 51.176936 -392.020552) (xy 51.171348 -392.012678) (xy 51.157191 -391.992833) (xy 51.134705 -391.949585)
			(xy 51.119387 -391.90331) (xy 51.111628 -391.855186) (xy 51.11115 -391.830814) (xy 51.111672 -391.805559)
			(xy 51.119985 -391.755737) (xy 51.136386 -391.707963) (xy 51.160427 -391.66354) (xy 51.191451 -391.62368)
			(xy 51.228613 -391.58947) (xy 51.270899 -391.561844) (xy 51.317155 -391.541554) (xy 51.36612 -391.529154)
			(xy 51.416458 -391.524983) (xy 51.466796 -391.529154) (xy 51.515761 -391.541554) (xy 51.562017 -391.561844)
			(xy 51.604303 -391.58947) (xy 51.641465 -391.62368) (xy 51.672489 -391.66354) (xy 51.69653 -391.707963)
			(xy 51.712931 -391.755737) (xy 51.721244 -391.805559) (xy 51.721766 -391.830814) (xy 51.721268 -391.855184)
			(xy 51.713488 -391.9033) (xy 51.698177 -391.949573) (xy 51.675721 -391.992833) (xy 51.661568 -392.012678)
			(xy 51.65598 -392.020552) (xy 51.6509 -392.038332) (xy 51.659282 -392.124946) (xy 51.66741 -392.14171)
			(xy 51.674522 -392.14806) (xy 51.693646 -392.166201) (xy 51.727222 -392.206837) (xy 51.754885 -392.251708)
			(xy 51.776109 -392.299959) (xy 51.790489 -392.350672) (xy 51.797753 -392.402882) (xy 51.79822 -392.429238)
			(xy 51.79822 -393.292838) (xy 51.797663 -393.321751) (xy 51.788899 -393.37891) (xy 51.771623 -393.434097)
			(xy 51.746228 -393.48605) (xy 51.713295 -393.533583) (xy 51.693826 -393.554966) (xy 51.68773 -393.56157)
			(xy 51.680618 -393.577572) (xy 51.67503 -393.659868) (xy 51.679856 -393.676886) (xy 51.684936 -393.683998)
			(xy 51.699596 -393.705213) (xy 51.722853 -393.751237) (xy 51.738676 -393.800315) (xy 51.746681 -393.851255)
			(xy 51.747166 -393.877038) (xy 51.746617 -393.905231) (xy 51.737091 -393.960804) (xy 51.718271 -394.013955)
			(xy 51.705002 -394.038836) (xy 51.698398 -394.05052) (xy 51.698652 -394.077444) (xy 51.749706 -394.16482)
			(xy 51.754458 -394.172314) (xy 51.768087 -394.183662) (xy 51.784779 -394.189654) (xy 51.793648 -394.189966)
			(xy 52.215288 -394.189966) (xy 52.227734 -394.189283) (xy 52.249709 -394.177577) (xy 52.257198 -394.167614)
			(xy 52.311554 -394.08735) (xy 52.314348 -394.062458) (xy 52.309522 -394.050774) (xy 52.298527 -394.021235)
			(xy 52.286633 -393.959348) (xy 52.2859 -393.927838) (xy 52.286302 -393.90444) (xy 52.292889 -393.858111)
			(xy 52.305938 -393.813172) (xy 52.325188 -393.770519) (xy 52.350255 -393.731004) (xy 52.365148 -393.712954)
			(xy 52.371752 -393.705334) (xy 52.377848 -393.687046) (xy 52.372514 -393.596876) (xy 52.364386 -393.57935)
			(xy 52.35702 -393.572492) (xy 52.33815 -393.554365) (xy 52.305048 -393.513841) (xy 52.277788 -393.469177)
			(xy 52.256883 -393.421209) (xy 52.242722 -393.370836) (xy 52.235573 -393.319001) (xy 52.2351 -393.292838)
			(xy 52.2351 -392.429238) (xy 52.235522 -392.402887) (xy 52.242733 -392.350682) (xy 52.257065 -392.299968)
			(xy 52.278245 -392.251711) (xy 52.305868 -392.20683) (xy 52.339409 -392.166181) (xy 52.358544 -392.14806)
			(xy 52.365656 -392.14171) (xy 52.373784 -392.124946) (xy 52.382166 -392.038332) (xy 52.377086 -392.020552)
			(xy 52.371498 -392.012678) (xy 52.357339 -391.992834) (xy 52.334849 -391.949586) (xy 52.319529 -391.903311)
			(xy 52.311769 -391.855187) (xy 52.3113 -391.830814) (xy 52.311822 -391.805559) (xy 52.320135 -391.755737)
			(xy 52.336536 -391.707963) (xy 52.360577 -391.66354) (xy 52.391601 -391.62368) (xy 52.428763 -391.58947)
			(xy 52.471049 -391.561844) (xy 52.517305 -391.541554) (xy 52.56627 -391.529154) (xy 52.616608 -391.524983)
			(xy 52.666946 -391.529154) (xy 52.715911 -391.541554) (xy 52.762167 -391.561844) (xy 52.804453 -391.58947)
			(xy 52.841615 -391.62368) (xy 52.872639 -391.66354) (xy 52.89668 -391.707963) (xy 52.913081 -391.755737)
			(xy 52.921394 -391.805559) (xy 52.921916 -391.830814) (xy 52.921418 -391.855184) (xy 52.913637 -391.903299)
			(xy 52.898324 -391.949571) (xy 52.875864 -391.992829) (xy 52.861718 -392.012678) (xy 52.85613 -392.020552)
			(xy 52.85105 -392.038332) (xy 52.859432 -392.124946) (xy 52.86756 -392.14171) (xy 52.874672 -392.14806)
			(xy 52.893771 -392.166214) (xy 52.927295 -392.206866) (xy 52.954909 -392.251744) (xy 52.976088 -392.299993)
			(xy 52.990428 -392.350697) (xy 52.997657 -392.402891) (xy 52.998116 -392.429238) (xy 52.998116 -393.292838)
			(xy 52.997689 -393.319004) (xy 52.990547 -393.370846) (xy 52.976387 -393.421227) (xy 52.955477 -393.469199)
			(xy 52.928207 -393.513865) (xy 52.89509 -393.554385) (xy 52.876196 -393.572492) (xy 52.86883 -393.57935)
			(xy 52.860702 -393.596876) (xy 52.855368 -393.687046) (xy 52.861464 -393.705334) (xy 52.868068 -393.712954)
			(xy 52.882947 -393.731013) (xy 52.908005 -393.770529) (xy 52.927247 -393.813181) (xy 52.940291 -393.858117)
			(xy 52.946876 -393.904442) (xy 52.947316 -393.927838) (xy 52.946635 -393.959353) (xy 52.934734 -394.021248)
			(xy 52.923694 -394.050774) (xy 52.918868 -394.062458) (xy 52.921662 -394.08735) (xy 52.976018 -394.167614)
			(xy 52.983495 -394.177596) (xy 53.005473 -394.189326) (xy 53.017928 -394.189966) (xy 53.415184 -394.189966)
			(xy 53.42763 -394.189284) (xy 53.449607 -394.177578) (xy 53.457094 -394.167614) (xy 53.51145 -394.08735)
			(xy 53.514244 -394.062458) (xy 53.509418 -394.050774) (xy 53.498424 -394.021235) (xy 53.486529 -393.959348)
			(xy 53.485796 -393.927838) (xy 53.486198 -393.90444) (xy 53.492785 -393.858111) (xy 53.505834 -393.813172)
			(xy 53.525084 -393.770519) (xy 53.550151 -393.731004) (xy 53.565044 -393.712954) (xy 53.571648 -393.705334)
			(xy 53.577744 -393.687046) (xy 53.57241 -393.596876) (xy 53.564282 -393.57935) (xy 53.556916 -393.572492)
			(xy 53.538046 -393.554365) (xy 53.504944 -393.51384) (xy 53.477685 -393.469176) (xy 53.45678 -393.421208)
			(xy 53.44262 -393.370835) (xy 53.43547 -393.319001) (xy 53.434996 -393.292838) (xy 53.434996 -392.429238)
			(xy 53.435418 -392.402887) (xy 53.442629 -392.350682) (xy 53.456961 -392.299968) (xy 53.47814 -392.25171)
			(xy 53.505764 -392.20683) (xy 53.539305 -392.16618) (xy 53.55844 -392.14806) (xy 53.565552 -392.14171)
			(xy 53.57368 -392.124946) (xy 53.582062 -392.038332) (xy 53.576982 -392.020552) (xy 53.571394 -392.012678)
			(xy 53.557235 -391.992834) (xy 53.534745 -391.949586) (xy 53.519425 -391.903311) (xy 53.511665 -391.855187)
			(xy 53.511196 -391.830814) (xy 53.511718 -391.805559) (xy 53.520031 -391.755737) (xy 53.536432 -391.707963)
			(xy 53.560473 -391.66354) (xy 53.591497 -391.62368) (xy 53.628659 -391.58947) (xy 53.670945 -391.561844)
			(xy 53.717201 -391.541554) (xy 53.766166 -391.529154) (xy 53.816504 -391.524983) (xy 53.866842 -391.529154)
			(xy 53.915807 -391.541554) (xy 53.962063 -391.561844) (xy 54.004349 -391.58947) (xy 54.041511 -391.62368)
			(xy 54.072535 -391.66354) (xy 54.096576 -391.707963) (xy 54.112977 -391.755737) (xy 54.12129 -391.805559)
			(xy 54.121812 -391.830814) (xy 54.121313 -391.855184) (xy 54.113533 -391.903299) (xy 54.098219 -391.949571)
			(xy 54.07576 -391.992828) (xy 54.061614 -392.012678) (xy 54.056026 -392.020552) (xy 54.050946 -392.038332)
			(xy 54.059328 -392.124946) (xy 54.067456 -392.14171) (xy 54.074568 -392.14806) (xy 54.093667 -392.166214)
			(xy 54.127192 -392.206866) (xy 54.154806 -392.251744) (xy 54.175985 -392.299993) (xy 54.190325 -392.350697)
			(xy 54.197554 -392.402891) (xy 54.198012 -392.429238) (xy 54.198012 -393.292838) (xy 54.197585 -393.319004)
			(xy 54.190443 -393.370846) (xy 54.176283 -393.421226) (xy 54.155372 -393.469199) (xy 54.128102 -393.513864)
			(xy 54.094985 -393.554384) (xy 54.076092 -393.572492) (xy 54.068726 -393.57935) (xy 54.060598 -393.596876)
			(xy 54.055264 -393.687046) (xy 54.06136 -393.705334) (xy 54.067964 -393.712954) (xy 54.082843 -393.731013)
			(xy 54.107901 -393.770529) (xy 54.127144 -393.81318) (xy 54.140188 -393.858117) (xy 54.146773 -393.904442)
			(xy 54.147212 -393.927838) (xy 54.146531 -393.959353) (xy 54.13463 -394.021248) (xy 54.12359 -394.050774)
			(xy 54.118764 -394.062458) (xy 54.121558 -394.08735) (xy 54.175914 -394.167614) (xy 54.183391 -394.177597)
			(xy 54.205369 -394.189329) (xy 54.217824 -394.189966) (xy 54.639464 -394.189966) (xy 54.648315 -394.189582)
			(xy 54.664964 -394.183561) (xy 54.678587 -394.172255) (xy 54.683406 -394.16482) (xy 54.73446 -394.077444)
			(xy 54.734714 -394.05052) (xy 54.72811 -394.038836) (xy 54.714841 -394.013957) (xy 54.696043 -393.960801)
			(xy 54.68652 -393.905229) (xy 54.685946 -393.877038) (xy 54.686445 -393.851257) (xy 54.694461 -393.800322)
			(xy 54.710288 -393.75125) (xy 54.733543 -393.70523) (xy 54.748176 -393.683998) (xy 54.753256 -393.676886)
			(xy 54.758082 -393.659868) (xy 54.752494 -393.577572) (xy 54.745382 -393.56157) (xy 54.739286 -393.554966)
			(xy 54.719803 -393.533594) (xy 54.686856 -393.486068) (xy 54.66146 -393.434112) (xy 54.644197 -393.378919)
			(xy 54.635462 -393.321753) (xy 54.634892 -393.292838) (xy 54.634892 -392.429238) (xy 54.635335 -392.40288)
			(xy 54.642591 -392.350666) (xy 54.656971 -392.29995) (xy 54.6782 -392.251698) (xy 54.705874 -392.20683)
			(xy 54.739464 -392.166202) (xy 54.75859 -392.14806) (xy 54.765702 -392.14171) (xy 54.77383 -392.124946)
			(xy 54.782212 -392.038332) (xy 54.777132 -392.020552) (xy 54.771544 -392.012678) (xy 54.757387 -391.992833)
			(xy 54.734901 -391.949585) (xy 54.719584 -391.903309) (xy 54.711825 -391.855186) (xy 54.711346 -391.830814)
			(xy 54.711868 -391.805559) (xy 54.720181 -391.755737) (xy 54.736582 -391.707963) (xy 54.760623 -391.66354)
			(xy 54.791647 -391.62368) (xy 54.828809 -391.58947) (xy 54.871095 -391.561844) (xy 54.917351 -391.541554)
			(xy 54.966316 -391.529154) (xy 55.016654 -391.524983) (xy 55.066992 -391.529154) (xy 55.115957 -391.541554)
			(xy 55.162213 -391.561844) (xy 55.204499 -391.58947) (xy 55.241661 -391.62368) (xy 55.272685 -391.66354)
			(xy 55.296726 -391.707963) (xy 55.313127 -391.755737) (xy 55.32144 -391.805559) (xy 55.321962 -391.830814)
			(xy 55.321464 -391.855184) (xy 55.313684 -391.9033) (xy 55.298373 -391.949573) (xy 55.275916 -391.992833)
			(xy 55.261764 -392.012678) (xy 55.256176 -392.020552) (xy 55.251096 -392.038332) (xy 55.259478 -392.124946)
			(xy 55.267606 -392.14171) (xy 55.274718 -392.14806) (xy 55.293843 -392.166201) (xy 55.327418 -392.206837)
			(xy 55.355082 -392.251708) (xy 55.376306 -392.299959) (xy 55.390687 -392.350672) (xy 55.39795 -392.402882)
			(xy 55.398416 -392.429238) (xy 55.398416 -393.292838) (xy 55.397859 -393.321751) (xy 55.389095 -393.37891)
			(xy 55.371818 -393.434096) (xy 55.346424 -393.486049) (xy 55.313491 -393.533582) (xy 55.294022 -393.554966)
			(xy 55.287926 -393.56157) (xy 55.280814 -393.577572) (xy 55.275226 -393.659868) (xy 55.280052 -393.676886)
			(xy 55.285132 -393.683998) (xy 55.299793 -393.705213) (xy 55.323049 -393.751236) (xy 55.338872 -393.800315)
			(xy 55.346878 -393.851255) (xy 55.347362 -393.877038) (xy 55.346813 -393.90523) (xy 55.337287 -393.960804)
			(xy 55.318466 -394.013954) (xy 55.305198 -394.038836) (xy 55.298594 -394.05052) (xy 55.298848 -394.077444)
			(xy 55.349902 -394.16482) (xy 55.354654 -394.172315) (xy 55.368283 -394.183663) (xy 55.384975 -394.189657)
			(xy 55.393844 -394.189966) (xy 55.826152 -394.189966) (xy 55.834743 -394.189676) (xy 55.850985 -394.184078)
			(xy 55.864466 -394.173429) (xy 55.869332 -394.166344) (xy 55.922164 -394.082524) (xy 55.923688 -394.056616)
			(xy 55.9181 -394.044678) (xy 55.907937 -394.022357) (xy 55.893579 -393.975462) (xy 55.88631 -393.92696)
			(xy 55.885842 -393.902438) (xy 55.88639 -393.874949) (xy 55.895485 -393.820728) (xy 55.913416 -393.768755)
			(xy 55.939688 -393.72046) (xy 55.9562 -393.698476) (xy 55.962042 -393.69111) (xy 55.967376 -393.67333)
			(xy 55.962042 -393.587224) (xy 55.954422 -393.57046) (xy 55.947818 -393.563856) (xy 55.926797 -393.542223)
			(xy 55.891164 -393.493557) (xy 55.863631 -393.439891) (xy 55.844884 -393.382561) (xy 55.835389 -393.322996)
			(xy 55.834788 -393.292838) (xy 55.834788 -392.429238) (xy 55.835231 -392.40288) (xy 55.842487 -392.350666)
			(xy 55.856867 -392.29995) (xy 55.878096 -392.251697) (xy 55.905769 -392.206829) (xy 55.939359 -392.166201)
			(xy 55.958486 -392.14806) (xy 55.965598 -392.14171) (xy 55.973726 -392.124946) (xy 55.982108 -392.038332)
			(xy 55.977028 -392.020552) (xy 55.97144 -392.012678) (xy 55.957283 -391.992833) (xy 55.934798 -391.949585)
			(xy 55.91948 -391.903309) (xy 55.911722 -391.855186) (xy 55.911242 -391.830814) (xy 55.911764 -391.805559)
			(xy 55.920077 -391.755737) (xy 55.936478 -391.707963) (xy 55.960519 -391.66354) (xy 55.991543 -391.62368)
			(xy 56.028705 -391.58947) (xy 56.070991 -391.561844) (xy 56.117247 -391.541554) (xy 56.166212 -391.529154)
			(xy 56.21655 -391.524983) (xy 56.266888 -391.529154) (xy 56.315853 -391.541554) (xy 56.362109 -391.561844)
			(xy 56.404395 -391.58947) (xy 56.441557 -391.62368) (xy 56.472581 -391.66354) (xy 56.496622 -391.707963)
			(xy 56.513023 -391.755737) (xy 56.521336 -391.805559) (xy 56.521858 -391.830814) (xy 56.52136 -391.855184)
			(xy 56.51358 -391.9033) (xy 56.498268 -391.949573) (xy 56.475812 -391.992832) (xy 56.46166 -392.012678)
			(xy 56.456072 -392.020552) (xy 56.450992 -392.038332) (xy 56.459374 -392.124946) (xy 56.467502 -392.14171)
			(xy 56.474614 -392.14806) (xy 56.493739 -392.166201) (xy 56.527315 -392.206837) (xy 56.554979 -392.251708)
			(xy 56.576203 -392.299959) (xy 56.590584 -392.350672) (xy 56.597848 -392.402882) (xy 56.598312 -392.429238)
			(xy 56.598312 -393.292838) (xy 56.597744 -393.322999) (xy 56.588256 -393.38257) (xy 56.569508 -393.439905)
			(xy 56.541966 -393.493572) (xy 56.506318 -393.542234) (xy 56.485282 -393.563856) (xy 56.478678 -393.57046)
			(xy 56.471058 -393.587224) (xy 56.465724 -393.67333) (xy 56.471058 -393.69111) (xy 56.4769 -393.698476)
			(xy 56.493422 -393.720453) (xy 56.519697 -393.768747) (xy 56.537619 -393.820723) (xy 56.546693 -393.874948)
			(xy 56.547258 -393.902438) (xy 56.546796 -393.92696) (xy 56.539523 -393.975463) (xy 56.525172 -394.022361)
			(xy 56.515 -394.044678) (xy 56.509412 -394.056616) (xy 56.510936 -394.082524) (xy 56.563768 -394.166344)
			(xy 56.568642 -394.173427) (xy 56.582113 -394.184093) (xy 56.598355 -394.1897) (xy 56.606948 -394.189966)
			(xy 57.01538 -394.189966) (xy 57.027827 -394.189285) (xy 57.049805 -394.17758) (xy 57.05729 -394.167614)
			(xy 57.111646 -394.08735) (xy 57.11444 -394.062458) (xy 57.109614 -394.050774) (xy 57.09862 -394.021235)
			(xy 57.086725 -393.959348) (xy 57.085992 -393.927838) (xy 57.086394 -393.90444) (xy 57.092981 -393.858111)
			(xy 57.10603 -393.813172) (xy 57.125279 -393.770519) (xy 57.150346 -393.731003) (xy 57.16524 -393.712954)
			(xy 57.171844 -393.705334) (xy 57.17794 -393.687046) (xy 57.172606 -393.596876) (xy 57.164478 -393.57935)
			(xy 57.157112 -393.572492) (xy 57.138242 -393.554364) (xy 57.105141 -393.51384) (xy 57.077882 -393.469176)
			(xy 57.056977 -393.421208) (xy 57.042817 -393.370835) (xy 57.035667 -393.319001) (xy 57.035192 -393.292838)
			(xy 57.035192 -392.429238) (xy 57.035612 -392.402919) (xy 57.04281 -392.350775) (xy 57.057115 -392.300119)
			(xy 57.078256 -392.251913) (xy 57.105829 -392.207075) (xy 57.139311 -392.166458) (xy 57.158382 -392.148314)
			(xy 57.165494 -392.14171) (xy 57.173876 -392.1252) (xy 57.182004 -392.038332) (xy 57.176924 -392.020552)
			(xy 57.171336 -392.012932) (xy 57.157175 -391.993053) (xy 57.134684 -391.949739) (xy 57.119364 -391.903401)
			(xy 57.111604 -391.855217) (xy 57.111138 -391.830814) (xy 57.11166 -391.805559) (xy 57.119973 -391.755737)
			(xy 57.136374 -391.707963) (xy 57.160415 -391.66354) (xy 57.191439 -391.62368) (xy 57.228601 -391.58947)
			(xy 57.270887 -391.561844) (xy 57.317143 -391.541554) (xy 57.366108 -391.529154) (xy 57.416446 -391.524983)
			(xy 57.466784 -391.529154) (xy 57.515749 -391.541554) (xy 57.562005 -391.561844) (xy 57.604291 -391.58947)
			(xy 57.641453 -391.62368) (xy 57.672477 -391.66354) (xy 57.696518 -391.707963) (xy 57.712919 -391.755737)
			(xy 57.721232 -391.805559) (xy 57.721754 -391.830814) (xy 57.7213 -391.855175) (xy 57.713595 -391.903284)
			(xy 57.698338 -391.949555) (xy 57.675915 -391.99281) (xy 57.66181 -392.012678) (xy 57.655968 -392.020298)
			(xy 57.651142 -392.038078) (xy 57.65927 -392.124946) (xy 57.667652 -392.141456) (xy 57.674764 -392.14806)
			(xy 57.693863 -392.166213) (xy 57.727389 -392.206866) (xy 57.755003 -392.251743) (xy 57.776182 -392.299993)
			(xy 57.790522 -392.350697) (xy 57.797752 -392.402891) (xy 57.798208 -392.429238) (xy 57.798208 -393.292838)
			(xy 57.797781 -393.319004) (xy 57.790639 -393.370846) (xy 57.776479 -393.421226) (xy 57.755568 -393.469199)
			(xy 57.728298 -393.513864) (xy 57.69518 -393.554384) (xy 57.676288 -393.572492) (xy 57.668922 -393.57935)
			(xy 57.660794 -393.596876) (xy 57.65546 -393.687046) (xy 57.661556 -393.705334) (xy 57.66816 -393.712954)
			(xy 57.683039 -393.731013) (xy 57.708098 -393.770529) (xy 57.727341 -393.81318) (xy 57.740385 -393.858117)
			(xy 57.746969 -393.904442) (xy 57.747408 -393.927838) (xy 57.746727 -393.959353) (xy 57.734826 -394.021248)
			(xy 57.723786 -394.050774) (xy 57.71896 -394.062458) (xy 57.721754 -394.08735) (xy 57.77611 -394.167614)
			(xy 57.783586 -394.177598) (xy 57.805564 -394.189331) (xy 57.81802 -394.189966) (xy 58.215276 -394.189966)
			(xy 58.227723 -394.189286) (xy 58.249703 -394.177582) (xy 58.257186 -394.167614) (xy 58.311542 -394.08735)
			(xy 58.314336 -394.062458) (xy 58.30951 -394.050774) (xy 58.298516 -394.021235) (xy 58.286622 -393.959348)
			(xy 58.285888 -393.927838) (xy 58.28629 -393.90444) (xy 58.292877 -393.858111) (xy 58.305926 -393.813171)
			(xy 58.325175 -393.770518) (xy 58.350242 -393.731003) (xy 58.365136 -393.712954) (xy 58.37174 -393.705334)
			(xy 58.377836 -393.687046) (xy 58.372502 -393.596876) (xy 58.364374 -393.57935) (xy 58.357008 -393.572492)
			(xy 58.338139 -393.554364) (xy 58.305037 -393.51384) (xy 58.277779 -393.469176) (xy 58.256874 -393.421208)
			(xy 58.242714 -393.370835) (xy 58.235564 -393.319001) (xy 58.235088 -393.292838) (xy 58.235088 -392.429238)
			(xy 58.23551 -392.402888) (xy 58.242722 -392.350685) (xy 58.257057 -392.299972) (xy 58.27824 -392.251718)
			(xy 58.305868 -392.206842) (xy 58.339414 -392.166198) (xy 58.358532 -392.14806) (xy 58.365644 -392.14171)
			(xy 58.373772 -392.124946) (xy 58.382154 -392.038332) (xy 58.377074 -392.020552) (xy 58.371486 -392.012678)
			(xy 58.357327 -391.992834) (xy 58.334838 -391.949586) (xy 58.319519 -391.903311) (xy 58.311759 -391.855187)
			(xy 58.311288 -391.830814) (xy 58.31181 -391.805559) (xy 58.320123 -391.755737) (xy 58.336524 -391.707963)
			(xy 58.360565 -391.66354) (xy 58.391589 -391.62368) (xy 58.428751 -391.58947) (xy 58.471037 -391.561844)
			(xy 58.517293 -391.541554) (xy 58.566258 -391.529154) (xy 58.616596 -391.524983) (xy 58.666934 -391.529154)
			(xy 58.715899 -391.541554) (xy 58.762155 -391.561844) (xy 58.804441 -391.58947) (xy 58.841603 -391.62368)
			(xy 58.872627 -391.66354) (xy 58.896668 -391.707963) (xy 58.913069 -391.755737) (xy 58.921382 -391.805559)
			(xy 58.921904 -391.830814) (xy 58.921405 -391.855184) (xy 58.913625 -391.903299) (xy 58.898311 -391.949571)
			(xy 58.875851 -391.992828) (xy 58.861706 -392.012678) (xy 58.856118 -392.020552) (xy 58.851038 -392.038332)
			(xy 58.85942 -392.124946) (xy 58.867548 -392.14171) (xy 58.87466 -392.14806) (xy 58.893759 -392.166213)
			(xy 58.927285 -392.206866) (xy 58.9549 -392.251743) (xy 58.976079 -392.299992) (xy 58.990419 -392.350697)
			(xy 58.997649 -392.402891) (xy 58.998104 -392.429238) (xy 58.998104 -393.292838) (xy 58.997677 -393.319004)
			(xy 58.990535 -393.370846) (xy 58.976375 -393.421226) (xy 58.955464 -393.469198) (xy 58.928193 -393.513863)
			(xy 58.895075 -393.554383) (xy 58.876184 -393.572492) (xy 58.868818 -393.57935) (xy 58.86069 -393.596876)
			(xy 58.855356 -393.687046) (xy 58.861452 -393.705334) (xy 58.868056 -393.712954) (xy 58.882936 -393.731013)
			(xy 58.907994 -393.770529) (xy 58.927237 -393.81318) (xy 58.940281 -393.858117) (xy 58.946866 -393.904442)
			(xy 58.947304 -393.927838) (xy 58.946623 -393.959353) (xy 58.934722 -394.021248) (xy 58.923682 -394.050774)
			(xy 58.918856 -394.062458) (xy 58.92165 -394.08735) (xy 58.976006 -394.167614) (xy 58.983482 -394.177599)
			(xy 59.00546 -394.189334) (xy 59.017916 -394.189966) (xy 59.415426 -394.189966) (xy 59.427867 -394.189275)
			(xy 59.449829 -394.177559) (xy 59.457336 -394.167614) (xy 59.511692 -394.08735) (xy 59.514486 -394.062458)
			(xy 59.50966 -394.050774) (xy 59.498664 -394.021235) (xy 59.486768 -393.959348) (xy 59.486038 -393.927838)
			(xy 59.48644 -393.90444) (xy 59.493026 -393.85811) (xy 59.506073 -393.813169) (xy 59.52532 -393.770515)
			(xy 59.550384 -393.730997) (xy 59.565286 -393.712954) (xy 59.57189 -393.705334) (xy 59.577986 -393.687046)
			(xy 59.572652 -393.596876) (xy 59.564524 -393.57935) (xy 59.557158 -393.572492) (xy 59.538258 -393.554378)
			(xy 59.505096 -393.513873) (xy 59.477777 -393.469217) (xy 59.456814 -393.421248) (xy 59.442601 -393.370865)
			(xy 59.435404 -393.319012) (xy 59.434984 -393.292838) (xy 59.434984 -392.429238) (xy 59.435449 -392.402915)
			(xy 59.442726 -392.350773) (xy 59.457092 -392.300125) (xy 59.478276 -392.251928) (xy 59.505875 -392.207095)
			(xy 59.539368 -392.166476) (xy 59.558428 -392.148314) (xy 59.56554 -392.14171) (xy 59.573922 -392.1252)
			(xy 59.58205 -392.038332) (xy 59.57697 -392.020552) (xy 59.571382 -392.012932) (xy 59.557219 -391.993054)
			(xy 59.534725 -391.949741) (xy 59.519402 -391.903402) (xy 59.511641 -391.855217) (xy 59.511184 -391.830814)
			(xy 59.511706 -391.805559) (xy 59.520019 -391.755737) (xy 59.53642 -391.707963) (xy 59.560461 -391.66354)
			(xy 59.591485 -391.62368) (xy 59.628647 -391.58947) (xy 59.670933 -391.561844) (xy 59.717189 -391.541554)
			(xy 59.766154 -391.529154) (xy 59.816492 -391.524983) (xy 59.86683 -391.529154) (xy 59.915795 -391.541554)
			(xy 59.962051 -391.561844) (xy 60.004337 -391.58947) (xy 60.041499 -391.62368) (xy 60.072523 -391.66354)
			(xy 60.096564 -391.707963) (xy 60.112965 -391.755737) (xy 60.121278 -391.805559) (xy 60.1218 -391.830814)
			(xy 60.121346 -391.855175) (xy 60.113643 -391.903285) (xy 60.098387 -391.949557) (xy 60.075967 -391.992814)
			(xy 60.061856 -392.012678) (xy 60.056014 -392.020298) (xy 60.051188 -392.038078) (xy 60.059316 -392.124946)
			(xy 60.067698 -392.141456) (xy 60.07481 -392.14806) (xy 60.093935 -392.166201) (xy 60.127511 -392.206837)
			(xy 60.155175 -392.251707) (xy 60.1764 -392.299958) (xy 60.190781 -392.350672) (xy 60.198045 -392.402882)
			(xy 60.198508 -392.429238) (xy 60.198508 -393.292838) (xy 60.19806 -393.319012) (xy 60.190874 -393.370865)
			(xy 60.17667 -393.421249) (xy 60.155713 -393.46922) (xy 60.128398 -393.513877) (xy 60.095237 -393.554382)
			(xy 60.076334 -393.572492) (xy 60.068968 -393.57935) (xy 60.06084 -393.596876) (xy 60.055506 -393.687046)
			(xy 60.061602 -393.705334) (xy 60.068206 -393.712954) (xy 60.083088 -393.731012) (xy 60.10815 -393.770527)
			(xy 60.127396 -393.813178) (xy 60.140442 -393.858115) (xy 60.147028 -393.904442) (xy 60.147454 -393.927838)
			(xy 60.146773 -393.959353) (xy 60.13487 -394.021247) (xy 60.123832 -394.050774) (xy 60.119006 -394.062458)
			(xy 60.1218 -394.08735) (xy 60.176156 -394.167614) (xy 60.183636 -394.17759) (xy 60.205614 -394.189303)
			(xy 60.218066 -394.189966) (xy 60.615322 -394.189966) (xy 60.627764 -394.189276) (xy 60.649727 -394.177561)
			(xy 60.657232 -394.167614) (xy 60.711588 -394.08735) (xy 60.714382 -394.062458) (xy 60.709556 -394.050774)
			(xy 60.69856 -394.021235) (xy 60.686665 -393.959348) (xy 60.685934 -393.927838) (xy 60.686336 -393.90444)
			(xy 60.692922 -393.85811) (xy 60.705969 -393.813169) (xy 60.725216 -393.770514) (xy 60.750279 -393.730996)
			(xy 60.765182 -393.712954) (xy 60.771786 -393.705334) (xy 60.777882 -393.687046) (xy 60.772548 -393.596876)
			(xy 60.76442 -393.57935) (xy 60.757054 -393.572492) (xy 60.738155 -393.554378) (xy 60.704992 -393.513873)
			(xy 60.677674 -393.469217) (xy 60.656711 -393.421248) (xy 60.642499 -393.370865) (xy 60.635302 -393.319012)
			(xy 60.63488 -393.292838) (xy 60.63488 -392.429238) (xy 60.635323 -392.40288) (xy 60.642579 -392.350666)
			(xy 60.656959 -392.299949) (xy 60.678187 -392.251697) (xy 60.70586 -392.206828) (xy 60.739449 -392.166199)
			(xy 60.758578 -392.14806) (xy 60.76569 -392.14171) (xy 60.773818 -392.124946) (xy 60.7822 -392.038332)
			(xy 60.77712 -392.020552) (xy 60.771532 -392.012678) (xy 60.757376 -391.992833) (xy 60.734891 -391.949584)
			(xy 60.719574 -391.903309) (xy 60.711815 -391.855186) (xy 60.711334 -391.830814) (xy 60.711856 -391.805559)
			(xy 60.720169 -391.755737) (xy 60.73657 -391.707963) (xy 60.760611 -391.66354) (xy 60.791635 -391.62368)
			(xy 60.828797 -391.58947) (xy 60.871083 -391.561844) (xy 60.917339 -391.541554) (xy 60.966304 -391.529154)
			(xy 61.016642 -391.524983) (xy 61.06698 -391.529154) (xy 61.115945 -391.541554) (xy 61.162201 -391.561844)
			(xy 61.204487 -391.58947) (xy 61.241649 -391.62368) (xy 61.272673 -391.66354) (xy 61.296714 -391.707963)
			(xy 61.313115 -391.755737) (xy 61.321428 -391.805559) (xy 61.32195 -391.830814) (xy 61.321452 -391.855184)
			(xy 61.313672 -391.9033) (xy 61.29836 -391.949573) (xy 61.275903 -391.992832) (xy 61.261752 -392.012678)
			(xy 61.256164 -392.020552) (xy 61.251084 -392.038332) (xy 61.259466 -392.124946) (xy 61.267594 -392.14171)
			(xy 61.274706 -392.14806) (xy 61.293831 -392.166201) (xy 61.327408 -392.206837) (xy 61.355072 -392.251707)
			(xy 61.376297 -392.299958) (xy 61.390678 -392.350671) (xy 61.397942 -392.402882) (xy 61.398404 -392.429238)
			(xy 61.398404 -393.292838) (xy 61.397956 -393.319012) (xy 61.39077 -393.370865) (xy 61.376566 -393.421249)
			(xy 61.355609 -393.46922) (xy 61.328294 -393.513877) (xy 61.295132 -393.554382) (xy 61.27623 -393.572492)
			(xy 61.268864 -393.57935) (xy 61.260736 -393.596876) (xy 61.255402 -393.687046) (xy 61.261498 -393.705334)
			(xy 61.268102 -393.712954) (xy 61.282984 -393.731012) (xy 61.308046 -393.770527) (xy 61.327293 -393.813178)
			(xy 61.340339 -393.858115) (xy 61.346925 -393.904442) (xy 61.34735 -393.927838) (xy 61.346669 -393.959353)
			(xy 61.334766 -394.021247) (xy 61.323728 -394.050774) (xy 61.318902 -394.062458) (xy 61.321696 -394.08735)
			(xy 61.376052 -394.167614) (xy 61.383532 -394.177591) (xy 61.40551 -394.189306) (xy 61.417962 -394.189966)
			(xy 61.839348 -394.189966) (xy 61.848201 -394.189584) (xy 61.864853 -394.183567) (xy 61.878481 -394.172262)
			(xy 61.88329 -394.16482) (xy 61.934344 -394.077444) (xy 61.934598 -394.05052) (xy 61.927994 -394.038836)
			(xy 61.914722 -394.013958) (xy 61.895919 -393.960802) (xy 61.886394 -393.90523) (xy 61.88583 -393.877038)
			(xy 61.886329 -393.851257) (xy 61.894344 -393.800322) (xy 61.910171 -393.751249) (xy 61.933425 -393.705229)
			(xy 61.94806 -393.683998) (xy 61.95314 -393.676886) (xy 61.957966 -393.659868) (xy 61.952378 -393.577572)
			(xy 61.945266 -393.56157) (xy 61.93917 -393.554966) (xy 61.919687 -393.533594) (xy 61.886742 -393.486067)
			(xy 61.861347 -393.434112) (xy 61.844085 -393.378919) (xy 61.835351 -393.321753) (xy 61.834776 -393.292838)
			(xy 61.834776 -392.429238) (xy 61.835219 -392.40288) (xy 61.842475 -392.350666) (xy 61.856854 -392.299949)
			(xy 61.878083 -392.251696) (xy 61.905755 -392.206828) (xy 61.939345 -392.166199) (xy 61.958474 -392.14806)
			(xy 61.965586 -392.14171) (xy 61.973714 -392.124946) (xy 61.982096 -392.038332) (xy 61.977016 -392.020552)
			(xy 61.971428 -392.012678) (xy 61.957272 -391.992833) (xy 61.934787 -391.949584) (xy 61.91947 -391.903309)
			(xy 61.911712 -391.855186) (xy 61.91123 -391.830814) (xy 61.911752 -391.805559) (xy 61.920065 -391.755737)
			(xy 61.936466 -391.707963) (xy 61.960507 -391.66354) (xy 61.991531 -391.62368) (xy 62.028693 -391.58947)
			(xy 62.070979 -391.561844) (xy 62.117235 -391.541554) (xy 62.1662 -391.529154) (xy 62.216538 -391.524983)
			(xy 62.266876 -391.529154) (xy 62.315841 -391.541554) (xy 62.362097 -391.561844) (xy 62.404383 -391.58947)
			(xy 62.441545 -391.62368) (xy 62.472569 -391.66354) (xy 62.49661 -391.707963) (xy 62.513011 -391.755737)
			(xy 62.521324 -391.805559) (xy 62.521846 -391.830814) (xy 62.521348 -391.855184) (xy 62.513568 -391.9033)
			(xy 62.498256 -391.949572) (xy 62.475798 -391.992831) (xy 62.461648 -392.012678) (xy 62.45606 -392.020552)
			(xy 62.45098 -392.038332) (xy 62.459362 -392.124946) (xy 62.46749 -392.14171) (xy 62.474602 -392.14806)
			(xy 62.493727 -392.166201) (xy 62.527305 -392.206836) (xy 62.554969 -392.251707) (xy 62.576194 -392.299958)
			(xy 62.590575 -392.350671) (xy 62.597839 -392.402882) (xy 62.5983 -392.429238) (xy 62.5983 -393.292838)
			(xy 62.597743 -393.321751) (xy 62.588978 -393.37891) (xy 62.571701 -393.434095) (xy 62.546306 -393.486048)
			(xy 62.513372 -393.53358) (xy 62.493906 -393.554966) (xy 62.48781 -393.56157) (xy 62.480698 -393.577572)
			(xy 62.47511 -393.659868) (xy 62.479936 -393.676886) (xy 62.485016 -393.683998) (xy 62.499677 -393.705213)
			(xy 62.522935 -393.751236) (xy 62.538759 -393.800314) (xy 62.546765 -393.851255) (xy 62.547246 -393.877038)
			(xy 62.546697 -393.90523) (xy 62.53717 -393.960804) (xy 62.518349 -394.013954) (xy 62.505082 -394.038836)
			(xy 62.498478 -394.05052) (xy 62.498732 -394.077444) (xy 62.549786 -394.16482) (xy 62.554537 -394.172316)
			(xy 62.568166 -394.183669) (xy 62.584858 -394.189668) (xy 62.593728 -394.189966) (xy 63.015114 -394.189966)
			(xy 63.027557 -394.189277) (xy 63.049523 -394.177565) (xy 63.057024 -394.167614) (xy 63.11138 -394.08735)
			(xy 63.114174 -394.062458) (xy 63.109348 -394.050774) (xy 63.098353 -394.021235) (xy 63.086457 -393.959348)
			(xy 63.085726 -393.927838) (xy 63.086128 -393.90444) (xy 63.092714 -393.85811) (xy 63.105761 -393.813169)
			(xy 63.125007 -393.770514) (xy 63.15007 -393.730995) (xy 63.164974 -393.712954) (xy 63.171578 -393.705334)
			(xy 63.177674 -393.687046) (xy 63.17234 -393.596876) (xy 63.164212 -393.57935) (xy 63.156846 -393.572492)
			(xy 63.137947 -393.554378) (xy 63.104785 -393.513872) (xy 63.077467 -393.469216) (xy 63.056506 -393.421247)
			(xy 63.042293 -393.370864) (xy 63.035096 -393.319012) (xy 63.034672 -393.292838) (xy 63.034672 -392.429238)
			(xy 63.035115 -392.40288) (xy 63.042371 -392.350666) (xy 63.05675 -392.299949) (xy 63.077978 -392.251696)
			(xy 63.105651 -392.206827) (xy 63.13924 -392.166198) (xy 63.15837 -392.14806) (xy 63.165482 -392.14171)
			(xy 63.17361 -392.124946) (xy 63.181992 -392.038332) (xy 63.176912 -392.020552) (xy 63.171324 -392.012678)
			(xy 63.157168 -391.992833) (xy 63.134684 -391.949584) (xy 63.119367 -391.903309) (xy 63.111609 -391.855186)
			(xy 63.111126 -391.830814) (xy 63.111648 -391.805559) (xy 63.119961 -391.755737) (xy 63.136362 -391.707963)
			(xy 63.160403 -391.66354) (xy 63.191427 -391.62368) (xy 63.228589 -391.58947) (xy 63.270875 -391.561844)
			(xy 63.317131 -391.541554) (xy 63.366096 -391.529154) (xy 63.416434 -391.524983) (xy 63.466772 -391.529154)
			(xy 63.515737 -391.541554) (xy 63.561993 -391.561844) (xy 63.604279 -391.58947) (xy 63.641441 -391.62368)
			(xy 63.672465 -391.66354) (xy 63.696506 -391.707963) (xy 63.712907 -391.755737) (xy 63.72122 -391.805559)
			(xy 63.721742 -391.830814) (xy 63.721244 -391.855184) (xy 63.713464 -391.9033) (xy 63.698151 -391.949572)
			(xy 63.675694 -391.992831) (xy 63.661544 -392.012678) (xy 63.655956 -392.020552) (xy 63.650876 -392.038332)
			(xy 63.659258 -392.124946) (xy 63.667386 -392.14171) (xy 63.674498 -392.14806) (xy 63.693623 -392.166201)
			(xy 63.727201 -392.206836) (xy 63.754866 -392.251706) (xy 63.776091 -392.299958) (xy 63.790473 -392.350671)
			(xy 63.797737 -392.402881) (xy 63.798196 -392.429238) (xy 63.798196 -393.292838) (xy 63.797748 -393.319012)
			(xy 63.790562 -393.370865) (xy 63.776357 -393.421249) (xy 63.7554 -393.469219) (xy 63.728085 -393.513876)
			(xy 63.694922 -393.55438) (xy 63.676022 -393.572492) (xy 63.668656 -393.57935) (xy 63.660528 -393.596876)
			(xy 63.655194 -393.687046) (xy 63.66129 -393.705334) (xy 63.667894 -393.712954) (xy 63.682776 -393.731012)
			(xy 63.707839 -393.770526) (xy 63.727086 -393.813177) (xy 63.740133 -393.858115) (xy 63.746719 -393.904442)
			(xy 63.747142 -393.927838) (xy 63.746461 -393.959353) (xy 63.734557 -394.021247) (xy 63.72352 -394.050774)
			(xy 63.718694 -394.062458) (xy 63.721488 -394.08735) (xy 63.775844 -394.167614) (xy 63.783323 -394.177592)
			(xy 63.805301 -394.189311) (xy 63.817754 -394.189966) (xy 64.215264 -394.189966) (xy 64.227701 -394.189267)
			(xy 64.249648 -394.177542) (xy 64.257174 -394.167614) (xy 64.31153 -394.08735) (xy 64.314324 -394.062458)
			(xy 64.309498 -394.050774) (xy 64.298504 -394.021235) (xy 64.28661 -393.959348) (xy 64.285876 -393.927838)
			(xy 64.286278 -393.90444) (xy 64.292865 -393.858111) (xy 64.305913 -393.813171) (xy 64.325162 -393.770518)
			(xy 64.350228 -393.731001) (xy 64.365124 -393.712954) (xy 64.371728 -393.705334) (xy 64.377824 -393.687046)
			(xy 64.37249 -393.596876) (xy 64.364362 -393.57935) (xy 64.356996 -393.572492) (xy 64.338127 -393.554364)
			(xy 64.305026 -393.51384) (xy 64.277769 -393.469175) (xy 64.256864 -393.421207) (xy 64.242705 -393.370835)
			(xy 64.235556 -393.319) (xy 64.235076 -393.292838) (xy 64.235076 -392.429238) (xy 64.235498 -392.402888)
			(xy 64.24271 -392.350684) (xy 64.257044 -392.299972) (xy 64.278227 -392.251717) (xy 64.305855 -392.20684)
			(xy 64.3394 -392.166196) (xy 64.35852 -392.14806) (xy 64.365632 -392.14171) (xy 64.37376 -392.124946)
			(xy 64.382142 -392.038332) (xy 64.377062 -392.020552) (xy 64.371474 -392.012678) (xy 64.357316 -391.992834)
			(xy 64.334828 -391.949586) (xy 64.319509 -391.90331) (xy 64.311749 -391.855187) (xy 64.311276 -391.830814)
			(xy 64.311798 -391.805559) (xy 64.320111 -391.755737) (xy 64.336512 -391.707963) (xy 64.360553 -391.66354)
			(xy 64.391577 -391.62368) (xy 64.428739 -391.58947) (xy 64.471025 -391.561844) (xy 64.517281 -391.541554)
			(xy 64.566246 -391.529154) (xy 64.616584 -391.524983) (xy 64.666922 -391.529154) (xy 64.715887 -391.541554)
			(xy 64.762143 -391.561844) (xy 64.804429 -391.58947) (xy 64.841591 -391.62368) (xy 64.872615 -391.66354)
			(xy 64.896656 -391.707963) (xy 64.913057 -391.755737) (xy 64.92137 -391.805559) (xy 64.921892 -391.830814)
			(xy 64.921393 -391.855184) (xy 64.913613 -391.903299) (xy 64.898298 -391.94957) (xy 64.875837 -391.992826)
			(xy 64.861694 -392.012678) (xy 64.856106 -392.020552) (xy 64.851026 -392.038332) (xy 64.859408 -392.124946)
			(xy 64.867536 -392.14171) (xy 64.874648 -392.14806) (xy 64.893748 -392.166213) (xy 64.927275 -392.206865)
			(xy 64.95489 -392.251742) (xy 64.97607 -392.299992) (xy 64.990411 -392.350696) (xy 64.997641 -392.402891)
			(xy 64.998092 -392.429238) (xy 64.998092 -393.292838) (xy 64.997665 -393.319004) (xy 64.990522 -393.370846)
			(xy 64.976362 -393.421225) (xy 64.955451 -393.469197) (xy 64.92818 -393.513862) (xy 64.895061 -393.55438)
			(xy 64.876172 -393.572492) (xy 64.868806 -393.57935) (xy 64.860678 -393.596876) (xy 64.855344 -393.687046)
			(xy 64.86144 -393.705334) (xy 64.868044 -393.712954) (xy 64.882924 -393.731013) (xy 64.907984 -393.770528)
			(xy 64.927227 -393.81318) (xy 64.940272 -393.858116) (xy 64.946857 -393.904442) (xy 64.947292 -393.927838)
			(xy 64.946611 -393.959353) (xy 64.934709 -394.021248) (xy 64.92367 -394.050774) (xy 64.918844 -394.062458)
			(xy 64.921638 -394.08735) (xy 64.975994 -394.167614) (xy 64.983469 -394.177601) (xy 65.005447 -394.189341)
			(xy 65.017904 -394.189966) (xy 65.426082 -394.189966) (xy 65.434671 -394.189671) (xy 65.450906 -394.184067)
			(xy 65.464378 -394.173415) (xy 65.469262 -394.166344) (xy 65.522094 -394.082524) (xy 65.523618 -394.056616)
			(xy 65.51803 -394.044678) (xy 65.507866 -394.022357) (xy 65.493507 -393.975462) (xy 65.486238 -393.92696)
			(xy 65.485772 -393.902438) (xy 65.486321 -393.874949) (xy 65.495417 -393.820729) (xy 65.513348 -393.768757)
			(xy 65.539622 -393.720463) (xy 65.55613 -393.698476) (xy 65.561972 -393.69111) (xy 65.567306 -393.67333)
			(xy 65.561972 -393.587224) (xy 65.554352 -393.57046) (xy 65.547748 -393.563856) (xy 65.526752 -393.542212)
			(xy 65.491169 -393.493533) (xy 65.463684 -393.439863) (xy 65.44498 -393.382539) (xy 65.435523 -393.322987)
			(xy 65.434972 -393.292838) (xy 65.434972 -392.429238) (xy 65.435394 -392.402888) (xy 65.442606 -392.350684)
			(xy 65.45694 -392.299972) (xy 65.478123 -392.251717) (xy 65.50575 -392.20684) (xy 65.539295 -392.166195)
			(xy 65.558416 -392.14806) (xy 65.565528 -392.14171) (xy 65.573656 -392.124946) (xy 65.582038 -392.038332)
			(xy 65.576958 -392.020552) (xy 65.57137 -392.012678) (xy 65.557212 -391.992834) (xy 65.534724 -391.949586)
			(xy 65.519405 -391.90331) (xy 65.511646 -391.855187) (xy 65.511172 -391.830814) (xy 65.511694 -391.805559)
			(xy 65.520007 -391.755737) (xy 65.536408 -391.707963) (xy 65.560449 -391.66354) (xy 65.591473 -391.62368)
			(xy 65.628635 -391.58947) (xy 65.670921 -391.561844) (xy 65.717177 -391.541554) (xy 65.766142 -391.529154)
			(xy 65.81648 -391.524983) (xy 65.866818 -391.529154) (xy 65.915783 -391.541554) (xy 65.962039 -391.561844)
			(xy 66.004325 -391.58947) (xy 66.041487 -391.62368) (xy 66.072511 -391.66354) (xy 66.096552 -391.707963)
			(xy 66.112953 -391.755737) (xy 66.121266 -391.805559) (xy 66.121788 -391.830814) (xy 66.121289 -391.855184)
			(xy 66.113508 -391.903298) (xy 66.098194 -391.94957) (xy 66.075733 -391.992826) (xy 66.06159 -392.012678)
			(xy 66.056002 -392.020552) (xy 66.050922 -392.038332) (xy 66.059304 -392.124946) (xy 66.067432 -392.14171)
			(xy 66.074544 -392.14806) (xy 66.093644 -392.166213) (xy 66.127171 -392.206865) (xy 66.154787 -392.251742)
			(xy 66.175967 -392.299991) (xy 66.190308 -392.350696) (xy 66.197538 -392.402891) (xy 66.197988 -392.429238)
			(xy 66.197988 -392.724737) (xy 67.384461 -392.724737) (xy 67.387066 -392.661703) (xy 67.397448 -392.599474)
			(xy 67.415448 -392.539008) (xy 67.440789 -392.481233) (xy 67.473082 -392.427036) (xy 67.511831 -392.37725)
			(xy 67.556441 -392.332639) (xy 67.606226 -392.293889) (xy 67.660422 -392.261594) (xy 67.718197 -392.236252)
			(xy 67.778663 -392.218251) (xy 67.840891 -392.207867) (xy 67.903925 -392.20526) (xy 67.966798 -392.210471)
			(xy 68.028544 -392.223418) (xy 68.088214 -392.243904) (xy 68.144891 -392.271614) (xy 68.197706 -392.306121)
			(xy 68.245847 -392.346897) (xy 68.288574 -392.393314) (xy 68.325231 -392.444659) (xy 68.355256 -392.500145)
			(xy 68.378187 -392.558919) (xy 68.393671 -392.620077) (xy 68.401472 -392.682682) (xy 68.401946 -392.714226)
			(xy 68.401411 -392.747119) (xy 68.392874 -392.81235) (xy 68.384928 -392.844274) (xy 68.381534 -392.859219)
			(xy 68.382844 -392.889825) (xy 68.39316 -392.918669) (xy 68.411556 -392.943163) (xy 68.436382 -392.96111)
			(xy 68.46541 -392.970897) (xy 68.496034 -392.971648) (xy 68.510912 -392.967972) (xy 68.536476 -392.961194)
			(xy 68.588862 -392.953928) (xy 68.615306 -392.953494) (xy 68.642557 -392.953984) (xy 68.696503 -392.961741)
			(xy 68.748797 -392.977097) (xy 68.798373 -392.999738) (xy 68.844222 -393.029205) (xy 68.885411 -393.064896)
			(xy 68.921101 -393.106086) (xy 68.950566 -393.151936) (xy 68.973206 -393.201512) (xy 68.988561 -393.253806)
			(xy 68.996316 -393.307753) (xy 68.996316 -393.362254) (xy 68.988559 -393.416201) (xy 68.973204 -393.468494)
			(xy 68.950563 -393.51807) (xy 68.921097 -393.56392) (xy 68.885406 -393.605109) (xy 68.844216 -393.640799)
			(xy 68.798367 -393.670265) (xy 68.74879 -393.692905) (xy 68.696497 -393.70826) (xy 68.64255 -393.716016)
			(xy 68.588049 -393.716016) (xy 68.534102 -393.70826) (xy 68.481808 -393.692905) (xy 68.432232 -393.670264)
			(xy 68.386383 -393.640799) (xy 68.345193 -393.605108) (xy 68.309502 -393.563919) (xy 68.280036 -393.518069)
			(xy 68.257396 -393.468493) (xy 68.242041 -393.416199) (xy 68.234284 -393.362253) (xy 68.233798 -393.335002)
			(xy 68.233897 -393.322904) (xy 68.235421 -393.298756) (xy 68.236846 -393.286742) (xy 68.238241 -393.271484)
			(xy 68.232882 -393.241331) (xy 68.218837 -393.214116) (xy 68.197363 -393.19228) (xy 68.170387 -393.17778)
			(xy 68.140328 -393.171918) (xy 68.109881 -393.175217) (xy 68.095622 -393.180824) (xy 68.063582 -393.194079)
			(xy 67.996802 -393.212738) (xy 67.928107 -393.22215) (xy 67.893438 -393.222734) (xy 67.861894 -393.222273)
			(xy 67.799289 -393.214473) (xy 67.73813 -393.19899) (xy 67.679356 -393.176061) (xy 67.62387 -393.146038)
			(xy 67.572523 -393.109381) (xy 67.526105 -393.066655) (xy 67.485328 -393.018516) (xy 67.45082 -392.965702)
			(xy 67.423109 -392.909025) (xy 67.402622 -392.849355) (xy 67.389673 -392.78761) (xy 67.384461 -392.724737)
			(xy 66.197988 -392.724737) (xy 66.197988 -393.292838) (xy 66.197438 -393.322988) (xy 66.18799 -393.382542)
			(xy 66.169289 -393.439868) (xy 66.141801 -393.493537) (xy 66.106209 -393.542212) (xy 66.085212 -393.563856)
			(xy 66.078608 -393.57046) (xy 66.070988 -393.587224) (xy 66.065654 -393.67333) (xy 66.070988 -393.69111)
			(xy 66.07683 -393.698476) (xy 66.093355 -393.720452) (xy 66.119636 -393.768745) (xy 66.137561 -393.820721)
			(xy 66.146638 -393.874947) (xy 66.147188 -393.902438) (xy 66.146726 -393.92696) (xy 66.139454 -393.975463)
			(xy 66.125104 -394.022362) (xy 66.11493 -394.044678) (xy 66.109342 -394.056616) (xy 66.110866 -394.082524)
			(xy 66.163698 -394.166344) (xy 66.168573 -394.173424) (xy 66.182046 -394.184082) (xy 66.198287 -394.189679)
			(xy 66.206878 -394.189966) (xy 72.000618 -394.189966) (xy 72.030082 -394.162026) (xy 72.031098 -394.141706)
			(xy 72.033066 -394.111864) (xy 72.043121 -394.052909) (xy 72.051164 -394.024104) (xy 72.053818 -394.012901)
			(xy 72.05015 -393.990205) (xy 72.037008 -393.971341) (xy 72.027288 -393.965176) (xy 72.016739 -393.959193)
			(xy 71.996156 -393.946361) (xy 71.98614 -393.939522) (xy 71.977388 -393.934051) (xy 71.957184 -393.929923)
			(xy 71.93698 -393.934051) (xy 71.928228 -393.939522) (xy 71.902701 -393.956577) (xy 71.848338 -393.985106)
			(xy 71.790935 -394.006878) (xy 71.731326 -394.021574) (xy 71.670381 -394.028982) (xy 71.639684 -394.029438)
			(xy 71.608989 -394.028958) (xy 71.54805 -394.021536) (xy 71.488446 -394.006836) (xy 71.431042 -393.985073)
			(xy 71.376674 -393.956563) (xy 71.35114 -393.939522) (xy 71.342388 -393.934051) (xy 71.322184 -393.929923)
			(xy 71.30198 -393.934051) (xy 71.293228 -393.939522) (xy 71.267701 -393.956577) (xy 71.213338 -393.985106)
			(xy 71.155935 -394.006878) (xy 71.096326 -394.021574) (xy 71.035381 -394.028982) (xy 71.004684 -394.029438)
			(xy 70.973989 -394.028958) (xy 70.91305 -394.021536) (xy 70.853446 -394.006836) (xy 70.796042 -393.985073)
			(xy 70.741674 -393.956563) (xy 70.71614 -393.939522) (xy 70.707388 -393.934051) (xy 70.687184 -393.929923)
			(xy 70.66698 -393.934051) (xy 70.658228 -393.939522) (xy 70.632701 -393.956577) (xy 70.578338 -393.985106)
			(xy 70.520935 -394.006878) (xy 70.461326 -394.021574) (xy 70.400381 -394.028982) (xy 70.369684 -394.029438)
			(xy 70.338989 -394.028958) (xy 70.27805 -394.021536) (xy 70.218446 -394.006836) (xy 70.161042 -393.985073)
			(xy 70.106674 -393.956563) (xy 70.08114 -393.939522) (xy 70.072388 -393.934051) (xy 70.052184 -393.929923)
			(xy 70.03198 -393.934051) (xy 70.023228 -393.939522) (xy 69.997701 -393.956577) (xy 69.943338 -393.985106)
			(xy 69.885935 -394.006878) (xy 69.826326 -394.021574) (xy 69.765381 -394.028982) (xy 69.734684 -394.029438)
			(xy 69.703953 -394.028973) (xy 69.642939 -394.021563) (xy 69.583263 -394.006853) (xy 69.525796 -393.985058)
			(xy 69.471374 -393.956495) (xy 69.420791 -393.92158) (xy 69.374786 -393.880824) (xy 69.334028 -393.83482)
			(xy 69.299112 -393.784238) (xy 69.270548 -393.729817) (xy 69.248751 -393.67235) (xy 69.234039 -393.612675)
			(xy 69.226628 -393.551661) (xy 69.226176 -393.52093) (xy 69.226659 -393.490236) (xy 69.234086 -393.429298)
			(xy 69.248789 -393.369696) (xy 69.270554 -393.312295) (xy 69.299064 -393.257928) (xy 69.316092 -393.232386)
			(xy 69.321571 -393.223634) (xy 69.325711 -393.203425) (xy 69.321591 -393.183212) (xy 69.316092 -393.174474)
			(xy 69.299039 -393.148946) (xy 69.270515 -393.094583) (xy 69.248749 -393.037179) (xy 69.234058 -392.97757)
			(xy 69.226657 -392.916626) (xy 69.226176 -392.88593) (xy 69.22662 -392.855196) (xy 69.234025 -392.794177)
			(xy 69.248732 -392.734495) (xy 69.270526 -392.677021) (xy 69.299088 -392.622593) (xy 69.334003 -392.572005)
			(xy 69.374761 -392.525994) (xy 69.420769 -392.485232) (xy 69.471354 -392.450312) (xy 69.525779 -392.421745)
			(xy 69.583251 -392.399946) (xy 69.642932 -392.385234) (xy 69.70395 -392.377823) (xy 69.734684 -392.377422)
			(xy 69.765379 -392.3779) (xy 69.826321 -392.385318) (xy 69.885928 -392.400014) (xy 69.943334 -392.421772)
			(xy 69.997706 -392.450278) (xy 70.023228 -392.467338) (xy 70.03198 -392.472809) (xy 70.052184 -392.476937)
			(xy 70.072388 -392.472809) (xy 70.08114 -392.467338) (xy 70.106667 -392.450285) (xy 70.16103 -392.421759)
			(xy 70.218434 -392.399993) (xy 70.278043 -392.385302) (xy 70.338988 -392.377902) (xy 70.369684 -392.377422)
			(xy 70.400379 -392.3779) (xy 70.461321 -392.385318) (xy 70.520928 -392.400014) (xy 70.578334 -392.421772)
			(xy 70.632706 -392.450278) (xy 70.658228 -392.467338) (xy 70.66698 -392.472809) (xy 70.687184 -392.476937)
			(xy 70.707388 -392.472809) (xy 70.71614 -392.467338) (xy 70.741667 -392.450285) (xy 70.79603 -392.421759)
			(xy 70.853434 -392.399993) (xy 70.913043 -392.385302) (xy 70.973988 -392.377902) (xy 71.004684 -392.377422)
			(xy 71.025766 -392.37793) (xy 71.036688 -392.378438) (xy 71.056246 -392.370818) (xy 71.124572 -392.302492)
			(xy 71.132192 -392.282934) (xy 71.131684 -392.272012) (xy 71.131176 -392.25093) (xy 71.131659 -392.220236)
			(xy 71.139086 -392.159298) (xy 71.153789 -392.099696) (xy 71.175554 -392.042295) (xy 71.204064 -391.987928)
			(xy 71.221092 -391.962386) (xy 71.226571 -391.953634) (xy 71.230711 -391.933425) (xy 71.226591 -391.913212)
			(xy 71.221092 -391.904474) (xy 71.204039 -391.878946) (xy 71.175515 -391.824583) (xy 71.153749 -391.767179)
			(xy 71.139058 -391.70757) (xy 71.131657 -391.646626) (xy 71.131176 -391.61593) (xy 71.131715 -391.582692)
			(xy 71.140375 -391.516782) (xy 71.157551 -391.452563) (xy 71.182951 -391.39113) (xy 71.216141 -391.333531)
			(xy 71.256554 -391.28075) (xy 71.303502 -391.233686) (xy 71.356183 -391.193142) (xy 71.413699 -391.159809)
			(xy 71.475069 -391.134258) (xy 71.539245 -391.116922) (xy 71.57212 -391.111994) (xy 71.58355 -391.11047)
			(xy 71.602092 -391.098532) (xy 71.65594 -391.013188) (xy 71.658734 -390.991344) (xy 71.655178 -390.980168)
			(xy 71.643905 -390.942429) (xy 71.631786 -390.864608) (xy 71.631048 -390.825228) (xy 71.63151 -390.794495)
			(xy 71.638915 -390.733477) (xy 71.653622 -390.673796) (xy 71.675414 -390.616322) (xy 71.703975 -390.561895)
			(xy 71.738889 -390.511307) (xy 71.779645 -390.465296) (xy 71.82565 -390.424533) (xy 71.876233 -390.389613)
			(xy 71.930657 -390.361044) (xy 71.988127 -390.339243) (xy 72.047806 -390.324528) (xy 72.108823 -390.317114)
			(xy 72.139556 -390.31672) (xy 72.17025 -390.317202) (xy 72.231188 -390.324629) (xy 72.29079 -390.339331)
			(xy 72.348192 -390.361096) (xy 72.402558 -390.389607) (xy 72.4281 -390.406636) (xy 72.436852 -390.412107)
			(xy 72.457056 -390.416235) (xy 72.47726 -390.412107) (xy 72.486012 -390.406636) (xy 72.511539 -390.389581)
			(xy 72.565901 -390.361053) (xy 72.623305 -390.339283) (xy 72.682914 -390.32459) (xy 72.743859 -390.317187)
			(xy 72.774556 -390.31672) (xy 72.805289 -390.317163) (xy 72.866308 -390.324567) (xy 72.925989 -390.339273)
			(xy 72.983462 -390.361067) (xy 73.037889 -390.389629) (xy 73.088476 -390.424544) (xy 73.134486 -390.465303)
			(xy 73.175246 -390.511311) (xy 73.210163 -390.561897) (xy 73.238727 -390.616323) (xy 73.260522 -390.673795)
			(xy 73.27523 -390.733476) (xy 73.282636 -390.794495) (xy 73.283064 -390.825228) (xy 73.28249 -390.860073)
			(xy 73.272972 -390.929111) (xy 73.254118 -390.996203) (xy 73.226281 -391.060093) (xy 73.208642 -391.09015)
			(xy 73.203562 -391.098278) (xy 73.20026 -391.116058) (xy 73.214738 -391.200386) (xy 73.223882 -391.21588)
			(xy 73.230994 -391.221976) (xy 73.253321 -391.240713) (xy 73.293982 -391.28248) (xy 73.32961 -391.328615)
			(xy 73.359737 -391.378516) (xy 73.372218 -391.404856) (xy 73.378568 -391.418572) (xy 73.40346 -391.43432)
			(xy 73.525888 -391.43432) (xy 73.55078 -391.418572) (xy 73.55713 -391.404856) (xy 73.57076 -391.376124)
			(xy 73.604135 -391.321991) (xy 73.643996 -391.272439) (xy 73.689723 -391.228242) (xy 73.714864 -391.208768)
			(xy 73.721964 -391.203006) (xy 73.731861 -391.187644) (xy 73.734168 -391.178796) (xy 73.740518 -391.149078)
			(xy 73.742018 -391.140189) (xy 73.739433 -391.12236) (xy 73.735438 -391.11428) (xy 73.721051 -391.086238)
			(xy 73.700659 -391.026607) (xy 73.690346 -390.964435) (xy 73.689718 -390.932924) (xy 73.690195 -390.905556)
			(xy 73.698029 -390.851383) (xy 73.713525 -390.798886) (xy 73.736365 -390.749143) (xy 73.76608 -390.703175)
			(xy 73.783698 -390.682226) (xy 73.789794 -390.675114) (xy 73.796144 -390.658096) (xy 73.796144 -390.572752)
			(xy 73.789794 -390.555734) (xy 73.783698 -390.548622) (xy 73.766055 -390.527691) (xy 73.736326 -390.481725)
			(xy 73.71348 -390.431978) (xy 73.697987 -390.379475) (xy 73.690166 -390.325295) (xy 73.689718 -390.297924)
			(xy 73.690204 -390.270673) (xy 73.69796 -390.216725) (xy 73.713315 -390.16443) (xy 73.735957 -390.114853)
			(xy 73.765423 -390.069003) (xy 73.801114 -390.027812) (xy 73.842305 -389.992121) (xy 73.888155 -389.962655)
			(xy 73.937732 -389.940013) (xy 73.990027 -389.924658) (xy 74.043975 -389.916902) (xy 74.098477 -389.916902)
			(xy 74.152425 -389.924658) (xy 74.20472 -389.940013) (xy 74.254297 -389.962655) (xy 74.300147 -389.992121)
			(xy 74.341338 -390.027812) (xy 74.377029 -390.069003) (xy 74.406495 -390.114853) (xy 74.429137 -390.16443)
			(xy 74.444492 -390.216725) (xy 74.452248 -390.270673) (xy 74.452734 -390.297924) (xy 74.45226 -390.325293)
			(xy 74.444432 -390.379469) (xy 74.428941 -390.431969) (xy 74.406103 -390.481715) (xy 74.376389 -390.527687)
			(xy 74.358754 -390.548622) (xy 74.352658 -390.555734) (xy 74.346308 -390.572752) (xy 74.346308 -390.658096)
			(xy 74.352658 -390.675114) (xy 74.358754 -390.682226) (xy 74.376396 -390.703157) (xy 74.406123 -390.749123)
			(xy 74.428965 -390.79887) (xy 74.444454 -390.851374) (xy 74.45227 -390.905554) (xy 74.452734 -390.932924)
			(xy 74.452563 -390.949263) (xy 74.449769 -390.98182) (xy 74.447146 -390.997948) (xy 74.445114 -391.010394)
			(xy 74.45248 -391.034016) (xy 74.529188 -391.110216) (xy 74.55281 -391.117582) (xy 74.565002 -391.115296)
			(xy 74.587231 -391.111585) (xy 74.632129 -391.107643) (xy 74.654664 -391.107422) (xy 74.685358 -391.107904)
			(xy 74.746296 -391.115332) (xy 74.805897 -391.130035) (xy 74.863298 -391.151801) (xy 74.917664 -391.180313)
			(xy 74.943208 -391.197338) (xy 74.95196 -391.202809) (xy 74.972164 -391.206937) (xy 74.992368 -391.202809)
			(xy 75.00112 -391.197338) (xy 75.026647 -391.180284) (xy 75.08101 -391.151756) (xy 75.138414 -391.129987)
			(xy 75.198023 -391.115295) (xy 75.258968 -391.107892) (xy 75.289664 -391.107422) (xy 75.320358 -391.107904)
			(xy 75.381296 -391.115332) (xy 75.440897 -391.130035) (xy 75.498298 -391.151801) (xy 75.552664 -391.180313)
			(xy 75.578208 -391.197338) (xy 75.58696 -391.202809) (xy 75.607164 -391.206937) (xy 75.627368 -391.202809)
			(xy 75.63612 -391.197338) (xy 75.661647 -391.180284) (xy 75.71601 -391.151756) (xy 75.773414 -391.129987)
			(xy 75.833023 -391.115295) (xy 75.893968 -391.107892) (xy 75.924664 -391.107422) (xy 75.955397 -391.107866)
			(xy 76.016415 -391.115271) (xy 76.076095 -391.129977) (xy 76.133567 -391.151771) (xy 76.187994 -391.180334)
			(xy 76.238579 -391.215249) (xy 76.284588 -391.256008) (xy 76.325347 -391.302016) (xy 76.360263 -391.352601)
			(xy 76.388826 -391.407027) (xy 76.410621 -391.464499) (xy 76.425328 -391.524179) (xy 76.432734 -391.585197)
			(xy 76.433172 -391.61593) (xy 76.432692 -391.646625) (xy 76.425268 -391.707564) (xy 76.410568 -391.767168)
			(xy 76.388805 -391.82457) (xy 76.360295 -391.878939) (xy 76.343256 -391.904474) (xy 76.337794 -391.913227)
			(xy 76.33368 -391.933425) (xy 76.337813 -391.953619) (xy 76.343256 -391.962386) (xy 76.361544 -391.990834)
			(xy 76.368402 -392.002518) (xy 76.391516 -392.015472) (xy 76.50607 -392.015726) (xy 76.52893 -392.002518)
			(xy 76.536042 -391.990834) (xy 76.553843 -391.962167) (xy 76.595849 -391.909356) (xy 76.644465 -391.862559)
			(xy 76.698837 -391.822595) (xy 76.758013 -391.790165) (xy 76.78928 -391.777474) (xy 76.797543 -391.773916)
			(xy 76.811076 -391.762079) (xy 76.815696 -391.75436) (xy 76.82992 -391.72769) (xy 76.833928 -391.719473)
			(xy 76.83641 -391.701373) (xy 76.834746 -391.692384) (xy 76.828425 -391.661916) (xy 76.821681 -391.600054)
			(xy 76.821284 -391.56894) (xy 76.821284 -390.859264) (xy 76.821699 -390.82746) (xy 76.828795 -390.764248)
			(xy 76.842926 -390.702229) (xy 76.863915 -390.642183) (xy 76.891498 -390.584867) (xy 76.925328 -390.531)
			(xy 76.964978 -390.481262) (xy 76.987146 -390.458452) (xy 77.092302 -390.353296) (xy 77.099223 -390.345776)
			(xy 77.106937 -390.326869) (xy 77.106635 -390.306451) (xy 77.10297 -390.296908) (xy 77.091358 -390.269726)
			(xy 77.073189 -390.213476) (xy 77.06097 -390.15564) (xy 77.054833 -390.096848) (xy 77.054456 -390.067292)
			(xy 77.054973 -390.03304) (xy 77.063229 -389.965036) (xy 77.079619 -389.898522) (xy 77.103904 -389.834467)
			(xy 77.135731 -389.773806) (xy 77.174636 -389.717422) (xy 77.220051 -389.666136) (xy 77.271315 -389.620697)
			(xy 77.327682 -389.581767) (xy 77.388328 -389.549912) (xy 77.452371 -389.525597) (xy 77.518878 -389.509176)
			(xy 77.586878 -389.500889) (xy 77.62113 -389.500364) (xy 77.943202 -389.500364) (xy 77.975014 -389.500795)
			(xy 78.038236 -389.507923) (xy 78.100262 -389.522089) (xy 78.160311 -389.543115) (xy 78.217625 -389.570737)
			(xy 78.271485 -389.604605) (xy 78.321211 -389.644295) (xy 78.344014 -389.66648) (xy 78.837536 -390.160002)
			(xy 79.61301 -390.160002) (xy 79.61697 -390.110948) (xy 79.628747 -390.063164) (xy 79.648038 -390.017888)
			(xy 79.674341 -389.976292) (xy 79.706976 -389.939455) (xy 79.745097 -389.90833) (xy 79.787718 -389.883723)
			(xy 79.833734 -389.866271) (xy 79.881953 -389.856427) (xy 79.931128 -389.854446) (xy 79.979983 -389.860378)
			(xy 80.027254 -389.87407) (xy 80.071716 -389.895168) (xy 80.112219 -389.923124) (xy 80.147712 -389.957216)
			(xy 80.177277 -389.99656) (xy 80.200148 -390.040137) (xy 80.215732 -390.086818) (xy 80.223627 -390.135395)
			(xy 80.224122 -390.160002) (xy 80.81316 -390.160002) (xy 80.81712 -390.110948) (xy 80.828897 -390.063164)
			(xy 80.848188 -390.017888) (xy 80.874491 -389.976292) (xy 80.907126 -389.939455) (xy 80.945247 -389.90833)
			(xy 80.987868 -389.883723) (xy 81.033884 -389.866271) (xy 81.082103 -389.856427) (xy 81.131278 -389.854446)
			(xy 81.180133 -389.860378) (xy 81.227404 -389.87407) (xy 81.271866 -389.895168) (xy 81.312369 -389.923124)
			(xy 81.347862 -389.957216) (xy 81.377427 -389.99656) (xy 81.400298 -390.040137) (xy 81.415882 -390.086818)
			(xy 81.423777 -390.135395) (xy 81.424272 -390.160002) (xy 82.01331 -390.160002) (xy 82.01727 -390.110948)
			(xy 82.029047 -390.063164) (xy 82.048338 -390.017888) (xy 82.074641 -389.976292) (xy 82.107276 -389.939455)
			(xy 82.145397 -389.90833) (xy 82.188018 -389.883723) (xy 82.234034 -389.866271) (xy 82.282253 -389.856427)
			(xy 82.331428 -389.854446) (xy 82.380283 -389.860378) (xy 82.427554 -389.87407) (xy 82.472016 -389.895168)
			(xy 82.512519 -389.923124) (xy 82.548012 -389.957216) (xy 82.577577 -389.99656) (xy 82.600448 -390.040137)
			(xy 82.616032 -390.086818) (xy 82.623927 -390.135395) (xy 82.624422 -390.160002) (xy 83.213206 -390.160002)
			(xy 83.217166 -390.110948) (xy 83.228943 -390.063164) (xy 83.248234 -390.017888) (xy 83.274537 -389.976292)
			(xy 83.307172 -389.939455) (xy 83.345293 -389.90833) (xy 83.387914 -389.883723) (xy 83.43393 -389.866271)
			(xy 83.482149 -389.856427) (xy 83.531324 -389.854446) (xy 83.580179 -389.860378) (xy 83.62745 -389.87407)
			(xy 83.671912 -389.895168) (xy 83.712415 -389.923124) (xy 83.747908 -389.957216) (xy 83.777473 -389.99656)
			(xy 83.800344 -390.040137) (xy 83.815928 -390.086818) (xy 83.823823 -390.135395) (xy 83.824318 -390.160002)
			(xy 84.413356 -390.160002) (xy 84.417316 -390.110948) (xy 84.429093 -390.063164) (xy 84.448384 -390.017888)
			(xy 84.474687 -389.976292) (xy 84.507322 -389.939455) (xy 84.545443 -389.90833) (xy 84.588064 -389.883723)
			(xy 84.63408 -389.866271) (xy 84.682299 -389.856427) (xy 84.731474 -389.854446) (xy 84.780329 -389.860378)
			(xy 84.8276 -389.87407) (xy 84.872062 -389.895168) (xy 84.912565 -389.923124) (xy 84.948058 -389.957216)
			(xy 84.977623 -389.99656) (xy 85.000494 -390.040137) (xy 85.016078 -390.086818) (xy 85.023973 -390.135395)
			(xy 85.024468 -390.160002) (xy 85.613252 -390.160002) (xy 85.617212 -390.110948) (xy 85.628989 -390.063164)
			(xy 85.64828 -390.017888) (xy 85.674583 -389.976292) (xy 85.707218 -389.939455) (xy 85.745339 -389.90833)
			(xy 85.78796 -389.883723) (xy 85.833976 -389.866271) (xy 85.882195 -389.856427) (xy 85.93137 -389.854446)
			(xy 85.980225 -389.860378) (xy 86.027496 -389.87407) (xy 86.071958 -389.895168) (xy 86.112461 -389.923124)
			(xy 86.147954 -389.957216) (xy 86.177519 -389.99656) (xy 86.20039 -390.040137) (xy 86.215974 -390.086818)
			(xy 86.223869 -390.135395) (xy 86.224364 -390.160002) (xy 86.813148 -390.160002) (xy 86.817108 -390.110948)
			(xy 86.828885 -390.063164) (xy 86.848176 -390.017888) (xy 86.874479 -389.976292) (xy 86.907114 -389.939455)
			(xy 86.945235 -389.90833) (xy 86.987856 -389.883723) (xy 87.033872 -389.866271) (xy 87.082091 -389.856427)
			(xy 87.131266 -389.854446) (xy 87.180121 -389.860378) (xy 87.227392 -389.87407) (xy 87.271854 -389.895168)
			(xy 87.312357 -389.923124) (xy 87.34785 -389.957216) (xy 87.377415 -389.99656) (xy 87.400286 -390.040137)
			(xy 87.41587 -390.086818) (xy 87.423765 -390.135395) (xy 87.42426 -390.160002) (xy 88.013298 -390.160002)
			(xy 88.017258 -390.110948) (xy 88.029035 -390.063164) (xy 88.048326 -390.017888) (xy 88.074629 -389.976292)
			(xy 88.107264 -389.939455) (xy 88.145385 -389.90833) (xy 88.188006 -389.883723) (xy 88.234022 -389.866271)
			(xy 88.282241 -389.856427) (xy 88.331416 -389.854446) (xy 88.380271 -389.860378) (xy 88.427542 -389.87407)
			(xy 88.472004 -389.895168) (xy 88.512507 -389.923124) (xy 88.548 -389.957216) (xy 88.577565 -389.99656)
			(xy 88.600436 -390.040137) (xy 88.61602 -390.086818) (xy 88.623915 -390.135395) (xy 88.62441 -390.160002)
			(xy 89.213194 -390.160002) (xy 89.217154 -390.110948) (xy 89.228931 -390.063164) (xy 89.248222 -390.017888)
			(xy 89.274525 -389.976292) (xy 89.30716 -389.939455) (xy 89.345281 -389.90833) (xy 89.387902 -389.883723)
			(xy 89.433918 -389.866271) (xy 89.482137 -389.856427) (xy 89.531312 -389.854446) (xy 89.580167 -389.860378)
			(xy 89.627438 -389.87407) (xy 89.6719 -389.895168) (xy 89.712403 -389.923124) (xy 89.747896 -389.957216)
			(xy 89.777461 -389.99656) (xy 89.800332 -390.040137) (xy 89.815916 -390.086818) (xy 89.823811 -390.135395)
			(xy 89.824306 -390.160002) (xy 90.413344 -390.160002) (xy 90.417304 -390.110948) (xy 90.429081 -390.063164)
			(xy 90.448372 -390.017888) (xy 90.474675 -389.976292) (xy 90.50731 -389.939455) (xy 90.545431 -389.90833)
			(xy 90.588052 -389.883723) (xy 90.634068 -389.866271) (xy 90.682287 -389.856427) (xy 90.731462 -389.854446)
			(xy 90.780317 -389.860378) (xy 90.827588 -389.87407) (xy 90.87205 -389.895168) (xy 90.912553 -389.923124)
			(xy 90.948046 -389.957216) (xy 90.977611 -389.99656) (xy 91.000482 -390.040137) (xy 91.016066 -390.086818)
			(xy 91.023961 -390.135395) (xy 91.024456 -390.160002) (xy 91.61324 -390.160002) (xy 91.6172 -390.110948)
			(xy 91.628977 -390.063164) (xy 91.648268 -390.017888) (xy 91.674571 -389.976292) (xy 91.707206 -389.939455)
			(xy 91.745327 -389.90833) (xy 91.787948 -389.883723) (xy 91.833964 -389.866271) (xy 91.882183 -389.856427)
			(xy 91.931358 -389.854446) (xy 91.980213 -389.860378) (xy 92.027484 -389.87407) (xy 92.071946 -389.895168)
			(xy 92.112449 -389.923124) (xy 92.147942 -389.957216) (xy 92.177507 -389.99656) (xy 92.200378 -390.040137)
			(xy 92.215962 -390.086818) (xy 92.223857 -390.135395) (xy 92.224352 -390.160002) (xy 92.813136 -390.160002)
			(xy 92.817096 -390.110948) (xy 92.828873 -390.063164) (xy 92.848164 -390.017888) (xy 92.874467 -389.976292)
			(xy 92.907102 -389.939455) (xy 92.945223 -389.90833) (xy 92.987844 -389.883723) (xy 93.03386 -389.866271)
			(xy 93.082079 -389.856427) (xy 93.131254 -389.854446) (xy 93.180109 -389.860378) (xy 93.22738 -389.87407)
			(xy 93.271842 -389.895168) (xy 93.312345 -389.923124) (xy 93.347838 -389.957216) (xy 93.377403 -389.99656)
			(xy 93.400274 -390.040137) (xy 93.415858 -390.086818) (xy 93.423753 -390.135395) (xy 93.424248 -390.160002)
			(xy 94.013286 -390.160002) (xy 94.017246 -390.110948) (xy 94.029023 -390.063164) (xy 94.048314 -390.017888)
			(xy 94.074617 -389.976292) (xy 94.107252 -389.939455) (xy 94.145373 -389.90833) (xy 94.187994 -389.883723)
			(xy 94.23401 -389.866271) (xy 94.282229 -389.856427) (xy 94.331404 -389.854446) (xy 94.380259 -389.860378)
			(xy 94.42753 -389.87407) (xy 94.471992 -389.895168) (xy 94.512495 -389.923124) (xy 94.547988 -389.957216)
			(xy 94.577553 -389.99656) (xy 94.600424 -390.040137) (xy 94.616008 -390.086818) (xy 94.623903 -390.135395)
			(xy 94.624398 -390.160002) (xy 95.213182 -390.160002) (xy 95.217142 -390.110948) (xy 95.228919 -390.063164)
			(xy 95.24821 -390.017888) (xy 95.274513 -389.976292) (xy 95.307148 -389.939455) (xy 95.345269 -389.90833)
			(xy 95.38789 -389.883723) (xy 95.433906 -389.866271) (xy 95.482125 -389.856427) (xy 95.5313 -389.854446)
			(xy 95.580155 -389.860378) (xy 95.627426 -389.87407) (xy 95.671888 -389.895168) (xy 95.712391 -389.923124)
			(xy 95.747884 -389.957216) (xy 95.777449 -389.99656) (xy 95.80032 -390.040137) (xy 95.815904 -390.086818)
			(xy 95.823799 -390.135395) (xy 95.824294 -390.160002) (xy 96.413332 -390.160002) (xy 96.417292 -390.110948)
			(xy 96.429069 -390.063164) (xy 96.44836 -390.017888) (xy 96.474663 -389.976292) (xy 96.507298 -389.939455)
			(xy 96.545419 -389.90833) (xy 96.58804 -389.883723) (xy 96.634056 -389.866271) (xy 96.682275 -389.856427)
			(xy 96.73145 -389.854446) (xy 96.780305 -389.860378) (xy 96.827576 -389.87407) (xy 96.872038 -389.895168)
			(xy 96.912541 -389.923124) (xy 96.948034 -389.957216) (xy 96.977599 -389.99656) (xy 97.00047 -390.040137)
			(xy 97.016054 -390.086818) (xy 97.023949 -390.135395) (xy 97.024444 -390.160002) (xy 97.613228 -390.160002)
			(xy 97.617188 -390.110948) (xy 97.628965 -390.063164) (xy 97.648256 -390.017888) (xy 97.674559 -389.976292)
			(xy 97.707194 -389.939455) (xy 97.745315 -389.90833) (xy 97.787936 -389.883723) (xy 97.833952 -389.866271)
			(xy 97.882171 -389.856427) (xy 97.931346 -389.854446) (xy 97.980201 -389.860378) (xy 98.027472 -389.87407)
			(xy 98.071934 -389.895168) (xy 98.112437 -389.923124) (xy 98.14793 -389.957216) (xy 98.177495 -389.99656)
			(xy 98.200366 -390.040137) (xy 98.21595 -390.086818) (xy 98.223845 -390.135395) (xy 98.22434 -390.160002)
			(xy 98.223845 -390.184609) (xy 98.223621 -390.185989) (xy 98.942908 -390.185989) (xy 98.942908 -390.134015)
			(xy 98.951038 -390.08268) (xy 98.967099 -390.03325) (xy 98.990695 -389.98694) (xy 99.021245 -389.944892)
			(xy 99.057996 -389.908141) (xy 99.100044 -389.877591) (xy 99.146354 -389.853995) (xy 99.195784 -389.837934)
			(xy 99.247119 -389.829804) (xy 99.299093 -389.829804) (xy 99.350428 -389.837934) (xy 99.399858 -389.853995)
			(xy 99.446168 -389.877591) (xy 99.488216 -389.908141) (xy 99.524967 -389.944892) (xy 99.555517 -389.98694)
			(xy 99.579113 -390.03325) (xy 99.595174 -390.08268) (xy 99.603304 -390.134015) (xy 99.603814 -390.160002)
			(xy 99.603304 -390.185989) (xy 99.595174 -390.237324) (xy 99.579113 -390.286754) (xy 99.555517 -390.333064)
			(xy 99.524967 -390.375112) (xy 99.488216 -390.411863) (xy 99.446168 -390.442413) (xy 99.399858 -390.466009)
			(xy 99.350428 -390.48207) (xy 99.299093 -390.4902) (xy 99.247119 -390.4902) (xy 99.195784 -390.48207)
			(xy 99.146354 -390.466009) (xy 99.100044 -390.442413) (xy 99.057996 -390.411863) (xy 99.021245 -390.375112)
			(xy 98.990695 -390.333064) (xy 98.967099 -390.286754) (xy 98.951038 -390.237324) (xy 98.942908 -390.185989)
			(xy 98.223621 -390.185989) (xy 98.21595 -390.233186) (xy 98.200366 -390.279867) (xy 98.177495 -390.323444)
			(xy 98.14793 -390.362788) (xy 98.112437 -390.39688) (xy 98.071934 -390.424836) (xy 98.027472 -390.445934)
			(xy 97.980201 -390.459626) (xy 97.931346 -390.465558) (xy 97.882171 -390.463577) (xy 97.833952 -390.453733)
			(xy 97.787936 -390.436281) (xy 97.745315 -390.411674) (xy 97.707194 -390.380549) (xy 97.674559 -390.343712)
			(xy 97.648256 -390.302116) (xy 97.628965 -390.25684) (xy 97.617188 -390.209056) (xy 97.613228 -390.160002)
			(xy 97.024444 -390.160002) (xy 97.023949 -390.184609) (xy 97.016054 -390.233186) (xy 97.00047 -390.279867)
			(xy 96.977599 -390.323444) (xy 96.948034 -390.362788) (xy 96.912541 -390.39688) (xy 96.872038 -390.424836)
			(xy 96.827576 -390.445934) (xy 96.780305 -390.459626) (xy 96.73145 -390.465558) (xy 96.682275 -390.463577)
			(xy 96.634056 -390.453733) (xy 96.58804 -390.436281) (xy 96.545419 -390.411674) (xy 96.507298 -390.380549)
			(xy 96.474663 -390.343712) (xy 96.44836 -390.302116) (xy 96.429069 -390.25684) (xy 96.417292 -390.209056)
			(xy 96.413332 -390.160002) (xy 95.824294 -390.160002) (xy 95.823799 -390.184609) (xy 95.815904 -390.233186)
			(xy 95.80032 -390.279867) (xy 95.777449 -390.323444) (xy 95.747884 -390.362788) (xy 95.712391 -390.39688)
			(xy 95.671888 -390.424836) (xy 95.627426 -390.445934) (xy 95.580155 -390.459626) (xy 95.5313 -390.465558)
			(xy 95.482125 -390.463577) (xy 95.433906 -390.453733) (xy 95.38789 -390.436281) (xy 95.345269 -390.411674)
			(xy 95.307148 -390.380549) (xy 95.274513 -390.343712) (xy 95.24821 -390.302116) (xy 95.228919 -390.25684)
			(xy 95.217142 -390.209056) (xy 95.213182 -390.160002) (xy 94.624398 -390.160002) (xy 94.623903 -390.184609)
			(xy 94.616008 -390.233186) (xy 94.600424 -390.279867) (xy 94.577553 -390.323444) (xy 94.547988 -390.362788)
			(xy 94.512495 -390.39688) (xy 94.471992 -390.424836) (xy 94.42753 -390.445934) (xy 94.380259 -390.459626)
			(xy 94.331404 -390.465558) (xy 94.282229 -390.463577) (xy 94.23401 -390.453733) (xy 94.187994 -390.436281)
			(xy 94.145373 -390.411674) (xy 94.107252 -390.380549) (xy 94.074617 -390.343712) (xy 94.048314 -390.302116)
			(xy 94.029023 -390.25684) (xy 94.017246 -390.209056) (xy 94.013286 -390.160002) (xy 93.424248 -390.160002)
			(xy 93.423753 -390.184609) (xy 93.415858 -390.233186) (xy 93.400274 -390.279867) (xy 93.377403 -390.323444)
			(xy 93.347838 -390.362788) (xy 93.312345 -390.39688) (xy 93.271842 -390.424836) (xy 93.22738 -390.445934)
			(xy 93.180109 -390.459626) (xy 93.131254 -390.465558) (xy 93.082079 -390.463577) (xy 93.03386 -390.453733)
			(xy 92.987844 -390.436281) (xy 92.945223 -390.411674) (xy 92.907102 -390.380549) (xy 92.874467 -390.343712)
			(xy 92.848164 -390.302116) (xy 92.828873 -390.25684) (xy 92.817096 -390.209056) (xy 92.813136 -390.160002)
			(xy 92.224352 -390.160002) (xy 92.223857 -390.184609) (xy 92.215962 -390.233186) (xy 92.200378 -390.279867)
			(xy 92.177507 -390.323444) (xy 92.147942 -390.362788) (xy 92.112449 -390.39688) (xy 92.071946 -390.424836)
			(xy 92.027484 -390.445934) (xy 91.980213 -390.459626) (xy 91.931358 -390.465558) (xy 91.882183 -390.463577)
			(xy 91.833964 -390.453733) (xy 91.787948 -390.436281) (xy 91.745327 -390.411674) (xy 91.707206 -390.380549)
			(xy 91.674571 -390.343712) (xy 91.648268 -390.302116) (xy 91.628977 -390.25684) (xy 91.6172 -390.209056)
			(xy 91.61324 -390.160002) (xy 91.024456 -390.160002) (xy 91.023961 -390.184609) (xy 91.016066 -390.233186)
			(xy 91.000482 -390.279867) (xy 90.977611 -390.323444) (xy 90.948046 -390.362788) (xy 90.912553 -390.39688)
			(xy 90.87205 -390.424836) (xy 90.827588 -390.445934) (xy 90.780317 -390.459626) (xy 90.731462 -390.465558)
			(xy 90.682287 -390.463577) (xy 90.634068 -390.453733) (xy 90.588052 -390.436281) (xy 90.545431 -390.411674)
			(xy 90.50731 -390.380549) (xy 90.474675 -390.343712) (xy 90.448372 -390.302116) (xy 90.429081 -390.25684)
			(xy 90.417304 -390.209056) (xy 90.413344 -390.160002) (xy 89.824306 -390.160002) (xy 89.823811 -390.184609)
			(xy 89.815916 -390.233186) (xy 89.800332 -390.279867) (xy 89.777461 -390.323444) (xy 89.747896 -390.362788)
			(xy 89.712403 -390.39688) (xy 89.6719 -390.424836) (xy 89.627438 -390.445934) (xy 89.580167 -390.459626)
			(xy 89.531312 -390.465558) (xy 89.482137 -390.463577) (xy 89.433918 -390.453733) (xy 89.387902 -390.436281)
			(xy 89.345281 -390.411674) (xy 89.30716 -390.380549) (xy 89.274525 -390.343712) (xy 89.248222 -390.302116)
			(xy 89.228931 -390.25684) (xy 89.217154 -390.209056) (xy 89.213194 -390.160002) (xy 88.62441 -390.160002)
			(xy 88.623915 -390.184609) (xy 88.61602 -390.233186) (xy 88.600436 -390.279867) (xy 88.577565 -390.323444)
			(xy 88.548 -390.362788) (xy 88.512507 -390.39688) (xy 88.472004 -390.424836) (xy 88.427542 -390.445934)
			(xy 88.380271 -390.459626) (xy 88.331416 -390.465558) (xy 88.282241 -390.463577) (xy 88.234022 -390.453733)
			(xy 88.188006 -390.436281) (xy 88.145385 -390.411674) (xy 88.107264 -390.380549) (xy 88.074629 -390.343712)
			(xy 88.048326 -390.302116) (xy 88.029035 -390.25684) (xy 88.017258 -390.209056) (xy 88.013298 -390.160002)
			(xy 87.42426 -390.160002) (xy 87.423765 -390.184609) (xy 87.41587 -390.233186) (xy 87.400286 -390.279867)
			(xy 87.377415 -390.323444) (xy 87.34785 -390.362788) (xy 87.312357 -390.39688) (xy 87.271854 -390.424836)
			(xy 87.227392 -390.445934) (xy 87.180121 -390.459626) (xy 87.131266 -390.465558) (xy 87.082091 -390.463577)
			(xy 87.033872 -390.453733) (xy 86.987856 -390.436281) (xy 86.945235 -390.411674) (xy 86.907114 -390.380549)
			(xy 86.874479 -390.343712) (xy 86.848176 -390.302116) (xy 86.828885 -390.25684) (xy 86.817108 -390.209056)
			(xy 86.813148 -390.160002) (xy 86.224364 -390.160002) (xy 86.223869 -390.184609) (xy 86.215974 -390.233186)
			(xy 86.20039 -390.279867) (xy 86.177519 -390.323444) (xy 86.147954 -390.362788) (xy 86.112461 -390.39688)
			(xy 86.071958 -390.424836) (xy 86.027496 -390.445934) (xy 85.980225 -390.459626) (xy 85.93137 -390.465558)
			(xy 85.882195 -390.463577) (xy 85.833976 -390.453733) (xy 85.78796 -390.436281) (xy 85.745339 -390.411674)
			(xy 85.707218 -390.380549) (xy 85.674583 -390.343712) (xy 85.64828 -390.302116) (xy 85.628989 -390.25684)
			(xy 85.617212 -390.209056) (xy 85.613252 -390.160002) (xy 85.024468 -390.160002) (xy 85.023973 -390.184609)
			(xy 85.016078 -390.233186) (xy 85.000494 -390.279867) (xy 84.977623 -390.323444) (xy 84.948058 -390.362788)
			(xy 84.912565 -390.39688) (xy 84.872062 -390.424836) (xy 84.8276 -390.445934) (xy 84.780329 -390.459626)
			(xy 84.731474 -390.465558) (xy 84.682299 -390.463577) (xy 84.63408 -390.453733) (xy 84.588064 -390.436281)
			(xy 84.545443 -390.411674) (xy 84.507322 -390.380549) (xy 84.474687 -390.343712) (xy 84.448384 -390.302116)
			(xy 84.429093 -390.25684) (xy 84.417316 -390.209056) (xy 84.413356 -390.160002) (xy 83.824318 -390.160002)
			(xy 83.823823 -390.184609) (xy 83.815928 -390.233186) (xy 83.800344 -390.279867) (xy 83.777473 -390.323444)
			(xy 83.747908 -390.362788) (xy 83.712415 -390.39688) (xy 83.671912 -390.424836) (xy 83.62745 -390.445934)
			(xy 83.580179 -390.459626) (xy 83.531324 -390.465558) (xy 83.482149 -390.463577) (xy 83.43393 -390.453733)
			(xy 83.387914 -390.436281) (xy 83.345293 -390.411674) (xy 83.307172 -390.380549) (xy 83.274537 -390.343712)
			(xy 83.248234 -390.302116) (xy 83.228943 -390.25684) (xy 83.217166 -390.209056) (xy 83.213206 -390.160002)
			(xy 82.624422 -390.160002) (xy 82.623927 -390.184609) (xy 82.616032 -390.233186) (xy 82.600448 -390.279867)
			(xy 82.577577 -390.323444) (xy 82.548012 -390.362788) (xy 82.512519 -390.39688) (xy 82.472016 -390.424836)
			(xy 82.427554 -390.445934) (xy 82.380283 -390.459626) (xy 82.331428 -390.465558) (xy 82.282253 -390.463577)
			(xy 82.234034 -390.453733) (xy 82.188018 -390.436281) (xy 82.145397 -390.411674) (xy 82.107276 -390.380549)
			(xy 82.074641 -390.343712) (xy 82.048338 -390.302116) (xy 82.029047 -390.25684) (xy 82.01727 -390.209056)
			(xy 82.01331 -390.160002) (xy 81.424272 -390.160002) (xy 81.423777 -390.184609) (xy 81.415882 -390.233186)
			(xy 81.400298 -390.279867) (xy 81.377427 -390.323444) (xy 81.347862 -390.362788) (xy 81.312369 -390.39688)
			(xy 81.271866 -390.424836) (xy 81.227404 -390.445934) (xy 81.180133 -390.459626) (xy 81.131278 -390.465558)
			(xy 81.082103 -390.463577) (xy 81.033884 -390.453733) (xy 80.987868 -390.436281) (xy 80.945247 -390.411674)
			(xy 80.907126 -390.380549) (xy 80.874491 -390.343712) (xy 80.848188 -390.302116) (xy 80.828897 -390.25684)
			(xy 80.81712 -390.209056) (xy 80.81316 -390.160002) (xy 80.224122 -390.160002) (xy 80.223627 -390.184609)
			(xy 80.215732 -390.233186) (xy 80.200148 -390.279867) (xy 80.177277 -390.323444) (xy 80.147712 -390.362788)
			(xy 80.112219 -390.39688) (xy 80.071716 -390.424836) (xy 80.027254 -390.445934) (xy 79.979983 -390.459626)
			(xy 79.931128 -390.465558) (xy 79.881953 -390.463577) (xy 79.833734 -390.453733) (xy 79.787718 -390.436281)
			(xy 79.745097 -390.411674) (xy 79.706976 -390.380549) (xy 79.674341 -390.343712) (xy 79.648038 -390.302116)
			(xy 79.628747 -390.25684) (xy 79.61697 -390.209056) (xy 79.61301 -390.160002) (xy 78.837536 -390.160002)
			(xy 78.858872 -390.181338) (xy 78.881067 -390.20413) (xy 78.920746 -390.253864) (xy 78.954605 -390.307727)
			(xy 78.98222 -390.365044) (xy 79.003242 -390.425093) (xy 79.017407 -390.487118) (xy 79.024538 -390.550339)
			(xy 79.024988 -390.58215) (xy 79.024988 -391.417048) (xy 79.04988 -391.44575) (xy 79.068676 -391.448544)
			(xy 79.094653 -391.452711) (xy 79.144933 -391.468193) (xy 79.192128 -391.491438) (xy 79.235049 -391.521861)
			(xy 79.272614 -391.558694) (xy 79.303874 -391.601008) (xy 79.328043 -391.647738) (xy 79.34451 -391.697703)
			(xy 79.352861 -391.749646) (xy 79.35341 -391.77595) (xy 79.353013 -391.799183) (xy 79.346504 -391.84519)
			(xy 79.333621 -391.889833) (xy 79.314618 -391.932235) (xy 79.289868 -391.97156) (xy 79.275178 -391.989564)
			(xy 79.269082 -391.996676) (xy 79.262986 -392.013186) (xy 79.262986 -392.097514) (xy 79.269082 -392.114024)
			(xy 79.275178 -392.121136) (xy 79.289886 -392.139126) (xy 79.31464 -392.178452) (xy 79.333643 -392.220857)
			(xy 79.346522 -392.265505) (xy 79.353022 -392.311516) (xy 79.35341 -392.33475) (xy 79.352904 -392.361059)
			(xy 79.344575 -392.413014) (xy 79.32812 -392.462993) (xy 79.303953 -392.509733) (xy 79.272686 -392.552054)
			(xy 79.235109 -392.588887) (xy 79.19217 -392.6193) (xy 79.144955 -392.642526) (xy 79.094657 -392.657977)
			(xy 79.068676 -392.662156) (xy 79.04988 -392.66495) (xy 79.024988 -392.693652) (xy 79.024988 -393.869164)
			(xy 79.025439 -393.878949) (xy 79.032761 -393.897098) (xy 79.039212 -393.90447) (xy 79.095854 -393.962382)
			(xy 79.113888 -393.970256) (xy 79.124048 -393.97051) (xy 79.152161 -393.971681) (xy 79.207603 -393.981271)
			(xy 79.261034 -393.998906) (xy 79.311292 -394.024203) (xy 79.357285 -394.056613) (xy 79.398015 -394.095433)
			(xy 79.432596 -394.139817) (xy 79.446882 -394.164058) (xy 79.451598 -394.171708) (xy 79.465262 -394.183363)
			(xy 79.4821 -394.189611) (xy 79.491078 -394.189966) (xy 79.953866 -394.189966) (xy 79.962456 -394.189673)
			(xy 79.978695 -394.184073) (xy 79.992172 -394.173423) (xy 79.997046 -394.166344) (xy 80.049878 -394.082524)
			(xy 80.051402 -394.056616) (xy 80.045814 -394.044678) (xy 80.035651 -394.022357) (xy 80.021292 -393.975462)
			(xy 80.014023 -393.92696) (xy 80.013556 -393.902438) (xy 80.014104 -393.874949) (xy 80.0232 -393.820728)
			(xy 80.041131 -393.768756) (xy 80.067404 -393.720462) (xy 80.083914 -393.698476) (xy 80.089756 -393.69111)
			(xy 80.09509 -393.67333) (xy 80.089756 -393.587224) (xy 80.082136 -393.57046) (xy 80.075532 -393.563856)
			(xy 80.054537 -393.542212) (xy 80.018955 -393.493532) (xy 79.991471 -393.439862) (xy 79.972768 -393.382539)
			(xy 79.963312 -393.322987) (xy 79.962756 -393.292838) (xy 79.962756 -392.429238) (xy 79.963178 -392.402888)
			(xy 79.97039 -392.350684) (xy 79.984724 -392.299971) (xy 80.005905 -392.251715) (xy 80.033532 -392.206837)
			(xy 80.067076 -392.166192) (xy 80.0862 -392.14806) (xy 80.093312 -392.14171) (xy 80.10144 -392.124946)
			(xy 80.109822 -392.038332) (xy 80.104742 -392.020552) (xy 80.099154 -392.012678) (xy 80.084997 -391.992833)
			(xy 80.06251 -391.949585) (xy 80.047192 -391.90331) (xy 80.039433 -391.855186) (xy 80.038956 -391.830814)
			(xy 80.039478 -391.805559) (xy 80.047791 -391.755737) (xy 80.064192 -391.707963) (xy 80.088233 -391.66354)
			(xy 80.119257 -391.62368) (xy 80.156419 -391.58947) (xy 80.198705 -391.561844) (xy 80.244961 -391.541554)
			(xy 80.293926 -391.529154) (xy 80.344264 -391.524983) (xy 80.394602 -391.529154) (xy 80.443567 -391.541554)
			(xy 80.489823 -391.561844) (xy 80.532109 -391.58947) (xy 80.569271 -391.62368) (xy 80.600295 -391.66354)
			(xy 80.624336 -391.707963) (xy 80.640737 -391.755737) (xy 80.64905 -391.805559) (xy 80.649572 -391.830814)
			(xy 80.649074 -391.855184) (xy 80.641295 -391.9033) (xy 80.625983 -391.949574) (xy 80.603527 -391.992833)
			(xy 80.589374 -392.012678) (xy 80.583786 -392.020552) (xy 80.578706 -392.038332) (xy 80.587088 -392.124946)
			(xy 80.595216 -392.14171) (xy 80.602328 -392.14806) (xy 80.621429 -392.166213) (xy 80.654957 -392.206864)
			(xy 80.682574 -392.251741) (xy 80.703755 -392.29999) (xy 80.718097 -392.350695) (xy 80.725327 -392.402891)
			(xy 80.725772 -392.429238) (xy 80.725772 -393.292838) (xy 80.725222 -393.322988) (xy 80.715774 -393.382542)
			(xy 80.697072 -393.439867) (xy 80.669583 -393.493536) (xy 80.633991 -393.54221) (xy 80.612996 -393.563856)
			(xy 80.606392 -393.57046) (xy 80.598772 -393.587224) (xy 80.593438 -393.67333) (xy 80.598772 -393.69111)
			(xy 80.604614 -393.698476) (xy 80.62114 -393.720451) (xy 80.647422 -393.768744) (xy 80.665348 -393.820721)
			(xy 80.674425 -393.874947) (xy 80.674972 -393.902438) (xy 80.67451 -393.92696) (xy 80.667237 -393.975463)
			(xy 80.652887 -394.022361) (xy 80.642714 -394.044678) (xy 80.637126 -394.056616) (xy 80.63865 -394.082524)
			(xy 80.691482 -394.166344) (xy 80.696357 -394.173425) (xy 80.709829 -394.184088) (xy 80.72607 -394.18969)
			(xy 80.734662 -394.189966) (xy 81.153762 -394.189966) (xy 81.162352 -394.189674) (xy 81.178592 -394.184075)
			(xy 81.19207 -394.173425) (xy 81.196942 -394.166344) (xy 81.249774 -394.082524) (xy 81.251298 -394.056616)
			(xy 81.24571 -394.044678) (xy 81.235547 -394.022357) (xy 81.221189 -393.975462) (xy 81.213919 -393.92696)
			(xy 81.213452 -393.902438) (xy 81.214 -393.874949) (xy 81.223096 -393.820728) (xy 81.241026 -393.768756)
			(xy 81.267299 -393.720461) (xy 81.28381 -393.698476) (xy 81.289652 -393.69111) (xy 81.294986 -393.67333)
			(xy 81.289652 -393.587224) (xy 81.282032 -393.57046) (xy 81.275428 -393.563856) (xy 81.254433 -393.542212)
			(xy 81.218852 -393.493532) (xy 81.191368 -393.439862) (xy 81.172665 -393.382538) (xy 81.163209 -393.322987)
			(xy 81.162652 -393.292838) (xy 81.162652 -392.429238) (xy 81.163074 -392.402888) (xy 81.170286 -392.350684)
			(xy 81.184619 -392.299971) (xy 81.205801 -392.251715) (xy 81.233427 -392.206837) (xy 81.266971 -392.166191)
			(xy 81.286096 -392.14806) (xy 81.293208 -392.141456) (xy 81.30159 -392.124946) (xy 81.309718 -392.038078)
			(xy 81.304892 -392.020298) (xy 81.29905 -392.012678) (xy 81.284945 -391.992813) (xy 81.262553 -391.949546)
			(xy 81.247307 -391.903276) (xy 81.239593 -391.855173) (xy 81.239106 -391.830814) (xy 81.239628 -391.805559)
			(xy 81.247941 -391.755737) (xy 81.264342 -391.707963) (xy 81.288383 -391.66354) (xy 81.319407 -391.62368)
			(xy 81.356569 -391.58947) (xy 81.398855 -391.561844) (xy 81.445111 -391.541554) (xy 81.494076 -391.529154)
			(xy 81.544414 -391.524983) (xy 81.594752 -391.529154) (xy 81.643717 -391.541554) (xy 81.689973 -391.561844)
			(xy 81.732259 -391.58947) (xy 81.769421 -391.62368) (xy 81.800445 -391.66354) (xy 81.824486 -391.707963)
			(xy 81.840887 -391.755737) (xy 81.8492 -391.805559) (xy 81.849722 -391.830814) (xy 81.849244 -391.855216)
			(xy 81.841486 -391.903399) (xy 81.826169 -391.949737) (xy 81.803683 -391.993052) (xy 81.789524 -392.012932)
			(xy 81.783936 -392.020552) (xy 81.778856 -392.038332) (xy 81.786984 -392.1252) (xy 81.795366 -392.14171)
			(xy 81.802478 -392.148314) (xy 81.821541 -392.166463) (xy 81.855001 -392.207093) (xy 81.882562 -392.251934)
			(xy 81.903703 -392.300136) (xy 81.918021 -392.350785) (xy 81.925246 -392.402921) (xy 81.925668 -392.429238)
			(xy 81.925668 -393.292838) (xy 81.925118 -393.322988) (xy 81.91567 -393.382542) (xy 81.896968 -393.439867)
			(xy 81.869478 -393.493535) (xy 81.833886 -393.542209) (xy 81.812892 -393.563856) (xy 81.806288 -393.57046)
			(xy 81.798668 -393.587224) (xy 81.793334 -393.67333) (xy 81.798668 -393.69111) (xy 81.80451 -393.698476)
			(xy 81.821036 -393.720451) (xy 81.847318 -393.768744) (xy 81.865245 -393.82072) (xy 81.874322 -393.874947)
			(xy 81.874868 -393.902438) (xy 81.874406 -393.92696) (xy 81.867133 -393.975463) (xy 81.852783 -394.022361)
			(xy 81.84261 -394.044678) (xy 81.837022 -394.056616) (xy 81.838546 -394.082524) (xy 81.891378 -394.166344)
			(xy 81.896252 -394.173426) (xy 81.909724 -394.184089) (xy 81.925966 -394.189693) (xy 81.934558 -394.189966)
			(xy 82.34299 -394.189966) (xy 82.355436 -394.189283) (xy 82.37741 -394.177576) (xy 82.3849 -394.167614)
			(xy 82.439256 -394.08735) (xy 82.44205 -394.062458) (xy 82.437224 -394.050774) (xy 82.426229 -394.021235)
			(xy 82.414335 -393.959348) (xy 82.413602 -393.927838) (xy 82.414004 -393.90444) (xy 82.42059 -393.858109)
			(xy 82.433635 -393.813168) (xy 82.452881 -393.770512) (xy 82.477942 -393.730992) (xy 82.49285 -393.712954)
			(xy 82.499454 -393.705334) (xy 82.50555 -393.687046) (xy 82.500216 -393.596876) (xy 82.492088 -393.57935)
			(xy 82.484722 -393.572492) (xy 82.465824 -393.554377) (xy 82.432664 -393.513871) (xy 82.405348 -393.469215)
			(xy 82.384388 -393.421246) (xy 82.370176 -393.370863) (xy 82.36298 -393.319012) (xy 82.362548 -393.292838)
			(xy 82.362548 -392.429238) (xy 82.362991 -392.40288) (xy 82.370247 -392.350665) (xy 82.384625 -392.299948)
			(xy 82.405852 -392.251694) (xy 82.433524 -392.206824) (xy 82.467111 -392.166193) (xy 82.486246 -392.14806)
			(xy 82.493358 -392.14171) (xy 82.501486 -392.124946) (xy 82.509868 -392.038332) (xy 82.504788 -392.020552)
			(xy 82.4992 -392.012678) (xy 82.485041 -391.992834) (xy 82.462551 -391.949587) (xy 82.44723 -391.903311)
			(xy 82.43947 -391.855187) (xy 82.439002 -391.830814) (xy 82.439524 -391.805559) (xy 82.447837 -391.755737)
			(xy 82.464238 -391.707963) (xy 82.488279 -391.66354) (xy 82.519303 -391.62368) (xy 82.556465 -391.58947)
			(xy 82.598751 -391.561844) (xy 82.645007 -391.541554) (xy 82.693972 -391.529154) (xy 82.74431 -391.524983)
			(xy 82.794648 -391.529154) (xy 82.843613 -391.541554) (xy 82.889869 -391.561844) (xy 82.932155 -391.58947)
			(xy 82.969317 -391.62368) (xy 83.000341 -391.66354) (xy 83.024382 -391.707963) (xy 83.040783 -391.755737)
			(xy 83.049096 -391.805559) (xy 83.049618 -391.830814) (xy 83.04912 -391.855184) (xy 83.041339 -391.903299)
			(xy 83.026026 -391.949571) (xy 83.003567 -391.992829) (xy 82.98942 -392.012678) (xy 82.983832 -392.020552)
			(xy 82.978752 -392.038332) (xy 82.987134 -392.124946) (xy 82.995262 -392.14171) (xy 83.002374 -392.14806)
			(xy 83.021496 -392.166203) (xy 83.055067 -392.20684) (xy 83.082726 -392.251712) (xy 83.103947 -392.299962)
			(xy 83.118326 -392.350674) (xy 83.125588 -392.402883) (xy 83.126072 -392.429238) (xy 83.126072 -393.292838)
			(xy 83.125624 -393.319012) (xy 83.118438 -393.370864) (xy 83.104232 -393.421248) (xy 83.083274 -393.469217)
			(xy 83.055957 -393.513872) (xy 83.022794 -393.554375) (xy 83.003898 -393.572492) (xy 82.996532 -393.57935)
			(xy 82.988404 -393.596876) (xy 82.98307 -393.687046) (xy 82.989166 -393.705334) (xy 82.99577 -393.712954)
			(xy 83.010649 -393.731013) (xy 83.035707 -393.770529) (xy 83.054949 -393.813181) (xy 83.067992 -393.858117)
			(xy 83.074577 -393.904442) (xy 83.075018 -393.927838) (xy 83.074337 -393.959353) (xy 83.062436 -394.021248)
			(xy 83.051396 -394.050774) (xy 83.04657 -394.062458) (xy 83.049364 -394.08735) (xy 83.10372 -394.167614)
			(xy 83.111197 -394.177596) (xy 83.133175 -394.189325) (xy 83.14563 -394.189966) (xy 83.567016 -394.189966)
			(xy 83.575863 -394.189574) (xy 83.592498 -394.183542) (xy 83.606107 -394.172231) (xy 83.610958 -394.16482)
			(xy 83.662012 -394.077444) (xy 83.662266 -394.05052) (xy 83.655662 -394.038836) (xy 83.642391 -394.013957)
			(xy 83.62359 -393.960802) (xy 83.614066 -393.90523) (xy 83.613498 -393.877038) (xy 83.613997 -393.851257)
			(xy 83.622012 -393.800321) (xy 83.637837 -393.751248) (xy 83.661089 -393.705226) (xy 83.675728 -393.683998)
			(xy 83.680808 -393.676886) (xy 83.685634 -393.659868) (xy 83.680046 -393.577572) (xy 83.672934 -393.56157)
			(xy 83.666838 -393.554966) (xy 83.647352 -393.533595) (xy 83.614401 -393.48607) (xy 83.589001 -393.434115)
			(xy 83.571736 -393.378921) (xy 83.563 -393.321754) (xy 83.562444 -393.292838) (xy 83.562444 -392.429238)
			(xy 83.562887 -392.40288) (xy 83.570142 -392.350665) (xy 83.584521 -392.299947) (xy 83.605748 -392.251694)
			(xy 83.633419 -392.206824) (xy 83.667007 -392.166192) (xy 83.686142 -392.14806) (xy 83.693254 -392.14171)
			(xy 83.701382 -392.124946) (xy 83.709764 -392.038332) (xy 83.704684 -392.020552) (xy 83.699096 -392.012678)
			(xy 83.684937 -391.992834) (xy 83.662447 -391.949586) (xy 83.647127 -391.903311) (xy 83.639367 -391.855187)
			(xy 83.638898 -391.830814) (xy 83.63942 -391.805559) (xy 83.647733 -391.755737) (xy 83.664134 -391.707963)
			(xy 83.688175 -391.66354) (xy 83.719199 -391.62368) (xy 83.756361 -391.58947) (xy 83.798647 -391.561844)
			(xy 83.844903 -391.541554) (xy 83.893868 -391.529154) (xy 83.944206 -391.524983) (xy 83.994544 -391.529154)
			(xy 84.043509 -391.541554) (xy 84.089765 -391.561844) (xy 84.132051 -391.58947) (xy 84.169213 -391.62368)
			(xy 84.200237 -391.66354) (xy 84.224278 -391.707963) (xy 84.240679 -391.755737) (xy 84.248992 -391.805559)
			(xy 84.249514 -391.830814) (xy 84.249015 -391.855184) (xy 84.241235 -391.903299) (xy 84.225921 -391.949571)
			(xy 84.203462 -391.992828) (xy 84.189316 -392.012678) (xy 84.183728 -392.020552) (xy 84.178648 -392.038332)
			(xy 84.18703 -392.124946) (xy 84.195158 -392.14171) (xy 84.20227 -392.14806) (xy 84.221392 -392.166203)
			(xy 84.254964 -392.20684) (xy 84.282623 -392.251711) (xy 84.303844 -392.299962) (xy 84.318223 -392.350674)
			(xy 84.325486 -392.402883) (xy 84.325968 -392.429238) (xy 84.325968 -393.292838) (xy 84.32541 -393.321751)
			(xy 84.316646 -393.378909) (xy 84.299367 -393.434094) (xy 84.27397 -393.486045) (xy 84.241034 -393.533575)
			(xy 84.221574 -393.554966) (xy 84.215478 -393.56157) (xy 84.208366 -393.577572) (xy 84.202778 -393.659868)
			(xy 84.207604 -393.676886) (xy 84.212684 -393.683998) (xy 84.227346 -393.705212) (xy 84.250606 -393.751235)
			(xy 84.266431 -393.800313) (xy 84.274439 -393.851255) (xy 84.274914 -393.877038) (xy 84.274365 -393.905231)
			(xy 84.26484 -393.960805) (xy 84.246023 -394.013957) (xy 84.23275 -394.038836) (xy 84.226146 -394.05052)
			(xy 84.2264 -394.077444) (xy 84.277454 -394.16482) (xy 84.282204 -394.17232) (xy 84.295831 -394.183681)
			(xy 84.312524 -394.18969) (xy 84.321396 -394.189966) (xy 84.743036 -394.189966) (xy 84.755476 -394.189273)
			(xy 84.777434 -394.177555) (xy 84.784946 -394.167614) (xy 84.839302 -394.08735) (xy 84.842096 -394.062458)
			(xy 84.83727 -394.050774) (xy 84.826277 -394.021235) (xy 84.814384 -393.959348) (xy 84.813648 -393.927838)
			(xy 84.81405 -393.90444) (xy 84.820636 -393.85811) (xy 84.833684 -393.81317) (xy 84.852931 -393.770516)
			(xy 84.877995 -393.730998) (xy 84.892896 -393.712954) (xy 84.8995 -393.705334) (xy 84.905596 -393.687046)
			(xy 84.900262 -393.596876) (xy 84.892134 -393.57935) (xy 84.884768 -393.572492) (xy 84.865896 -393.554366)
			(xy 84.832789 -393.513843) (xy 84.805527 -393.46918) (xy 84.784618 -393.421211) (xy 84.770456 -393.370837)
			(xy 84.763305 -393.319001) (xy 84.762848 -393.292838) (xy 84.762848 -392.429238) (xy 84.76327 -392.402888)
			(xy 84.770482 -392.350684) (xy 84.784815 -392.299971) (xy 84.805997 -392.251715) (xy 84.833623 -392.206836)
			(xy 84.867167 -392.166191) (xy 84.886292 -392.14806) (xy 84.893404 -392.14171) (xy 84.901532 -392.124946)
			(xy 84.909914 -392.038332) (xy 84.904834 -392.020552) (xy 84.899246 -392.012678) (xy 84.885089 -391.992833)
			(xy 84.862603 -391.949585) (xy 84.847285 -391.903309) (xy 84.839527 -391.855186) (xy 84.839048 -391.830814)
			(xy 84.83957 -391.805559) (xy 84.847883 -391.755737) (xy 84.864284 -391.707963) (xy 84.888325 -391.66354)
			(xy 84.919349 -391.62368) (xy 84.956511 -391.58947) (xy 84.998797 -391.561844) (xy 85.045053 -391.541554)
			(xy 85.094018 -391.529154) (xy 85.144356 -391.524983) (xy 85.194694 -391.529154) (xy 85.243659 -391.541554)
			(xy 85.289915 -391.561844) (xy 85.332201 -391.58947) (xy 85.369363 -391.62368) (xy 85.400387 -391.66354)
			(xy 85.424428 -391.707963) (xy 85.440829 -391.755737) (xy 85.449142 -391.805559) (xy 85.449664 -391.830814)
			(xy 85.449166 -391.855184) (xy 85.441386 -391.9033) (xy 85.426075 -391.949573) (xy 85.403618 -391.992833)
			(xy 85.389466 -392.012678) (xy 85.383878 -392.020552) (xy 85.378798 -392.038332) (xy 85.38718 -392.124946)
			(xy 85.395308 -392.14171) (xy 85.40242 -392.14806) (xy 85.421517 -392.166215) (xy 85.455037 -392.206869)
			(xy 85.482648 -392.251747) (xy 85.503823 -392.299996) (xy 85.518161 -392.350699) (xy 85.52539 -392.402892)
			(xy 85.525864 -392.429238) (xy 85.525864 -393.292838) (xy 85.525437 -393.319004) (xy 85.518296 -393.370848)
			(xy 85.504138 -393.421229) (xy 85.483229 -393.469203) (xy 85.455961 -393.513871) (xy 85.422847 -393.554394)
			(xy 85.403944 -393.572492) (xy 85.396578 -393.57935) (xy 85.38845 -393.596876) (xy 85.383116 -393.687046)
			(xy 85.389212 -393.705334) (xy 85.395816 -393.712954) (xy 85.410697 -393.731012) (xy 85.435759 -393.770527)
			(xy 85.455004 -393.813178) (xy 85.46805 -393.858115) (xy 85.474636 -393.904442) (xy 85.475064 -393.927838)
			(xy 85.474383 -393.959353) (xy 85.46248 -394.021247) (xy 85.451442 -394.050774) (xy 85.446616 -394.062458)
			(xy 85.44941 -394.08735) (xy 85.503766 -394.167614) (xy 85.511246 -394.177588) (xy 85.533225 -394.189298)
			(xy 85.545676 -394.189966) (xy 85.942932 -394.189966) (xy 85.955373 -394.189274) (xy 85.977332 -394.177557)
			(xy 85.984842 -394.167614) (xy 86.039198 -394.08735) (xy 86.041992 -394.062458) (xy 86.037166 -394.050774)
			(xy 86.02617 -394.021235) (xy 86.014274 -393.959348) (xy 86.013544 -393.927838) (xy 86.013946 -393.90444)
			(xy 86.020532 -393.85811) (xy 86.033579 -393.81317) (xy 86.052827 -393.770515) (xy 86.077891 -393.730997)
			(xy 86.092792 -393.712954) (xy 86.099396 -393.705334) (xy 86.105492 -393.687046) (xy 86.100158 -393.596876)
			(xy 86.09203 -393.57935) (xy 86.084664 -393.572492) (xy 86.065792 -393.554366) (xy 86.032686 -393.513843)
			(xy 86.005423 -393.469179) (xy 85.984515 -393.421211) (xy 85.970353 -393.370837) (xy 85.963203 -393.319001)
			(xy 85.962744 -393.292838) (xy 85.962744 -392.429238) (xy 85.963166 -392.402888) (xy 85.970378 -392.350684)
			(xy 85.984711 -392.29997) (xy 86.005892 -392.251714) (xy 86.033518 -392.206836) (xy 86.067062 -392.16619)
			(xy 86.086188 -392.14806) (xy 86.0933 -392.14171) (xy 86.101428 -392.124946) (xy 86.10981 -392.038332)
			(xy 86.10473 -392.020552) (xy 86.099142 -392.012678) (xy 86.084985 -391.992833) (xy 86.062499 -391.949585)
			(xy 86.047182 -391.903309) (xy 86.039423 -391.855186) (xy 86.038944 -391.830814) (xy 86.039466 -391.805559)
			(xy 86.047779 -391.755737) (xy 86.06418 -391.707963) (xy 86.088221 -391.66354) (xy 86.119245 -391.62368)
			(xy 86.156407 -391.58947) (xy 86.198693 -391.561844) (xy 86.244949 -391.541554) (xy 86.293914 -391.529154)
			(xy 86.344252 -391.524983) (xy 86.39459 -391.529154) (xy 86.443555 -391.541554) (xy 86.489811 -391.561844)
			(xy 86.532097 -391.58947) (xy 86.569259 -391.62368) (xy 86.600283 -391.66354) (xy 86.624324 -391.707963)
			(xy 86.640725 -391.755737) (xy 86.649038 -391.805559) (xy 86.64956 -391.830814) (xy 86.649062 -391.855184)
			(xy 86.641282 -391.9033) (xy 86.62597 -391.949573) (xy 86.603514 -391.992832) (xy 86.589362 -392.012678)
			(xy 86.583774 -392.020552) (xy 86.578694 -392.038332) (xy 86.587076 -392.124946) (xy 86.595204 -392.14171)
			(xy 86.602316 -392.14806) (xy 86.621413 -392.166215) (xy 86.654934 -392.206869) (xy 86.682545 -392.251747)
			(xy 86.70372 -392.299996) (xy 86.718059 -392.350699) (xy 86.725287 -392.402892) (xy 86.72576 -392.429238)
			(xy 86.72576 -393.292838) (xy 86.725333 -393.319004) (xy 86.718192 -393.370848) (xy 86.704033 -393.421229)
			(xy 86.683124 -393.469203) (xy 86.655857 -393.513871) (xy 86.622742 -393.554394) (xy 86.60384 -393.572492)
			(xy 86.596474 -393.57935) (xy 86.588346 -393.596876) (xy 86.583012 -393.687046) (xy 86.589108 -393.705334)
			(xy 86.595712 -393.712954) (xy 86.610593 -393.731012) (xy 86.635655 -393.770527) (xy 86.654901 -393.813178)
			(xy 86.667947 -393.858115) (xy 86.674533 -393.904442) (xy 86.67496 -393.927838) (xy 86.674279 -393.959353)
			(xy 86.662376 -394.021247) (xy 86.651338 -394.050774) (xy 86.646512 -394.062458) (xy 86.649306 -394.08735)
			(xy 86.703662 -394.167614) (xy 86.711142 -394.177589) (xy 86.733121 -394.1893) (xy 86.745572 -394.189966)
			(xy 87.167212 -394.189966) (xy 87.176059 -394.189574) (xy 87.192696 -394.183543) (xy 87.206305 -394.172233)
			(xy 87.211154 -394.16482) (xy 87.262208 -394.077444) (xy 87.262462 -394.05052) (xy 87.255858 -394.038836)
			(xy 87.242587 -394.013957) (xy 87.223787 -393.960802) (xy 87.214262 -393.905229) (xy 87.213694 -393.877038)
			(xy 87.214193 -393.851257) (xy 87.222208 -393.800321) (xy 87.238033 -393.751248) (xy 87.261285 -393.705226)
			(xy 87.275924 -393.683998) (xy 87.281004 -393.676886) (xy 87.28583 -393.659868) (xy 87.280242 -393.577572)
			(xy 87.27313 -393.56157) (xy 87.267034 -393.554966) (xy 87.247548 -393.533595) (xy 87.214597 -393.48607)
			(xy 87.189198 -393.434115) (xy 87.171933 -393.378921) (xy 87.163197 -393.321754) (xy 87.16264 -393.292838)
			(xy 87.16264 -392.429238) (xy 87.163083 -392.40288) (xy 87.170338 -392.350665) (xy 87.184717 -392.299947)
			(xy 87.205944 -392.251693) (xy 87.233614 -392.206823) (xy 87.267202 -392.166192) (xy 87.286338 -392.14806)
			(xy 87.29345 -392.14171) (xy 87.301578 -392.124946) (xy 87.30996 -392.038332) (xy 87.30488 -392.020552)
			(xy 87.299292 -392.012678) (xy 87.285133 -391.992834) (xy 87.262644 -391.949586) (xy 87.247324 -391.903311)
			(xy 87.239564 -391.855187) (xy 87.239094 -391.830814) (xy 87.239616 -391.805559) (xy 87.247929 -391.755737)
			(xy 87.26433 -391.707963) (xy 87.288371 -391.66354) (xy 87.319395 -391.62368) (xy 87.356557 -391.58947)
			(xy 87.398843 -391.561844) (xy 87.445099 -391.541554) (xy 87.494064 -391.529154) (xy 87.544402 -391.524983)
			(xy 87.59474 -391.529154) (xy 87.643705 -391.541554) (xy 87.689961 -391.561844) (xy 87.732247 -391.58947)
			(xy 87.769409 -391.62368) (xy 87.800433 -391.66354) (xy 87.824474 -391.707963) (xy 87.840875 -391.755737)
			(xy 87.849188 -391.805559) (xy 87.84971 -391.830814) (xy 87.849211 -391.855184) (xy 87.841431 -391.903299)
			(xy 87.826117 -391.949571) (xy 87.803658 -391.992828) (xy 87.789512 -392.012678) (xy 87.783924 -392.020552)
			(xy 87.778844 -392.038332) (xy 87.787226 -392.124946) (xy 87.795354 -392.14171) (xy 87.802466 -392.14806)
			(xy 87.821588 -392.166202) (xy 87.85516 -392.20684) (xy 87.88282 -392.251711) (xy 87.904041 -392.299962)
			(xy 87.91842 -392.350674) (xy 87.925683 -392.402882) (xy 87.926164 -392.429238) (xy 87.926164 -393.292838)
			(xy 87.925606 -393.321751) (xy 87.916842 -393.378909) (xy 87.899563 -393.434094) (xy 87.874166 -393.486044)
			(xy 87.84123 -393.533574) (xy 87.82177 -393.554966) (xy 87.815674 -393.56157) (xy 87.808562 -393.577572)
			(xy 87.802974 -393.659868) (xy 87.8078 -393.676886) (xy 87.81288 -393.683998) (xy 87.827542 -393.705212)
			(xy 87.850802 -393.751235) (xy 87.866628 -393.800313) (xy 87.874635 -393.851255) (xy 87.87511 -393.877038)
			(xy 87.874561 -393.905231) (xy 87.865036 -393.960805) (xy 87.846218 -394.013956) (xy 87.832946 -394.038836)
			(xy 87.826342 -394.05052) (xy 87.826596 -394.077444) (xy 87.87765 -394.16482) (xy 87.8824 -394.17232)
			(xy 87.896027 -394.183683) (xy 87.91272 -394.189693) (xy 87.921592 -394.189966) (xy 88.3539 -394.189966)
			(xy 88.362487 -394.189668) (xy 88.378718 -394.18406) (xy 88.392185 -394.173407) (xy 88.39708 -394.166344)
			(xy 88.449912 -394.082524) (xy 88.451436 -394.056616) (xy 88.445848 -394.044678) (xy 88.435684 -394.022357)
			(xy 88.421324 -393.975462) (xy 88.414054 -393.92696) (xy 88.41359 -393.902438) (xy 88.414139 -393.874949)
			(xy 88.423235 -393.820729) (xy 88.441167 -393.768758) (xy 88.467442 -393.720465) (xy 88.483948 -393.698476)
			(xy 88.48979 -393.69111) (xy 88.495124 -393.67333) (xy 88.48979 -393.587224) (xy 88.48217 -393.57046)
			(xy 88.475566 -393.563856) (xy 88.454547 -393.542222) (xy 88.418919 -393.493554) (xy 88.39139 -393.439888)
			(xy 88.372645 -393.382559) (xy 88.363151 -393.322996) (xy 88.362536 -393.292838) (xy 88.362536 -392.429238)
			(xy 88.362979 -392.40288) (xy 88.370234 -392.350665) (xy 88.384613 -392.299947) (xy 88.405839 -392.251693)
			(xy 88.43351 -392.206822) (xy 88.467097 -392.166191) (xy 88.486234 -392.14806) (xy 88.493346 -392.14171)
			(xy 88.501474 -392.124946) (xy 88.509856 -392.038332) (xy 88.504776 -392.020552) (xy 88.499188 -392.012678)
			(xy 88.485029 -391.992834) (xy 88.46254 -391.949586) (xy 88.44722 -391.903311) (xy 88.43946 -391.855187)
			(xy 88.43899 -391.830814) (xy 88.439512 -391.805559) (xy 88.447825 -391.755737) (xy 88.464226 -391.707963)
			(xy 88.488267 -391.66354) (xy 88.519291 -391.62368) (xy 88.556453 -391.58947) (xy 88.598739 -391.561844)
			(xy 88.644995 -391.541554) (xy 88.69396 -391.529154) (xy 88.744298 -391.524983) (xy 88.794636 -391.529154)
			(xy 88.843601 -391.541554) (xy 88.889857 -391.561844) (xy 88.932143 -391.58947) (xy 88.969305 -391.62368)
			(xy 89.000329 -391.66354) (xy 89.02437 -391.707963) (xy 89.040771 -391.755737) (xy 89.049084 -391.805559)
			(xy 89.049606 -391.830814) (xy 89.049107 -391.855184) (xy 89.041327 -391.903299) (xy 89.026013 -391.949571)
			(xy 89.003553 -391.992828) (xy 88.989408 -392.012678) (xy 88.98382 -392.020552) (xy 88.97874 -392.038332)
			(xy 88.987122 -392.124946) (xy 88.99525 -392.14171) (xy 89.002362 -392.14806) (xy 89.021485 -392.166202)
			(xy 89.055057 -392.20684) (xy 89.082717 -392.251711) (xy 89.103938 -392.299962) (xy 89.118317 -392.350674)
			(xy 89.12558 -392.402882) (xy 89.12606 -392.429238) (xy 89.12606 -393.292838) (xy 89.125493 -393.323)
			(xy 89.116006 -393.382572) (xy 89.097259 -393.439908) (xy 89.06972 -393.493577) (xy 89.034074 -393.542242)
			(xy 89.01303 -393.563856) (xy 89.006426 -393.57046) (xy 88.998806 -393.587224) (xy 88.993472 -393.67333)
			(xy 88.998806 -393.69111) (xy 89.004648 -393.698476) (xy 89.021173 -393.720452) (xy 89.047452 -393.768745)
			(xy 89.065376 -393.820722) (xy 89.074452 -393.874948) (xy 89.075006 -393.902438) (xy 89.074544 -393.92696)
			(xy 89.067272 -393.975463) (xy 89.052923 -394.022362) (xy 89.042748 -394.044678) (xy 89.03716 -394.056616)
			(xy 89.038684 -394.082524) (xy 89.091516 -394.166344) (xy 89.096392 -394.173422) (xy 89.109865 -394.184075)
			(xy 89.126106 -394.189667) (xy 89.134696 -394.189966) (xy 89.543128 -394.189966) (xy 89.555569 -394.189274)
			(xy 89.57753 -394.177558) (xy 89.585038 -394.167614) (xy 89.639394 -394.08735) (xy 89.642188 -394.062458)
			(xy 89.637362 -394.050774) (xy 89.626366 -394.021235) (xy 89.61447 -393.959348) (xy 89.61374 -393.927838)
			(xy 89.614142 -393.90444) (xy 89.620728 -393.85811) (xy 89.633775 -393.813169) (xy 89.653022 -393.770515)
			(xy 89.678086 -393.730997) (xy 89.692988 -393.712954) (xy 89.699592 -393.705334) (xy 89.705688 -393.687046)
			(xy 89.700354 -393.596876) (xy 89.692226 -393.57935) (xy 89.68486 -393.572492) (xy 89.665988 -393.554366)
			(xy 89.632882 -393.513843) (xy 89.60562 -393.469179) (xy 89.584712 -393.421211) (xy 89.57055 -393.370837)
			(xy 89.5634 -393.319001) (xy 89.56294 -393.292838) (xy 89.56294 -392.429238) (xy 89.56336 -392.402918)
			(xy 89.570557 -392.350774) (xy 89.584861 -392.300116) (xy 89.605999 -392.251908) (xy 89.63357 -392.207068)
			(xy 89.66705 -392.166448) (xy 89.68613 -392.148314) (xy 89.693242 -392.14171) (xy 89.701624 -392.1252)
			(xy 89.709752 -392.038332) (xy 89.704672 -392.020552) (xy 89.699084 -392.012932) (xy 89.684921 -391.993054)
			(xy 89.662426 -391.949741) (xy 89.647104 -391.903402) (xy 89.639343 -391.855217) (xy 89.638886 -391.830814)
			(xy 89.639408 -391.805559) (xy 89.647721 -391.755737) (xy 89.664122 -391.707963) (xy 89.688163 -391.66354)
			(xy 89.719187 -391.62368) (xy 89.756349 -391.58947) (xy 89.798635 -391.561844) (xy 89.844891 -391.541554)
			(xy 89.893856 -391.529154) (xy 89.944194 -391.524983) (xy 89.994532 -391.529154) (xy 90.043497 -391.541554)
			(xy 90.089753 -391.561844) (xy 90.132039 -391.58947) (xy 90.169201 -391.62368) (xy 90.200225 -391.66354)
			(xy 90.224266 -391.707963) (xy 90.240667 -391.755737) (xy 90.24898 -391.805559) (xy 90.249502 -391.830814)
			(xy 90.249048 -391.855175) (xy 90.241345 -391.903285) (xy 90.226089 -391.949557) (xy 90.203669 -391.992814)
			(xy 90.189558 -392.012678) (xy 90.183716 -392.020298) (xy 90.17889 -392.038078) (xy 90.187018 -392.124946)
			(xy 90.1954 -392.141456) (xy 90.202512 -392.14806) (xy 90.221609 -392.166215) (xy 90.25513 -392.206868)
			(xy 90.282741 -392.251746) (xy 90.303917 -392.299996) (xy 90.318256 -392.350699) (xy 90.325484 -392.402892)
			(xy 90.325956 -392.429238) (xy 90.325956 -393.292838) (xy 90.325529 -393.319004) (xy 90.318387 -393.370847)
			(xy 90.304229 -393.421229) (xy 90.28332 -393.469203) (xy 90.256052 -393.51387) (xy 90.222937 -393.554393)
			(xy 90.204036 -393.572492) (xy 90.19667 -393.57935) (xy 90.188542 -393.596876) (xy 90.183208 -393.687046)
			(xy 90.189304 -393.705334) (xy 90.195908 -393.712954) (xy 90.21079 -393.731012) (xy 90.235852 -393.770527)
			(xy 90.255098 -393.813178) (xy 90.268144 -393.858115) (xy 90.27473 -393.904442) (xy 90.275156 -393.927838)
			(xy 90.274475 -393.959353) (xy 90.262572 -394.021247) (xy 90.251534 -394.050774) (xy 90.246708 -394.062458)
			(xy 90.249502 -394.08735) (xy 90.303858 -394.167614) (xy 90.311338 -394.17759) (xy 90.333316 -394.189302)
			(xy 90.345768 -394.189966) (xy 90.743024 -394.189966) (xy 90.755466 -394.189275) (xy 90.777428 -394.17756)
			(xy 90.784934 -394.167614) (xy 90.83929 -394.08735) (xy 90.842084 -394.062458) (xy 90.837258 -394.050774)
			(xy 90.826262 -394.021235) (xy 90.814366 -393.959348) (xy 90.813636 -393.927838) (xy 90.814038 -393.90444)
			(xy 90.820624 -393.85811) (xy 90.833671 -393.813169) (xy 90.852918 -393.770515) (xy 90.877982 -393.730996)
			(xy 90.892884 -393.712954) (xy 90.899488 -393.705334) (xy 90.905584 -393.687046) (xy 90.90025 -393.596876)
			(xy 90.892122 -393.57935) (xy 90.884756 -393.572492) (xy 90.865885 -393.554365) (xy 90.832779 -393.513843)
			(xy 90.805517 -393.469179) (xy 90.784609 -393.421211) (xy 90.770448 -393.370837) (xy 90.763297 -393.319001)
			(xy 90.762836 -393.292838) (xy 90.762836 -392.429238) (xy 90.763258 -392.402888) (xy 90.77047 -392.350683)
			(xy 90.784803 -392.29997) (xy 90.805984 -392.251714) (xy 90.833609 -392.206835) (xy 90.867152 -392.166188)
			(xy 90.88628 -392.14806) (xy 90.893392 -392.14171) (xy 90.90152 -392.124946) (xy 90.909902 -392.038332)
			(xy 90.904822 -392.020552) (xy 90.899234 -392.012678) (xy 90.885078 -391.992833) (xy 90.862592 -391.949584)
			(xy 90.847275 -391.903309) (xy 90.839517 -391.855186) (xy 90.839036 -391.830814) (xy 90.839558 -391.805559)
			(xy 90.847871 -391.755737) (xy 90.864272 -391.707963) (xy 90.888313 -391.66354) (xy 90.919337 -391.62368)
			(xy 90.956499 -391.58947) (xy 90.998785 -391.561844) (xy 91.045041 -391.541554) (xy 91.094006 -391.529154)
			(xy 91.144344 -391.524983) (xy 91.194682 -391.529154) (xy 91.243647 -391.541554) (xy 91.289903 -391.561844)
			(xy 91.332189 -391.58947) (xy 91.369351 -391.62368) (xy 91.400375 -391.66354) (xy 91.424416 -391.707963)
			(xy 91.440817 -391.755737) (xy 91.44913 -391.805559) (xy 91.449652 -391.830814) (xy 91.449154 -391.855184)
			(xy 91.441374 -391.9033) (xy 91.426062 -391.949573) (xy 91.403605 -391.992832) (xy 91.389454 -392.012678)
			(xy 91.383866 -392.020552) (xy 91.378786 -392.038332) (xy 91.387168 -392.124946) (xy 91.395296 -392.14171)
			(xy 91.402408 -392.14806) (xy 91.421505 -392.166215) (xy 91.455027 -392.206868) (xy 91.482638 -392.251746)
			(xy 91.503814 -392.299995) (xy 91.518153 -392.350699) (xy 91.525382 -392.402892) (xy 91.525852 -392.429238)
			(xy 91.525852 -393.292838) (xy 91.525425 -393.319004) (xy 91.518283 -393.370847) (xy 91.504125 -393.421228)
			(xy 91.483216 -393.469202) (xy 91.455948 -393.51387) (xy 91.422832 -393.554392) (xy 91.403932 -393.572492)
			(xy 91.396566 -393.57935) (xy 91.388438 -393.596876) (xy 91.383104 -393.687046) (xy 91.3892 -393.705334)
			(xy 91.395804 -393.712954) (xy 91.410686 -393.731012) (xy 91.435748 -393.770527) (xy 91.454994 -393.813178)
			(xy 91.468041 -393.858115) (xy 91.474627 -393.904442) (xy 91.475052 -393.927838) (xy 91.474371 -393.959353)
			(xy 91.462468 -394.021247) (xy 91.45143 -394.050774) (xy 91.446604 -394.062458) (xy 91.449398 -394.08735)
			(xy 91.503754 -394.167614) (xy 91.511234 -394.17759) (xy 91.533212 -394.189305) (xy 91.545664 -394.189966)
			(xy 91.943174 -394.189966) (xy 91.955622 -394.189286) (xy 91.977602 -394.177583) (xy 91.985084 -394.167614)
			(xy 92.03944 -394.08735) (xy 92.042234 -394.062458) (xy 92.037408 -394.050774) (xy 92.026414 -394.021235)
			(xy 92.01452 -393.959348) (xy 92.013786 -393.927838) (xy 92.014188 -393.90444) (xy 92.020775 -393.858111)
			(xy 92.033824 -393.813171) (xy 92.053073 -393.770518) (xy 92.078139 -393.731003) (xy 92.093034 -393.712954)
			(xy 92.099638 -393.705334) (xy 92.105734 -393.687046) (xy 92.1004 -393.596876) (xy 92.092272 -393.57935)
			(xy 92.084906 -393.572492) (xy 92.066004 -393.554379) (xy 92.032837 -393.513875) (xy 92.005515 -393.46922)
			(xy 91.98455 -393.421251) (xy 91.970335 -393.370867) (xy 91.963137 -393.319013) (xy 91.962732 -393.292838)
			(xy 91.962732 -392.429238) (xy 91.963197 -392.402915) (xy 91.970473 -392.350772) (xy 91.984838 -392.300122)
			(xy 92.006019 -392.251923) (xy 92.033616 -392.207088) (xy 92.067106 -392.166466) (xy 92.086176 -392.148314)
			(xy 92.093288 -392.14171) (xy 92.10167 -392.1252) (xy 92.109798 -392.038332) (xy 92.104718 -392.020552)
			(xy 92.09913 -392.012932) (xy 92.084969 -391.993053) (xy 92.062479 -391.949739) (xy 92.047159 -391.903401)
			(xy 92.039399 -391.855216) (xy 92.038932 -391.830814) (xy 92.039454 -391.805559) (xy 92.047767 -391.755737)
			(xy 92.064168 -391.707963) (xy 92.088209 -391.66354) (xy 92.119233 -391.62368) (xy 92.156395 -391.58947)
			(xy 92.198681 -391.561844) (xy 92.244937 -391.541554) (xy 92.293902 -391.529154) (xy 92.34424 -391.524983)
			(xy 92.394578 -391.529154) (xy 92.443543 -391.541554) (xy 92.489799 -391.561844) (xy 92.532085 -391.58947)
			(xy 92.569247 -391.62368) (xy 92.600271 -391.66354) (xy 92.624312 -391.707963) (xy 92.640713 -391.755737)
			(xy 92.649026 -391.805559) (xy 92.649548 -391.830814) (xy 92.649094 -391.855175) (xy 92.641389 -391.903284)
			(xy 92.626131 -391.949554) (xy 92.603708 -391.992809) (xy 92.589604 -392.012678) (xy 92.583762 -392.020298)
			(xy 92.578936 -392.038078) (xy 92.587064 -392.124946) (xy 92.595446 -392.141456) (xy 92.602558 -392.14806)
			(xy 92.621681 -392.166202) (xy 92.655253 -392.206839) (xy 92.682914 -392.25171) (xy 92.704135 -392.299961)
			(xy 92.718514 -392.350674) (xy 92.725777 -392.402882) (xy 92.726256 -392.429238) (xy 92.726256 -393.292838)
			(xy 92.725808 -393.319012) (xy 92.718622 -393.370864) (xy 92.704416 -393.421247) (xy 92.683457 -393.469216)
			(xy 92.656139 -393.51387) (xy 92.622975 -393.554372) (xy 92.604082 -393.572492) (xy 92.596716 -393.57935)
			(xy 92.588588 -393.596876) (xy 92.583254 -393.687046) (xy 92.58935 -393.705334) (xy 92.595954 -393.712954)
			(xy 92.610834 -393.731013) (xy 92.635892 -393.770529) (xy 92.655136 -393.81318) (xy 92.66818 -393.858116)
			(xy 92.674765 -393.904442) (xy 92.675202 -393.927838) (xy 92.674521 -393.959353) (xy 92.66262 -394.021248)
			(xy 92.65158 -394.050774) (xy 92.646754 -394.062458) (xy 92.649548 -394.08735) (xy 92.703904 -394.167614)
			(xy 92.71138 -394.177599) (xy 92.733358 -394.189335) (xy 92.745814 -394.189966) (xy 93.14307 -394.189966)
			(xy 93.155506 -394.189265) (xy 93.177451 -394.177539) (xy 93.18498 -394.167614) (xy 93.239336 -394.08735)
			(xy 93.24213 -394.062458) (xy 93.237304 -394.050774) (xy 93.22631 -394.021235) (xy 93.214416 -393.959348)
			(xy 93.213682 -393.927838) (xy 93.214084 -393.90444) (xy 93.220671 -393.858111) (xy 93.233719 -393.813171)
			(xy 93.252969 -393.770518) (xy 93.278035 -393.731002) (xy 93.29293 -393.712954) (xy 93.299534 -393.705334)
			(xy 93.30563 -393.687046) (xy 93.300296 -393.596876) (xy 93.292168 -393.57935) (xy 93.284802 -393.572492)
			(xy 93.265901 -393.554379) (xy 93.232734 -393.513875) (xy 93.205412 -393.46922) (xy 93.184447 -393.42125)
			(xy 93.170232 -393.370866) (xy 93.163034 -393.319013) (xy 93.162628 -393.292838) (xy 93.162628 -392.429238)
			(xy 93.163071 -392.40288) (xy 93.170326 -392.350665) (xy 93.184704 -392.299947) (xy 93.205931 -392.251692)
			(xy 93.233601 -392.206821) (xy 93.267187 -392.166189) (xy 93.286326 -392.14806) (xy 93.293438 -392.14171)
			(xy 93.301566 -392.124946) (xy 93.309948 -392.038332) (xy 93.304868 -392.020552) (xy 93.29928 -392.012678)
			(xy 93.285122 -391.992834) (xy 93.262633 -391.949586) (xy 93.247314 -391.90331) (xy 93.239554 -391.855187)
			(xy 93.239082 -391.830814) (xy 93.239604 -391.805559) (xy 93.247917 -391.755737) (xy 93.264318 -391.707963)
			(xy 93.288359 -391.66354) (xy 93.319383 -391.62368) (xy 93.356545 -391.58947) (xy 93.398831 -391.561844)
			(xy 93.445087 -391.541554) (xy 93.494052 -391.529154) (xy 93.54439 -391.524983) (xy 93.594728 -391.529154)
			(xy 93.643693 -391.541554) (xy 93.689949 -391.561844) (xy 93.732235 -391.58947) (xy 93.769397 -391.62368)
			(xy 93.800421 -391.66354) (xy 93.824462 -391.707963) (xy 93.840863 -391.755737) (xy 93.849176 -391.805559)
			(xy 93.849698 -391.830814) (xy 93.849199 -391.855184) (xy 93.841419 -391.903299) (xy 93.826104 -391.94957)
			(xy 93.803644 -391.992827) (xy 93.7895 -392.012678) (xy 93.783912 -392.020552) (xy 93.778832 -392.038332)
			(xy 93.787214 -392.124946) (xy 93.795342 -392.14171) (xy 93.802454 -392.14806) (xy 93.821577 -392.166202)
			(xy 93.85515 -392.206839) (xy 93.88281 -392.25171) (xy 93.904032 -392.299961) (xy 93.918412 -392.350673)
			(xy 93.925675 -392.402882) (xy 93.926152 -392.429238) (xy 93.926152 -393.292838) (xy 93.925704 -393.319012)
			(xy 93.918517 -393.370864) (xy 93.904311 -393.421247) (xy 93.883353 -393.469216) (xy 93.856035 -393.51387)
			(xy 93.82287 -393.554371) (xy 93.803978 -393.572492) (xy 93.796612 -393.57935) (xy 93.788484 -393.596876)
			(xy 93.78315 -393.687046) (xy 93.789246 -393.705334) (xy 93.79585 -393.712954) (xy 93.81073 -393.731013)
			(xy 93.835789 -393.770528) (xy 93.855032 -393.81318) (xy 93.868077 -393.858116) (xy 93.874662 -393.904442)
			(xy 93.875098 -393.927838) (xy 93.874417 -393.959353) (xy 93.862515 -394.021248) (xy 93.851476 -394.050774)
			(xy 93.84665 -394.062458) (xy 93.849444 -394.08735) (xy 93.9038 -394.167614) (xy 93.911276 -394.1776)
			(xy 93.933253 -394.189337) (xy 93.94571 -394.189966) (xy 94.367096 -394.189966) (xy 94.375945 -394.189577)
			(xy 94.392585 -394.183549) (xy 94.406199 -394.17224) (xy 94.411038 -394.16482) (xy 94.462092 -394.077444)
			(xy 94.462346 -394.05052) (xy 94.455742 -394.038836) (xy 94.442472 -394.013957) (xy 94.423672 -393.960801)
			(xy 94.414148 -393.905229) (xy 94.413578 -393.877038) (xy 94.414077 -393.851257) (xy 94.422091 -393.800321)
			(xy 94.437916 -393.751247) (xy 94.461167 -393.705224) (xy 94.475808 -393.683998) (xy 94.480888 -393.676886)
			(xy 94.485714 -393.659868) (xy 94.480126 -393.577572) (xy 94.473014 -393.56157) (xy 94.466918 -393.554966)
			(xy 94.447433 -393.533595) (xy 94.414483 -393.486069) (xy 94.389085 -393.434114) (xy 94.371821 -393.37892)
			(xy 94.363086 -393.321753) (xy 94.362524 -393.292838) (xy 94.362524 -392.429238) (xy 94.362967 -392.40288)
			(xy 94.370222 -392.350665) (xy 94.3846 -392.299946) (xy 94.405826 -392.251692) (xy 94.433496 -392.206821)
			(xy 94.467083 -392.166188) (xy 94.486222 -392.14806) (xy 94.493334 -392.14171) (xy 94.501462 -392.124946)
			(xy 94.509844 -392.038332) (xy 94.504764 -392.020552) (xy 94.499176 -392.012678) (xy 94.485018 -391.992834)
			(xy 94.46253 -391.949586) (xy 94.44721 -391.90331) (xy 94.439451 -391.855187) (xy 94.438978 -391.830814)
			(xy 94.4395 -391.805559) (xy 94.447813 -391.755737) (xy 94.464214 -391.707963) (xy 94.488255 -391.66354)
			(xy 94.519279 -391.62368) (xy 94.556441 -391.58947) (xy 94.598727 -391.561844) (xy 94.644983 -391.541554)
			(xy 94.693948 -391.529154) (xy 94.744286 -391.524983) (xy 94.794624 -391.529154) (xy 94.843589 -391.541554)
			(xy 94.889845 -391.561844) (xy 94.932131 -391.58947) (xy 94.969293 -391.62368) (xy 95.000317 -391.66354)
			(xy 95.024358 -391.707963) (xy 95.040759 -391.755737) (xy 95.049072 -391.805559) (xy 95.049594 -391.830814)
			(xy 95.049095 -391.855184) (xy 95.041315 -391.903299) (xy 95.026 -391.94957) (xy 95.00354 -391.992827)
			(xy 94.989396 -392.012678) (xy 94.983808 -392.020552) (xy 94.978728 -392.038332) (xy 94.98711 -392.124946)
			(xy 94.995238 -392.14171) (xy 95.00235 -392.14806) (xy 95.021473 -392.166202) (xy 95.055046 -392.206839)
			(xy 95.082707 -392.25171) (xy 95.103929 -392.299961) (xy 95.118309 -392.350673) (xy 95.125572 -392.402882)
			(xy 95.126048 -392.429238) (xy 95.126048 -393.292838) (xy 95.12549 -393.321751) (xy 95.116725 -393.378909)
			(xy 95.099446 -393.434093) (xy 95.074048 -393.486043) (xy 95.041111 -393.533572) (xy 95.021654 -393.554966)
			(xy 95.015558 -393.56157) (xy 95.008446 -393.577572) (xy 95.002858 -393.659868) (xy 95.007684 -393.676886)
			(xy 95.012764 -393.683998) (xy 95.027427 -393.705212) (xy 95.050688 -393.751235) (xy 95.066515 -393.800313)
			(xy 95.074522 -393.851254) (xy 95.074994 -393.877038) (xy 95.074445 -393.905231) (xy 95.06492 -393.960805)
			(xy 95.046101 -394.013956) (xy 95.03283 -394.038836) (xy 95.026226 -394.05052) (xy 95.02648 -394.077444)
			(xy 95.077534 -394.16482) (xy 95.082288 -394.172311) (xy 95.095918 -394.183651) (xy 95.112609 -394.189634)
			(xy 95.121476 -394.189966) (xy 95.542862 -394.189966) (xy 95.555299 -394.189267) (xy 95.577247 -394.177543)
			(xy 95.584772 -394.167614) (xy 95.639128 -394.08735) (xy 95.641922 -394.062458) (xy 95.637096 -394.050774)
			(xy 95.626102 -394.021235) (xy 95.614209 -393.959348) (xy 95.613474 -393.927838) (xy 95.613876 -393.90444)
			(xy 95.620463 -393.858111) (xy 95.633511 -393.813171) (xy 95.65276 -393.770517) (xy 95.677825 -393.731001)
			(xy 95.692722 -393.712954) (xy 95.699326 -393.705334) (xy 95.705422 -393.687046) (xy 95.700088 -393.596876)
			(xy 95.69196 -393.57935) (xy 95.684594 -393.572492) (xy 95.665693 -393.554379) (xy 95.632527 -393.513875)
			(xy 95.605206 -393.469219) (xy 95.584241 -393.42125) (xy 95.570027 -393.370866) (xy 95.562829 -393.319013)
			(xy 95.56242 -393.292838) (xy 95.56242 -392.429238) (xy 95.562863 -392.40288) (xy 95.570118 -392.350664)
			(xy 95.584496 -392.299946) (xy 95.605722 -392.251692) (xy 95.633392 -392.20682) (xy 95.666978 -392.166188)
			(xy 95.686118 -392.14806) (xy 95.69323 -392.14171) (xy 95.701358 -392.124946) (xy 95.70974 -392.038332)
			(xy 95.70466 -392.020552) (xy 95.699072 -392.012678) (xy 95.684914 -391.992834) (xy 95.662426 -391.949586)
			(xy 95.647107 -391.90331) (xy 95.639348 -391.855187) (xy 95.638874 -391.830814) (xy 95.639396 -391.805559)
			(xy 95.647709 -391.755737) (xy 95.66411 -391.707963) (xy 95.688151 -391.66354) (xy 95.719175 -391.62368)
			(xy 95.756337 -391.58947) (xy 95.798623 -391.561844) (xy 95.844879 -391.541554) (xy 95.893844 -391.529154)
			(xy 95.944182 -391.524983) (xy 95.99452 -391.529154) (xy 96.043485 -391.541554) (xy 96.089741 -391.561844)
			(xy 96.132027 -391.58947) (xy 96.169189 -391.62368) (xy 96.200213 -391.66354) (xy 96.224254 -391.707963)
			(xy 96.240655 -391.755737) (xy 96.248968 -391.805559) (xy 96.24949 -391.830814) (xy 96.248991 -391.855184)
			(xy 96.241211 -391.903298) (xy 96.225896 -391.94957) (xy 96.203435 -391.992826) (xy 96.189292 -392.012678)
			(xy 96.183704 -392.020552) (xy 96.178624 -392.038332) (xy 96.187006 -392.124946) (xy 96.195134 -392.14171)
			(xy 96.202246 -392.14806) (xy 96.221369 -392.166202) (xy 96.254943 -392.206839) (xy 96.282604 -392.25171)
			(xy 96.303826 -392.299961) (xy 96.318206 -392.350673) (xy 96.325469 -392.402882) (xy 96.325944 -392.429238)
			(xy 96.325944 -393.292838) (xy 96.325496 -393.319012) (xy 96.318311 -393.370866) (xy 96.304108 -393.421251)
			(xy 96.283153 -393.469223) (xy 96.255839 -393.513882) (xy 96.22268 -393.554389) (xy 96.20377 -393.572492)
			(xy 96.196404 -393.57935) (xy 96.188276 -393.596876) (xy 96.182942 -393.687046) (xy 96.189038 -393.705334)
			(xy 96.195642 -393.712954) (xy 96.210522 -393.731013) (xy 96.235582 -393.770528) (xy 96.254826 -393.813179)
			(xy 96.26787 -393.858116) (xy 96.274456 -393.904442) (xy 96.27489 -393.927838) (xy 96.274209 -393.959353)
			(xy 96.262307 -394.021248) (xy 96.251268 -394.050774) (xy 96.246442 -394.062458) (xy 96.249236 -394.08735)
			(xy 96.303592 -394.167614) (xy 96.311067 -394.177601) (xy 96.333045 -394.189342) (xy 96.345502 -394.189966)
			(xy 96.743012 -394.189966) (xy 96.755455 -394.189278) (xy 96.777422 -394.177566) (xy 96.784922 -394.167614)
			(xy 96.839278 -394.08735) (xy 96.842072 -394.062458) (xy 96.837246 -394.050774) (xy 96.826251 -394.021235)
			(xy 96.814355 -393.959348) (xy 96.813624 -393.927838) (xy 96.814026 -393.90444) (xy 96.820612 -393.85811)
			(xy 96.833658 -393.813169) (xy 96.852905 -393.770514) (xy 96.877968 -393.730995) (xy 96.892872 -393.712954)
			(xy 96.899476 -393.705334) (xy 96.905572 -393.687046) (xy 96.900238 -393.596876) (xy 96.89211 -393.57935)
			(xy 96.884744 -393.572492) (xy 96.865873 -393.554365) (xy 96.832769 -393.513842) (xy 96.805507 -393.469178)
			(xy 96.7846 -393.42121) (xy 96.770439 -393.370836) (xy 96.763289 -393.319001) (xy 96.762824 -393.292838)
			(xy 96.762824 -392.429238) (xy 96.763246 -392.402888) (xy 96.770457 -392.350683) (xy 96.78479 -392.299969)
			(xy 96.805971 -392.251713) (xy 96.833596 -392.206833) (xy 96.867138 -392.166186) (xy 96.886268 -392.14806)
			(xy 96.89338 -392.14171) (xy 96.901508 -392.124946) (xy 96.90989 -392.038332) (xy 96.90481 -392.020552)
			(xy 96.899222 -392.012678) (xy 96.885066 -391.992833) (xy 96.862582 -391.949584) (xy 96.847265 -391.903309)
			(xy 96.839507 -391.855186) (xy 96.839024 -391.830814) (xy 96.839546 -391.805559) (xy 96.847859 -391.755737)
			(xy 96.86426 -391.707963) (xy 96.888301 -391.66354) (xy 96.919325 -391.62368) (xy 96.956487 -391.58947)
			(xy 96.998773 -391.561844) (xy 97.045029 -391.541554) (xy 97.093994 -391.529154) (xy 97.144332 -391.524983)
			(xy 97.19467 -391.529154) (xy 97.243635 -391.541554) (xy 97.289891 -391.561844) (xy 97.332177 -391.58947)
			(xy 97.369339 -391.62368) (xy 97.400363 -391.66354) (xy 97.424404 -391.707963) (xy 97.440805 -391.755737)
			(xy 97.449118 -391.805559) (xy 97.44964 -391.830814) (xy 97.449142 -391.855184) (xy 97.441362 -391.903299)
			(xy 97.426049 -391.949572) (xy 97.403591 -391.992831) (xy 97.389442 -392.012678) (xy 97.383854 -392.020552)
			(xy 97.378774 -392.038332) (xy 97.387156 -392.124946) (xy 97.395284 -392.14171) (xy 97.402396 -392.14806)
			(xy 97.421494 -392.166214) (xy 97.455016 -392.206868) (xy 97.482629 -392.251745) (xy 97.503806 -392.299995)
			(xy 97.518145 -392.350698) (xy 97.525373 -392.402892) (xy 97.52584 -392.429238) (xy 97.52584 -393.292838)
			(xy 97.525413 -393.319004) (xy 97.518271 -393.370847) (xy 97.504112 -393.421228) (xy 97.483203 -393.469201)
			(xy 97.455934 -393.513868) (xy 97.422818 -393.55439) (xy 97.40392 -393.572492) (xy 97.396554 -393.57935)
			(xy 97.388426 -393.596876) (xy 97.383092 -393.687046) (xy 97.389188 -393.705334) (xy 97.395792 -393.712954)
			(xy 97.410674 -393.731012) (xy 97.435737 -393.770526) (xy 97.454984 -393.813177) (xy 97.468031 -393.858115)
			(xy 97.474618 -393.904442) (xy 97.47504 -393.927838) (xy 97.47436 -393.959353) (xy 97.462459 -394.021248)
			(xy 97.451418 -394.050774) (xy 97.446592 -394.062458) (xy 97.449386 -394.08735) (xy 97.503742 -394.167614)
			(xy 97.511221 -394.177593) (xy 97.533199 -394.189312) (xy 97.545652 -394.189966) (xy 97.95383 -394.189966)
			(xy 97.962423 -394.189679) (xy 97.97867 -394.184087) (xy 97.992157 -394.173439) (xy 97.99701 -394.166344)
			(xy 98.049842 -394.082524) (xy 98.051366 -394.056616) (xy 98.045778 -394.044678) (xy 98.035616 -394.022357)
			(xy 98.021259 -393.975462) (xy 98.01399 -393.92696) (xy 98.01352 -393.902438) (xy 98.014069 -393.874949)
			(xy 98.023166 -393.82073) (xy 98.0411 -393.768759) (xy 98.067376 -393.720468) (xy 98.083878 -393.698476)
			(xy 98.08972 -393.69111) (xy 98.095054 -393.67333) (xy 98.08972 -393.587224) (xy 98.0821 -393.57046)
			(xy 98.075496 -393.563856) (xy 98.054502 -393.542211) (xy 98.018924 -393.49353) (xy 97.991443 -393.43986)
			(xy 97.972742 -393.382537) (xy 97.963286 -393.322986) (xy 97.96272 -393.292838) (xy 97.96272 -392.429238)
			(xy 97.963142 -392.402887) (xy 97.970353 -392.350683) (xy 97.984686 -392.299969) (xy 98.005866 -392.251712)
			(xy 98.033491 -392.206833) (xy 98.067033 -392.166185) (xy 98.086164 -392.14806) (xy 98.093276 -392.14171)
			(xy 98.101404 -392.124946) (xy 98.109786 -392.038332) (xy 98.104706 -392.020552) (xy 98.099118 -392.012678)
			(xy 98.084958 -391.992834) (xy 98.062467 -391.949587) (xy 98.047145 -391.903311) (xy 98.039385 -391.855187)
			(xy 98.03892 -391.830814) (xy 98.039442 -391.805559) (xy 98.047755 -391.755737) (xy 98.064156 -391.707963)
			(xy 98.088197 -391.66354) (xy 98.119221 -391.62368) (xy 98.156383 -391.58947) (xy 98.198669 -391.561844)
			(xy 98.244925 -391.541554) (xy 98.29389 -391.529154) (xy 98.344228 -391.524983) (xy 98.394566 -391.529154)
			(xy 98.443531 -391.541554) (xy 98.489787 -391.561844) (xy 98.532073 -391.58947) (xy 98.569235 -391.62368)
			(xy 98.600259 -391.66354) (xy 98.6243 -391.707963) (xy 98.640701 -391.755737) (xy 98.649014 -391.805559)
			(xy 98.649536 -391.830814) (xy 98.649038 -391.855184) (xy 98.641258 -391.903299) (xy 98.625945 -391.949572)
			(xy 98.603487 -391.99283) (xy 98.589338 -392.012678) (xy 98.58375 -392.020552) (xy 98.57867 -392.038332)
			(xy 98.587052 -392.124946) (xy 98.59518 -392.14171) (xy 98.602292 -392.14806) (xy 98.62139 -392.166214)
			(xy 98.654913 -392.206867) (xy 98.682525 -392.251745) (xy 98.703703 -392.299994) (xy 98.718042 -392.350698)
			(xy 98.725271 -392.402892) (xy 98.725736 -392.429238) (xy 98.725736 -392.826301) (xy 99.912312 -392.826301)
			(xy 99.914921 -392.763275) (xy 99.925306 -392.701055) (xy 99.943307 -392.640597) (xy 99.968649 -392.582831)
			(xy 100.000941 -392.528642) (xy 100.039688 -392.478864) (xy 100.084294 -392.434261) (xy 100.134075 -392.395518)
			(xy 100.188266 -392.36323) (xy 100.246035 -392.337894) (xy 100.306494 -392.319897) (xy 100.368715 -392.309517)
			(xy 100.431741 -392.306913) (xy 100.494606 -392.312125) (xy 100.556344 -392.325072) (xy 100.616006 -392.345557)
			(xy 100.672676 -392.373265) (xy 100.725483 -392.407769) (xy 100.773617 -392.44854) (xy 100.816338 -392.494952)
			(xy 100.85299 -392.546292) (xy 100.883011 -392.601771) (xy 100.905938 -392.660538) (xy 100.921421 -392.721689)
			(xy 100.92922 -392.784286) (xy 100.929694 -392.815826) (xy 100.927916 -392.857228) (xy 100.9269 -392.86942)
			(xy 100.936298 -392.892026) (xy 101.017578 -392.961368) (xy 101.0412 -392.96721) (xy 101.053138 -392.964162)
			(xy 101.075281 -392.959171) (xy 101.120358 -392.953821) (xy 101.143054 -392.953494) (xy 101.170309 -392.95395)
			(xy 101.224265 -392.961702) (xy 101.276569 -392.977054) (xy 101.326155 -392.999694) (xy 101.372014 -393.029161)
			(xy 101.413213 -393.064855) (xy 101.448911 -393.106049) (xy 101.478384 -393.151904) (xy 101.50103 -393.201488)
			(xy 101.516388 -393.25379) (xy 101.524147 -393.307745) (xy 101.524147 -393.362255) (xy 101.516388 -393.41621)
			(xy 101.50103 -393.468512) (xy 101.478384 -393.518096) (xy 101.448911 -393.563951) (xy 101.413213 -393.605145)
			(xy 101.372014 -393.640839) (xy 101.326155 -393.670306) (xy 101.276569 -393.692946) (xy 101.224265 -393.708298)
			(xy 101.170309 -393.71605) (xy 101.143054 -393.71651) (xy 101.114724 -393.716013) (xy 101.058691 -393.7076)
			(xy 101.004518 -393.690994) (xy 100.953395 -393.666562) (xy 100.906446 -393.63484) (xy 100.864704 -393.596525)
			(xy 100.829084 -393.55246) (xy 100.800372 -393.503613) (xy 100.779197 -393.451057) (xy 100.766024 -393.395949)
			(xy 100.76307 -393.367768) (xy 100.7618 -393.355576) (xy 100.748846 -393.334748) (xy 100.657406 -393.279884)
			(xy 100.633022 -393.27836) (xy 100.621592 -393.283186) (xy 100.589807 -393.296211) (xy 100.523601 -393.314528)
			(xy 100.455532 -393.32377) (xy 100.421186 -393.324334) (xy 100.389646 -393.323817) (xy 100.32705 -393.316013)
			(xy 100.2659 -393.300526) (xy 100.207135 -393.277594) (xy 100.151658 -393.247569) (xy 100.100321 -393.210913)
			(xy 100.053913 -393.168188) (xy 100.013145 -393.120051) (xy 99.978645 -393.067241) (xy 99.950942 -393.010569)
			(xy 99.930462 -392.950905) (xy 99.917519 -392.889167) (xy 99.912312 -392.826301) (xy 98.725736 -392.826301)
			(xy 98.725736 -393.079986) (xy 98.726142 -393.088986) (xy 98.732457 -393.105846) (xy 98.744208 -393.119487)
			(xy 98.751898 -393.124182) (xy 98.841306 -393.17422) (xy 98.868992 -393.173712) (xy 98.880676 -393.166346)
			(xy 98.903337 -393.152897) (xy 98.951577 -393.131689) (xy 99.002281 -393.117336) (xy 99.05448 -393.110113)
			(xy 99.080828 -393.109704) (xy 99.108077 -393.110192) (xy 99.16202 -393.117952) (xy 99.21431 -393.133309)
			(xy 99.263882 -393.155951) (xy 99.309727 -393.185417) (xy 99.350913 -393.221107) (xy 99.3866 -393.262295)
			(xy 99.416063 -393.308143) (xy 99.438701 -393.357717) (xy 99.454054 -393.410007) (xy 99.46181 -393.463951)
			(xy 99.46181 -393.518449) (xy 99.454054 -393.572393) (xy 99.438701 -393.624683) (xy 99.416063 -393.674257)
			(xy 99.3866 -393.720105) (xy 99.350913 -393.761293) (xy 99.309727 -393.796983) (xy 99.263882 -393.826449)
			(xy 99.21431 -393.849091) (xy 99.16202 -393.864448) (xy 99.108077 -393.872208) (xy 99.080828 -393.87272)
			(xy 99.05387 -393.872256) (xy 99.000491 -393.864668) (xy 98.948712 -393.849637) (xy 98.899566 -393.827465)
			(xy 98.854032 -393.798593) (xy 98.813018 -393.763597) (xy 98.77734 -393.723173) (xy 98.747711 -393.678128)
			(xy 98.724721 -393.62936) (xy 98.716338 -393.603734) (xy 98.713502 -393.595652) (xy 98.703348 -393.581873)
			(xy 98.689218 -393.572212) (xy 98.681032 -393.569698) (xy 98.622612 -393.55395) (xy 98.61296 -393.563856)
			(xy 98.606356 -393.57046) (xy 98.598736 -393.587224) (xy 98.593402 -393.67333) (xy 98.598736 -393.69111)
			(xy 98.604578 -393.698476) (xy 98.621101 -393.720452) (xy 98.647378 -393.768746) (xy 98.665301 -393.820723)
			(xy 98.674376 -393.874948) (xy 98.674936 -393.902438) (xy 98.674474 -393.92696) (xy 98.667201 -393.975462)
			(xy 98.652849 -394.02236) (xy 98.642678 -394.044678) (xy 98.63709 -394.056616) (xy 98.638614 -394.082524)
			(xy 98.691446 -394.166344) (xy 98.696319 -394.173429) (xy 98.709789 -394.184101) (xy 98.726032 -394.189715)
			(xy 98.734626 -394.189966) (xy 100.318824 -394.189966) (xy 100.328892 -394.189538) (xy 100.347487 -394.181813)
			(xy 100.354892 -394.17498) (xy 100.519484 -394.010388) (xy 100.542276 -393.988192) (xy 100.592009 -393.948511)
			(xy 100.645873 -393.914649) (xy 100.703189 -393.887031) (xy 100.763237 -393.866005) (xy 100.825263 -393.851835)
			(xy 100.888484 -393.844699) (xy 100.920296 -393.844272) (xy 103.122476 -393.844272) (xy 103.132437 -393.843783)
			(xy 103.150856 -393.83619) (xy 103.15829 -393.82954) (xy 103.231442 -393.756388) (xy 103.254235 -393.734194)
			(xy 103.303969 -393.694519) (xy 103.357834 -393.660662) (xy 103.415151 -393.63305) (xy 103.475199 -393.61203)
			(xy 103.537223 -393.597866) (xy 103.600444 -393.590737) (xy 103.632254 -393.590272) (xy 104.076246 -393.590272)
			(xy 104.086246 -393.589776) (xy 104.104717 -393.582107) (xy 104.118849 -393.567955) (xy 104.12649 -393.549472)
			(xy 104.127046 -393.539472) (xy 104.127046 -390.59358) (xy 104.127474 -390.583512) (xy 104.135199 -390.564918)
			(xy 104.142032 -390.557512) (xy 105.583736 -389.115808) (xy 105.590086 -389.086852) (xy 105.585006 -389.072882)
			(xy 105.574022 -389.041037) (xy 105.562148 -388.974734) (xy 105.561384 -388.941056) (xy 105.561873 -388.913807)
			(xy 105.569634 -388.859863) (xy 105.584993 -388.807573) (xy 105.607637 -388.758001) (xy 105.637104 -388.712156)
			(xy 105.672795 -388.67097) (xy 105.713984 -388.635282) (xy 105.759833 -388.605819) (xy 105.809407 -388.583181)
			(xy 105.861698 -388.567827) (xy 105.915643 -388.56007) (xy 105.942892 -388.559548) (xy 105.969652 -388.559998)
			(xy 106.022647 -388.56747) (xy 106.07408 -388.582269) (xy 106.122943 -388.604105) (xy 106.168277 -388.63255)
			(xy 106.189018 -388.649464) (xy 106.198162 -388.657338) (xy 106.221022 -388.662926) (xy 106.323638 -388.639558)
			(xy 106.341926 -388.624826) (xy 106.347006 -388.61365) (xy 106.358713 -388.588962) (xy 106.388142 -388.542927)
			(xy 106.423837 -388.501561) (xy 106.465067 -388.465709) (xy 106.510991 -388.436106) (xy 106.560667 -388.413356)
			(xy 106.61308 -388.397924) (xy 106.667159 -388.390127) (xy 106.694478 -388.389622) (xy 106.721846 -388.390099)
			(xy 106.776018 -388.397933) (xy 106.828515 -388.41343) (xy 106.878258 -388.43627) (xy 106.924226 -388.465985)
			(xy 106.945176 -388.483602) (xy 106.952288 -388.489698) (xy 106.969306 -388.496048) (xy 107.05465 -388.496048)
			(xy 107.071668 -388.489698) (xy 107.07878 -388.483602) (xy 107.099711 -388.465959) (xy 107.145677 -388.43623)
			(xy 107.195423 -388.413384) (xy 107.247927 -388.397891) (xy 107.302107 -388.39007) (xy 107.329478 -388.389622)
			(xy 107.355747 -388.390065) (xy 107.407788 -388.397282) (xy 107.458348 -388.411569) (xy 107.506469 -388.432655)
			(xy 107.551244 -388.460142) (xy 107.591826 -388.493511) (xy 107.627447 -388.532131) (xy 107.657435 -388.575271)
			(xy 107.681222 -388.622117) (xy 107.698358 -388.671782) (xy 107.703874 -388.69747) (xy 107.70743 -388.715504)
			(xy 107.735116 -388.738364) (xy 108.184188 -388.738364) (xy 108.196518 -388.737779) (xy 108.218359 -388.726335)
			(xy 108.225844 -388.71652) (xy 108.280708 -388.63778) (xy 108.283756 -388.613142) (xy 108.279438 -388.601204)
			(xy 108.26822 -388.569077) (xy 108.256077 -388.502128) (xy 108.255308 -388.468108) (xy 108.255606 -388.446585)
			(xy 108.260445 -388.403811) (xy 108.26496 -388.382764) (xy 108.266992 -388.37362) (xy 108.264706 -388.355586)
			(xy 108.22432 -388.280148) (xy 108.210858 -388.26821) (xy 108.201968 -388.264908) (xy 108.17344 -388.253555)
			(xy 108.119104 -388.224961) (xy 108.068606 -388.190033) (xy 108.02268 -388.149279) (xy 107.981995 -388.103292)
			(xy 107.947143 -388.052741) (xy 107.918631 -387.998362) (xy 107.896873 -387.940946) (xy 107.882187 -387.881327)
			(xy 107.874786 -387.820374) (xy 107.874308 -387.789674) (xy 107.874889 -387.75472) (xy 107.884462 -387.685469)
			(xy 107.903424 -387.618181) (xy 107.931418 -387.554122) (xy 107.967917 -387.494498) (xy 107.989624 -387.467094)
			(xy 107.994966 -387.460117) (xy 108.000963 -387.443615) (xy 108.001308 -387.434836) (xy 108.001308 -387.280912)
			(xy 108.000889 -387.272147) (xy 107.994903 -387.255665) (xy 107.989624 -387.248654) (xy 107.96791 -387.221256)
			(xy 107.931407 -387.161633) (xy 107.903415 -387.097573) (xy 107.884461 -387.030282) (xy 107.874902 -386.961029)
			(xy 107.874308 -386.926074) (xy 107.874774 -386.895344) (xy 107.882185 -386.834334) (xy 107.896896 -386.774661)
			(xy 107.918692 -386.717196) (xy 107.947256 -386.662778) (xy 107.982171 -386.6122) (xy 108.022928 -386.566199)
			(xy 108.068933 -386.525445) (xy 108.119514 -386.490534) (xy 108.173935 -386.461975) (xy 108.231401 -386.440183)
			(xy 108.291075 -386.425477) (xy 108.352086 -386.418071) (xy 108.382816 -386.417566) (xy 108.40355 -386.417808)
			(xy 108.444877 -386.421238) (xy 108.465366 -386.424424) (xy 108.474021 -386.425466) (xy 108.491161 -386.422351)
			(xy 108.498894 -386.418328) (xy 108.524802 -386.403342) (xy 108.532114 -386.398796) (xy 108.543407 -386.385812)
			(xy 108.5469 -386.377942) (xy 108.557888 -386.351686) (xy 108.586512 -386.302493) (xy 108.622127 -386.258098)
			(xy 108.663941 -386.219487) (xy 108.711028 -386.187516) (xy 108.762342 -386.162895) (xy 108.816744 -386.14617)
			(xy 108.873027 -386.137712) (xy 108.901484 -386.13715) (xy 108.940346 -386.139182) (xy 108.951268 -386.140198)
			(xy 108.971588 -386.133594) (xy 109.035596 -386.075682) (xy 109.043098 -386.068134) (xy 109.051745 -386.048715)
			(xy 109.05236 -386.03809) (xy 109.05236 -383.897886) (xy 109.051933 -383.887818) (xy 109.044211 -383.869221)
			(xy 109.037374 -383.861818) (xy 108.592112 -383.416556) (xy 108.571284 -383.408936) (xy 108.560362 -383.409698)
			(xy 108.530644 -383.410968) (xy 108.504448 -383.41053) (xy 108.45255 -383.403351) (xy 108.402124 -383.389134)
			(xy 108.354118 -383.368149) (xy 108.309437 -383.340791) (xy 108.268922 -383.307573) (xy 108.233335 -383.269122)
			(xy 108.21797 -383.2479) (xy 108.210356 -383.238254) (xy 108.188584 -383.22694) (xy 108.176314 -383.22631)
			(xy 103.12019 -383.22631) (xy 103.108477 -383.226903) (xy 103.087442 -383.237222) (xy 103.079804 -383.246122)
			(xy 103.023416 -383.319528) (xy 103.018844 -383.342388) (xy 103.022146 -383.354072) (xy 103.028097 -383.378144)
			(xy 103.034461 -383.427322) (xy 103.034846 -383.452116) (xy 103.034222 -383.483767) (xy 103.023748 -383.546197)
			(xy 103.014018 -383.576322) (xy 103.01157 -383.584614) (xy 103.01183 -383.601889) (xy 103.014526 -383.610104)
			(xy 103.024686 -383.638298) (xy 103.028059 -383.646493) (xy 103.039357 -383.660132) (xy 103.046784 -383.664968)
			(xy 103.075118 -383.68213) (xy 103.127501 -383.722681) (xy 103.174171 -383.769693) (xy 103.214338 -383.822371)
			(xy 103.247322 -383.87982) (xy 103.272561 -383.941068) (xy 103.289631 -384.005075) (xy 103.298239 -384.070758)
			(xy 103.298752 -384.10388) (xy 103.298308 -384.13399) (xy 103.291194 -384.193789) (xy 103.277063 -384.252328)
			(xy 103.256114 -384.308787) (xy 103.228639 -384.362375) (xy 103.195024 -384.41234) (xy 103.15574 -384.457983)
			(xy 103.111337 -384.498663) (xy 103.08717 -384.51663) (xy 103.077739 -384.524287) (xy 103.066728 -384.545902)
			(xy 103.066088 -384.558032) (xy 103.066088 -384.640328) (xy 103.066718 -384.652461) (xy 103.077734 -384.674075)
			(xy 103.08717 -384.68173) (xy 103.111351 -384.699675) (xy 103.155736 -384.740372) (xy 103.195006 -384.786024)
			(xy 103.22861 -384.835994) (xy 103.256078 -384.889583) (xy 103.277027 -384.94604) (xy 103.291162 -385.004576)
			(xy 103.298287 -385.064371) (xy 103.298752 -385.09448) (xy 103.29829 -385.125213) (xy 103.290883 -385.18623)
			(xy 103.276176 -385.245911) (xy 103.254383 -385.303383) (xy 103.225822 -385.357809) (xy 103.190908 -385.408397)
			(xy 103.150152 -385.454407) (xy 103.104147 -385.495169) (xy 103.053564 -385.530089) (xy 102.999141 -385.558657)
			(xy 102.941672 -385.580457) (xy 102.881993 -385.595172) (xy 102.820977 -385.602586) (xy 102.790244 -385.602988)
			(xy 102.759926 -385.602569) (xy 102.699718 -385.595396) (xy 102.64079 -385.581111) (xy 102.58398 -385.559916)
			(xy 102.530095 -385.532114) (xy 102.479901 -385.498098) (xy 102.456742 -385.478528) (xy 102.449884 -385.472178)
			(xy 102.432866 -385.466082) (xy 102.347522 -385.466082) (xy 102.330504 -385.472178) (xy 102.323646 -385.478528)
			(xy 102.296214 -385.500626) (xy 102.286872 -385.508533) (xy 102.276278 -385.530555) (xy 102.275894 -385.54279)
			(xy 102.27691 -385.574286) (xy 102.278051 -385.586528) (xy 102.290113 -385.607909) (xy 102.300024 -385.61518)
			(xy 102.326114 -385.632849) (xy 102.374145 -385.673638) (xy 102.416772 -385.720045) (xy 102.453343 -385.771359)
			(xy 102.4833 -385.826796) (xy 102.506184 -385.885508) (xy 102.521644 -385.946595) (xy 102.529444 -386.009124)
			(xy 102.529894 -386.04063) (xy 102.529428 -386.07136) (xy 102.522017 -386.13237) (xy 102.507305 -386.192042)
			(xy 102.485509 -386.249507) (xy 102.456944 -386.303924) (xy 102.422029 -386.354503) (xy 102.381272 -386.400504)
			(xy 102.335268 -386.441257) (xy 102.284687 -386.476167) (xy 102.230266 -386.504727) (xy 102.1728 -386.526518)
			(xy 102.113127 -386.541225) (xy 102.052116 -386.548631) (xy 102.021386 -386.549138) (xy 101.989884 -386.548663)
			(xy 101.927363 -386.540872) (xy 101.866285 -386.525411) (xy 101.807587 -386.502518) (xy 101.75217 -386.472544)
			(xy 101.726238 -386.45465) (xy 101.715316 -386.44703) (xy 101.689408 -386.444236) (xy 101.585014 -386.488178)
			(xy 101.569012 -386.508752) (xy 101.56698 -386.52196) (xy 101.561496 -386.554302) (xy 101.543285 -386.617324)
			(xy 101.51712 -386.67748) (xy 101.483435 -386.733772) (xy 101.442791 -386.785264) (xy 101.395862 -386.831101)
			(xy 101.343428 -386.870522) (xy 101.286359 -386.902872) (xy 101.225604 -386.927613) (xy 101.162171 -386.944336)
			(xy 101.097114 -386.952762) (xy 101.064314 -386.953252) (xy 101.032908 -386.952785) (xy 100.970575 -386.94505)
			(xy 100.909669 -386.929696) (xy 100.851118 -386.906956) (xy 100.795814 -386.877177) (xy 100.744599 -386.840813)
			(xy 100.698254 -386.798417) (xy 100.657483 -386.750635) (xy 100.622909 -386.698195) (xy 100.595058 -386.641896)
			(xy 100.574354 -386.582594) (xy 100.561112 -386.521195) (xy 100.557838 -386.489956) (xy 100.556822 -386.479796)
			(xy 100.548186 -386.462778) (xy 100.480114 -386.403342) (xy 100.461826 -386.396992) (xy 100.451666 -386.3975)
			(xy 100.427536 -386.398008) (xy 100.396802 -386.397564) (xy 100.335783 -386.390159) (xy 100.276101 -386.375453)
			(xy 100.218628 -386.35366) (xy 100.1642 -386.325097) (xy 100.113612 -386.290182) (xy 100.067602 -386.249424)
			(xy 100.02684 -386.203416) (xy 99.991921 -386.152831) (xy 99.963355 -386.098405) (xy 99.941558 -386.040933)
			(xy 99.926847 -385.981252) (xy 99.919438 -385.920233) (xy 99.919028 -385.8895) (xy 99.919459 -385.858718)
			(xy 99.926859 -385.797601) (xy 99.941587 -385.737826) (xy 99.963427 -385.680266) (xy 99.992059 -385.625767)
			(xy 100.009198 -385.600194) (xy 100.014278 -385.592204) (xy 100.018702 -385.573809) (xy 100.017834 -385.56438)
			(xy 100.013516 -385.533646) (xy 100.011779 -385.524409) (xy 100.002668 -385.507987) (xy 99.995736 -385.501642)
			(xy 99.973896 -385.482967) (xy 99.934583 -385.441057) (xy 99.900828 -385.394552) (xy 99.873165 -385.344185)
			(xy 99.852029 -385.29075) (xy 99.837753 -385.235088) (xy 99.830562 -385.178076) (xy 99.830128 -385.149344)
			(xy 99.830569 -385.120708) (xy 99.837709 -385.063883) (xy 99.851883 -385.008393) (xy 99.87287 -384.955106)
			(xy 99.900342 -384.904853) (xy 99.916742 -384.881374) (xy 99.922331 -384.872824) (xy 99.926882 -384.852929)
			(xy 99.923362 -384.832825) (xy 99.918266 -384.82397) (xy 99.900771 -384.795996) (xy 99.873131 -384.736086)
			(xy 99.854382 -384.672827) (xy 99.844914 -384.607531) (xy 99.844352 -384.574542) (xy 99.844818 -384.545304)
			(xy 99.852271 -384.487306) (xy 99.867047 -384.430729) (xy 99.888908 -384.376493) (xy 99.917496 -384.325483)
			(xy 99.952346 -384.278527) (xy 99.992892 -384.236391) (xy 100.038472 -384.199761) (xy 100.088345 -384.169232)
			(xy 100.1417 -384.145302) (xy 100.197667 -384.128361) (xy 100.255336 -384.118683) (xy 100.284534 -384.117088)
			(xy 100.294186 -384.116834) (xy 100.311712 -384.109214) (xy 100.374196 -384.046222) (xy 100.381816 -384.02895)
			(xy 100.38207 -384.019044) (xy 100.383677 -383.986492) (xy 100.394156 -383.922164) (xy 100.412768 -383.859703)
			(xy 100.439208 -383.800132) (xy 100.473043 -383.744427) (xy 100.513719 -383.693502) (xy 100.560568 -383.648192)
			(xy 100.612822 -383.60924) (xy 100.669626 -383.577284) (xy 100.730047 -383.552847) (xy 100.793095 -383.536331)
			(xy 100.857736 -383.528006) (xy 100.890324 -383.527554) (xy 100.923907 -383.528096) (xy 100.990487 -383.536942)
			(xy 101.055322 -383.554478) (xy 101.117285 -383.580397) (xy 101.175295 -383.614249) (xy 101.228344 -383.655444)
			(xy 101.275506 -383.703265) (xy 101.315962 -383.75688) (xy 101.349006 -383.815354) (xy 101.362002 -383.846324)
			(xy 101.36759 -383.86004) (xy 101.391212 -383.877058) (xy 101.51237 -383.884678) (xy 101.538024 -383.870454)
			(xy 101.545136 -383.8575) (xy 101.562042 -383.828146) (xy 101.60245 -383.77378) (xy 101.649715 -383.725256)
			(xy 101.703002 -383.683435) (xy 101.761368 -383.649055) (xy 101.82378 -383.622725) (xy 101.889134 -383.60491)
			(xy 101.956275 -383.595927) (xy 101.990144 -383.595372) (xy 102.029398 -383.596118) (xy 102.106966 -383.608237)
			(xy 102.144576 -383.619502) (xy 102.157022 -383.623312) (xy 102.18293 -383.618232) (xy 102.268528 -383.545334)
			(xy 102.277926 -383.520696) (xy 102.275894 -383.507742) (xy 102.273983 -383.493915) (xy 102.271952 -383.466074)
			(xy 102.27183 -383.452116) (xy 102.27219 -383.42732) (xy 102.278557 -383.37814) (xy 102.28453 -383.354072)
			(xy 102.287832 -383.342388) (xy 102.28326 -383.319528) (xy 102.226872 -383.246122) (xy 102.219274 -383.237167)
			(xy 102.198218 -383.22683) (xy 102.186486 -383.22631) (xy 79.088234 -383.22631) (xy 79.08163 -383.228088)
			(xy 79.060686 -383.233335) (xy 79.017875 -383.238938) (xy 78.996286 -383.239264) (xy 78.974699 -383.238912)
			(xy 78.931892 -383.233303) (xy 78.910942 -383.228088) (xy 78.904338 -383.22631) (xy 74.31278 -383.22631)
			(xy 74.300532 -383.227037) (xy 74.278783 -383.238315) (xy 74.271124 -383.2479) (xy 74.25456 -383.270747)
			(xy 74.2158 -383.311758) (xy 74.171419 -383.346609) (xy 74.122385 -383.374537) (xy 74.069771 -383.394934)
			(xy 74.014725 -383.407352) (xy 73.95845 -383.411522) (xy 73.902175 -383.407352) (xy 73.847129 -383.394934)
			(xy 73.794515 -383.374537) (xy 73.745481 -383.346609) (xy 73.7011 -383.311758) (xy 73.66234 -383.270747)
			(xy 73.645776 -383.2479) (xy 73.638162 -383.238253) (xy 73.616391 -383.226937) (xy 73.60412 -383.22631)
			(xy 70.592442 -383.22631) (xy 70.580734 -383.226913) (xy 70.559716 -383.237244) (xy 70.552056 -383.246122)
			(xy 70.495668 -383.319528) (xy 70.491096 -383.342388) (xy 70.494398 -383.354072) (xy 70.50035 -383.378144)
			(xy 70.506715 -383.427322) (xy 70.507098 -383.452116) (xy 70.506474 -383.483767) (xy 70.495998 -383.546196)
			(xy 70.48627 -383.576322) (xy 70.483823 -383.584614) (xy 70.484083 -383.601889) (xy 70.486778 -383.610104)
			(xy 70.496938 -383.638298) (xy 70.500309 -383.646496) (xy 70.511601 -383.660144) (xy 70.519036 -383.664968)
			(xy 70.547373 -383.682128) (xy 70.59976 -383.722677) (xy 70.620136 -383.7432) (xy 76.211682 -383.7432)
			(xy 76.215753 -383.687578) (xy 76.227879 -383.633141) (xy 76.247802 -383.58105) (xy 76.275098 -383.532415)
			(xy 76.309184 -383.488272) (xy 76.349333 -383.449563) (xy 76.394691 -383.417112) (xy 76.444291 -383.391611)
			(xy 76.497075 -383.373604) (xy 76.551918 -383.363474) (xy 76.607652 -383.361437) (xy 76.663089 -383.367537)
			(xy 76.717046 -383.381643) (xy 76.768375 -383.403455) (xy 76.815981 -383.432509) (xy 76.858849 -383.468184)
			(xy 76.896066 -383.509721) (xy 76.926839 -383.556234) (xy 76.950511 -383.606731) (xy 76.966579 -383.660138)
			(xy 76.974699 -383.715314) (xy 76.975208 -383.7432) (xy 76.974699 -383.771086) (xy 76.966579 -383.826262)
			(xy 76.950511 -383.879669) (xy 76.926839 -383.930166) (xy 76.896066 -383.976679) (xy 76.858849 -384.018216)
			(xy 76.815981 -384.053891) (xy 76.768375 -384.082945) (xy 76.717046 -384.104757) (xy 76.663089 -384.118863)
			(xy 76.607652 -384.124963) (xy 76.551918 -384.122926) (xy 76.497075 -384.112796) (xy 76.444291 -384.094789)
			(xy 76.394691 -384.069288) (xy 76.349333 -384.036837) (xy 76.309184 -383.998128) (xy 76.275098 -383.953985)
			(xy 76.247802 -383.90535) (xy 76.227879 -383.853259) (xy 76.215753 -383.798822) (xy 76.211682 -383.7432)
			(xy 70.620136 -383.7432) (xy 70.646434 -383.769688) (xy 70.686605 -383.822365) (xy 70.719592 -383.879815)
			(xy 70.744834 -383.941063) (xy 70.761905 -384.005072) (xy 70.770515 -384.070757) (xy 70.771004 -384.10388)
			(xy 70.77056 -384.133991) (xy 70.763447 -384.19379) (xy 70.749317 -384.252331) (xy 70.728369 -384.308791)
			(xy 70.700896 -384.36238) (xy 70.667283 -384.412348) (xy 70.628001 -384.457994) (xy 70.583601 -384.498679)
			(xy 70.559422 -384.51663) (xy 70.549998 -384.524291) (xy 70.538998 -384.545904) (xy 70.53834 -384.558032)
			(xy 70.53834 -384.640328) (xy 70.538972 -384.652459) (xy 70.544187 -384.66268) (xy 76.211682 -384.66268)
			(xy 76.215753 -384.607058) (xy 76.227879 -384.552621) (xy 76.247802 -384.50053) (xy 76.275098 -384.451895)
			(xy 76.309184 -384.407752) (xy 76.349333 -384.369043) (xy 76.394691 -384.336592) (xy 76.444291 -384.311091)
			(xy 76.497075 -384.293084) (xy 76.551918 -384.282954) (xy 76.607652 -384.280917) (xy 76.663089 -384.287017)
			(xy 76.717046 -384.301123) (xy 76.768375 -384.322935) (xy 76.815981 -384.351989) (xy 76.85846 -384.38734)
			(xy 77.47176 -384.38734) (xy 77.47176 -384.327404) (xy 77.479583 -384.267982) (xy 77.495096 -384.210089)
			(xy 77.518032 -384.154716) (xy 77.547999 -384.10281) (xy 77.584486 -384.05526) (xy 77.626866 -384.01288)
			(xy 77.674416 -383.976393) (xy 77.726322 -383.946426) (xy 77.781695 -383.92349) (xy 77.839588 -383.907977)
			(xy 77.89901 -383.900154) (xy 77.958946 -383.900154) (xy 78.018368 -383.907977) (xy 78.076261 -383.92349)
			(xy 78.131634 -383.946426) (xy 78.18354 -383.976393) (xy 78.23109 -384.01288) (xy 78.27347 -384.05526)
			(xy 78.309957 -384.10281) (xy 78.339924 -384.154716) (xy 78.36286 -384.210089) (xy 78.378373 -384.267982)
			(xy 78.386196 -384.327404) (xy 78.386686 -384.357372) (xy 78.386196 -384.38734) (xy 78.378373 -384.446762)
			(xy 78.36286 -384.504655) (xy 78.339924 -384.560028) (xy 78.309957 -384.611934) (xy 78.27347 -384.659484)
			(xy 78.23109 -384.701864) (xy 78.18354 -384.738351) (xy 78.131634 -384.768318) (xy 78.076261 -384.791254)
			(xy 78.018368 -384.806767) (xy 77.958946 -384.81459) (xy 77.89901 -384.81459) (xy 77.839588 -384.806767)
			(xy 77.781695 -384.791254) (xy 77.726322 -384.768318) (xy 77.674416 -384.738351) (xy 77.626866 -384.701864)
			(xy 77.584486 -384.659484) (xy 77.547999 -384.611934) (xy 77.518032 -384.560028) (xy 77.495096 -384.504655)
			(xy 77.479583 -384.446762) (xy 77.47176 -384.38734) (xy 76.85846 -384.38734) (xy 76.858849 -384.387664)
			(xy 76.896066 -384.429201) (xy 76.926839 -384.475714) (xy 76.950511 -384.526211) (xy 76.966579 -384.579618)
			(xy 76.974699 -384.634794) (xy 76.975208 -384.66268) (xy 76.974699 -384.690566) (xy 76.966579 -384.745742)
			(xy 76.950511 -384.799149) (xy 76.926839 -384.849646) (xy 76.896066 -384.896159) (xy 76.858849 -384.937696)
			(xy 76.815981 -384.973371) (xy 76.768375 -385.002425) (xy 76.717046 -385.024237) (xy 76.663089 -385.038343)
			(xy 76.607652 -385.044443) (xy 76.551918 -385.042406) (xy 76.497075 -385.032276) (xy 76.444291 -385.014269)
			(xy 76.394691 -384.988768) (xy 76.349333 -384.956317) (xy 76.309184 -384.917608) (xy 76.275098 -384.873465)
			(xy 76.247802 -384.82483) (xy 76.227879 -384.772739) (xy 76.215753 -384.718302) (xy 76.211682 -384.66268)
			(xy 70.544187 -384.66268) (xy 70.549995 -384.674065) (xy 70.559422 -384.68173) (xy 70.583601 -384.699677)
			(xy 70.627982 -384.740375) (xy 70.667247 -384.786029) (xy 70.700848 -384.835999) (xy 70.728313 -384.889588)
			(xy 70.74926 -384.946044) (xy 70.763393 -385.004578) (xy 70.770517 -385.064372) (xy 70.771004 -385.09448)
			(xy 70.77056 -385.125213) (xy 70.763153 -385.186231) (xy 70.748445 -385.24591) (xy 70.726651 -385.303382)
			(xy 70.698088 -385.357808) (xy 70.663172 -385.408394) (xy 70.622414 -385.454402) (xy 70.576407 -385.495162)
			(xy 70.525822 -385.530079) (xy 70.471397 -385.558644) (xy 70.413926 -385.58044) (xy 70.354246 -385.59515)
			(xy 70.293229 -385.602559) (xy 70.262496 -385.602988) (xy 70.232179 -385.602566) (xy 70.171973 -385.595388)
			(xy 70.113048 -385.581098) (xy 70.056242 -385.5599) (xy 70.002361 -385.532094) (xy 69.952171 -385.498075)
			(xy 69.928994 -385.478528) (xy 69.922136 -385.472178) (xy 69.905118 -385.466082) (xy 69.819774 -385.466082)
			(xy 69.802756 -385.472178) (xy 69.795898 -385.478528) (xy 69.768466 -385.500626) (xy 69.759116 -385.508529)
			(xy 69.748511 -385.530552) (xy 69.748146 -385.54279) (xy 69.749162 -385.574286) (xy 69.750306 -385.586525)
			(xy 69.762374 -385.607897) (xy 69.764491 -385.609454) (xy 76.212638 -385.609454) (xy 76.212638 -385.554946)
			(xy 76.220395 -385.500993) (xy 76.235752 -385.448692) (xy 76.258395 -385.39911) (xy 76.287865 -385.353255)
			(xy 76.32356 -385.31206) (xy 76.364755 -385.276365) (xy 76.41061 -385.246895) (xy 76.460192 -385.224252)
			(xy 76.512493 -385.208895) (xy 76.566446 -385.201138) (xy 76.5937 -385.200652) (xy 76.622333 -385.201201)
			(xy 76.678955 -385.20976) (xy 76.733663 -385.226685) (xy 76.785226 -385.251597) (xy 76.832487 -385.283936)
			(xy 76.874383 -385.322976) (xy 76.909974 -385.367838) (xy 76.924662 -385.392422) (xy 76.931774 -385.404614)
			(xy 76.95565 -385.41833) (xy 77.072744 -385.416044) (xy 77.096112 -385.40182) (xy 77.102716 -385.389374)
			(xy 77.117644 -385.362116) (xy 77.153776 -385.311551) (xy 77.196421 -385.266343) (xy 77.244793 -385.227325)
			(xy 77.298002 -385.195214) (xy 77.355068 -385.170602) (xy 77.414941 -385.153942) (xy 77.476518 -385.145541)
			(xy 77.507592 -385.145026) (xy 77.537562 -385.145469) (xy 77.59699 -385.153292) (xy 77.654888 -385.168805)
			(xy 77.710266 -385.191744) (xy 77.762175 -385.221715) (xy 77.809729 -385.258205) (xy 77.852112 -385.300591)
			(xy 77.8886 -385.348146) (xy 77.918567 -385.400058) (xy 77.941503 -385.455437) (xy 77.957013 -385.513336)
			(xy 77.964833 -385.572764) (xy 77.9653 -385.602734) (xy 77.964787 -385.633614) (xy 77.956473 -385.694811)
			(xy 77.939999 -385.754332) (xy 77.915666 -385.811096) (xy 77.883916 -385.864069) (xy 77.874744 -385.87553)
			(xy 79.361792 -385.87553) (xy 79.362303 -385.849542) (xy 79.37043 -385.798204) (xy 79.386488 -385.74877)
			(xy 79.410082 -385.702457) (xy 79.440631 -385.660405) (xy 79.477382 -385.62365) (xy 79.519431 -385.593097)
			(xy 79.565742 -385.569499) (xy 79.615175 -385.553437) (xy 79.666512 -385.545305) (xy 79.6925 -385.544822)
			(xy 79.708933 -385.545053) (xy 79.741633 -385.548357) (xy 79.757778 -385.551426) (xy 79.770732 -385.553966)
			(xy 79.795878 -385.546092) (xy 79.873094 -385.464304) (xy 79.879698 -385.438904) (xy 79.876396 -385.426204)
			(xy 79.86939 -385.397762) (xy 79.861872 -385.339669) (xy 79.86141 -385.31038) (xy 79.861934 -385.279492)
			(xy 79.87024 -385.218276) (xy 79.886697 -385.158733) (xy 79.911007 -385.101941) (xy 79.926434 -385.075176)
			(xy 79.932276 -385.06527) (xy 79.934562 -385.042918) (xy 79.901288 -384.947668) (xy 79.88554 -384.931666)
			(xy 79.874872 -384.927602) (xy 79.851485 -384.918431) (xy 79.807589 -384.894009) (xy 79.767893 -384.863226)
			(xy 79.733313 -384.826791) (xy 79.704644 -384.785542) (xy 79.682547 -384.740431) (xy 79.667531 -384.692495)
			(xy 79.659942 -384.642839) (xy 79.65948 -384.617722) (xy 79.65999 -384.591735) (xy 79.66812 -384.5404)
			(xy 79.684181 -384.49097) (xy 79.707777 -384.44466) (xy 79.738327 -384.402612) (xy 79.775078 -384.365861)
			(xy 79.817126 -384.335311) (xy 79.863436 -384.311715) (xy 79.912866 -384.295654) (xy 79.964201 -384.287524)
			(xy 80.016175 -384.287524) (xy 80.06751 -384.295654) (xy 80.11694 -384.311715) (xy 80.16325 -384.335311)
			(xy 80.205298 -384.365861) (xy 80.242049 -384.402612) (xy 80.272599 -384.44466) (xy 80.296195 -384.49097)
			(xy 80.312256 -384.5404) (xy 80.320386 -384.591735) (xy 80.320896 -384.617722) (xy 80.859376 -384.617722)
			(xy 80.859886 -384.591735) (xy 80.868016 -384.5404) (xy 80.884077 -384.49097) (xy 80.907673 -384.44466)
			(xy 80.938223 -384.402612) (xy 80.974974 -384.365861) (xy 81.017022 -384.335311) (xy 81.063332 -384.311715)
			(xy 81.112762 -384.295654) (xy 81.164097 -384.287524) (xy 81.216071 -384.287524) (xy 81.267406 -384.295654)
			(xy 81.316836 -384.311715) (xy 81.363146 -384.335311) (xy 81.405194 -384.365861) (xy 81.441945 -384.402612)
			(xy 81.472495 -384.44466) (xy 81.496091 -384.49097) (xy 81.512152 -384.5404) (xy 81.520282 -384.591735)
			(xy 81.520792 -384.617722) (xy 82.059526 -384.617722) (xy 82.060036 -384.591735) (xy 82.068166 -384.5404)
			(xy 82.084227 -384.49097) (xy 82.107823 -384.44466) (xy 82.138373 -384.402612) (xy 82.175124 -384.365861)
			(xy 82.217172 -384.335311) (xy 82.263482 -384.311715) (xy 82.312912 -384.295654) (xy 82.364247 -384.287524)
			(xy 82.416221 -384.287524) (xy 82.467556 -384.295654) (xy 82.516986 -384.311715) (xy 82.563296 -384.335311)
			(xy 82.605344 -384.365861) (xy 82.642095 -384.402612) (xy 82.672645 -384.44466) (xy 82.696241 -384.49097)
			(xy 82.712302 -384.5404) (xy 82.720432 -384.591735) (xy 82.720942 -384.617722) (xy 83.259422 -384.617722)
			(xy 83.259932 -384.591735) (xy 83.268062 -384.5404) (xy 83.284123 -384.49097) (xy 83.307719 -384.44466)
			(xy 83.338269 -384.402612) (xy 83.37502 -384.365861) (xy 83.417068 -384.335311) (xy 83.463378 -384.311715)
			(xy 83.512808 -384.295654) (xy 83.564143 -384.287524) (xy 83.616117 -384.287524) (xy 83.667452 -384.295654)
			(xy 83.716882 -384.311715) (xy 83.763192 -384.335311) (xy 83.80524 -384.365861) (xy 83.841991 -384.402612)
			(xy 83.872541 -384.44466) (xy 83.896137 -384.49097) (xy 83.912198 -384.5404) (xy 83.920328 -384.591735)
			(xy 83.920838 -384.617722) (xy 84.459572 -384.617722) (xy 84.460082 -384.591735) (xy 84.468212 -384.5404)
			(xy 84.484273 -384.49097) (xy 84.507869 -384.44466) (xy 84.538419 -384.402612) (xy 84.57517 -384.365861)
			(xy 84.617218 -384.335311) (xy 84.663528 -384.311715) (xy 84.712958 -384.295654) (xy 84.764293 -384.287524)
			(xy 84.816267 -384.287524) (xy 84.867602 -384.295654) (xy 84.917032 -384.311715) (xy 84.963342 -384.335311)
			(xy 85.00539 -384.365861) (xy 85.042141 -384.402612) (xy 85.072691 -384.44466) (xy 85.096287 -384.49097)
			(xy 85.112348 -384.5404) (xy 85.120478 -384.591735) (xy 85.120988 -384.617722) (xy 85.659468 -384.617722)
			(xy 85.659978 -384.591735) (xy 85.668108 -384.5404) (xy 85.684169 -384.49097) (xy 85.707765 -384.44466)
			(xy 85.738315 -384.402612) (xy 85.775066 -384.365861) (xy 85.817114 -384.335311) (xy 85.863424 -384.311715)
			(xy 85.912854 -384.295654) (xy 85.964189 -384.287524) (xy 86.016163 -384.287524) (xy 86.067498 -384.295654)
			(xy 86.116928 -384.311715) (xy 86.163238 -384.335311) (xy 86.205286 -384.365861) (xy 86.242037 -384.402612)
			(xy 86.272587 -384.44466) (xy 86.296183 -384.49097) (xy 86.312244 -384.5404) (xy 86.320374 -384.591735)
			(xy 86.320884 -384.617722) (xy 86.859364 -384.617722) (xy 86.859874 -384.591735) (xy 86.868004 -384.5404)
			(xy 86.884065 -384.49097) (xy 86.907661 -384.44466) (xy 86.938211 -384.402612) (xy 86.974962 -384.365861)
			(xy 87.01701 -384.335311) (xy 87.06332 -384.311715) (xy 87.11275 -384.295654) (xy 87.164085 -384.287524)
			(xy 87.216059 -384.287524) (xy 87.267394 -384.295654) (xy 87.316824 -384.311715) (xy 87.363134 -384.335311)
			(xy 87.405182 -384.365861) (xy 87.441933 -384.402612) (xy 87.472483 -384.44466) (xy 87.496079 -384.49097)
			(xy 87.51214 -384.5404) (xy 87.52027 -384.591735) (xy 87.52078 -384.617722) (xy 88.059514 -384.617722)
			(xy 88.060024 -384.591735) (xy 88.068154 -384.5404) (xy 88.084215 -384.49097) (xy 88.107811 -384.44466)
			(xy 88.138361 -384.402612) (xy 88.175112 -384.365861) (xy 88.21716 -384.335311) (xy 88.26347 -384.311715)
			(xy 88.3129 -384.295654) (xy 88.364235 -384.287524) (xy 88.416209 -384.287524) (xy 88.467544 -384.295654)
			(xy 88.516974 -384.311715) (xy 88.563284 -384.335311) (xy 88.605332 -384.365861) (xy 88.642083 -384.402612)
			(xy 88.672633 -384.44466) (xy 88.696229 -384.49097) (xy 88.71229 -384.5404) (xy 88.72042 -384.591735)
			(xy 88.72093 -384.617722) (xy 89.25941 -384.617722) (xy 89.25992 -384.591735) (xy 89.26805 -384.5404)
			(xy 89.284111 -384.49097) (xy 89.307707 -384.44466) (xy 89.338257 -384.402612) (xy 89.375008 -384.365861)
			(xy 89.417056 -384.335311) (xy 89.463366 -384.311715) (xy 89.512796 -384.295654) (xy 89.564131 -384.287524)
			(xy 89.616105 -384.287524) (xy 89.66744 -384.295654) (xy 89.71687 -384.311715) (xy 89.76318 -384.335311)
			(xy 89.805228 -384.365861) (xy 89.841979 -384.402612) (xy 89.872529 -384.44466) (xy 89.896125 -384.49097)
			(xy 89.912186 -384.5404) (xy 89.920316 -384.591735) (xy 89.920826 -384.617722) (xy 90.45956 -384.617722)
			(xy 90.46007 -384.591735) (xy 90.4682 -384.5404) (xy 90.484261 -384.49097) (xy 90.507857 -384.44466)
			(xy 90.538407 -384.402612) (xy 90.575158 -384.365861) (xy 90.617206 -384.335311) (xy 90.663516 -384.311715)
			(xy 90.712946 -384.295654) (xy 90.764281 -384.287524) (xy 90.816255 -384.287524) (xy 90.86759 -384.295654)
			(xy 90.91702 -384.311715) (xy 90.96333 -384.335311) (xy 91.005378 -384.365861) (xy 91.042129 -384.402612)
			(xy 91.072679 -384.44466) (xy 91.096275 -384.49097) (xy 91.112336 -384.5404) (xy 91.120466 -384.591735)
			(xy 91.120976 -384.617722) (xy 91.659456 -384.617722) (xy 91.659966 -384.591735) (xy 91.668096 -384.5404)
			(xy 91.684157 -384.49097) (xy 91.707753 -384.44466) (xy 91.738303 -384.402612) (xy 91.775054 -384.365861)
			(xy 91.817102 -384.335311) (xy 91.863412 -384.311715) (xy 91.912842 -384.295654) (xy 91.964177 -384.287524)
			(xy 92.016151 -384.287524) (xy 92.067486 -384.295654) (xy 92.116916 -384.311715) (xy 92.163226 -384.335311)
			(xy 92.205274 -384.365861) (xy 92.242025 -384.402612) (xy 92.272575 -384.44466) (xy 92.296171 -384.49097)
			(xy 92.312232 -384.5404) (xy 92.320362 -384.591735) (xy 92.320872 -384.617722) (xy 92.859352 -384.617722)
			(xy 92.859862 -384.591735) (xy 92.867992 -384.5404) (xy 92.884053 -384.49097) (xy 92.907649 -384.44466)
			(xy 92.938199 -384.402612) (xy 92.97495 -384.365861) (xy 93.016998 -384.335311) (xy 93.063308 -384.311715)
			(xy 93.112738 -384.295654) (xy 93.164073 -384.287524) (xy 93.216047 -384.287524) (xy 93.267382 -384.295654)
			(xy 93.316812 -384.311715) (xy 93.363122 -384.335311) (xy 93.40517 -384.365861) (xy 93.441921 -384.402612)
			(xy 93.472471 -384.44466) (xy 93.496067 -384.49097) (xy 93.512128 -384.5404) (xy 93.520258 -384.591735)
			(xy 93.520768 -384.617722) (xy 94.059502 -384.617722) (xy 94.060012 -384.591735) (xy 94.068142 -384.5404)
			(xy 94.084203 -384.49097) (xy 94.107799 -384.44466) (xy 94.138349 -384.402612) (xy 94.1751 -384.365861)
			(xy 94.217148 -384.335311) (xy 94.263458 -384.311715) (xy 94.312888 -384.295654) (xy 94.364223 -384.287524)
			(xy 94.416197 -384.287524) (xy 94.467532 -384.295654) (xy 94.516962 -384.311715) (xy 94.563272 -384.335311)
			(xy 94.60532 -384.365861) (xy 94.642071 -384.402612) (xy 94.672621 -384.44466) (xy 94.696217 -384.49097)
			(xy 94.712278 -384.5404) (xy 94.720408 -384.591735) (xy 94.720918 -384.617722) (xy 95.259398 -384.617722)
			(xy 95.259908 -384.591735) (xy 95.268038 -384.5404) (xy 95.284099 -384.49097) (xy 95.307695 -384.44466)
			(xy 95.338245 -384.402612) (xy 95.374996 -384.365861) (xy 95.417044 -384.335311) (xy 95.463354 -384.311715)
			(xy 95.512784 -384.295654) (xy 95.564119 -384.287524) (xy 95.616093 -384.287524) (xy 95.667428 -384.295654)
			(xy 95.716858 -384.311715) (xy 95.763168 -384.335311) (xy 95.805216 -384.365861) (xy 95.841967 -384.402612)
			(xy 95.872517 -384.44466) (xy 95.896113 -384.49097) (xy 95.912174 -384.5404) (xy 95.920304 -384.591735)
			(xy 95.920814 -384.617722) (xy 96.459548 -384.617722) (xy 96.460058 -384.591735) (xy 96.468188 -384.5404)
			(xy 96.484249 -384.49097) (xy 96.507845 -384.44466) (xy 96.538395 -384.402612) (xy 96.575146 -384.365861)
			(xy 96.617194 -384.335311) (xy 96.663504 -384.311715) (xy 96.712934 -384.295654) (xy 96.764269 -384.287524)
			(xy 96.816243 -384.287524) (xy 96.867578 -384.295654) (xy 96.917008 -384.311715) (xy 96.963318 -384.335311)
			(xy 97.005366 -384.365861) (xy 97.042117 -384.402612) (xy 97.072667 -384.44466) (xy 97.096263 -384.49097)
			(xy 97.112324 -384.5404) (xy 97.120454 -384.591735) (xy 97.120964 -384.617722) (xy 97.659444 -384.617722)
			(xy 97.659954 -384.591735) (xy 97.668084 -384.5404) (xy 97.684145 -384.49097) (xy 97.707741 -384.44466)
			(xy 97.738291 -384.402612) (xy 97.775042 -384.365861) (xy 97.81709 -384.335311) (xy 97.8634 -384.311715)
			(xy 97.91283 -384.295654) (xy 97.964165 -384.287524) (xy 98.016139 -384.287524) (xy 98.067474 -384.295654)
			(xy 98.116904 -384.311715) (xy 98.163214 -384.335311) (xy 98.205262 -384.365861) (xy 98.242013 -384.402612)
			(xy 98.272563 -384.44466) (xy 98.296159 -384.49097) (xy 98.31222 -384.5404) (xy 98.32035 -384.591735)
			(xy 98.32086 -384.617722) (xy 98.320329 -384.644824) (xy 98.31152 -384.698307) (xy 98.303334 -384.724148)
			(xy 98.299524 -384.73507) (xy 98.302064 -384.757422) (xy 98.354642 -384.843274) (xy 98.373692 -384.85572)
			(xy 98.384868 -384.857498) (xy 98.414191 -384.862176) (xy 98.471362 -384.878229) (xy 98.525976 -384.901543)
			(xy 98.577115 -384.931726) (xy 98.62392 -384.968271) (xy 98.665604 -385.010563) (xy 98.701467 -385.057892)
			(xy 98.730907 -385.109462) (xy 98.753428 -385.164408) (xy 98.768652 -385.221805) (xy 98.776323 -385.280689)
			(xy 98.77679 -385.31038) (xy 98.776262 -385.341443) (xy 98.767851 -385.402996) (xy 98.760026 -385.433062)
			(xy 98.757232 -385.443222) (xy 98.759772 -385.463034) (xy 98.80727 -385.54533) (xy 98.823272 -385.557522)
			(xy 98.833432 -385.560062) (xy 98.862538 -385.568075) (xy 98.918504 -385.590707) (xy 98.97101 -385.620499)
			(xy 99.019144 -385.656935) (xy 99.062071 -385.699382) (xy 99.099045 -385.747103) (xy 99.129426 -385.799271)
			(xy 99.152685 -385.85498) (xy 99.16842 -385.913262) (xy 99.176356 -385.973107) (xy 99.17684 -386.003292)
			(xy 99.176738 -386.017042) (xy 99.175086 -386.044493) (xy 99.173538 -386.058156) (xy 99.172818 -386.066844)
			(xy 99.176592 -386.083853) (xy 99.180904 -386.09143) (xy 99.196906 -386.11683) (xy 99.201673 -386.123868)
			(xy 99.214917 -386.134509) (xy 99.222814 -386.137658) (xy 99.24659 -386.146579) (xy 99.291239 -386.170772)
			(xy 99.331664 -386.201507) (xy 99.366915 -386.238061) (xy 99.396163 -386.279575) (xy 99.41872 -386.325073)
			(xy 99.434056 -386.373484) (xy 99.441811 -386.423671) (xy 99.44227 -386.449062) (xy 99.44179 -386.475052)
			(xy 99.433663 -386.526393) (xy 99.417604 -386.57583) (xy 99.394007 -386.622146) (xy 99.363455 -386.664199)
			(xy 99.326699 -386.700955) (xy 99.284646 -386.731507) (xy 99.23833 -386.755104) (xy 99.188893 -386.771163)
			(xy 99.137552 -386.77929) (xy 99.111562 -386.77977) (xy 99.086655 -386.779263) (xy 99.037401 -386.771813)
			(xy 98.989822 -386.757059) (xy 98.944996 -386.735333) (xy 98.903936 -386.707128) (xy 98.867573 -386.673082)
			(xy 98.836729 -386.633966) (xy 98.812102 -386.590665) (xy 98.794251 -386.54416) (xy 98.788474 -386.519928)
			(xy 98.786308 -386.511709) (xy 98.777499 -386.497188) (xy 98.771202 -386.49148) (xy 98.747834 -386.47243)
			(xy 98.740942 -386.467229) (xy 98.724709 -386.461383) (xy 98.716084 -386.461) (xy 98.686248 -386.460288)
			(xy 98.627126 -386.45214) (xy 98.569564 -386.436377) (xy 98.51454 -386.413266) (xy 98.462987 -386.383199)
			(xy 98.415779 -386.346685) (xy 98.373718 -386.304346) (xy 98.337517 -386.256898) (xy 98.307791 -386.205147)
			(xy 98.285044 -386.149971) (xy 98.269662 -386.092307) (xy 98.261905 -386.033132) (xy 98.261424 -386.003292)
			(xy 98.261946 -385.972229) (xy 98.270361 -385.910675) (xy 98.278188 -385.88061) (xy 98.280982 -385.87045)
			(xy 98.278442 -385.850638) (xy 98.230944 -385.768342) (xy 98.214942 -385.75615) (xy 98.204782 -385.75361)
			(xy 98.175671 -385.745613) (xy 98.119703 -385.722981) (xy 98.067196 -385.693188) (xy 98.019061 -385.656751)
			(xy 97.976134 -385.614302) (xy 97.93916 -385.566578) (xy 97.90878 -385.514408) (xy 97.885522 -385.458698)
			(xy 97.86979 -385.400413) (xy 97.861856 -385.340565) (xy 97.861374 -385.31038) (xy 97.861903 -385.279492)
			(xy 97.870208 -385.218277) (xy 97.886664 -385.158733) (xy 97.910972 -385.101941) (xy 97.926398 -385.075176)
			(xy 97.93224 -385.06527) (xy 97.934526 -385.042918) (xy 97.901252 -384.947668) (xy 97.885504 -384.931666)
			(xy 97.874836 -384.927602) (xy 97.851442 -384.91845) (xy 97.807546 -384.894024) (xy 97.767852 -384.863237)
			(xy 97.733273 -384.826799) (xy 97.704606 -384.785548) (xy 97.68251 -384.740434) (xy 97.667495 -384.692497)
			(xy 97.659906 -384.642839) (xy 97.659444 -384.617722) (xy 97.120964 -384.617722) (xy 97.120433 -384.644824)
			(xy 97.111624 -384.698307) (xy 97.103438 -384.724148) (xy 97.099628 -384.73507) (xy 97.102168 -384.757422)
			(xy 97.154746 -384.843274) (xy 97.173796 -384.85572) (xy 97.184972 -384.857498) (xy 97.214296 -384.862173)
			(xy 97.271466 -384.878227) (xy 97.32608 -384.901541) (xy 97.377219 -384.931724) (xy 97.424024 -384.968269)
			(xy 97.465708 -385.010561) (xy 97.501571 -385.057891) (xy 97.531011 -385.109462) (xy 97.553532 -385.164407)
			(xy 97.568756 -385.221805) (xy 97.576427 -385.280689) (xy 97.576894 -385.31038) (xy 97.57637 -385.341506)
			(xy 97.567965 -385.403188) (xy 97.56013 -385.433316) (xy 97.557336 -385.443476) (xy 97.559876 -385.463542)
			(xy 97.60712 -385.54533) (xy 97.623122 -385.557522) (xy 97.633282 -385.560062) (xy 97.662397 -385.568042)
			(xy 97.718363 -385.59068) (xy 97.770868 -385.620477) (xy 97.819001 -385.656918) (xy 97.861926 -385.699369)
			(xy 97.898899 -385.747093) (xy 97.929278 -385.799264) (xy 97.952537 -385.854975) (xy 97.968271 -385.913259)
			(xy 97.976207 -385.973106) (xy 97.97669 -386.003292) (xy 97.976565 -386.017427) (xy 97.974783 -386.045641)
			(xy 97.973134 -386.05968) (xy 97.972377 -386.068287) (xy 97.976015 -386.085167) (xy 97.980246 -386.0927)
			(xy 97.995994 -386.1181) (xy 98.000703 -386.125161) (xy 98.013809 -386.135929) (xy 98.021648 -386.139182)
			(xy 98.045033 -386.148356) (xy 98.088929 -386.172778) (xy 98.128623 -386.203562) (xy 98.163203 -386.239997)
			(xy 98.191871 -386.281245) (xy 98.213969 -386.326356) (xy 98.228986 -386.374291) (xy 98.236577 -386.423946)
			(xy 98.23704 -386.449062) (xy 98.236625 -386.473265) (xy 98.22955 -386.52115) (xy 98.215561 -386.56749)
			(xy 98.194957 -386.611291) (xy 98.181922 -386.631688) (xy 98.177131 -386.639643) (xy 98.1731 -386.657755)
			(xy 98.174048 -386.666994) (xy 98.178366 -386.697982) (xy 98.180058 -386.707275) (xy 98.189333 -386.723717)
			(xy 98.1964 -386.729986) (xy 98.218475 -386.748684) (xy 98.25825 -386.790691) (xy 98.292414 -386.837376)
			(xy 98.320425 -386.887993) (xy 98.341834 -386.941736) (xy 98.356301 -386.997748) (xy 98.363595 -387.055137)
			(xy 98.36404 -387.084062) (xy 102.411528 -387.084062) (xy 102.415599 -387.02844) (xy 102.427725 -386.974003)
			(xy 102.447648 -386.921912) (xy 102.474944 -386.873277) (xy 102.50903 -386.829134) (xy 102.549179 -386.790425)
			(xy 102.594537 -386.757974) (xy 102.644137 -386.732473) (xy 102.696921 -386.714466) (xy 102.751764 -386.704336)
			(xy 102.807498 -386.702299) (xy 102.862935 -386.708399) (xy 102.916892 -386.722505) (xy 102.968221 -386.744317)
			(xy 103.015827 -386.773371) (xy 103.058695 -386.809046) (xy 103.095912 -386.850583) (xy 103.126685 -386.897096)
			(xy 103.150357 -386.947593) (xy 103.166425 -387.001) (xy 103.174545 -387.056176) (xy 103.175054 -387.084062)
			(xy 103.174545 -387.111948) (xy 103.166425 -387.167124) (xy 103.150357 -387.220531) (xy 103.126685 -387.271028)
			(xy 103.095912 -387.317541) (xy 103.058695 -387.359078) (xy 103.015827 -387.394753) (xy 102.968221 -387.423807)
			(xy 102.916892 -387.445619) (xy 102.862935 -387.459725) (xy 102.807498 -387.465825) (xy 102.751764 -387.463788)
			(xy 102.696921 -387.453658) (xy 102.644137 -387.435651) (xy 102.594537 -387.41015) (xy 102.549179 -387.377699)
			(xy 102.50903 -387.33899) (xy 102.474944 -387.294847) (xy 102.447648 -387.246212) (xy 102.427725 -387.194121)
			(xy 102.415599 -387.139684) (xy 102.411528 -387.084062) (xy 98.36404 -387.084062) (xy 98.36345 -387.117383)
			(xy 98.353788 -387.183322) (xy 98.334662 -387.247161) (xy 98.321114 -387.27761) (xy 98.316854 -387.288072)
			(xy 98.316968 -387.310635) (xy 98.326709 -387.330988) (xy 98.335084 -387.33857) (xy 98.357311 -387.357267)
			(xy 98.397376 -387.399318) (xy 98.431799 -387.4461) (xy 98.460026 -387.496861) (xy 98.481605 -387.550785)
			(xy 98.496188 -387.607007) (xy 98.503541 -387.664621) (xy 98.503994 -387.693662) (xy 98.503502 -387.722666)
			(xy 98.496192 -387.780212) (xy 98.492498 -387.7945) (xy 104.48493 -387.7945) (xy 104.489001 -387.738878)
			(xy 104.501127 -387.684441) (xy 104.52105 -387.63235) (xy 104.548346 -387.583715) (xy 104.582432 -387.539572)
			(xy 104.622581 -387.500863) (xy 104.667939 -387.468412) (xy 104.717539 -387.442911) (xy 104.770323 -387.424904)
			(xy 104.825166 -387.414774) (xy 104.8809 -387.412737) (xy 104.936337 -387.418837) (xy 104.990294 -387.432943)
			(xy 105.041623 -387.454755) (xy 105.089229 -387.483809) (xy 105.132097 -387.519484) (xy 105.169314 -387.561021)
			(xy 105.200087 -387.607534) (xy 105.223759 -387.658031) (xy 105.239827 -387.711438) (xy 105.247947 -387.766614)
			(xy 105.248456 -387.7945) (xy 105.247947 -387.822386) (xy 105.239827 -387.877562) (xy 105.223759 -387.930969)
			(xy 105.200087 -387.981466) (xy 105.169314 -388.027979) (xy 105.132097 -388.069516) (xy 105.089229 -388.105191)
			(xy 105.041623 -388.134245) (xy 104.990294 -388.156057) (xy 104.936337 -388.170163) (xy 104.8809 -388.176263)
			(xy 104.825166 -388.174226) (xy 104.770323 -388.164096) (xy 104.717539 -388.146089) (xy 104.667939 -388.120588)
			(xy 104.622581 -388.088137) (xy 104.582432 -388.049428) (xy 104.548346 -388.005285) (xy 104.52105 -387.95665)
			(xy 104.501127 -387.904559) (xy 104.489001 -387.850122) (xy 104.48493 -387.7945) (xy 98.492498 -387.7945)
			(xy 98.481671 -387.836374) (xy 98.460173 -387.890252) (xy 98.432041 -387.940982) (xy 98.397727 -387.987753)
			(xy 98.35778 -388.029814) (xy 98.335592 -388.0485) (xy 98.32848 -388.054088) (xy 98.319336 -388.069328)
			(xy 98.304096 -388.152132) (xy 98.30689 -388.169404) (xy 98.311462 -388.177532) (xy 98.324039 -388.200718)
			(xy 98.341912 -388.25034) (xy 98.348735 -388.289292) (xy 99.89693 -388.289292) (xy 99.89742 -388.259324)
			(xy 99.905243 -388.199902) (xy 99.920756 -388.142009) (xy 99.943692 -388.086636) (xy 99.973659 -388.03473)
			(xy 100.010146 -387.98718) (xy 100.052526 -387.9448) (xy 100.100076 -387.908313) (xy 100.151982 -387.878346)
			(xy 100.207355 -387.85541) (xy 100.265248 -387.839897) (xy 100.32467 -387.832074) (xy 100.384606 -387.832074)
			(xy 100.444028 -387.839897) (xy 100.501921 -387.85541) (xy 100.557294 -387.878346) (xy 100.6092 -387.908313)
			(xy 100.65675 -387.9448) (xy 100.69913 -387.98718) (xy 100.735617 -388.03473) (xy 100.765584 -388.086636)
			(xy 100.78852 -388.142009) (xy 100.804033 -388.199902) (xy 100.811856 -388.259324) (xy 100.812346 -388.289292)
			(xy 100.811783 -388.321116) (xy 100.802966 -388.384151) (xy 100.7855 -388.445356) (xy 100.759723 -388.503551)
			(xy 100.726132 -388.557614) (xy 100.706174 -388.582408) (xy 100.700332 -388.58952) (xy 100.694236 -388.607046)
			(xy 100.696776 -388.693152) (xy 100.703888 -388.71017) (xy 100.710238 -388.717028) (xy 100.722725 -388.730555)
			(xy 100.745739 -388.759292) (xy 100.756212 -388.774432) (xy 100.76434 -388.786116) (xy 100.789994 -388.798054)
			(xy 100.907596 -388.784846) (xy 100.929948 -388.767574) (xy 100.935028 -388.754366) (xy 100.94587 -388.72786)
			(xy 100.974353 -388.67818) (xy 101.009943 -388.633316) (xy 101.051839 -388.594275) (xy 101.099099 -388.561936)
			(xy 101.150663 -388.537025) (xy 101.205372 -388.520101) (xy 101.261995 -388.511545) (xy 101.290628 -388.511034)
			(xy 101.317999 -388.511475) (xy 101.37218 -388.519298) (xy 101.424683 -388.534792) (xy 101.47443 -388.55764)
			(xy 101.520395 -388.58737) (xy 101.541326 -388.605014) (xy 101.548438 -388.61111) (xy 101.565456 -388.61746)
			(xy 101.6508 -388.61746) (xy 101.667818 -388.61111) (xy 101.67493 -388.605014) (xy 101.695863 -388.587373)
			(xy 101.741831 -388.557649) (xy 101.791577 -388.534803) (xy 101.844079 -388.519307) (xy 101.898257 -388.511478)
			(xy 101.952999 -388.511478) (xy 102.007177 -388.519307) (xy 102.059679 -388.534803) (xy 102.109425 -388.557649)
			(xy 102.155393 -388.587373) (xy 102.176326 -388.605014) (xy 102.183438 -388.61111) (xy 102.200456 -388.61746)
			(xy 102.2858 -388.61746) (xy 102.302818 -388.61111) (xy 102.30993 -388.605014) (xy 102.330879 -388.587396)
			(xy 102.376847 -388.557681) (xy 102.42659 -388.534841) (xy 102.479087 -388.519345) (xy 102.53326 -388.511511)
			(xy 102.560628 -388.511034) (xy 102.587881 -388.511438) (xy 102.641832 -388.519198) (xy 102.694129 -388.534558)
			(xy 102.743708 -388.557203) (xy 102.78956 -388.586673) (xy 102.830751 -388.622369) (xy 102.866444 -388.663563)
			(xy 102.895911 -388.709417) (xy 102.918552 -388.758998) (xy 102.933908 -388.811296) (xy 102.941664 -388.865247)
			(xy 102.941664 -388.919753) (xy 102.933908 -388.973704) (xy 102.918552 -389.026002) (xy 102.895911 -389.075583)
			(xy 102.866444 -389.121437) (xy 102.830751 -389.162631) (xy 102.78956 -389.198327) (xy 102.743708 -389.227797)
			(xy 102.694129 -389.250442) (xy 102.641832 -389.265802) (xy 102.587881 -389.273562) (xy 102.560628 -389.27405)
			(xy 102.533258 -389.27358) (xy 102.479078 -389.265765) (xy 102.426575 -389.250277) (xy 102.376828 -389.227436)
			(xy 102.330861 -389.197712) (xy 102.30993 -389.18007) (xy 102.302818 -389.173974) (xy 102.2858 -389.167624)
			(xy 102.200456 -389.167624) (xy 102.183438 -389.173974) (xy 102.176326 -389.18007) (xy 102.155393 -389.197711)
			(xy 102.109425 -389.227435) (xy 102.059679 -389.250281) (xy 102.007177 -389.265777) (xy 101.952999 -389.273606)
			(xy 101.898257 -389.273606) (xy 101.844079 -389.265777) (xy 101.791577 -389.250281) (xy 101.741831 -389.227435)
			(xy 101.695863 -389.197711) (xy 101.67493 -389.18007) (xy 101.667818 -389.173974) (xy 101.6508 -389.167624)
			(xy 101.565456 -389.167624) (xy 101.548438 -389.173974) (xy 101.541326 -389.18007) (xy 101.520391 -389.197706)
			(xy 101.47442 -389.227419) (xy 101.424673 -389.250256) (xy 101.372173 -389.265748) (xy 101.317997 -389.273576)
			(xy 101.290628 -389.27405) (xy 101.262027 -389.27353) (xy 101.205464 -389.264999) (xy 101.150808 -389.248124)
			(xy 101.099281 -389.223283) (xy 101.052037 -389.191032) (xy 101.010135 -389.152092) (xy 100.991924 -389.130032)
			(xy 100.983288 -389.118856) (xy 100.956618 -389.10895) (xy 100.840286 -389.131302) (xy 100.819458 -389.150098)
			(xy 100.815394 -389.163814) (xy 100.805297 -389.19516) (xy 100.777325 -389.254779) (xy 100.741085 -389.309766)
			(xy 100.719636 -389.334756) (xy 100.713286 -389.341868) (xy 100.706682 -389.35914) (xy 100.706682 -389.445246)
			(xy 100.713286 -389.462518) (xy 100.719636 -389.46963) (xy 100.741215 -389.494865) (xy 100.777588 -389.550413)
			(xy 100.805554 -389.610632) (xy 100.824528 -389.67426) (xy 100.834111 -389.739962) (xy 100.834698 -389.77316)
			(xy 100.834179 -389.804762) (xy 100.825475 -389.867363) (xy 100.808228 -389.928168) (xy 100.782766 -389.986016)
			(xy 100.766626 -390.01319) (xy 100.762111 -390.021424) (xy 100.758677 -390.039866) (xy 100.762086 -390.058312)
			(xy 100.766626 -390.06653) (xy 100.782752 -390.09371) (xy 100.808179 -390.151567) (xy 100.825419 -390.212368)
			(xy 100.834146 -390.274961) (xy 100.834698 -390.30656) (xy 100.834154 -390.338174) (xy 100.825437 -390.400798)
			(xy 100.80819 -390.461628) (xy 100.78274 -390.519508) (xy 100.749573 -390.573339) (xy 100.709318 -390.622096)
			(xy 100.66274 -390.664854) (xy 100.610724 -390.7008) (xy 100.58273 -390.7155) (xy 100.573422 -390.720772)
			(xy 100.559907 -390.737327) (xy 100.554252 -390.757937) (xy 100.555298 -390.768586) (xy 100.557103 -390.781144)
			(xy 100.559009 -390.806445) (xy 100.559108 -390.819132) (xy 100.558598 -390.845119) (xy 100.550468 -390.896454)
			(xy 100.534407 -390.945884) (xy 100.510811 -390.992194) (xy 100.480261 -391.034242) (xy 100.44351 -391.070993)
			(xy 100.401462 -391.101543) (xy 100.355152 -391.125139) (xy 100.305722 -391.1412) (xy 100.254387 -391.14933)
			(xy 100.202413 -391.14933) (xy 100.151078 -391.1412) (xy 100.101648 -391.125139) (xy 100.055338 -391.101543)
			(xy 100.01329 -391.070993) (xy 99.976539 -391.034242) (xy 99.945989 -390.992194) (xy 99.922393 -390.945884)
			(xy 99.906332 -390.896454) (xy 99.898202 -390.845119) (xy 99.897692 -390.819132) (xy 99.898096 -390.795394)
			(xy 99.904893 -390.748407) (xy 99.918336 -390.702875) (xy 99.93815 -390.659731) (xy 99.963928 -390.619864)
			(xy 99.979226 -390.601708) (xy 99.985937 -390.59331) (xy 99.992271 -390.572789) (xy 99.989681 -390.551469)
			(xy 99.98456 -390.542018) (xy 99.969052 -390.51525) (xy 99.944637 -390.458408) (xy 99.928114 -390.398792)
			(xy 99.919785 -390.337492) (xy 99.919282 -390.30656) (xy 99.919799 -390.274958) (xy 99.928501 -390.212356)
			(xy 99.945749 -390.151551) (xy 99.971213 -390.093704) (xy 99.987354 -390.06653) (xy 99.991935 -390.058328)
			(xy 99.995349 -390.039866) (xy 99.991911 -390.021408) (xy 99.987354 -390.01319) (xy 99.971234 -389.986007)
			(xy 99.945806 -389.928151) (xy 99.928564 -389.86735) (xy 99.919836 -389.804758) (xy 99.919282 -389.77316)
			(xy 99.919842 -389.739925) (xy 99.929452 -389.674154) (xy 99.948476 -389.610466) (xy 99.976516 -389.550201)
			(xy 100.012982 -389.494627) (xy 100.034598 -389.469376) (xy 100.040948 -389.462264) (xy 100.047552 -389.444992)
			(xy 100.047552 -389.358886) (xy 100.040948 -389.341614) (xy 100.034598 -389.334502) (xy 100.013024 -389.309263)
			(xy 99.976653 -389.253716) (xy 99.948686 -389.193497) (xy 99.929711 -389.12987) (xy 99.920125 -389.06417)
			(xy 99.919536 -389.030972) (xy 99.920083 -388.999147) (xy 99.928904 -388.936112) (xy 99.946374 -388.874907)
			(xy 99.972154 -388.816712) (xy 100.005748 -388.76265) (xy 100.025708 -388.737856) (xy 100.03155 -388.730744)
			(xy 100.037646 -388.713218) (xy 100.035106 -388.627112) (xy 100.027994 -388.610094) (xy 100.021644 -388.603236)
			(xy 100.002155 -388.581968) (xy 99.968162 -388.535359) (xy 99.940298 -388.484846) (xy 99.919004 -388.431232)
			(xy 99.904618 -388.375367) (xy 99.897368 -388.318136) (xy 99.89693 -388.289292) (xy 98.348735 -388.289292)
			(xy 98.351012 -388.302291) (xy 98.351594 -388.328662) (xy 98.35149 -388.339943) (xy 98.349839 -388.362445)
			(xy 98.348292 -388.37362) (xy 98.347022 -388.38251) (xy 98.350578 -388.400036) (xy 98.394012 -388.470902)
			(xy 98.407728 -388.482078) (xy 98.416364 -388.484872) (xy 98.438611 -388.492803) (xy 98.480532 -388.514555)
			(xy 98.518605 -388.542501) (xy 98.551923 -388.575974) (xy 98.579691 -388.614176) (xy 98.590862 -388.634986)
			(xy 98.59137 -388.636002) (xy 98.9838 -389.314944) (xy 98.996532 -389.33831) (xy 99.014648 -389.388338)
			(xy 99.023858 -389.440741) (xy 99.02444 -389.467344) (xy 99.023978 -389.491335) (xy 99.016466 -389.538725)
			(xy 99.001635 -389.584357) (xy 98.979849 -389.627107) (xy 98.951644 -389.665924) (xy 98.917715 -389.699852)
			(xy 98.878897 -389.728055) (xy 98.836146 -389.74984) (xy 98.790513 -389.764669) (xy 98.743123 -389.772179)
			(xy 98.719132 -389.772652) (xy 98.6956 -389.772223) (xy 98.649091 -389.765013) (xy 98.604242 -389.750742)
			(xy 98.562119 -389.72975) (xy 98.52372 -389.702536) (xy 98.489959 -389.669745) (xy 98.461636 -389.632157)
			(xy 98.450146 -389.611616) (xy 98.449892 -389.611108) (xy 98.449384 -389.610346) (xy 98.05162 -388.922006)
			(xy 98.039706 -388.899337) (xy 98.022768 -388.851012) (xy 98.014108 -388.800542) (xy 98.01352 -388.77494)
			(xy 98.01352 -388.774432) (xy 98.013677 -388.763083) (xy 98.015454 -388.740453) (xy 98.017076 -388.72922)
			(xy 98.018346 -388.72033) (xy 98.01479 -388.703058) (xy 97.971356 -388.631938) (xy 97.957386 -388.621016)
			(xy 97.949004 -388.617968) (xy 97.926594 -388.609957) (xy 97.884376 -388.587993) (xy 97.846081 -388.559741)
			(xy 97.812636 -388.525886) (xy 97.784853 -388.487248) (xy 97.763406 -388.444766) (xy 97.748814 -388.39947)
			(xy 97.741431 -388.352457) (xy 97.740978 -388.328662) (xy 97.741547 -388.302289) (xy 97.750629 -388.250331)
			(xy 97.768516 -388.20071) (xy 97.78111 -388.177532) (xy 97.785682 -388.169404) (xy 97.788476 -388.152132)
			(xy 97.773236 -388.069328) (xy 97.764092 -388.054088) (xy 97.75698 -388.0485) (xy 97.734805 -388.029799)
			(xy 97.694859 -387.987736) (xy 97.660543 -387.940967) (xy 97.632405 -387.89024) (xy 97.610895 -387.836367)
			(xy 97.596359 -387.780209) (xy 97.589029 -387.722666) (xy 97.588578 -387.693662) (xy 97.589175 -387.660341)
			(xy 97.598834 -387.594402) (xy 97.617957 -387.530563) (xy 97.631504 -387.500114) (xy 97.635735 -387.489643)
			(xy 97.63563 -387.467088) (xy 97.625902 -387.446738) (xy 97.617534 -387.439154) (xy 97.595274 -387.420495)
			(xy 97.55521 -387.378438) (xy 97.52079 -387.331649) (xy 97.492566 -387.280882) (xy 97.470993 -387.226951)
			(xy 97.456417 -387.170724) (xy 97.449072 -387.113105) (xy 97.448624 -387.084062) (xy 97.449086 -387.055136)
			(xy 97.456369 -386.997745) (xy 97.470827 -386.941728) (xy 97.492229 -386.887981) (xy 97.520234 -386.83736)
			(xy 97.554396 -386.790671) (xy 97.594169 -386.74866) (xy 97.616264 -386.729986) (xy 97.623236 -386.723639)
			(xy 97.632494 -386.707235) (xy 97.634298 -386.697982) (xy 97.638616 -386.666994) (xy 97.639525 -386.657758)
			(xy 97.635498 -386.639657) (xy 97.630742 -386.631688) (xy 97.614438 -386.60584) (xy 97.590532 -386.549606)
			(xy 97.583244 -386.519928) (xy 97.581173 -386.51177) (xy 97.57248 -386.497367) (xy 97.566226 -386.491734)
			(xy 97.543112 -386.472684) (xy 97.536224 -386.467451) (xy 97.52 -386.461477) (xy 97.511362 -386.461)
			(xy 97.481725 -386.459991) (xy 97.423061 -386.451342) (xy 97.366003 -386.435191) (xy 97.311509 -386.411808)
			(xy 97.26049 -386.381585) (xy 97.2138 -386.345028) (xy 97.172221 -386.302749) (xy 97.136449 -386.255455)
			(xy 97.107082 -386.203938) (xy 97.084613 -386.149061) (xy 97.069417 -386.091742) (xy 97.061749 -386.032941)
			(xy 97.061274 -386.003292) (xy 97.061794 -385.972229) (xy 97.070211 -385.910675) (xy 97.078038 -385.88061)
			(xy 97.080832 -385.87045) (xy 97.078292 -385.850638) (xy 97.030794 -385.768342) (xy 97.014792 -385.75615)
			(xy 97.004632 -385.75361) (xy 96.975544 -385.745579) (xy 96.919617 -385.722912) (xy 96.867151 -385.693096)
			(xy 96.819057 -385.656647) (xy 96.776167 -385.614197) (xy 96.739224 -385.566481) (xy 96.708869 -385.514325)
			(xy 96.685627 -385.458635) (xy 96.669902 -385.400374) (xy 96.661965 -385.340553) (xy 96.661478 -385.31038)
			(xy 96.662007 -385.279492) (xy 96.670311 -385.218277) (xy 96.686767 -385.158733) (xy 96.711076 -385.101941)
			(xy 96.726502 -385.075176) (xy 96.732344 -385.06527) (xy 96.73463 -385.042918) (xy 96.701356 -384.947668)
			(xy 96.685608 -384.931666) (xy 96.67494 -384.927602) (xy 96.651546 -384.918448) (xy 96.607651 -384.894022)
			(xy 96.567957 -384.863236) (xy 96.533378 -384.826798) (xy 96.50471 -384.785547) (xy 96.482614 -384.740434)
			(xy 96.467599 -384.692496) (xy 96.46001 -384.642839) (xy 96.459548 -384.617722) (xy 95.920814 -384.617722)
			(xy 95.920281 -384.644824) (xy 95.911473 -384.698306) (xy 95.903288 -384.724148) (xy 95.899478 -384.73507)
			(xy 95.902018 -384.757422) (xy 95.954596 -384.843274) (xy 95.973646 -384.85572) (xy 95.984822 -384.857498)
			(xy 96.014139 -384.862212) (xy 96.071309 -384.87826) (xy 96.125923 -384.901568) (xy 96.177063 -384.931747)
			(xy 96.223869 -384.968287) (xy 96.265554 -385.010575) (xy 96.301419 -385.057901) (xy 96.330859 -385.109469)
			(xy 96.353381 -385.164412) (xy 96.368605 -385.221808) (xy 96.376277 -385.28069) (xy 96.376744 -385.31038)
			(xy 96.376217 -385.341443) (xy 96.367805 -385.402996) (xy 96.35998 -385.433062) (xy 96.357186 -385.443222)
			(xy 96.359726 -385.463034) (xy 96.407224 -385.54533) (xy 96.423226 -385.557522) (xy 96.433386 -385.560062)
			(xy 96.462502 -385.568039) (xy 96.518468 -385.590677) (xy 96.570973 -385.620475) (xy 96.619105 -385.656916)
			(xy 96.66203 -385.699367) (xy 96.699003 -385.747092) (xy 96.729383 -385.799263) (xy 96.752641 -385.854974)
			(xy 96.768375 -385.913259) (xy 96.776311 -385.973106) (xy 96.776794 -386.003292) (xy 96.776669 -386.017427)
			(xy 96.774887 -386.045641) (xy 96.773238 -386.05968) (xy 96.77248 -386.068287) (xy 96.776118 -386.085167)
			(xy 96.78035 -386.0927) (xy 96.796098 -386.1181) (xy 96.800805 -386.125162) (xy 96.813913 -386.13593)
			(xy 96.821752 -386.139182) (xy 96.845138 -386.148353) (xy 96.889033 -386.172777) (xy 96.928728 -386.203561)
			(xy 96.963307 -386.239996) (xy 96.991976 -386.281244) (xy 97.014073 -386.326355) (xy 97.02909 -386.37429)
			(xy 97.036681 -386.423946) (xy 97.037144 -386.449062) (xy 97.036728 -386.473265) (xy 97.029653 -386.52115)
			(xy 97.015664 -386.56749) (xy 96.995061 -386.611291) (xy 96.982026 -386.631688) (xy 96.977235 -386.639643)
			(xy 96.973204 -386.657756) (xy 96.974152 -386.666994) (xy 96.97847 -386.697982) (xy 96.980161 -386.707276)
			(xy 96.989436 -386.723718) (xy 96.996504 -386.729986) (xy 97.01858 -386.748683) (xy 97.058354 -386.79069)
			(xy 97.092519 -386.837375) (xy 97.120529 -386.887992) (xy 97.141938 -386.941736) (xy 97.156405 -386.997748)
			(xy 97.163699 -387.055137) (xy 97.164144 -387.084062) (xy 97.163554 -387.117383) (xy 97.153891 -387.183322)
			(xy 97.134766 -387.247161) (xy 97.121218 -387.27761) (xy 97.116957 -387.288071) (xy 97.11707 -387.310635)
			(xy 97.126812 -387.330988) (xy 97.135188 -387.33857) (xy 97.157416 -387.357266) (xy 97.197481 -387.399317)
			(xy 97.231903 -387.446099) (xy 97.260131 -387.496861) (xy 97.281709 -387.550785) (xy 97.296292 -387.607007)
			(xy 97.303645 -387.664621) (xy 97.304098 -387.693662) (xy 97.30364 -387.722668) (xy 97.296329 -387.780216)
			(xy 97.281805 -387.83638) (xy 97.260302 -387.890259) (xy 97.232164 -387.940989) (xy 97.197842 -387.987758)
			(xy 97.157887 -388.029816) (xy 97.135696 -388.0485) (xy 97.128584 -388.054088) (xy 97.11944 -388.069328)
			(xy 97.1042 -388.152132) (xy 97.106994 -388.169404) (xy 97.111566 -388.177532) (xy 97.124143 -388.200718)
			(xy 97.142016 -388.25034) (xy 97.151116 -388.302291) (xy 97.151698 -388.328662) (xy 97.151594 -388.339943)
			(xy 97.149943 -388.362445) (xy 97.148396 -388.37362) (xy 97.147126 -388.382764) (xy 97.150428 -388.400036)
			(xy 97.194116 -388.471156) (xy 97.207832 -388.482078) (xy 97.216468 -388.484872) (xy 97.244632 -388.495072)
			(xy 97.296578 -388.524881) (xy 97.319592 -388.544054) (xy 97.341076 -388.563636) (xy 97.376889 -388.609414)
			(xy 97.390712 -388.634986) (xy 97.391474 -388.636256) (xy 97.78365 -389.314944) (xy 97.796457 -389.338285)
			(xy 97.814684 -389.388304) (xy 97.823951 -389.440726) (xy 97.824544 -389.467344) (xy 97.824102 -389.491349)
			(xy 97.816582 -389.538767) (xy 97.801734 -389.584424) (xy 97.779924 -389.627195) (xy 97.75169 -389.666026)
			(xy 97.717726 -389.69996) (xy 97.678871 -389.728161) (xy 97.636082 -389.749934) (xy 97.590412 -389.764743)
			(xy 97.542988 -389.772222) (xy 97.518982 -389.772652) (xy 97.495451 -389.772183) (xy 97.448944 -389.76498)
			(xy 97.404096 -389.750716) (xy 97.361973 -389.729731) (xy 97.323574 -389.702523) (xy 97.289811 -389.669738)
			(xy 97.261487 -389.632155) (xy 97.249996 -389.611616) (xy 97.249742 -389.611108) (xy 97.249234 -389.610346)
			(xy 96.851724 -388.921752) (xy 96.841152 -388.901825) (xy 96.825349 -388.859575) (xy 96.815941 -388.815459)
			(xy 96.814132 -388.792974) (xy 96.813624 -388.781798) (xy 96.813624 -388.774432) (xy 96.813715 -388.763087)
			(xy 96.81537 -388.740458) (xy 96.816926 -388.72922) (xy 96.818196 -388.72033) (xy 96.81464 -388.703058)
			(xy 96.771206 -388.631938) (xy 96.75749 -388.620762) (xy 96.748854 -388.617968) (xy 96.726448 -388.609981)
			(xy 96.684278 -388.587976) (xy 96.64603 -388.559697) (xy 96.612631 -388.525829) (xy 96.584888 -388.487191)
			(xy 96.563473 -388.444717) (xy 96.548904 -388.399437) (xy 96.541533 -388.352445) (xy 96.541082 -388.328662)
			(xy 96.54165 -388.302289) (xy 96.550732 -388.250331) (xy 96.56862 -388.20071) (xy 96.581214 -388.177532)
			(xy 96.585786 -388.169404) (xy 96.58858 -388.152132) (xy 96.57334 -388.069328) (xy 96.564196 -388.054088)
			(xy 96.557084 -388.0485) (xy 96.53491 -388.029798) (xy 96.494964 -387.987735) (xy 96.460647 -387.940967)
			(xy 96.432509 -387.89024) (xy 96.411 -387.836367) (xy 96.396463 -387.780209) (xy 96.389133 -387.722666)
			(xy 96.388682 -387.693662) (xy 96.389278 -387.660341) (xy 96.398938 -387.594402) (xy 96.418061 -387.530563)
			(xy 96.431608 -387.500114) (xy 96.435838 -387.489643) (xy 96.435732 -387.467088) (xy 96.426005 -387.446739)
			(xy 96.417638 -387.439154) (xy 96.395379 -387.420494) (xy 96.355315 -387.378437) (xy 96.320894 -387.331649)
			(xy 96.29267 -387.280881) (xy 96.271097 -387.226951) (xy 96.256521 -387.170724) (xy 96.249176 -387.113105)
			(xy 96.248728 -387.084062) (xy 96.249188 -387.055136) (xy 96.256471 -386.997744) (xy 96.27093 -386.941728)
			(xy 96.292332 -386.887981) (xy 96.320338 -386.837359) (xy 96.3545 -386.790671) (xy 96.394273 -386.74866)
			(xy 96.416368 -386.729986) (xy 96.423341 -386.72364) (xy 96.432598 -386.707235) (xy 96.434402 -386.697982)
			(xy 96.43872 -386.666994) (xy 96.439628 -386.657757) (xy 96.435602 -386.639657) (xy 96.430846 -386.631688)
			(xy 96.414542 -386.60584) (xy 96.390636 -386.549606) (xy 96.383348 -386.519928) (xy 96.381276 -386.51177)
			(xy 96.372583 -386.497368) (xy 96.36633 -386.491734) (xy 96.343216 -386.472684) (xy 96.336327 -386.467452)
			(xy 96.320103 -386.461478) (xy 96.311466 -386.461) (xy 96.28183 -386.459987) (xy 96.223165 -386.451338)
			(xy 96.166108 -386.435188) (xy 96.111614 -386.411806) (xy 96.060594 -386.381583) (xy 96.013905 -386.345027)
			(xy 95.972325 -386.302748) (xy 95.936553 -386.255454) (xy 95.907186 -386.203938) (xy 95.884717 -386.149061)
			(xy 95.869521 -386.091742) (xy 95.861853 -386.032941) (xy 95.861378 -386.003292) (xy 95.861898 -385.972229)
			(xy 95.870315 -385.910675) (xy 95.878142 -385.88061) (xy 95.880936 -385.87045) (xy 95.878396 -385.850638)
			(xy 95.830898 -385.768342) (xy 95.814896 -385.75615) (xy 95.804736 -385.75361) (xy 95.775617 -385.745644)
			(xy 95.719649 -385.723006) (xy 95.667143 -385.693208) (xy 95.619009 -385.656767) (xy 95.576083 -385.614314)
			(xy 95.53911 -385.566588) (xy 95.508731 -385.514415) (xy 95.485474 -385.458702) (xy 95.469743 -385.400415)
			(xy 95.461809 -385.340566) (xy 95.461328 -385.31038) (xy 95.46185 -385.279492) (xy 95.470155 -385.218276)
			(xy 95.486613 -385.158732) (xy 95.510925 -385.10194) (xy 95.526352 -385.075176) (xy 95.532194 -385.06527)
			(xy 95.53448 -385.042918) (xy 95.501206 -384.947668) (xy 95.485458 -384.931666) (xy 95.47479 -384.927602)
			(xy 95.451407 -384.918421) (xy 95.40751 -384.894002) (xy 95.367814 -384.863221) (xy 95.333233 -384.826787)
			(xy 95.304564 -384.785539) (xy 95.282466 -384.740429) (xy 95.26745 -384.692494) (xy 95.25986 -384.642838)
			(xy 95.259398 -384.617722) (xy 94.720918 -384.617722) (xy 94.720385 -384.644824) (xy 94.711577 -384.698306)
			(xy 94.703392 -384.724148) (xy 94.699582 -384.73507) (xy 94.702122 -384.757422) (xy 94.7547 -384.843274)
			(xy 94.77375 -384.85572) (xy 94.784926 -384.857498) (xy 94.814243 -384.862209) (xy 94.871414 -384.878257)
			(xy 94.926028 -384.901566) (xy 94.977168 -384.931745) (xy 95.023973 -384.968286) (xy 95.065659 -385.010574)
			(xy 95.101523 -385.057901) (xy 95.130963 -385.109469) (xy 95.153485 -385.164412) (xy 95.168709 -385.221807)
			(xy 95.176381 -385.28069) (xy 95.176848 -385.31038) (xy 95.176325 -385.341506) (xy 95.167919 -385.403188)
			(xy 95.160084 -385.433316) (xy 95.15729 -385.443476) (xy 95.15983 -385.463542) (xy 95.207074 -385.54533)
			(xy 95.223076 -385.557522) (xy 95.233236 -385.560062) (xy 95.262342 -385.568073) (xy 95.318309 -385.590705)
			(xy 95.370815 -385.620498) (xy 95.418948 -385.656934) (xy 95.461875 -385.699381) (xy 95.498849 -385.747103)
			(xy 95.52923 -385.79927) (xy 95.552489 -385.854979) (xy 95.568224 -385.913262) (xy 95.57616 -385.973107)
			(xy 95.576644 -386.003292) (xy 95.576519 -386.017427) (xy 95.574737 -386.045641) (xy 95.573088 -386.05968)
			(xy 95.572323 -386.068287) (xy 95.575965 -386.085168) (xy 95.5802 -386.0927) (xy 95.595948 -386.1181)
			(xy 95.600639 -386.125174) (xy 95.613758 -386.135936) (xy 95.621602 -386.139182) (xy 95.644977 -386.14838)
			(xy 95.688874 -386.172797) (xy 95.72857 -386.203576) (xy 95.763152 -386.240007) (xy 95.791822 -386.281252)
			(xy 95.813921 -386.32636) (xy 95.828939 -386.374293) (xy 95.836531 -386.423947) (xy 95.836994 -386.449062)
			(xy 95.83657 -386.473264) (xy 95.829496 -386.521149) (xy 95.815509 -386.567488) (xy 95.794909 -386.61129)
			(xy 95.781876 -386.631688) (xy 95.777089 -386.639645) (xy 95.773054 -386.657756) (xy 95.774002 -386.666994)
			(xy 95.77832 -386.697982) (xy 95.779996 -386.70728) (xy 95.789281 -386.723721) (xy 95.796354 -386.729986)
			(xy 95.81844 -386.74867) (xy 95.858212 -386.790681) (xy 95.892375 -386.837369) (xy 95.920383 -386.887988)
			(xy 95.94179 -386.941733) (xy 95.956256 -386.997747) (xy 95.963549 -387.055136) (xy 95.963994 -387.084062)
			(xy 95.963399 -387.117383) (xy 95.953738 -387.183321) (xy 95.934614 -387.247161) (xy 95.921068 -387.27761)
			(xy 95.916823 -387.288076) (xy 95.916937 -387.310634) (xy 95.926669 -387.330985) (xy 95.935038 -387.33857)
			(xy 95.957276 -387.357254) (xy 95.997338 -387.399308) (xy 96.031759 -387.446093) (xy 96.059984 -387.496857)
			(xy 96.081561 -387.550783) (xy 96.096143 -387.607005) (xy 96.103495 -387.664621) (xy 96.103948 -387.693662)
			(xy 96.103473 -387.722667) (xy 96.096162 -387.780214) (xy 96.08164 -387.836377) (xy 96.060139 -387.890255)
			(xy 96.032004 -387.940986) (xy 95.997687 -387.987756) (xy 95.957735 -388.029815) (xy 95.935546 -388.0485)
			(xy 95.928434 -388.054088) (xy 95.91929 -388.069328) (xy 95.90405 -388.152132) (xy 95.906844 -388.169404)
			(xy 95.911416 -388.177532) (xy 95.923989 -388.20072) (xy 95.941864 -388.25034) (xy 95.950966 -388.302291)
			(xy 95.951548 -388.328662) (xy 95.951445 -388.339943) (xy 95.949793 -388.362445) (xy 95.948246 -388.37362)
			(xy 95.946976 -388.38251) (xy 95.950532 -388.400036) (xy 95.993966 -388.470902) (xy 96.007682 -388.482078)
			(xy 96.016318 -388.484872) (xy 96.038574 -388.492778) (xy 96.080494 -388.514537) (xy 96.118565 -388.542489)
			(xy 96.151881 -388.575967) (xy 96.179647 -388.614174) (xy 96.190816 -388.634986) (xy 96.191324 -388.636002)
			(xy 96.583754 -389.314944) (xy 96.596562 -389.338285) (xy 96.614788 -389.388304) (xy 96.624055 -389.440726)
			(xy 96.624648 -389.467344) (xy 96.624202 -389.491349) (xy 96.616682 -389.538767) (xy 96.601834 -389.584423)
			(xy 96.580025 -389.627194) (xy 96.551791 -389.666025) (xy 96.517828 -389.699959) (xy 96.478973 -389.72816)
			(xy 96.436184 -389.749933) (xy 96.390515 -389.764742) (xy 96.343091 -389.772222) (xy 96.319086 -389.772652)
			(xy 96.295555 -389.77218) (xy 96.249049 -389.764977) (xy 96.204201 -389.750714) (xy 96.162077 -389.72973)
			(xy 96.123678 -389.702522) (xy 96.089916 -389.669737) (xy 96.061591 -389.632154) (xy 96.0501 -389.611616)
			(xy 96.049846 -389.611108) (xy 96.049338 -389.610346) (xy 95.651574 -388.922006) (xy 95.639699 -388.899329)
			(xy 95.622848 -388.850996) (xy 95.614274 -388.800533) (xy 95.613728 -388.77494) (xy 95.613728 -388.774432)
			(xy 95.613819 -388.763087) (xy 95.615474 -388.740458) (xy 95.61703 -388.72922) (xy 95.6183 -388.72033)
			(xy 95.614744 -388.703058) (xy 95.57131 -388.631938) (xy 95.55734 -388.621016) (xy 95.548958 -388.617968)
			(xy 95.526559 -388.609926) (xy 95.48434 -388.587969) (xy 95.446043 -388.559723) (xy 95.412596 -388.525873)
			(xy 95.384811 -388.48724) (xy 95.363362 -388.444761) (xy 95.348769 -388.399466) (xy 95.341385 -388.352456)
			(xy 95.340932 -388.328662) (xy 95.341494 -388.302289) (xy 95.350578 -388.25033) (xy 95.368468 -388.20071)
			(xy 95.381064 -388.177532) (xy 95.385636 -388.169404) (xy 95.38843 -388.152132) (xy 95.37319 -388.069328)
			(xy 95.364046 -388.054088) (xy 95.356934 -388.0485) (xy 95.33477 -388.029786) (xy 95.294822 -387.987727)
			(xy 95.260503 -387.940961) (xy 95.232362 -387.890236) (xy 95.210851 -387.836364) (xy 95.196314 -387.780208)
			(xy 95.188983 -387.722666) (xy 95.188532 -387.693662) (xy 95.189133 -387.660341) (xy 95.198791 -387.594403)
			(xy 95.217913 -387.530563) (xy 95.231458 -387.500114) (xy 95.235704 -387.489647) (xy 95.2356 -387.467087)
			(xy 95.225862 -387.446735) (xy 95.217488 -387.439154) (xy 95.195218 -387.420506) (xy 95.155157 -387.378446)
			(xy 95.120739 -387.331655) (xy 95.092517 -387.280885) (xy 95.070945 -387.226953) (xy 95.05637 -387.170725)
			(xy 95.049026 -387.113105) (xy 95.048578 -387.084062) (xy 95.04902 -387.055135) (xy 95.056304 -386.997742)
			(xy 95.070764 -386.941725) (xy 95.092169 -386.887977) (xy 95.120178 -386.837355) (xy 95.154343 -386.790668)
			(xy 95.194121 -386.748659) (xy 95.216218 -386.729986) (xy 95.223183 -386.723632) (xy 95.232446 -386.707233)
			(xy 95.234252 -386.697982) (xy 95.23857 -386.666994) (xy 95.239471 -386.657757) (xy 95.235448 -386.639658)
			(xy 95.230696 -386.631688) (xy 95.214387 -386.605843) (xy 95.190484 -386.549607) (xy 95.183198 -386.519928)
			(xy 95.181139 -386.511766) (xy 95.172438 -386.497365) (xy 95.16618 -386.491734) (xy 95.143066 -386.472684)
			(xy 95.13619 -386.467432) (xy 95.119956 -386.46147) (xy 95.111316 -386.461) (xy 95.081681 -386.459941)
			(xy 95.023018 -386.451299) (xy 94.965962 -386.435154) (xy 94.911468 -386.411777) (xy 94.860449 -386.38156)
			(xy 94.813758 -386.345007) (xy 94.772178 -386.302732) (xy 94.736405 -386.255442) (xy 94.707038 -386.203929)
			(xy 94.684568 -386.149055) (xy 94.669371 -386.091739) (xy 94.661703 -386.03294) (xy 94.661228 -386.003292)
			(xy 94.661749 -385.972229) (xy 94.670165 -385.910675) (xy 94.677992 -385.88061) (xy 94.680786 -385.87045)
			(xy 94.678246 -385.850638) (xy 94.630748 -385.768342) (xy 94.614746 -385.75615) (xy 94.604586 -385.75361)
			(xy 94.575508 -385.745543) (xy 94.51958 -385.722883) (xy 94.467114 -385.693073) (xy 94.419018 -385.656629)
			(xy 94.376126 -385.614182) (xy 94.339182 -385.56647) (xy 94.308825 -385.514318) (xy 94.285582 -385.45863)
			(xy 94.269856 -385.400371) (xy 94.261919 -385.340552) (xy 94.261432 -385.31038) (xy 94.261953 -385.279492)
			(xy 94.270259 -385.218276) (xy 94.286717 -385.158732) (xy 94.311029 -385.10194) (xy 94.326456 -385.075176)
			(xy 94.332298 -385.06527) (xy 94.334584 -385.042918) (xy 94.30131 -384.947668) (xy 94.285562 -384.931666)
			(xy 94.274894 -384.927602) (xy 94.251512 -384.918419) (xy 94.207615 -384.894) (xy 94.167919 -384.863219)
			(xy 94.133337 -384.826786) (xy 94.104668 -384.785539) (xy 94.08257 -384.740428) (xy 94.067554 -384.692493)
			(xy 94.059964 -384.642838) (xy 94.059502 -384.617722) (xy 93.520768 -384.617722) (xy 93.520237 -384.644824)
			(xy 93.511428 -384.698307) (xy 93.503242 -384.724148) (xy 93.499432 -384.73507) (xy 93.501972 -384.757422)
			(xy 93.55455 -384.843274) (xy 93.5736 -384.85572) (xy 93.584776 -384.857498) (xy 93.6141 -384.86217)
			(xy 93.671271 -384.878224) (xy 93.725885 -384.901539) (xy 93.777024 -384.931722) (xy 93.823828 -384.968268)
			(xy 93.865513 -385.01056) (xy 93.901376 -385.05789) (xy 93.930815 -385.109461) (xy 93.953336 -385.164407)
			(xy 93.96856 -385.221804) (xy 93.976231 -385.280689) (xy 93.976698 -385.31038) (xy 93.976173 -385.341443)
			(xy 93.96776 -385.402997) (xy 93.959934 -385.433062) (xy 93.95714 -385.443222) (xy 93.95968 -385.463034)
			(xy 94.007178 -385.54533) (xy 94.02318 -385.557522) (xy 94.03334 -385.560062) (xy 94.062447 -385.56807)
			(xy 94.118413 -385.590703) (xy 94.170919 -385.620496) (xy 94.219053 -385.656932) (xy 94.261979 -385.69938)
			(xy 94.298954 -385.747102) (xy 94.329334 -385.79927) (xy 94.352593 -385.854979) (xy 94.368328 -385.913262)
			(xy 94.376264 -385.973107) (xy 94.376748 -386.003292) (xy 94.376623 -386.017427) (xy 94.374841 -386.045641)
			(xy 94.373192 -386.05968) (xy 94.372426 -386.068287) (xy 94.376068 -386.085168) (xy 94.380304 -386.0927)
			(xy 94.396052 -386.1181) (xy 94.400774 -386.125151) (xy 94.413871 -386.135925) (xy 94.421706 -386.139182)
			(xy 94.445082 -386.148378) (xy 94.488979 -386.172796) (xy 94.528675 -386.203575) (xy 94.563256 -386.240006)
			(xy 94.591926 -386.281251) (xy 94.614025 -386.32636) (xy 94.629043 -386.374293) (xy 94.636635 -386.423947)
			(xy 94.637098 -386.449062) (xy 94.636673 -386.473264) (xy 94.6296 -386.521149) (xy 94.615613 -386.567488)
			(xy 94.595013 -386.61129) (xy 94.58198 -386.631688) (xy 94.577193 -386.639645) (xy 94.573158 -386.657756)
			(xy 94.574106 -386.666994) (xy 94.578424 -386.697982) (xy 94.580099 -386.70728) (xy 94.589384 -386.723721)
			(xy 94.596458 -386.729986) (xy 94.618545 -386.748669) (xy 94.658317 -386.790681) (xy 94.692479 -386.837368)
			(xy 94.720487 -386.887988) (xy 94.741894 -386.941733) (xy 94.75636 -386.997747) (xy 94.763653 -387.055136)
			(xy 94.764098 -387.084062) (xy 94.763512 -387.117384) (xy 94.753849 -387.183322) (xy 94.734721 -387.247161)
			(xy 94.721172 -387.27761) (xy 94.716926 -387.288075) (xy 94.71704 -387.310634) (xy 94.726773 -387.330985)
			(xy 94.735142 -387.33857) (xy 94.75736 -387.357277) (xy 94.797427 -387.399325) (xy 94.831852 -387.446105)
			(xy 94.860082 -387.496864) (xy 94.881662 -387.550787) (xy 94.896246 -387.607008) (xy 94.903599 -387.664621)
			(xy 94.904052 -387.693662) (xy 94.903575 -387.722667) (xy 94.896264 -387.780214) (xy 94.881742 -387.836377)
			(xy 94.860242 -387.890255) (xy 94.832108 -387.940985) (xy 94.79779 -387.987755) (xy 94.757839 -388.029815)
			(xy 94.73565 -388.0485) (xy 94.728538 -388.054088) (xy 94.719394 -388.069328) (xy 94.704154 -388.152132)
			(xy 94.706948 -388.169404) (xy 94.71152 -388.177532) (xy 94.724093 -388.200719) (xy 94.741969 -388.25034)
			(xy 94.75107 -388.302291) (xy 94.751652 -388.328662) (xy 94.751549 -388.339943) (xy 94.749897 -388.362445)
			(xy 94.74835 -388.37362) (xy 94.74708 -388.382764) (xy 94.750382 -388.400036) (xy 94.79407 -388.471156)
			(xy 94.807786 -388.482078) (xy 94.816422 -388.484872) (xy 94.844591 -388.49506) (xy 94.896534 -388.524878)
			(xy 94.919546 -388.544054) (xy 94.941036 -388.563629) (xy 94.976845 -388.609412) (xy 94.990666 -388.634986)
			(xy 94.991428 -388.636256) (xy 95.383604 -389.314944) (xy 95.396337 -389.33831) (xy 95.414452 -389.388337)
			(xy 95.423662 -389.440741) (xy 95.424244 -389.467344) (xy 95.423778 -389.491335) (xy 95.416267 -389.538724)
			(xy 95.401435 -389.584356) (xy 95.379649 -389.627106) (xy 95.351445 -389.665923) (xy 95.317517 -389.69985)
			(xy 95.278699 -389.728054) (xy 95.235949 -389.749838) (xy 95.190317 -389.764668) (xy 95.142927 -389.772179)
			(xy 95.118936 -389.772652) (xy 95.095404 -389.77222) (xy 95.048895 -389.76501) (xy 95.004047 -389.75074)
			(xy 94.961923 -389.729749) (xy 94.923525 -389.702535) (xy 94.889763 -389.669745) (xy 94.86144 -389.632157)
			(xy 94.84995 -389.611616) (xy 94.849696 -389.611108) (xy 94.849188 -389.610346) (xy 94.451678 -388.921752)
			(xy 94.441103 -388.901827) (xy 94.425301 -388.859576) (xy 94.415895 -388.815459) (xy 94.414086 -388.792974)
			(xy 94.413578 -388.781798) (xy 94.413324 -388.774432) (xy 94.413481 -388.763083) (xy 94.415258 -388.740453)
			(xy 94.41688 -388.72922) (xy 94.41815 -388.72033) (xy 94.414594 -388.703058) (xy 94.37116 -388.631938)
			(xy 94.357444 -388.620762) (xy 94.348808 -388.617968) (xy 94.326414 -388.60995) (xy 94.284242 -388.587952)
			(xy 94.245992 -388.559679) (xy 94.212591 -388.525816) (xy 94.184846 -388.487182) (xy 94.163429 -388.444712)
			(xy 94.148859 -388.399434) (xy 94.141487 -388.352444) (xy 94.141036 -388.328662) (xy 94.141597 -388.302289)
			(xy 94.150681 -388.25033) (xy 94.168572 -388.20071) (xy 94.181168 -388.177532) (xy 94.18574 -388.169404)
			(xy 94.188534 -388.152132) (xy 94.173294 -388.069328) (xy 94.16415 -388.054088) (xy 94.157038 -388.0485)
			(xy 94.134875 -388.029785) (xy 94.094926 -387.987726) (xy 94.060607 -387.94096) (xy 94.032467 -387.890236)
			(xy 94.010956 -387.836364) (xy 93.996418 -387.780208) (xy 93.989087 -387.722666) (xy 93.988636 -387.693662)
			(xy 93.989236 -387.660341) (xy 93.998895 -387.594403) (xy 94.018017 -387.530563) (xy 94.031562 -387.500114)
			(xy 94.035807 -387.489647) (xy 94.035702 -387.467087) (xy 94.025966 -387.446735) (xy 94.017592 -387.439154)
			(xy 93.995323 -387.420505) (xy 93.955262 -387.378445) (xy 93.920843 -387.331654) (xy 93.892621 -387.280885)
			(xy 93.871049 -387.226953) (xy 93.856474 -387.170725) (xy 93.84913 -387.113105) (xy 93.848682 -387.084062)
			(xy 93.849122 -387.055135) (xy 93.856407 -386.997742) (xy 93.870867 -386.941725) (xy 93.892272 -386.887977)
			(xy 93.920281 -386.837355) (xy 93.954447 -386.790668) (xy 93.994225 -386.748659) (xy 94.016322 -386.729986)
			(xy 94.023288 -386.723632) (xy 94.03255 -386.707234) (xy 94.034356 -386.697982) (xy 94.038674 -386.666994)
			(xy 94.039574 -386.657757) (xy 94.035552 -386.639658) (xy 94.0308 -386.631688) (xy 94.014492 -386.605843)
			(xy 93.990588 -386.549607) (xy 93.983302 -386.519928) (xy 93.981242 -386.511766) (xy 93.972542 -386.497365)
			(xy 93.966284 -386.491734) (xy 93.94317 -386.472684) (xy 93.936293 -386.467434) (xy 93.92006 -386.461471)
			(xy 93.91142 -386.461) (xy 93.881782 -386.460029) (xy 93.823116 -386.451375) (xy 93.766058 -386.435219)
			(xy 93.711564 -386.411832) (xy 93.660545 -386.381605) (xy 93.613855 -386.345044) (xy 93.572277 -386.302762)
			(xy 93.536505 -386.255465) (xy 93.507139 -386.203946) (xy 93.48467 -386.149066) (xy 93.469475 -386.091745)
			(xy 93.461807 -386.032942) (xy 93.461332 -386.003292) (xy 93.461853 -385.972229) (xy 93.470269 -385.910675)
			(xy 93.478096 -385.88061) (xy 93.48089 -385.87045) (xy 93.47835 -385.850638) (xy 93.430852 -385.768342)
			(xy 93.41485 -385.75615) (xy 93.40469 -385.75361) (xy 93.375581 -385.745608) (xy 93.319613 -385.722977)
			(xy 93.267105 -385.693184) (xy 93.21897 -385.656748) (xy 93.176043 -385.6143) (xy 93.139068 -385.566577)
			(xy 93.108688 -385.514407) (xy 93.08543 -385.458697) (xy 93.069698 -385.400412) (xy 93.061764 -385.340565)
			(xy 93.061282 -385.31038) (xy 93.06181 -385.279492) (xy 93.070115 -385.218277) (xy 93.086571 -385.158733)
			(xy 93.11088 -385.101941) (xy 93.126306 -385.075176) (xy 93.132148 -385.06527) (xy 93.134434 -385.042918)
			(xy 93.10116 -384.947668) (xy 93.085412 -384.931666) (xy 93.074744 -384.927602) (xy 93.051351 -384.918446)
			(xy 93.007456 -384.894021) (xy 92.967761 -384.863235) (xy 92.933182 -384.826797) (xy 92.904514 -384.785547)
			(xy 92.882418 -384.740433) (xy 92.867403 -384.692496) (xy 92.859814 -384.642839) (xy 92.859352 -384.617722)
			(xy 92.320872 -384.617722) (xy 92.320341 -384.644824) (xy 92.311532 -384.698307) (xy 92.303346 -384.724148)
			(xy 92.299536 -384.73507) (xy 92.302076 -384.757422) (xy 92.354654 -384.843274) (xy 92.373704 -384.85572)
			(xy 92.38488 -384.857498) (xy 92.414205 -384.862167) (xy 92.471376 -384.878222) (xy 92.525989 -384.901537)
			(xy 92.577128 -384.931721) (xy 92.623933 -384.968266) (xy 92.665617 -385.010559) (xy 92.70148 -385.057889)
			(xy 92.730919 -385.10946) (xy 92.75344 -385.164406) (xy 92.768664 -385.221804) (xy 92.776335 -385.280689)
			(xy 92.776802 -385.31038) (xy 92.776277 -385.341443) (xy 92.767864 -385.402997) (xy 92.760038 -385.433062)
			(xy 92.757244 -385.443222) (xy 92.759784 -385.463034) (xy 92.807282 -385.54533) (xy 92.823284 -385.557522)
			(xy 92.833444 -385.560062) (xy 92.862552 -385.568067) (xy 92.918518 -385.5907) (xy 92.971024 -385.620494)
			(xy 93.019158 -385.656931) (xy 93.062084 -385.699379) (xy 93.099058 -385.747101) (xy 93.129439 -385.799269)
			(xy 93.152698 -385.854978) (xy 93.168432 -385.913261) (xy 93.176369 -385.973107) (xy 93.176852 -386.003292)
			(xy 93.176727 -386.017427) (xy 93.174945 -386.045641) (xy 93.173296 -386.05968) (xy 93.172529 -386.068287)
			(xy 93.176172 -386.085168) (xy 93.180408 -386.0927) (xy 93.196156 -386.1181) (xy 93.200864 -386.125164)
			(xy 93.213964 -386.135942) (xy 93.22181 -386.139182) (xy 93.245154 -386.148421) (xy 93.288998 -386.172873)
			(xy 93.328643 -386.203671) (xy 93.363178 -386.240106) (xy 93.39181 -386.281341) (xy 93.413882 -386.32643)
			(xy 93.428887 -386.374337) (xy 93.436479 -386.423961) (xy 93.436948 -386.449062) (xy 93.436531 -386.473264)
			(xy 93.429457 -386.52115) (xy 93.415468 -386.56749) (xy 93.394865 -386.611291) (xy 93.38183 -386.631688)
			(xy 93.377039 -386.639643) (xy 93.373008 -386.657756) (xy 93.373956 -386.666994) (xy 93.378274 -386.697982)
			(xy 93.379964 -386.707276) (xy 93.38924 -386.723718) (xy 93.396308 -386.729986) (xy 93.418384 -386.748682)
			(xy 93.458159 -386.79069) (xy 93.492323 -386.837375) (xy 93.520333 -386.887992) (xy 93.541742 -386.941735)
			(xy 93.556209 -386.997748) (xy 93.563503 -387.055137) (xy 93.563948 -387.084062) (xy 93.563358 -387.117383)
			(xy 93.553695 -387.183322) (xy 93.534569 -387.247161) (xy 93.521022 -387.27761) (xy 93.51676 -387.288071)
			(xy 93.516873 -387.310635) (xy 93.526616 -387.330988) (xy 93.534992 -387.33857) (xy 93.557221 -387.357265)
			(xy 93.597285 -387.399316) (xy 93.631708 -387.446099) (xy 93.659935 -387.49686) (xy 93.681513 -387.550785)
			(xy 93.696096 -387.607006) (xy 93.703449 -387.664621) (xy 93.703902 -387.693662) (xy 93.703443 -387.722668)
			(xy 93.696131 -387.780216) (xy 93.681608 -387.83638) (xy 93.660105 -387.890259) (xy 93.631967 -387.940989)
			(xy 93.597646 -387.987758) (xy 93.557691 -388.029816) (xy 93.5355 -388.0485) (xy 93.528388 -388.054088)
			(xy 93.519244 -388.069328) (xy 93.504004 -388.152132) (xy 93.506798 -388.169404) (xy 93.51137 -388.177532)
			(xy 93.523939 -388.200722) (xy 93.541817 -388.250341) (xy 93.55092 -388.302292) (xy 93.551502 -388.328662)
			(xy 93.551398 -388.339943) (xy 93.549747 -388.362445) (xy 93.5482 -388.37362) (xy 93.54693 -388.38251)
			(xy 93.550486 -388.400036) (xy 93.59392 -388.470902) (xy 93.607636 -388.482078) (xy 93.616272 -388.484872)
			(xy 93.63852 -388.4928) (xy 93.680441 -388.514553) (xy 93.718514 -388.542499) (xy 93.751831 -388.575973)
			(xy 93.779599 -388.614176) (xy 93.79077 -388.634986) (xy 93.791278 -388.636002) (xy 94.183708 -389.314944)
			(xy 94.196441 -389.33831) (xy 94.214556 -389.388337) (xy 94.223766 -389.440741) (xy 94.224348 -389.467344)
			(xy 94.223878 -389.491334) (xy 94.216367 -389.538724) (xy 94.201536 -389.584355) (xy 94.17975 -389.627105)
			(xy 94.151546 -389.665922) (xy 94.117618 -389.699849) (xy 94.078802 -389.728052) (xy 94.036051 -389.749837)
			(xy 93.99042 -389.764668) (xy 93.94303 -389.772178) (xy 93.91904 -389.772652) (xy 93.895508 -389.772217)
			(xy 93.848999 -389.765007) (xy 93.804151 -389.750738) (xy 93.762027 -389.729747) (xy 93.723629 -389.702534)
			(xy 93.689867 -389.669744) (xy 93.661545 -389.632156) (xy 93.650054 -389.611616) (xy 93.6498 -389.611108)
			(xy 93.649292 -389.610346) (xy 93.251528 -388.922006) (xy 93.239615 -388.899337) (xy 93.222676 -388.851012)
			(xy 93.214016 -388.800542) (xy 93.213428 -388.77494) (xy 93.213428 -388.774432) (xy 93.213585 -388.763083)
			(xy 93.215362 -388.740453) (xy 93.216984 -388.72922) (xy 93.218254 -388.72033) (xy 93.214698 -388.703058)
			(xy 93.171264 -388.631938) (xy 93.157294 -388.621016) (xy 93.148912 -388.617968) (xy 93.126503 -388.609953)
			(xy 93.084286 -388.58799) (xy 93.04599 -388.559738) (xy 93.012545 -388.525884) (xy 92.984762 -388.487247)
			(xy 92.963314 -388.444766) (xy 92.948722 -388.399469) (xy 92.941339 -388.352456) (xy 92.940886 -388.328662)
			(xy 92.941454 -388.302289) (xy 92.950536 -388.250331) (xy 92.968424 -388.20071) (xy 92.981018 -388.177532)
			(xy 92.98559 -388.169404) (xy 92.988384 -388.152132) (xy 92.973144 -388.069328) (xy 92.964 -388.054088)
			(xy 92.956888 -388.0485) (xy 92.934715 -388.029797) (xy 92.894768 -387.987735) (xy 92.860451 -387.940966)
			(xy 92.832313 -387.890239) (xy 92.810804 -387.836366) (xy 92.796267 -387.780209) (xy 92.788937 -387.722666)
			(xy 92.788486 -387.693662) (xy 92.789082 -387.660341) (xy 92.798741 -387.594402) (xy 92.817865 -387.530563)
			(xy 92.831412 -387.500114) (xy 92.835641 -387.489643) (xy 92.835536 -387.467088) (xy 92.825809 -387.446739)
			(xy 92.817442 -387.439154) (xy 92.795184 -387.420493) (xy 92.755119 -387.378436) (xy 92.720699 -387.331648)
			(xy 92.692475 -387.280881) (xy 92.670901 -387.226951) (xy 92.656325 -387.170724) (xy 92.64898 -387.113105)
			(xy 92.648532 -387.084062) (xy 92.648991 -387.055136) (xy 92.656274 -386.997744) (xy 92.670732 -386.941728)
			(xy 92.692135 -386.887981) (xy 92.720141 -386.837359) (xy 92.754303 -386.790671) (xy 92.794077 -386.74866)
			(xy 92.816172 -386.729986) (xy 92.823146 -386.723641) (xy 92.832402 -386.707235) (xy 92.834206 -386.697982)
			(xy 92.838524 -386.666994) (xy 92.839432 -386.657757) (xy 92.835405 -386.639657) (xy 92.83065 -386.631688)
			(xy 92.814338 -386.605845) (xy 92.790437 -386.549608) (xy 92.783152 -386.519928) (xy 92.781079 -386.51177)
			(xy 92.772387 -386.497368) (xy 92.766134 -386.491734) (xy 92.74302 -386.472684) (xy 92.736188 -386.467481)
			(xy 92.720097 -386.461509) (xy 92.711524 -386.461) (xy 92.681886 -386.460025) (xy 92.62322 -386.451372)
			(xy 92.566162 -386.435216) (xy 92.511668 -386.41183) (xy 92.460649 -386.381603) (xy 92.41396 -386.345043)
			(xy 92.372381 -386.302761) (xy 92.336609 -386.255464) (xy 92.307243 -386.203945) (xy 92.284774 -386.149066)
			(xy 92.269579 -386.091745) (xy 92.261911 -386.032942) (xy 92.261436 -386.003292) (xy 92.261957 -385.972229)
			(xy 92.270373 -385.910675) (xy 92.2782 -385.88061) (xy 92.280994 -385.87045) (xy 92.278454 -385.850638)
			(xy 92.230956 -385.768342) (xy 92.214954 -385.75615) (xy 92.204794 -385.75361) (xy 92.175686 -385.745605)
			(xy 92.119717 -385.722974) (xy 92.06721 -385.693183) (xy 92.019075 -385.656747) (xy 91.976147 -385.614299)
			(xy 91.939173 -385.566576) (xy 91.908792 -385.514407) (xy 91.885534 -385.458696) (xy 91.869802 -385.400412)
			(xy 91.861868 -385.340565) (xy 91.861386 -385.31038) (xy 91.861914 -385.279492) (xy 91.870219 -385.218277)
			(xy 91.886675 -385.158733) (xy 91.910984 -385.101941) (xy 91.92641 -385.075176) (xy 91.932252 -385.06527)
			(xy 91.934538 -385.042918) (xy 91.901264 -384.947668) (xy 91.885516 -384.931666) (xy 91.874848 -384.927602)
			(xy 91.851456 -384.918444) (xy 91.80756 -384.894019) (xy 91.767866 -384.863233) (xy 91.733286 -384.826796)
			(xy 91.704619 -384.785546) (xy 91.682523 -384.740433) (xy 91.667507 -384.692496) (xy 91.659918 -384.642839)
			(xy 91.659456 -384.617722) (xy 91.120976 -384.617722) (xy 91.120445 -384.644824) (xy 91.111636 -384.698307)
			(xy 91.10345 -384.724148) (xy 91.09964 -384.73507) (xy 91.10218 -384.757422) (xy 91.154758 -384.843528)
			(xy 91.173554 -384.85572) (xy 91.184984 -384.857498) (xy 91.214278 -384.862274) (xy 91.271413 -384.878352)
			(xy 91.325989 -384.901682) (xy 91.377092 -384.931872) (xy 91.423862 -384.968414) (xy 91.465516 -385.010697)
			(xy 91.501354 -385.05801) (xy 91.530774 -385.109559) (xy 91.553283 -385.164479) (xy 91.568504 -385.221848)
			(xy 91.57618 -385.280703) (xy 91.576652 -385.31038) (xy 91.576125 -385.341443) (xy 91.567713 -385.402996)
			(xy 91.559888 -385.433062) (xy 91.557094 -385.443222) (xy 91.559634 -385.463034) (xy 91.607132 -385.54533)
			(xy 91.623134 -385.557522) (xy 91.633294 -385.560062) (xy 91.662411 -385.568034) (xy 91.718377 -385.590673)
			(xy 91.770882 -385.620472) (xy 91.819014 -385.656913) (xy 91.861939 -385.699365) (xy 91.898912 -385.747091)
			(xy 91.929291 -385.799262) (xy 91.952549 -385.854974) (xy 91.968283 -385.913259) (xy 91.976219 -385.973106)
			(xy 91.976702 -386.003292) (xy 91.976577 -386.017427) (xy 91.974795 -386.045641) (xy 91.973146 -386.05968)
			(xy 91.972387 -386.068287) (xy 91.976026 -386.085167) (xy 91.980258 -386.0927) (xy 91.996006 -386.1181)
			(xy 92.000711 -386.125164) (xy 92.01382 -386.135931) (xy 92.02166 -386.139182) (xy 92.045048 -386.148349)
			(xy 92.088943 -386.172773) (xy 92.128637 -386.203558) (xy 92.163216 -386.239994) (xy 92.191884 -386.281243)
			(xy 92.213981 -386.326354) (xy 92.228998 -386.37429) (xy 92.236589 -386.423946) (xy 92.237052 -386.449062)
			(xy 92.236635 -386.473264) (xy 92.22956 -386.52115) (xy 92.215572 -386.567489) (xy 92.194969 -386.611291)
			(xy 92.181934 -386.631688) (xy 92.177144 -386.639643) (xy 92.173112 -386.657756) (xy 92.17406 -386.666994)
			(xy 92.178378 -386.697982) (xy 92.180067 -386.707276) (xy 92.189343 -386.723718) (xy 92.196412 -386.729986)
			(xy 92.218489 -386.748681) (xy 92.258263 -386.790689) (xy 92.292428 -386.837374) (xy 92.320437 -386.887992)
			(xy 92.341846 -386.941735) (xy 92.356313 -386.997748) (xy 92.363607 -387.055137) (xy 92.364052 -387.084062)
			(xy 92.363461 -387.117383) (xy 92.353799 -387.183322) (xy 92.334673 -387.247161) (xy 92.321126 -387.27761)
			(xy 92.316862 -387.288071) (xy 92.316976 -387.310635) (xy 92.32672 -387.330988) (xy 92.335096 -387.33857)
			(xy 92.357325 -387.357264) (xy 92.39739 -387.399316) (xy 92.431812 -387.446098) (xy 92.460039 -387.49686)
			(xy 92.481618 -387.550785) (xy 92.4962 -387.607006) (xy 92.503553 -387.664621) (xy 92.504006 -387.693662)
			(xy 92.503546 -387.722668) (xy 92.496234 -387.780216) (xy 92.481711 -387.83638) (xy 92.460208 -387.890259)
			(xy 92.432071 -387.940989) (xy 92.39775 -387.987758) (xy 92.357795 -388.029817) (xy 92.335604 -388.0485)
			(xy 92.328492 -388.054088) (xy 92.319348 -388.069328) (xy 92.304108 -388.152132) (xy 92.306902 -388.169404)
			(xy 92.311474 -388.177532) (xy 92.324044 -388.200721) (xy 92.341921 -388.250341) (xy 92.351024 -388.302292)
			(xy 92.351606 -388.328662) (xy 92.351502 -388.339943) (xy 92.349851 -388.362445) (xy 92.348304 -388.37362)
			(xy 92.347034 -388.38251) (xy 92.35059 -388.400036) (xy 92.394024 -388.470902) (xy 92.40774 -388.482078)
			(xy 92.416376 -388.484872) (xy 92.438625 -388.492798) (xy 92.480545 -388.514551) (xy 92.518618 -388.542498)
			(xy 92.551936 -388.575972) (xy 92.579704 -388.614176) (xy 92.590874 -388.634986) (xy 92.591382 -388.636002)
			(xy 92.983812 -389.314944) (xy 92.996545 -389.338309) (xy 93.01466 -389.388337) (xy 93.02387 -389.440741)
			(xy 93.024452 -389.467344) (xy 93.023978 -389.491334) (xy 93.016467 -389.538723) (xy 93.001636 -389.584354)
			(xy 92.979851 -389.627104) (xy 92.951648 -389.66592) (xy 92.91772 -389.699848) (xy 92.878904 -389.728051)
			(xy 92.836154 -389.749836) (xy 92.790523 -389.764667) (xy 92.743134 -389.772178) (xy 92.719144 -389.772652)
			(xy 92.695612 -389.772214) (xy 92.649104 -389.765005) (xy 92.604255 -389.750736) (xy 92.562132 -389.729746)
			(xy 92.523733 -389.702533) (xy 92.489972 -389.669743) (xy 92.461649 -389.632156) (xy 92.450158 -389.611616)
			(xy 92.449904 -389.611108) (xy 92.449396 -389.610346) (xy 92.051632 -388.922006) (xy 92.039719 -388.899336)
			(xy 92.02278 -388.851012) (xy 92.01412 -388.800542) (xy 92.013532 -388.77494) (xy 92.013532 -388.774432)
			(xy 92.013689 -388.763083) (xy 92.015466 -388.740453) (xy 92.017088 -388.72922) (xy 92.018358 -388.72033)
			(xy 92.014802 -388.703058) (xy 91.971368 -388.631938) (xy 91.957398 -388.621016) (xy 91.949016 -388.617968)
			(xy 91.926608 -388.60995) (xy 91.884391 -388.587988) (xy 91.846095 -388.559737) (xy 91.81265 -388.525883)
			(xy 91.784866 -388.487246) (xy 91.763418 -388.444765) (xy 91.748826 -388.399469) (xy 91.741443 -388.352456)
			(xy 91.74099 -388.328662) (xy 91.741557 -388.302289) (xy 91.75064 -388.250331) (xy 91.768528 -388.20071)
			(xy 91.781122 -388.177532) (xy 91.785694 -388.169404) (xy 91.788488 -388.152132) (xy 91.773248 -388.069328)
			(xy 91.764104 -388.054088) (xy 91.756992 -388.0485) (xy 91.73482 -388.029796) (xy 91.694873 -387.987734)
			(xy 91.660556 -387.940966) (xy 91.632417 -387.890239) (xy 91.610908 -387.836366) (xy 91.596371 -387.780209)
			(xy 91.589041 -387.722666) (xy 91.58859 -387.693662) (xy 91.589185 -387.660341) (xy 91.598845 -387.594402)
			(xy 91.617969 -387.530563) (xy 91.631516 -387.500114) (xy 91.635743 -387.489642) (xy 91.635638 -387.467088)
			(xy 91.625912 -387.446739) (xy 91.617546 -387.439154) (xy 91.595289 -387.420492) (xy 91.555224 -387.378436)
			(xy 91.520803 -387.331648) (xy 91.492579 -387.280881) (xy 91.471005 -387.22695) (xy 91.456429 -387.170724)
			(xy 91.449084 -387.113105) (xy 91.448636 -387.084062) (xy 91.449093 -387.055136) (xy 91.456377 -386.997744)
			(xy 91.470835 -386.941728) (xy 91.492238 -386.88798) (xy 91.520244 -386.837359) (xy 91.554407 -386.790671)
			(xy 91.594181 -386.74866) (xy 91.616276 -386.729986) (xy 91.62325 -386.723641) (xy 91.632506 -386.707235)
			(xy 91.63431 -386.697982) (xy 91.638628 -386.666994) (xy 91.639535 -386.657757) (xy 91.635509 -386.639657)
			(xy 91.630754 -386.631688) (xy 91.614442 -386.605845) (xy 91.590541 -386.549608) (xy 91.583256 -386.519928)
			(xy 91.581182 -386.511771) (xy 91.572491 -386.497368) (xy 91.566238 -386.491734) (xy 91.543124 -386.472684)
			(xy 91.536232 -386.467455) (xy 91.520011 -386.461479) (xy 91.511374 -386.461) (xy 91.481738 -386.45998)
			(xy 91.423073 -386.451332) (xy 91.366016 -386.435183) (xy 91.311522 -386.411801) (xy 91.260503 -386.38158)
			(xy 91.213813 -386.345024) (xy 91.172234 -386.302745) (xy 91.136461 -386.255452) (xy 91.107095 -386.203936)
			(xy 91.084625 -386.14906) (xy 91.069429 -386.091742) (xy 91.061761 -386.032941) (xy 91.061286 -386.003292)
			(xy 91.061806 -385.972229) (xy 91.070222 -385.910675) (xy 91.07805 -385.88061) (xy 91.080844 -385.87045)
			(xy 91.078304 -385.850638) (xy 91.030806 -385.768342) (xy 91.014804 -385.75615) (xy 91.004644 -385.75361)
			(xy 90.975526 -385.745639) (xy 90.919558 -385.723002) (xy 90.867052 -385.693205) (xy 90.818918 -385.656764)
			(xy 90.775992 -385.614312) (xy 90.739018 -385.566586) (xy 90.70864 -385.514414) (xy 90.685383 -385.458701)
			(xy 90.669651 -385.400415) (xy 90.661717 -385.340566) (xy 90.661236 -385.31038) (xy 90.66171 -385.279458)
			(xy 90.669992 -385.218171) (xy 90.686457 -385.158559) (xy 90.710805 -385.10171) (xy 90.72626 -385.074922)
			(xy 90.732356 -385.06527) (xy 90.734642 -385.042918) (xy 90.701114 -384.947668) (xy 90.685366 -384.931666)
			(xy 90.674698 -384.927602) (xy 90.65135 -384.918372) (xy 90.607505 -384.893919) (xy 90.56786 -384.863121)
			(xy 90.533325 -384.826685) (xy 90.504692 -384.785448) (xy 90.482621 -384.740357) (xy 90.467618 -384.692449)
			(xy 90.460028 -384.642823) (xy 90.45956 -384.617722) (xy 89.920826 -384.617722) (xy 89.920297 -384.644824)
			(xy 89.911487 -384.698307) (xy 89.9033 -384.724148) (xy 89.89949 -384.73507) (xy 89.90203 -384.757422)
			(xy 89.954608 -384.843274) (xy 89.973658 -384.85572) (xy 89.984834 -384.857498) (xy 90.014153 -384.862203)
			(xy 90.071323 -384.878252) (xy 90.125937 -384.901562) (xy 90.177077 -384.931741) (xy 90.223882 -384.968283)
			(xy 90.265567 -385.010572) (xy 90.301431 -385.057899) (xy 90.330871 -385.109467) (xy 90.353393 -385.164411)
			(xy 90.368617 -385.221807) (xy 90.376289 -385.28069) (xy 90.376756 -385.31038) (xy 90.376229 -385.341443)
			(xy 90.367818 -385.402997) (xy 90.359992 -385.433062) (xy 90.357198 -385.443222) (xy 90.359738 -385.463034)
			(xy 90.407236 -385.54533) (xy 90.423238 -385.557522) (xy 90.433398 -385.560062) (xy 90.462516 -385.568031)
			(xy 90.518482 -385.590671) (xy 90.570987 -385.62047) (xy 90.619119 -385.656912) (xy 90.662044 -385.699364)
			(xy 90.699016 -385.74709) (xy 90.729395 -385.799261) (xy 90.752653 -385.854973) (xy 90.768387 -385.913259)
			(xy 90.776323 -385.973106) (xy 90.776806 -386.003292) (xy 90.776681 -386.017427) (xy 90.774899 -386.045641)
			(xy 90.77325 -386.05968) (xy 90.77249 -386.068287) (xy 90.77613 -386.085167) (xy 90.780362 -386.0927)
			(xy 90.79611 -386.1181) (xy 90.800833 -386.125152) (xy 90.813923 -386.135937) (xy 90.821764 -386.139182)
			(xy 90.84512 -386.148392) (xy 90.888962 -386.172851) (xy 90.928605 -386.203654) (xy 90.963138 -386.240094)
			(xy 90.991768 -386.281333) (xy 91.013838 -386.326425) (xy 91.028842 -386.374334) (xy 91.036433 -386.42396)
			(xy 91.036902 -386.449062) (xy 91.036476 -386.473264) (xy 91.029403 -386.521149) (xy 91.015417 -386.567488)
			(xy 90.994817 -386.61129) (xy 90.981784 -386.631688) (xy 90.976997 -386.639645) (xy 90.972962 -386.657756)
			(xy 90.97391 -386.666994) (xy 90.978228 -386.697982) (xy 90.979901 -386.70728) (xy 90.989188 -386.723722)
			(xy 90.996262 -386.729986) (xy 91.01835 -386.748668) (xy 91.058122 -386.79068) (xy 91.092284 -386.837368)
			(xy 91.120291 -386.887988) (xy 91.141699 -386.941733) (xy 91.156164 -386.997746) (xy 91.163457 -387.055136)
			(xy 91.163902 -387.084062) (xy 91.163316 -387.117384) (xy 91.153652 -387.183322) (xy 91.134525 -387.247161)
			(xy 91.120976 -387.27761) (xy 91.116729 -387.288075) (xy 91.116843 -387.310634) (xy 91.126576 -387.330985)
			(xy 91.134946 -387.33857) (xy 91.157165 -387.357276) (xy 91.197232 -387.399324) (xy 91.231657 -387.446104)
			(xy 91.259886 -387.496864) (xy 91.281466 -387.550787) (xy 91.29605 -387.607008) (xy 91.303403 -387.664621)
			(xy 91.303856 -387.693662) (xy 91.303378 -387.722667) (xy 91.296067 -387.780214) (xy 91.281545 -387.836376)
			(xy 91.260045 -387.890255) (xy 91.231911 -387.940985) (xy 91.197594 -387.987755) (xy 91.157643 -388.029815)
			(xy 91.135454 -388.0485) (xy 91.128342 -388.054088) (xy 91.119198 -388.069328) (xy 91.103958 -388.152132)
			(xy 91.106752 -388.169404) (xy 91.111324 -388.177532) (xy 91.123898 -388.200719) (xy 91.141773 -388.25034)
			(xy 91.150874 -388.302291) (xy 91.151456 -388.328662) (xy 91.151353 -388.339943) (xy 91.149701 -388.362445)
			(xy 91.148154 -388.37362) (xy 91.146884 -388.38251) (xy 91.15044 -388.400036) (xy 91.193874 -388.470902)
			(xy 91.20759 -388.482078) (xy 91.216226 -388.484872) (xy 91.238466 -388.492821) (xy 91.280388 -388.514568)
			(xy 91.318463 -388.542509) (xy 91.351782 -388.575978) (xy 91.379552 -388.614178) (xy 91.390724 -388.634986)
			(xy 91.391232 -388.636002) (xy 91.783662 -389.314944) (xy 91.79647 -389.338285) (xy 91.814696 -389.388304)
			(xy 91.823963 -389.440726) (xy 91.824556 -389.467344) (xy 91.824102 -389.491349) (xy 91.816582 -389.538765)
			(xy 91.801735 -389.584421) (xy 91.779926 -389.627191) (xy 91.751693 -389.666022) (xy 91.717731 -389.699956)
			(xy 91.678878 -389.728157) (xy 91.63609 -389.749931) (xy 91.590422 -389.76474) (xy 91.542999 -389.772221)
			(xy 91.518994 -389.772652) (xy 91.495463 -389.772173) (xy 91.448957 -389.764972) (xy 91.404109 -389.75071)
			(xy 91.361986 -389.729727) (xy 91.323587 -389.70252) (xy 91.289824 -389.669736) (xy 91.261499 -389.632154)
			(xy 91.250008 -389.611616) (xy 91.249754 -389.611108) (xy 91.249246 -389.610346) (xy 90.851482 -388.922006)
			(xy 90.839608 -388.899328) (xy 90.822756 -388.850996) (xy 90.814182 -388.800533) (xy 90.813636 -388.77494)
			(xy 90.813636 -388.774432) (xy 90.813727 -388.763087) (xy 90.815382 -388.740458) (xy 90.816938 -388.72922)
			(xy 90.818208 -388.72033) (xy 90.814652 -388.703058) (xy 90.771218 -388.631938) (xy 90.757248 -388.621016)
			(xy 90.748866 -388.617968) (xy 90.726469 -388.609922) (xy 90.68425 -388.587966) (xy 90.645952 -388.55972)
			(xy 90.612505 -388.525871) (xy 90.58472 -388.487238) (xy 90.56327 -388.44476) (xy 90.548677 -388.399466)
			(xy 90.541293 -388.352455) (xy 90.54084 -388.328662) (xy 90.541401 -388.302289) (xy 90.550485 -388.25033)
			(xy 90.568376 -388.20071) (xy 90.580972 -388.177532) (xy 90.585544 -388.169404) (xy 90.588338 -388.152132)
			(xy 90.573098 -388.069328) (xy 90.563954 -388.054088) (xy 90.556842 -388.0485) (xy 90.53468 -388.029784)
			(xy 90.494731 -387.987725) (xy 90.460411 -387.94096) (xy 90.432271 -387.890235) (xy 90.41076 -387.836364)
			(xy 90.396222 -387.780208) (xy 90.388891 -387.722666) (xy 90.38844 -387.693662) (xy 90.38904 -387.660341)
			(xy 90.398699 -387.594403) (xy 90.417821 -387.530563) (xy 90.431366 -387.500114) (xy 90.43561 -387.489646)
			(xy 90.435505 -387.467087) (xy 90.425769 -387.446736) (xy 90.417396 -387.439154) (xy 90.395128 -387.420504)
			(xy 90.355066 -387.378444) (xy 90.320648 -387.331654) (xy 90.292426 -387.280885) (xy 90.270853 -387.226953)
			(xy 90.256278 -387.170725) (xy 90.248934 -387.113105) (xy 90.248486 -387.084062) (xy 90.248925 -387.055135)
			(xy 90.256209 -386.997742) (xy 90.270669 -386.941724) (xy 90.292075 -386.887976) (xy 90.320084 -386.837355)
			(xy 90.35425 -386.790667) (xy 90.394029 -386.748659) (xy 90.416126 -386.729986) (xy 90.423092 -386.723633)
			(xy 90.432354 -386.707234) (xy 90.43416 -386.697982) (xy 90.438478 -386.666994) (xy 90.439377 -386.657757)
			(xy 90.435355 -386.639658) (xy 90.430604 -386.631688) (xy 90.414296 -386.605842) (xy 90.390392 -386.549607)
			(xy 90.383106 -386.519928) (xy 90.381045 -386.511766) (xy 90.372345 -386.497365) (xy 90.366088 -386.491734)
			(xy 90.342974 -386.472684) (xy 90.336154 -386.467463) (xy 90.320054 -386.461502) (xy 90.311478 -386.461)
			(xy 90.281842 -386.459976) (xy 90.223178 -386.451329) (xy 90.166121 -386.43518) (xy 90.111627 -386.411799)
			(xy 90.060607 -386.381578) (xy 90.013917 -386.345022) (xy 89.972338 -386.302744) (xy 89.936566 -386.255451)
			(xy 89.907199 -386.203936) (xy 89.884729 -386.149059) (xy 89.869533 -386.091741) (xy 89.861865 -386.032941)
			(xy 89.86139 -386.003292) (xy 89.86191 -385.972229) (xy 89.870326 -385.910675) (xy 89.878154 -385.88061)
			(xy 89.880948 -385.87045) (xy 89.878408 -385.850638) (xy 89.83091 -385.768342) (xy 89.814908 -385.75615)
			(xy 89.804748 -385.75361) (xy 89.775631 -385.745636) (xy 89.719663 -385.723) (xy 89.667156 -385.693203)
			(xy 89.619022 -385.656763) (xy 89.576096 -385.614311) (xy 89.539123 -385.566585) (xy 89.508744 -385.514414)
			(xy 89.485487 -385.458701) (xy 89.469755 -385.400415) (xy 89.461821 -385.340566) (xy 89.46134 -385.31038)
			(xy 89.46186 -385.279492) (xy 89.470166 -385.218276) (xy 89.486624 -385.158732) (xy 89.510936 -385.10194)
			(xy 89.526364 -385.075176) (xy 89.532206 -385.06527) (xy 89.534492 -385.042918) (xy 89.501218 -384.947668)
			(xy 89.48547 -384.931666) (xy 89.474802 -384.927602) (xy 89.451422 -384.918415) (xy 89.407525 -384.893997)
			(xy 89.367828 -384.863217) (xy 89.333246 -384.826784) (xy 89.304576 -384.785538) (xy 89.282479 -384.740428)
			(xy 89.267462 -384.692493) (xy 89.259872 -384.642838) (xy 89.25941 -384.617722) (xy 88.72093 -384.617722)
			(xy 88.720401 -384.644824) (xy 88.711591 -384.698307) (xy 88.703404 -384.724148) (xy 88.699594 -384.73507)
			(xy 88.702134 -384.757422) (xy 88.754712 -384.843274) (xy 88.773762 -384.85572) (xy 88.784938 -384.857498)
			(xy 88.814257 -384.8622) (xy 88.871428 -384.878249) (xy 88.926042 -384.90156) (xy 88.977181 -384.931739)
			(xy 89.023987 -384.968281) (xy 89.065672 -385.010571) (xy 89.101535 -385.057898) (xy 89.130976 -385.109467)
			(xy 89.153497 -385.164411) (xy 89.168721 -385.221807) (xy 89.176393 -385.28069) (xy 89.17686 -385.31038)
			(xy 89.176337 -385.341506) (xy 89.167931 -385.403188) (xy 89.160096 -385.433316) (xy 89.157302 -385.443476)
			(xy 89.159842 -385.463542) (xy 89.207086 -385.54533) (xy 89.223088 -385.557522) (xy 89.233248 -385.560062)
			(xy 89.262357 -385.568064) (xy 89.318323 -385.590698) (xy 89.370829 -385.620492) (xy 89.418962 -385.656929)
			(xy 89.461889 -385.699377) (xy 89.498863 -385.7471) (xy 89.529243 -385.799269) (xy 89.552502 -385.854978)
			(xy 89.568236 -385.913261) (xy 89.576173 -385.973107) (xy 89.576656 -386.003292) (xy 89.576531 -386.017427)
			(xy 89.574749 -386.045641) (xy 89.5731 -386.05968) (xy 89.572333 -386.068287) (xy 89.575976 -386.085168)
			(xy 89.580212 -386.0927) (xy 89.59596 -386.1181) (xy 89.600679 -386.125153) (xy 89.613778 -386.135926)
			(xy 89.621614 -386.139182) (xy 89.644992 -386.148374) (xy 89.688888 -386.172792) (xy 89.728584 -386.203572)
			(xy 89.763165 -386.240005) (xy 89.791835 -386.28125) (xy 89.813933 -386.326359) (xy 89.828951 -386.374292)
			(xy 89.836543 -386.423946) (xy 89.837006 -386.449062) (xy 89.83658 -386.473264) (xy 89.829506 -386.521149)
			(xy 89.81552 -386.567488) (xy 89.794921 -386.61129) (xy 89.781888 -386.631688) (xy 89.777101 -386.639645)
			(xy 89.773066 -386.657756) (xy 89.774014 -386.666994) (xy 89.778332 -386.697982) (xy 89.780004 -386.707281)
			(xy 89.789291 -386.723722) (xy 89.796366 -386.729986) (xy 89.818455 -386.748667) (xy 89.858226 -386.790679)
			(xy 89.892388 -386.837367) (xy 89.920396 -386.887987) (xy 89.941803 -386.941732) (xy 89.956268 -386.997746)
			(xy 89.963561 -387.055136) (xy 89.964006 -387.084062) (xy 89.963419 -387.117384) (xy 89.953756 -387.183322)
			(xy 89.934629 -387.247161) (xy 89.92108 -387.27761) (xy 89.916831 -387.288075) (xy 89.916945 -387.310634)
			(xy 89.92668 -387.330985) (xy 89.93505 -387.33857) (xy 89.95727 -387.357275) (xy 89.997337 -387.399324)
			(xy 90.031761 -387.446104) (xy 90.05999 -387.496864) (xy 90.08157 -387.550787) (xy 90.096154 -387.607008)
			(xy 90.103507 -387.664621) (xy 90.10396 -387.693662) (xy 90.10348 -387.722667) (xy 90.09617 -387.780214)
			(xy 90.081648 -387.836376) (xy 90.060148 -387.890254) (xy 90.032014 -387.940985) (xy 89.997697 -387.987755)
			(xy 89.957747 -388.029815) (xy 89.935558 -388.0485) (xy 89.928446 -388.054088) (xy 89.919302 -388.069328)
			(xy 89.904062 -388.152132) (xy 89.906856 -388.169404) (xy 89.911428 -388.177532) (xy 89.924002 -388.200719)
			(xy 89.941877 -388.25034) (xy 89.950978 -388.302291) (xy 89.95156 -388.328662) (xy 89.951457 -388.339943)
			(xy 89.949805 -388.362445) (xy 89.948258 -388.37362) (xy 89.946988 -388.38251) (xy 89.950544 -388.400036)
			(xy 89.993978 -388.470902) (xy 90.007694 -388.482078) (xy 90.01633 -388.484872) (xy 90.038571 -388.492819)
			(xy 90.080493 -388.514567) (xy 90.118567 -388.542508) (xy 90.151886 -388.575978) (xy 90.179656 -388.614178)
			(xy 90.190828 -388.634986) (xy 90.191336 -388.636002) (xy 90.583766 -389.314944) (xy 90.596575 -389.338285)
			(xy 90.6148 -389.388303) (xy 90.624067 -389.440726) (xy 90.62466 -389.467344) (xy 90.624301 -389.491353)
			(xy 90.616779 -389.53878) (xy 90.601926 -389.584444) (xy 90.580109 -389.62722) (xy 90.551865 -389.666055)
			(xy 90.517891 -389.69999) (xy 90.479025 -389.72819) (xy 90.436223 -389.749958) (xy 90.390542 -389.764759)
			(xy 90.343108 -389.772228) (xy 90.319098 -389.772652) (xy 90.295567 -389.77217) (xy 90.249061 -389.764969)
			(xy 90.204214 -389.750708) (xy 90.16209 -389.729725) (xy 90.123691 -389.702519) (xy 90.089928 -389.669736)
			(xy 90.061604 -389.632154) (xy 90.050112 -389.611616) (xy 90.049858 -389.611108) (xy 90.04935 -389.610346)
			(xy 89.651586 -388.922006) (xy 89.639712 -388.899328) (xy 89.62286 -388.850996) (xy 89.614286 -388.800533)
			(xy 89.61374 -388.77494) (xy 89.61374 -388.774432) (xy 89.613831 -388.763087) (xy 89.615486 -388.740458)
			(xy 89.617042 -388.72922) (xy 89.618312 -388.72033) (xy 89.614756 -388.703058) (xy 89.571322 -388.631938)
			(xy 89.557352 -388.621016) (xy 89.54897 -388.617968) (xy 89.526574 -388.609919) (xy 89.484355 -388.587964)
			(xy 89.446057 -388.559719) (xy 89.41261 -388.52587) (xy 89.384824 -388.487238) (xy 89.363374 -388.444759)
			(xy 89.348781 -388.399466) (xy 89.341397 -388.352455) (xy 89.340944 -388.328662) (xy 89.341504 -388.302289)
			(xy 89.350588 -388.25033) (xy 89.36848 -388.20071) (xy 89.381076 -388.177532) (xy 89.385648 -388.169404)
			(xy 89.388442 -388.152132) (xy 89.373202 -388.069328) (xy 89.364058 -388.054088) (xy 89.356946 -388.0485)
			(xy 89.334764 -388.029807) (xy 89.29482 -387.987742) (xy 89.260505 -387.940971) (xy 89.232368 -387.890243)
			(xy 89.21086 -387.836369) (xy 89.196325 -387.78021) (xy 89.188994 -387.722666) (xy 89.188544 -387.693662)
			(xy 89.189144 -387.660341) (xy 89.198802 -387.594403) (xy 89.217924 -387.530563) (xy 89.23147 -387.500114)
			(xy 89.235712 -387.489646) (xy 89.235608 -387.467087) (xy 89.225873 -387.446736) (xy 89.2175 -387.439154)
			(xy 89.195233 -387.420503) (xy 89.155171 -387.378444) (xy 89.120752 -387.331653) (xy 89.09253 -387.280884)
			(xy 89.070958 -387.226953) (xy 89.056382 -387.170725) (xy 89.049038 -387.113105) (xy 89.04859 -387.084062)
			(xy 89.049028 -387.055135) (xy 89.056312 -386.997742) (xy 89.070772 -386.941724) (xy 89.092178 -386.887976)
			(xy 89.120187 -386.837355) (xy 89.154354 -386.790667) (xy 89.194133 -386.748659) (xy 89.21623 -386.729986)
			(xy 89.223197 -386.723634) (xy 89.232458 -386.707234) (xy 89.234264 -386.697982) (xy 89.238582 -386.666994)
			(xy 89.239481 -386.657757) (xy 89.235459 -386.639658) (xy 89.230708 -386.631688) (xy 89.2144 -386.605842)
			(xy 89.190497 -386.549607) (xy 89.18321 -386.519928) (xy 89.181148 -386.511767) (xy 89.172449 -386.497365)
			(xy 89.166192 -386.491734) (xy 89.143078 -386.472684) (xy 89.136199 -386.467437) (xy 89.119968 -386.461472)
			(xy 89.111328 -386.461) (xy 89.08169 -386.460022) (xy 89.023024 -386.451369) (xy 88.965967 -386.435214)
			(xy 88.911472 -386.411827) (xy 88.860453 -386.381601) (xy 88.813764 -386.345041) (xy 88.772185 -386.302759)
			(xy 88.736413 -386.255463) (xy 88.707047 -386.203944) (xy 88.684578 -386.149065) (xy 88.669383 -386.091745)
			(xy 88.661715 -386.032942) (xy 88.66124 -386.003292) (xy 88.661761 -385.972229) (xy 88.670177 -385.910675)
			(xy 88.678004 -385.88061) (xy 88.680798 -385.87045) (xy 88.678258 -385.850638) (xy 88.63076 -385.768342)
			(xy 88.614758 -385.75615) (xy 88.604598 -385.75361) (xy 88.575503 -385.745601) (xy 88.519577 -385.722931)
			(xy 88.467112 -385.693111) (xy 88.419019 -385.656659) (xy 88.376129 -385.614206) (xy 88.339188 -385.566487)
			(xy 88.308833 -385.51433) (xy 88.285592 -385.458638) (xy 88.269867 -385.400376) (xy 88.261931 -385.340553)
			(xy 88.261444 -385.31038) (xy 88.261964 -385.279492) (xy 88.27027 -385.218276) (xy 88.286728 -385.158732)
			(xy 88.31104 -385.10194) (xy 88.326468 -385.075176) (xy 88.33231 -385.06527) (xy 88.334596 -385.042918)
			(xy 88.301322 -384.947668) (xy 88.285574 -384.931666) (xy 88.274906 -384.927602) (xy 88.251527 -384.918413)
			(xy 88.207629 -384.893995) (xy 88.167932 -384.863216) (xy 88.133351 -384.826783) (xy 88.104681 -384.785537)
			(xy 88.082583 -384.740427) (xy 88.067566 -384.692493) (xy 88.059976 -384.642838) (xy 88.059514 -384.617722)
			(xy 87.52078 -384.617722) (xy 87.520248 -384.644824) (xy 87.51144 -384.698307) (xy 87.503254 -384.724148)
			(xy 87.499444 -384.73507) (xy 87.501984 -384.757422) (xy 87.554562 -384.843274) (xy 87.573612 -384.85572)
			(xy 87.584788 -384.857498) (xy 87.6141 -384.862239) (xy 87.671271 -384.878282) (xy 87.725885 -384.901587)
			(xy 87.777025 -384.931762) (xy 87.823831 -384.968299) (xy 87.865518 -385.010585) (xy 87.901383 -385.057909)
			(xy 87.930824 -385.109475) (xy 87.953346 -385.164416) (xy 87.968571 -385.22181) (xy 87.976243 -385.280691)
			(xy 87.97671 -385.31038) (xy 87.976185 -385.341443) (xy 87.967772 -385.402997) (xy 87.959946 -385.433062)
			(xy 87.957152 -385.443222) (xy 87.959692 -385.463034) (xy 88.00719 -385.54533) (xy 88.023192 -385.557522)
			(xy 88.033352 -385.560062) (xy 88.062462 -385.568062) (xy 88.118428 -385.590696) (xy 88.170933 -385.62049)
			(xy 88.219067 -385.656928) (xy 88.261993 -385.699376) (xy 88.298967 -385.747099) (xy 88.329347 -385.799268)
			(xy 88.352606 -385.854978) (xy 88.36834 -385.913261) (xy 88.376277 -385.973107) (xy 88.37676 -386.003292)
			(xy 88.376635 -386.017427) (xy 88.374853 -386.045641) (xy 88.373204 -386.05968) (xy 88.372437 -386.068287)
			(xy 88.37608 -386.085168) (xy 88.380316 -386.0927) (xy 88.396064 -386.1181) (xy 88.400782 -386.125154)
			(xy 88.413882 -386.135926) (xy 88.421718 -386.139182) (xy 88.445097 -386.148372) (xy 88.488993 -386.172791)
			(xy 88.528689 -386.203571) (xy 88.563269 -386.240004) (xy 88.591939 -386.281249) (xy 88.614037 -386.326359)
			(xy 88.629055 -386.374292) (xy 88.636647 -386.423946) (xy 88.63711 -386.449062) (xy 88.636683 -386.473264)
			(xy 88.62961 -386.521149) (xy 88.615624 -386.567488) (xy 88.595025 -386.61129) (xy 88.581992 -386.631688)
			(xy 88.577205 -386.639646) (xy 88.57317 -386.657756) (xy 88.574118 -386.666994) (xy 88.578436 -386.697982)
			(xy 88.580107 -386.707281) (xy 88.589395 -386.723722) (xy 88.59647 -386.729986) (xy 88.61856 -386.748666)
			(xy 88.658331 -386.790679) (xy 88.692493 -386.837367) (xy 88.7205 -386.887987) (xy 88.741907 -386.941732)
			(xy 88.756372 -386.997746) (xy 88.763665 -387.055136) (xy 88.76411 -387.084062) (xy 88.763523 -387.117384)
			(xy 88.75386 -387.183322) (xy 88.734732 -387.247161) (xy 88.721184 -387.27761) (xy 88.716934 -387.288074)
			(xy 88.717048 -387.310634) (xy 88.726783 -387.330986) (xy 88.735154 -387.33857) (xy 88.757375 -387.357274)
			(xy 88.797441 -387.399323) (xy 88.831865 -387.446103) (xy 88.860094 -387.496863) (xy 88.881674 -387.550787)
			(xy 88.896258 -387.607007) (xy 88.903611 -387.664621) (xy 88.904064 -387.693662) (xy 88.903583 -387.722667)
			(xy 88.896272 -387.780214) (xy 88.881751 -387.836376) (xy 88.860251 -387.890254) (xy 88.832117 -387.940984)
			(xy 88.797801 -387.987755) (xy 88.757851 -388.029815) (xy 88.735662 -388.0485) (xy 88.72855 -388.054088)
			(xy 88.719406 -388.069328) (xy 88.704166 -388.152132) (xy 88.70696 -388.169404) (xy 88.711532 -388.177532)
			(xy 88.724106 -388.200719) (xy 88.741981 -388.25034) (xy 88.751082 -388.302291) (xy 88.751664 -388.328662)
			(xy 88.751561 -388.339943) (xy 88.749909 -388.362445) (xy 88.748362 -388.37362) (xy 88.747092 -388.382764)
			(xy 88.750394 -388.400036) (xy 88.794082 -388.471156) (xy 88.807798 -388.482078) (xy 88.816434 -388.484872)
			(xy 88.844604 -388.495057) (xy 88.896547 -388.524877) (xy 88.919558 -388.544054) (xy 88.941038 -388.56364)
			(xy 88.976854 -388.609415) (xy 88.990678 -388.634986) (xy 88.99144 -388.636256) (xy 89.383616 -389.314944)
			(xy 89.39635 -389.338309) (xy 89.414465 -389.388337) (xy 89.423674 -389.440741) (xy 89.424256 -389.467344)
			(xy 89.423778 -389.491334) (xy 89.416267 -389.538723) (xy 89.401436 -389.584353) (xy 89.379652 -389.627103)
			(xy 89.351449 -389.665919) (xy 89.317522 -389.699846) (xy 89.278706 -389.72805) (xy 89.235957 -389.749835)
			(xy 89.190327 -389.764666) (xy 89.142938 -389.772178) (xy 89.118948 -389.772652) (xy 89.095416 -389.772211)
			(xy 89.048908 -389.765002) (xy 89.00406 -389.750734) (xy 88.961936 -389.729744) (xy 88.923537 -389.702532)
			(xy 88.889776 -389.669743) (xy 88.861453 -389.632156) (xy 88.849962 -389.611616) (xy 88.849708 -389.611108)
			(xy 88.8492 -389.610346) (xy 88.45169 -388.921752) (xy 88.441116 -388.901826) (xy 88.425314 -388.859576)
			(xy 88.415907 -388.815459) (xy 88.414098 -388.792974) (xy 88.41359 -388.781798) (xy 88.413336 -388.774432)
			(xy 88.413493 -388.763083) (xy 88.41527 -388.740453) (xy 88.416892 -388.72922) (xy 88.418162 -388.72033)
			(xy 88.414606 -388.703058) (xy 88.371172 -388.631938) (xy 88.357456 -388.620762) (xy 88.34882 -388.617968)
			(xy 88.326428 -388.609943) (xy 88.284256 -388.587947) (xy 88.246006 -388.559675) (xy 88.212604 -388.525813)
			(xy 88.184859 -388.48718) (xy 88.163442 -388.444711) (xy 88.148871 -388.399433) (xy 88.141499 -388.352444)
			(xy 88.141048 -388.328662) (xy 88.141608 -388.302289) (xy 88.150692 -388.25033) (xy 88.168583 -388.20071)
			(xy 88.18118 -388.177532) (xy 88.185752 -388.169404) (xy 88.188546 -388.152132) (xy 88.173306 -388.069328)
			(xy 88.164162 -388.054088) (xy 88.15705 -388.0485) (xy 88.134869 -388.029806) (xy 88.094924 -387.987741)
			(xy 88.060609 -387.940971) (xy 88.032473 -387.890242) (xy 88.010964 -387.836368) (xy 87.996429 -387.78021)
			(xy 87.989098 -387.722666) (xy 87.988648 -387.693662) (xy 87.989247 -387.660341) (xy 87.998906 -387.594403)
			(xy 88.018028 -387.530563) (xy 88.031574 -387.500114) (xy 88.035815 -387.489646) (xy 88.03571 -387.467087)
			(xy 88.025976 -387.446736) (xy 88.017604 -387.439154) (xy 87.995338 -387.420502) (xy 87.955275 -387.378443)
			(xy 87.920857 -387.331653) (xy 87.892634 -387.280884) (xy 87.871062 -387.226952) (xy 87.856486 -387.170725)
			(xy 87.849142 -387.113105) (xy 87.848694 -387.084062) (xy 87.84913 -387.055135) (xy 87.856415 -386.997741)
			(xy 87.870875 -386.941724) (xy 87.892281 -386.887976) (xy 87.92029 -386.837354) (xy 87.954457 -386.790667)
			(xy 87.994236 -386.748659) (xy 88.016334 -386.729986) (xy 88.023301 -386.723634) (xy 88.032562 -386.707234)
			(xy 88.034368 -386.697982) (xy 88.038686 -386.666994) (xy 88.039584 -386.657757) (xy 88.035563 -386.639658)
			(xy 88.030812 -386.631688) (xy 88.014505 -386.605842) (xy 87.990601 -386.549607) (xy 87.983314 -386.519928)
			(xy 87.981251 -386.511767) (xy 87.972553 -386.497365) (xy 87.966296 -386.491734) (xy 87.943182 -386.472684)
			(xy 87.936302 -386.467439) (xy 87.920071 -386.461473) (xy 87.911432 -386.461) (xy 87.881794 -386.460018)
			(xy 87.823129 -386.451365) (xy 87.766071 -386.435211) (xy 87.711577 -386.411825) (xy 87.660558 -386.381599)
			(xy 87.613868 -386.34504) (xy 87.572289 -386.302758) (xy 87.536518 -386.255462) (xy 87.507151 -386.203944)
			(xy 87.484683 -386.149065) (xy 87.469487 -386.091745) (xy 87.461819 -386.032942) (xy 87.461344 -386.003292)
			(xy 87.461865 -385.972229) (xy 87.470281 -385.910675) (xy 87.478108 -385.88061) (xy 87.480902 -385.87045)
			(xy 87.478362 -385.850638) (xy 87.430864 -385.768342) (xy 87.414862 -385.75615) (xy 87.404702 -385.75361)
			(xy 87.375576 -385.745666) (xy 87.319609 -385.723025) (xy 87.267103 -385.693223) (xy 87.21897 -385.656778)
			(xy 87.176045 -385.614323) (xy 87.139073 -385.566594) (xy 87.108696 -385.51442) (xy 87.08544 -385.458705)
			(xy 87.069708 -385.400417) (xy 87.061775 -385.340567) (xy 87.061294 -385.31038) (xy 87.061821 -385.279492)
			(xy 87.070126 -385.218277) (xy 87.086582 -385.158733) (xy 87.110892 -385.101941) (xy 87.126318 -385.075176)
			(xy 87.13216 -385.06527) (xy 87.134446 -385.042918) (xy 87.101172 -384.947668) (xy 87.085424 -384.931666)
			(xy 87.074756 -384.927602) (xy 87.051366 -384.91844) (xy 87.00747 -384.894016) (xy 86.967775 -384.863231)
			(xy 86.933195 -384.826794) (xy 86.904527 -384.785545) (xy 86.882431 -384.740432) (xy 86.867415 -384.692496)
			(xy 86.859826 -384.642839) (xy 86.859364 -384.617722) (xy 86.320884 -384.617722) (xy 86.320352 -384.644824)
			(xy 86.311544 -384.698307) (xy 86.303358 -384.724148) (xy 86.299548 -384.73507) (xy 86.302088 -384.757422)
			(xy 86.354666 -384.843274) (xy 86.373716 -384.85572) (xy 86.384892 -384.857498) (xy 86.414205 -384.862236)
			(xy 86.471375 -384.87828) (xy 86.525989 -384.901585) (xy 86.577129 -384.93176) (xy 86.623936 -384.968298)
			(xy 86.665622 -385.010584) (xy 86.701487 -385.057908) (xy 86.730928 -385.109474) (xy 86.75345 -385.164416)
			(xy 86.768675 -385.221809) (xy 86.776347 -385.280691) (xy 86.776814 -385.31038) (xy 86.776288 -385.341443)
			(xy 86.767876 -385.402997) (xy 86.76005 -385.433062) (xy 86.757256 -385.443222) (xy 86.759796 -385.463034)
			(xy 86.807294 -385.54533) (xy 86.823296 -385.557522) (xy 86.833456 -385.560062) (xy 86.862566 -385.568059)
			(xy 86.918533 -385.590694) (xy 86.971038 -385.620489) (xy 87.019171 -385.656927) (xy 87.062097 -385.699375)
			(xy 87.099071 -385.747098) (xy 87.129451 -385.799267) (xy 87.15271 -385.854977) (xy 87.168444 -385.913261)
			(xy 87.176381 -385.973107) (xy 87.176864 -386.003292) (xy 87.176739 -386.017427) (xy 87.174957 -386.045641)
			(xy 87.173308 -386.05968) (xy 87.172554 -386.068287) (xy 87.17619 -386.085166) (xy 87.18042 -386.0927)
			(xy 87.196168 -386.1181) (xy 87.200872 -386.125167) (xy 87.213975 -386.135944) (xy 87.221822 -386.139182)
			(xy 87.245169 -386.148414) (xy 87.289012 -386.172868) (xy 87.328656 -386.203667) (xy 87.363191 -386.240103)
			(xy 87.391823 -386.281339) (xy 87.413895 -386.326429) (xy 87.428899 -386.374336) (xy 87.436491 -386.423961)
			(xy 87.43696 -386.449062) (xy 87.436541 -386.473264) (xy 87.429467 -386.52115) (xy 87.415479 -386.567489)
			(xy 87.394877 -386.611291) (xy 87.381842 -386.631688) (xy 87.377052 -386.639644) (xy 87.37302 -386.657756)
			(xy 87.373968 -386.666994) (xy 87.378286 -386.697982) (xy 87.379972 -386.707277) (xy 87.389251 -386.723719)
			(xy 87.39632 -386.729986) (xy 87.418399 -386.748679) (xy 87.458173 -386.790688) (xy 87.492337 -386.837373)
			(xy 87.520346 -386.887991) (xy 87.541755 -386.941735) (xy 87.556221 -386.997748) (xy 87.563515 -387.055137)
			(xy 87.56396 -387.084062) (xy 87.563368 -387.117383) (xy 87.553706 -387.183322) (xy 87.534581 -387.247161)
			(xy 87.521034 -387.27761) (xy 87.516768 -387.28807) (xy 87.516881 -387.310636) (xy 87.526626 -387.330989)
			(xy 87.535004 -387.33857) (xy 87.557235 -387.357262) (xy 87.597299 -387.399314) (xy 87.631721 -387.446097)
			(xy 87.659948 -387.496859) (xy 87.681526 -387.550784) (xy 87.696109 -387.607006) (xy 87.703461 -387.664621)
			(xy 87.703914 -387.693662) (xy 87.703451 -387.722668) (xy 87.69614 -387.780216) (xy 87.681616 -387.836379)
			(xy 87.660114 -387.890258) (xy 87.631977 -387.940988) (xy 87.597657 -387.987758) (xy 87.557703 -388.029816)
			(xy 87.535512 -388.0485) (xy 87.5284 -388.054088) (xy 87.519256 -388.069328) (xy 87.504016 -388.152132)
			(xy 87.50681 -388.169404) (xy 87.511382 -388.177532) (xy 87.523952 -388.200721) (xy 87.541829 -388.250341)
			(xy 87.550932 -388.302292) (xy 87.551514 -388.328662) (xy 87.55141 -388.339943) (xy 87.549759 -388.362445)
			(xy 87.548212 -388.37362) (xy 87.546942 -388.38251) (xy 87.550498 -388.400036) (xy 87.593932 -388.470902)
			(xy 87.607648 -388.482078) (xy 87.616284 -388.484872) (xy 87.638534 -388.492794) (xy 87.680455 -388.514548)
			(xy 87.718527 -388.542496) (xy 87.751845 -388.575971) (xy 87.779612 -388.614175) (xy 87.790782 -388.634986)
			(xy 87.79129 -388.636002) (xy 88.18372 -389.314944) (xy 88.196454 -389.338309) (xy 88.214569 -389.388337)
			(xy 88.223778 -389.440741) (xy 88.22436 -389.467344) (xy 88.224002 -389.491341) (xy 88.216487 -389.538742)
			(xy 88.20165 -389.584385) (xy 88.179855 -389.627144) (xy 88.151639 -389.665968) (xy 88.117698 -389.699899)
			(xy 88.078866 -389.728103) (xy 88.0361 -389.749885) (xy 87.990453 -389.764709) (xy 87.943049 -389.772209)
			(xy 87.919052 -389.772652) (xy 87.89552 -389.772207) (xy 87.849012 -389.765) (xy 87.804164 -389.750732)
			(xy 87.76204 -389.729743) (xy 87.723642 -389.702531) (xy 87.68988 -389.669742) (xy 87.661557 -389.632156)
			(xy 87.650066 -389.611616) (xy 87.649812 -389.611108) (xy 87.649304 -389.610346) (xy 87.25154 -388.922006)
			(xy 87.239628 -388.899336) (xy 87.222688 -388.851012) (xy 87.214028 -388.800542) (xy 87.21344 -388.77494)
			(xy 87.21344 -388.774432) (xy 87.213597 -388.763083) (xy 87.215374 -388.740453) (xy 87.216996 -388.72922)
			(xy 87.218266 -388.72033) (xy 87.21471 -388.703058) (xy 87.171276 -388.631938) (xy 87.157306 -388.621016)
			(xy 87.148924 -388.617968) (xy 87.126518 -388.609946) (xy 87.0843 -388.587984) (xy 87.046004 -388.559734)
			(xy 87.012559 -388.525881) (xy 86.984775 -388.487245) (xy 86.963327 -388.444764) (xy 86.948734 -388.399468)
			(xy 86.941351 -388.352456) (xy 86.940898 -388.328662) (xy 86.941464 -388.302289) (xy 86.950547 -388.250331)
			(xy 86.968435 -388.20071) (xy 86.98103 -388.177532) (xy 86.985602 -388.169404) (xy 86.988396 -388.152132)
			(xy 86.973156 -388.069328) (xy 86.964012 -388.054088) (xy 86.9569 -388.0485) (xy 86.934729 -388.029794)
			(xy 86.894782 -387.987733) (xy 86.860465 -387.940965) (xy 86.832326 -387.890239) (xy 86.810816 -387.836366)
			(xy 86.796279 -387.780209) (xy 86.788949 -387.722666) (xy 86.788498 -387.693662) (xy 86.789093 -387.660341)
			(xy 86.798753 -387.594402) (xy 86.817877 -387.530563) (xy 86.831424 -387.500114) (xy 86.835649 -387.489642)
			(xy 86.835543 -387.467089) (xy 86.825819 -387.446739) (xy 86.817454 -387.439154) (xy 86.795198 -387.42049)
			(xy 86.755133 -387.378434) (xy 86.720712 -387.331647) (xy 86.692488 -387.28088) (xy 86.670914 -387.22695)
			(xy 86.656337 -387.170724) (xy 86.648992 -387.113105) (xy 86.648544 -387.084062) (xy 86.648998 -387.055136)
			(xy 86.656282 -386.997744) (xy 86.670741 -386.941727) (xy 86.692144 -386.88798) (xy 86.72015 -386.837358)
			(xy 86.754314 -386.79067) (xy 86.794089 -386.74866) (xy 86.816184 -386.729986) (xy 86.82316 -386.723642)
			(xy 86.832415 -386.707236) (xy 86.834218 -386.697982) (xy 86.838536 -386.666994) (xy 86.839442 -386.657757)
			(xy 86.835416 -386.639657) (xy 86.830662 -386.631688) (xy 86.814351 -386.605845) (xy 86.79045 -386.549607)
			(xy 86.783164 -386.519928) (xy 86.781115 -386.511763) (xy 86.772408 -386.497363) (xy 86.766146 -386.491734)
			(xy 86.743032 -386.472684) (xy 86.736196 -386.467486) (xy 86.720108 -386.461511) (xy 86.711536 -386.461)
			(xy 86.681898 -386.460014) (xy 86.623233 -386.451362) (xy 86.566175 -386.435208) (xy 86.511681 -386.411823)
			(xy 86.460662 -386.381598) (xy 86.413972 -386.345038) (xy 86.372394 -386.302757) (xy 86.336622 -386.255461)
			(xy 86.307256 -386.203943) (xy 86.284787 -386.149064) (xy 86.269591 -386.091744) (xy 86.261923 -386.032942)
			(xy 86.261448 -386.003292) (xy 86.261969 -385.972229) (xy 86.270385 -385.910675) (xy 86.278212 -385.88061)
			(xy 86.281006 -385.87045) (xy 86.278466 -385.850638) (xy 86.230968 -385.768342) (xy 86.214966 -385.75615)
			(xy 86.204806 -385.75361) (xy 86.175681 -385.745664) (xy 86.119714 -385.723023) (xy 86.067208 -385.693221)
			(xy 86.019075 -385.656777) (xy 85.97615 -385.614322) (xy 85.939178 -385.566594) (xy 85.9088 -385.514419)
			(xy 85.885544 -385.458705) (xy 85.869812 -385.400417) (xy 85.861879 -385.340567) (xy 85.861398 -385.31038)
			(xy 85.861924 -385.279492) (xy 85.870229 -385.218277) (xy 85.886686 -385.158733) (xy 85.910996 -385.101941)
			(xy 85.926422 -385.075176) (xy 85.932264 -385.06527) (xy 85.93455 -385.042918) (xy 85.901276 -384.947668)
			(xy 85.885528 -384.931666) (xy 85.87486 -384.927602) (xy 85.851471 -384.918438) (xy 85.807575 -384.894014)
			(xy 85.76788 -384.86323) (xy 85.7333 -384.826793) (xy 85.704631 -384.785544) (xy 85.682535 -384.740432)
			(xy 85.667519 -384.692495) (xy 85.65993 -384.642839) (xy 85.659468 -384.617722) (xy 85.120988 -384.617722)
			(xy 85.120456 -384.644824) (xy 85.111648 -384.698306) (xy 85.103462 -384.724148) (xy 85.099652 -384.73507)
			(xy 85.102192 -384.757422) (xy 85.15477 -384.843528) (xy 85.173566 -384.85572) (xy 85.184996 -384.857498)
			(xy 85.214292 -384.862264) (xy 85.271427 -384.878344) (xy 85.326003 -384.901675) (xy 85.377105 -384.931866)
			(xy 85.423875 -384.96841) (xy 85.465529 -385.010694) (xy 85.501366 -385.058007) (xy 85.530787 -385.109557)
			(xy 85.553296 -385.164478) (xy 85.568516 -385.221847) (xy 85.576192 -385.280703) (xy 85.576664 -385.31038)
			(xy 85.576137 -385.341443) (xy 85.567725 -385.402996) (xy 85.5599 -385.433062) (xy 85.557106 -385.443222)
			(xy 85.559646 -385.463034) (xy 85.607144 -385.54533) (xy 85.623146 -385.557522) (xy 85.633306 -385.560062)
			(xy 85.662407 -385.568092) (xy 85.718373 -385.590721) (xy 85.77088 -385.620511) (xy 85.819014 -385.656944)
			(xy 85.861942 -385.699389) (xy 85.898917 -385.747109) (xy 85.929298 -385.799275) (xy 85.952558 -385.854982)
			(xy 85.968293 -385.913264) (xy 85.97623 -385.973108) (xy 85.976714 -386.003292) (xy 85.976589 -386.017427)
			(xy 85.974807 -386.045641) (xy 85.973158 -386.05968) (xy 85.972397 -386.068287) (xy 85.976037 -386.085167)
			(xy 85.98027 -386.0927) (xy 85.996018 -386.1181) (xy 86.000719 -386.125167) (xy 86.013831 -386.135932)
			(xy 86.021672 -386.139182) (xy 86.045062 -386.148343) (xy 86.088957 -386.172768) (xy 86.128651 -386.203554)
			(xy 86.163229 -386.239992) (xy 86.191897 -386.281241) (xy 86.213993 -386.326353) (xy 86.22901 -386.374289)
			(xy 86.236601 -386.423945) (xy 86.237064 -386.449062) (xy 86.236645 -386.473264) (xy 86.22957 -386.521149)
			(xy 86.215582 -386.567489) (xy 86.19498 -386.611291) (xy 86.181946 -386.631688) (xy 86.177156 -386.639644)
			(xy 86.173124 -386.657756) (xy 86.174072 -386.666994) (xy 86.17839 -386.697982) (xy 86.180075 -386.707277)
			(xy 86.189354 -386.723719) (xy 86.196424 -386.729986) (xy 86.218504 -386.748678) (xy 86.258277 -386.790687)
			(xy 86.292441 -386.837373) (xy 86.32045 -386.887991) (xy 86.341859 -386.941735) (xy 86.356325 -386.997747)
			(xy 86.363619 -387.055137) (xy 86.364064 -387.084062) (xy 86.363472 -387.117383) (xy 86.35381 -387.183322)
			(xy 86.334685 -387.247161) (xy 86.321138 -387.27761) (xy 86.31687 -387.28807) (xy 86.316984 -387.310636)
			(xy 86.32673 -387.330989) (xy 86.335108 -387.33857) (xy 86.35734 -387.357261) (xy 86.397404 -387.399314)
			(xy 86.431825 -387.446097) (xy 86.460052 -387.496859) (xy 86.48163 -387.550784) (xy 86.496213 -387.607006)
			(xy 86.503565 -387.664621) (xy 86.504018 -387.693662) (xy 86.503554 -387.722667) (xy 86.496242 -387.780216)
			(xy 86.481719 -387.836379) (xy 86.460217 -387.890258) (xy 86.43208 -387.940988) (xy 86.39776 -387.987757)
			(xy 86.357807 -388.029816) (xy 86.335616 -388.0485) (xy 86.328504 -388.054088) (xy 86.31936 -388.069328)
			(xy 86.30412 -388.152132) (xy 86.306914 -388.169404) (xy 86.311486 -388.177532) (xy 86.324057 -388.200721)
			(xy 86.341934 -388.250341) (xy 86.351036 -388.302292) (xy 86.351618 -388.328662) (xy 86.351514 -388.339943)
			(xy 86.349863 -388.362445) (xy 86.348316 -388.37362) (xy 86.347046 -388.38251) (xy 86.350602 -388.400036)
			(xy 86.394036 -388.470902) (xy 86.407752 -388.482078) (xy 86.416388 -388.484872) (xy 86.438639 -388.492792)
			(xy 86.48056 -388.514547) (xy 86.518632 -388.542495) (xy 86.551949 -388.575971) (xy 86.579716 -388.614175)
			(xy 86.590886 -388.634986) (xy 86.591394 -388.636002) (xy 86.983824 -389.314944) (xy 86.996558 -389.338309)
			(xy 87.014673 -389.388337) (xy 87.023882 -389.440741) (xy 87.024464 -389.467344) (xy 87.024078 -389.491339)
			(xy 87.016564 -389.538736) (xy 87.001728 -389.584375) (xy 86.979935 -389.62713) (xy 86.951722 -389.66595)
			(xy 86.917783 -389.699879) (xy 86.878955 -389.728081) (xy 86.836193 -389.749861) (xy 86.79055 -389.764684)
			(xy 86.743151 -389.772185) (xy 86.719156 -389.772652) (xy 86.695624 -389.772204) (xy 86.649117 -389.764997)
			(xy 86.604268 -389.75073) (xy 86.562145 -389.729741) (xy 86.523746 -389.70253) (xy 86.489984 -389.669742)
			(xy 86.461661 -389.632156) (xy 86.45017 -389.611616) (xy 86.449916 -389.611108) (xy 86.449408 -389.610346)
			(xy 86.051644 -388.922006) (xy 86.039732 -388.899336) (xy 86.022793 -388.851012) (xy 86.014132 -388.800542)
			(xy 86.013544 -388.77494) (xy 86.013544 -388.774432) (xy 86.013701 -388.763083) (xy 86.015478 -388.740453)
			(xy 86.0171 -388.72922) (xy 86.01837 -388.72033) (xy 86.014814 -388.703058) (xy 85.97138 -388.631938)
			(xy 85.95741 -388.621016) (xy 85.949028 -388.617968) (xy 85.926623 -388.609943) (xy 85.884405 -388.587982)
			(xy 85.846109 -388.559733) (xy 85.812663 -388.52588) (xy 85.784879 -388.487244) (xy 85.763431 -388.444764)
			(xy 85.748838 -388.399468) (xy 85.741455 -388.352456) (xy 85.741002 -388.328662) (xy 85.741567 -388.302289)
			(xy 85.750651 -388.25033) (xy 85.768539 -388.20071) (xy 85.781134 -388.177532) (xy 85.785706 -388.169404)
			(xy 85.7885 -388.152132) (xy 85.77326 -388.069328) (xy 85.764116 -388.054088) (xy 85.757004 -388.0485)
			(xy 85.734834 -388.029793) (xy 85.694887 -387.987732) (xy 85.660569 -387.940964) (xy 85.63243 -387.890238)
			(xy 85.61092 -387.836366) (xy 85.596384 -387.780209) (xy 85.589053 -387.722666) (xy 85.588602 -387.693662)
			(xy 85.589196 -387.660341) (xy 85.598856 -387.594402) (xy 85.617981 -387.530563) (xy 85.631528 -387.500114)
			(xy 85.635751 -387.489641) (xy 85.635646 -387.467089) (xy 85.625923 -387.44674) (xy 85.617558 -387.439154)
			(xy 85.595303 -387.420489) (xy 85.555238 -387.378433) (xy 85.520817 -387.331646) (xy 85.492592 -387.28088)
			(xy 85.471018 -387.22695) (xy 85.456441 -387.170723) (xy 85.449096 -387.113105) (xy 85.448648 -387.084062)
			(xy 85.449101 -387.055136) (xy 85.456384 -386.997743) (xy 85.470843 -386.941727) (xy 85.492247 -386.887979)
			(xy 85.520254 -386.837358) (xy 85.554417 -386.79067) (xy 85.594192 -386.74866) (xy 85.616288 -386.729986)
			(xy 85.623264 -386.723643) (xy 85.632519 -386.707236) (xy 85.634322 -386.697982) (xy 85.63864 -386.666994)
			(xy 85.639545 -386.657757) (xy 85.63552 -386.639657) (xy 85.630766 -386.631688) (xy 85.614455 -386.605844)
			(xy 85.590554 -386.549607) (xy 85.583268 -386.519928) (xy 85.581218 -386.511763) (xy 85.572511 -386.497363)
			(xy 85.56625 -386.491734) (xy 85.543136 -386.472684) (xy 85.536241 -386.46746) (xy 85.520022 -386.461481)
			(xy 85.511386 -386.461) (xy 85.48175 -386.459969) (xy 85.423086 -386.451323) (xy 85.366029 -386.435174)
			(xy 85.311535 -386.411794) (xy 85.260516 -386.381574) (xy 85.213826 -386.345019) (xy 85.172247 -386.302742)
			(xy 85.136474 -386.255449) (xy 85.107107 -386.203934) (xy 85.084637 -386.149058) (xy 85.069441 -386.091741)
			(xy 85.061773 -386.032941) (xy 85.061298 -386.003292) (xy 85.061818 -385.972229) (xy 85.070234 -385.910675)
			(xy 85.078062 -385.88061) (xy 85.080856 -385.87045) (xy 85.078316 -385.850638) (xy 85.030818 -385.768342)
			(xy 85.014816 -385.75615) (xy 85.004656 -385.75361) (xy 84.97554 -385.745631) (xy 84.919572 -385.722995)
			(xy 84.867066 -385.6932) (xy 84.818931 -385.65676) (xy 84.776005 -385.614309) (xy 84.739031 -385.566584)
			(xy 84.708652 -385.514412) (xy 84.685395 -385.4587) (xy 84.669663 -385.400414) (xy 84.661729 -385.340566)
			(xy 84.661248 -385.31038) (xy 84.66172 -385.279458) (xy 84.670003 -385.218171) (xy 84.686468 -385.158559)
			(xy 84.710817 -385.101709) (xy 84.726272 -385.074922) (xy 84.732368 -385.06527) (xy 84.734654 -385.042918)
			(xy 84.701126 -384.947668) (xy 84.685378 -384.931666) (xy 84.67471 -384.927602) (xy 84.651365 -384.918366)
			(xy 84.60752 -384.893914) (xy 84.567874 -384.863117) (xy 84.533338 -384.826682) (xy 84.504705 -384.785446)
			(xy 84.482634 -384.740356) (xy 84.46763 -384.692448) (xy 84.46004 -384.642823) (xy 84.459572 -384.617722)
			(xy 83.920838 -384.617722) (xy 83.920309 -384.644824) (xy 83.911499 -384.698307) (xy 83.903312 -384.724148)
			(xy 83.899502 -384.73507) (xy 83.902042 -384.757422) (xy 83.95462 -384.843274) (xy 83.97367 -384.85572)
			(xy 83.984846 -384.857498) (xy 84.014166 -384.862193) (xy 84.071337 -384.878244) (xy 84.125951 -384.901555)
			(xy 84.17709 -384.931736) (xy 84.223895 -384.968278) (xy 84.26558 -385.010569) (xy 84.301444 -385.057896)
			(xy 84.330884 -385.109466) (xy 84.353405 -385.16441) (xy 84.36863 -385.221806) (xy 84.376301 -385.280689)
			(xy 84.376768 -385.31038) (xy 84.376241 -385.341443) (xy 84.367829 -385.402996) (xy 84.360004 -385.433062)
			(xy 84.35721 -385.443222) (xy 84.35975 -385.463034) (xy 84.407248 -385.54533) (xy 84.42325 -385.557522)
			(xy 84.43341 -385.560062) (xy 84.462511 -385.56809) (xy 84.518478 -385.590719) (xy 84.570984 -385.620509)
			(xy 84.619119 -385.656943) (xy 84.662046 -385.699388) (xy 84.699021 -385.747108) (xy 84.729403 -385.799274)
			(xy 84.752662 -385.854982) (xy 84.768397 -385.913263) (xy 84.776334 -385.973108) (xy 84.776818 -386.003292)
			(xy 84.776693 -386.017427) (xy 84.774911 -386.045641) (xy 84.773262 -386.05968) (xy 84.772501 -386.068287)
			(xy 84.776141 -386.085167) (xy 84.780374 -386.0927) (xy 84.796122 -386.1181) (xy 84.800841 -386.125155)
			(xy 84.813934 -386.135938) (xy 84.821776 -386.139182) (xy 84.845135 -386.148385) (xy 84.888976 -386.172845)
			(xy 84.928619 -386.20365) (xy 84.963151 -386.240091) (xy 84.991781 -386.281331) (xy 85.013851 -386.326424)
			(xy 85.028854 -386.374333) (xy 85.036446 -386.42396) (xy 85.036914 -386.449062) (xy 85.036486 -386.473264)
			(xy 85.029413 -386.521148) (xy 85.015428 -386.567488) (xy 84.994829 -386.61129) (xy 84.981796 -386.631688)
			(xy 84.97701 -386.639646) (xy 84.972974 -386.657756) (xy 84.973922 -386.666994) (xy 84.97824 -386.697982)
			(xy 84.97991 -386.707281) (xy 84.989199 -386.723722) (xy 84.996274 -386.729986) (xy 85.018364 -386.748665)
			(xy 85.058136 -386.790678) (xy 85.092297 -386.837366) (xy 85.120304 -386.887987) (xy 85.141711 -386.941732)
			(xy 85.156176 -386.997746) (xy 85.163469 -387.055136) (xy 85.163914 -387.084062) (xy 85.163327 -387.117384)
			(xy 85.153664 -387.183322) (xy 85.134536 -387.247161) (xy 85.120988 -387.27761) (xy 85.116737 -387.288074)
			(xy 85.116851 -387.310634) (xy 85.126587 -387.330986) (xy 85.134958 -387.33857) (xy 85.15718 -387.357273)
			(xy 85.197246 -387.399322) (xy 85.23167 -387.446103) (xy 85.259899 -387.496863) (xy 85.281478 -387.550787)
			(xy 85.296062 -387.607007) (xy 85.303415 -387.664621) (xy 85.303868 -387.693662) (xy 85.303385 -387.722667)
			(xy 85.296075 -387.780213) (xy 85.281553 -387.836376) (xy 85.260054 -387.890254) (xy 85.231921 -387.940984)
			(xy 85.197604 -387.987754) (xy 85.157655 -388.029815) (xy 85.135466 -388.0485) (xy 85.128354 -388.054088)
			(xy 85.11921 -388.069328) (xy 85.10397 -388.152132) (xy 85.106764 -388.169404) (xy 85.111336 -388.177532)
			(xy 85.123911 -388.200719) (xy 85.141785 -388.25034) (xy 85.150886 -388.302291) (xy 85.151468 -388.328662)
			(xy 85.151364 -388.339943) (xy 85.149713 -388.362445) (xy 85.148166 -388.37362) (xy 85.146896 -388.38251)
			(xy 85.150452 -388.400036) (xy 85.193886 -388.470902) (xy 85.207602 -388.482078) (xy 85.216238 -388.484872)
			(xy 85.23848 -388.492816) (xy 85.280402 -388.514564) (xy 85.318476 -388.542506) (xy 85.351795 -388.575977)
			(xy 85.379565 -388.614177) (xy 85.390736 -388.634986) (xy 85.391244 -388.636002) (xy 85.783674 -389.314944)
			(xy 85.796483 -389.338284) (xy 85.814708 -389.388303) (xy 85.823975 -389.440726) (xy 85.824568 -389.467344)
			(xy 85.824201 -389.491353) (xy 85.816679 -389.538778) (xy 85.801826 -389.584442) (xy 85.78001 -389.627218)
			(xy 85.751767 -389.666052) (xy 85.717795 -389.699987) (xy 85.678929 -389.728187) (xy 85.636129 -389.749956)
			(xy 85.590449 -389.764758) (xy 85.543016 -389.772228) (xy 85.519006 -389.772652) (xy 85.495476 -389.772164)
			(xy 85.44897 -389.764964) (xy 85.404123 -389.750704) (xy 85.361999 -389.729722) (xy 85.3236 -389.702517)
			(xy 85.289837 -389.669735) (xy 85.261512 -389.632154) (xy 85.25002 -389.611616) (xy 85.249766 -389.611108)
			(xy 85.249258 -389.610346) (xy 84.851494 -388.922006) (xy 84.839621 -388.899328) (xy 84.822768 -388.850995)
			(xy 84.814194 -388.800532) (xy 84.813648 -388.77494) (xy 84.813648 -388.774432) (xy 84.81374 -388.763087)
			(xy 84.815394 -388.740458) (xy 84.81695 -388.72922) (xy 84.81822 -388.72033) (xy 84.814664 -388.703058)
			(xy 84.77123 -388.631938) (xy 84.75726 -388.621016) (xy 84.748878 -388.617968) (xy 84.726483 -388.609915)
			(xy 84.684264 -388.58796) (xy 84.645966 -388.559716) (xy 84.612518 -388.525868) (xy 84.584733 -388.487236)
			(xy 84.563283 -388.444759) (xy 84.548689 -388.399465) (xy 84.541305 -388.352455) (xy 84.540852 -388.328662)
			(xy 84.541424 -388.302289) (xy 84.550505 -388.250331) (xy 84.568391 -388.200711) (xy 84.580984 -388.177532)
			(xy 84.585556 -388.169404) (xy 84.58835 -388.152132) (xy 84.57311 -388.069328) (xy 84.563966 -388.054088)
			(xy 84.556854 -388.0485) (xy 84.534674 -388.029805) (xy 84.494729 -387.987741) (xy 84.460414 -387.94097)
			(xy 84.432277 -387.890242) (xy 84.410768 -387.836368) (xy 84.396233 -387.78021) (xy 84.388903 -387.722666)
			(xy 84.388452 -387.693662) (xy 84.389051 -387.660341) (xy 84.39871 -387.594403) (xy 84.417832 -387.530563)
			(xy 84.431378 -387.500114) (xy 84.435618 -387.489645) (xy 84.435513 -387.467087) (xy 84.425779 -387.446737)
			(xy 84.417408 -387.439154) (xy 84.395143 -387.420501) (xy 84.35508 -387.378442) (xy 84.320661 -387.331652)
			(xy 84.292438 -387.280884) (xy 84.270866 -387.226952) (xy 84.25629 -387.170725) (xy 84.248946 -387.113105)
			(xy 84.248498 -387.084062) (xy 84.248933 -387.055135) (xy 84.256217 -386.997741) (xy 84.270678 -386.941724)
			(xy 84.292084 -386.887975) (xy 84.320094 -386.837354) (xy 84.354261 -386.790667) (xy 84.39404 -386.748658)
			(xy 84.416138 -386.729986) (xy 84.423106 -386.723635) (xy 84.432367 -386.707234) (xy 84.434172 -386.697982)
			(xy 84.43849 -386.666994) (xy 84.439387 -386.657757) (xy 84.435366 -386.639658) (xy 84.430616 -386.631688)
			(xy 84.414309 -386.605842) (xy 84.390405 -386.549607) (xy 84.383118 -386.519928) (xy 84.381054 -386.511767)
			(xy 84.372357 -386.497366) (xy 84.3661 -386.491734) (xy 84.342986 -386.472684) (xy 84.336163 -386.467467)
			(xy 84.320065 -386.461504) (xy 84.31149 -386.461) (xy 84.281854 -386.459965) (xy 84.22319 -386.451319)
			(xy 84.166134 -386.435172) (xy 84.11164 -386.411792) (xy 84.06062 -386.381572) (xy 84.01393 -386.345017)
			(xy 83.972351 -386.30274) (xy 83.936578 -386.255448) (xy 83.907211 -386.203933) (xy 83.884741 -386.149058)
			(xy 83.869545 -386.09174) (xy 83.861877 -386.032941) (xy 83.861402 -386.003292) (xy 83.861921 -385.972229)
			(xy 83.870338 -385.910675) (xy 83.878166 -385.88061) (xy 83.88096 -385.87045) (xy 83.87842 -385.850638)
			(xy 83.830922 -385.768342) (xy 83.81492 -385.75615) (xy 83.80476 -385.75361) (xy 83.775645 -385.745627)
			(xy 83.719677 -385.722993) (xy 83.667171 -385.693197) (xy 83.619036 -385.656758) (xy 83.57611 -385.614308)
			(xy 83.539136 -385.566583) (xy 83.508757 -385.514412) (xy 83.485499 -385.4587) (xy 83.469767 -385.400414)
			(xy 83.461834 -385.340566) (xy 83.461352 -385.31038) (xy 83.46187 -385.279492) (xy 83.470177 -385.218276)
			(xy 83.486635 -385.158732) (xy 83.510948 -385.10194) (xy 83.526376 -385.075176) (xy 83.532218 -385.06527)
			(xy 83.534504 -385.042918) (xy 83.50123 -384.947668) (xy 83.485482 -384.931666) (xy 83.474814 -384.927602)
			(xy 83.451437 -384.918408) (xy 83.407539 -384.893992) (xy 83.367842 -384.863213) (xy 83.33326 -384.826781)
			(xy 83.304589 -384.785536) (xy 83.282491 -384.740426) (xy 83.267474 -384.692492) (xy 83.259884 -384.642838)
			(xy 83.259422 -384.617722) (xy 82.720942 -384.617722) (xy 82.720412 -384.644824) (xy 82.711603 -384.698307)
			(xy 82.703416 -384.724148) (xy 82.699606 -384.73507) (xy 82.702146 -384.757422) (xy 82.754724 -384.843274)
			(xy 82.773774 -384.85572) (xy 82.78495 -384.857498) (xy 82.814271 -384.86219) (xy 82.871441 -384.878241)
			(xy 82.926055 -384.901553) (xy 82.977194 -384.931734) (xy 83.024 -384.968277) (xy 83.065685 -385.010568)
			(xy 83.101548 -385.057895) (xy 83.130988 -385.109465) (xy 83.153509 -385.16441) (xy 83.168734 -385.221806)
			(xy 83.176405 -385.280689) (xy 83.176872 -385.31038) (xy 83.176349 -385.341506) (xy 83.167943 -385.403188)
			(xy 83.160108 -385.433316) (xy 83.157314 -385.443476) (xy 83.159854 -385.463542) (xy 83.207098 -385.54533)
			(xy 83.2231 -385.557522) (xy 83.23326 -385.560062) (xy 83.262371 -385.568056) (xy 83.318337 -385.590691)
			(xy 83.370843 -385.620487) (xy 83.418976 -385.656925) (xy 83.461902 -385.699374) (xy 83.498875 -385.747098)
			(xy 83.529255 -385.799267) (xy 83.552514 -385.854977) (xy 83.568248 -385.913261) (xy 83.576185 -385.973107)
			(xy 83.576668 -386.003292) (xy 83.576543 -386.017427) (xy 83.574761 -386.045641) (xy 83.573112 -386.05968)
			(xy 83.572357 -386.068287) (xy 83.575994 -386.085166) (xy 83.580224 -386.0927) (xy 83.595972 -386.1181)
			(xy 83.600688 -386.125156) (xy 83.613789 -386.135927) (xy 83.621626 -386.139182) (xy 83.645006 -386.148367)
			(xy 83.688902 -386.172787) (xy 83.728598 -386.203569) (xy 83.763178 -386.240002) (xy 83.791848 -386.281248)
			(xy 83.813946 -386.326358) (xy 83.828963 -386.374292) (xy 83.836555 -386.423946) (xy 83.837018 -386.449062)
			(xy 83.83659 -386.473264) (xy 83.829517 -386.521148) (xy 83.815531 -386.567488) (xy 83.794932 -386.61129)
			(xy 83.7819 -386.631688) (xy 83.777114 -386.639646) (xy 83.773078 -386.657756) (xy 83.774026 -386.666994)
			(xy 83.778344 -386.697982) (xy 83.780013 -386.707282) (xy 83.789302 -386.723722) (xy 83.796378 -386.729986)
			(xy 83.818469 -386.748664) (xy 83.85824 -386.790677) (xy 83.892401 -386.837366) (xy 83.920409 -386.887986)
			(xy 83.941815 -386.941732) (xy 83.95628 -386.997746) (xy 83.963573 -387.055136) (xy 83.964018 -387.084062)
			(xy 83.96343 -387.117384) (xy 83.953767 -387.183322) (xy 83.93464 -387.247161) (xy 83.921092 -387.27761)
			(xy 83.916839 -387.288074) (xy 83.916953 -387.310634) (xy 83.92669 -387.330986) (xy 83.935062 -387.33857)
			(xy 83.957284 -387.357272) (xy 83.99735 -387.399322) (xy 84.031774 -387.446102) (xy 84.060003 -387.496863)
			(xy 84.081582 -387.550787) (xy 84.096166 -387.607007) (xy 84.103519 -387.664621) (xy 84.103972 -387.693662)
			(xy 84.103488 -387.722667) (xy 84.096177 -387.780213) (xy 84.081656 -387.836375) (xy 84.060157 -387.890253)
			(xy 84.032024 -387.940984) (xy 83.997708 -387.987754) (xy 83.957758 -388.029815) (xy 83.93557 -388.0485)
			(xy 83.928458 -388.054088) (xy 83.919314 -388.069328) (xy 83.904074 -388.152132) (xy 83.906868 -388.169404)
			(xy 83.91144 -388.177532) (xy 83.924015 -388.200719) (xy 83.941889 -388.25034) (xy 83.95099 -388.302291)
			(xy 83.951572 -388.328662) (xy 83.951468 -388.339943) (xy 83.949817 -388.362445) (xy 83.94827 -388.37362)
			(xy 83.947 -388.38251) (xy 83.950556 -388.400036) (xy 83.99399 -388.470902) (xy 84.007706 -388.482078)
			(xy 84.016342 -388.484872) (xy 84.038585 -388.492814) (xy 84.080506 -388.514563) (xy 84.11858 -388.542506)
			(xy 84.151899 -388.575976) (xy 84.179669 -388.614177) (xy 84.19084 -388.634986) (xy 84.191348 -388.636002)
			(xy 84.583778 -389.314944) (xy 84.596588 -389.338284) (xy 84.614813 -389.388303) (xy 84.624079 -389.440726)
			(xy 84.624672 -389.467344) (xy 84.624301 -389.491353) (xy 84.616779 -389.538778) (xy 84.601927 -389.584441)
			(xy 84.580111 -389.627217) (xy 84.551868 -389.666051) (xy 84.517896 -389.699986) (xy 84.479031 -389.728185)
			(xy 84.436232 -389.749955) (xy 84.390552 -389.764757) (xy 84.343119 -389.772228) (xy 84.31911 -389.772652)
			(xy 84.295577 -389.772241) (xy 84.249067 -389.765027) (xy 84.204218 -389.750753) (xy 84.162095 -389.729759)
			(xy 84.123697 -389.702541) (xy 84.089936 -389.669748) (xy 84.061614 -389.632158) (xy 84.050124 -389.611616)
			(xy 84.04987 -389.611108) (xy 84.049362 -389.610346) (xy 83.651598 -388.922006) (xy 83.639725 -388.899328)
			(xy 83.622872 -388.850995) (xy 83.614298 -388.800532) (xy 83.613752 -388.77494) (xy 83.613752 -388.774432)
			(xy 83.613844 -388.763087) (xy 83.615498 -388.740458) (xy 83.617054 -388.72922) (xy 83.618324 -388.72033)
			(xy 83.614768 -388.703058) (xy 83.571334 -388.631938) (xy 83.557364 -388.621016) (xy 83.548982 -388.617968)
			(xy 83.526588 -388.609913) (xy 83.484369 -388.587959) (xy 83.446071 -388.559715) (xy 83.412623 -388.525867)
			(xy 83.384837 -388.487236) (xy 83.363387 -388.444758) (xy 83.348793 -388.399465) (xy 83.341409 -388.352455)
			(xy 83.340956 -388.328662) (xy 83.341527 -388.302289) (xy 83.350609 -388.250331) (xy 83.368495 -388.200711)
			(xy 83.381088 -388.177532) (xy 83.38566 -388.169404) (xy 83.388454 -388.152132) (xy 83.373214 -388.069328)
			(xy 83.36407 -388.054088) (xy 83.356958 -388.0485) (xy 83.334779 -388.029804) (xy 83.294834 -387.98774)
			(xy 83.260518 -387.94097) (xy 83.232381 -387.890242) (xy 83.210873 -387.836368) (xy 83.196337 -387.78021)
			(xy 83.189007 -387.722666) (xy 83.188556 -387.693662) (xy 83.189155 -387.660341) (xy 83.198813 -387.594403)
			(xy 83.217936 -387.530563) (xy 83.231482 -387.500114) (xy 83.23572 -387.489645) (xy 83.235615 -387.467087)
			(xy 83.225883 -387.446737) (xy 83.217512 -387.439154) (xy 83.195247 -387.4205) (xy 83.155185 -387.378441)
			(xy 83.120765 -387.331652) (xy 83.092543 -387.280883) (xy 83.07097 -387.226952) (xy 83.056394 -387.170725)
			(xy 83.04905 -387.113105) (xy 83.048602 -387.084062) (xy 83.049035 -387.055135) (xy 83.05632 -386.997741)
			(xy 83.07078 -386.941723) (xy 83.092187 -386.887975) (xy 83.120197 -386.837354) (xy 83.154364 -386.790666)
			(xy 83.194144 -386.748658) (xy 83.216242 -386.729986) (xy 83.223211 -386.723635) (xy 83.232471 -386.707234)
			(xy 83.234276 -386.697982) (xy 83.238594 -386.666994) (xy 83.239491 -386.657757) (xy 83.23547 -386.639658)
			(xy 83.23072 -386.631688) (xy 83.214414 -386.605841) (xy 83.190509 -386.549607) (xy 83.183222 -386.519928)
			(xy 83.181157 -386.511768) (xy 83.17246 -386.497366) (xy 83.166204 -386.491734) (xy 83.14309 -386.472684)
			(xy 83.136207 -386.467442) (xy 83.119979 -386.461474) (xy 83.11134 -386.461) (xy 83.081703 -386.460011)
			(xy 83.023037 -386.451359) (xy 82.96598 -386.435206) (xy 82.911485 -386.411821) (xy 82.860466 -386.381596)
			(xy 82.813777 -386.345037) (xy 82.772198 -386.302756) (xy 82.736426 -386.25546) (xy 82.70706 -386.203942)
			(xy 82.684591 -386.149064) (xy 82.669395 -386.091744) (xy 82.661727 -386.032942) (xy 82.661252 -386.003292)
			(xy 82.661773 -385.972229) (xy 82.670189 -385.910675) (xy 82.678016 -385.88061) (xy 82.68081 -385.87045)
			(xy 82.67827 -385.850638) (xy 82.630772 -385.768342) (xy 82.61477 -385.75615) (xy 82.60461 -385.75361)
			(xy 82.575517 -385.745593) (xy 82.519591 -385.722924) (xy 82.467126 -385.693106) (xy 82.419032 -385.656655)
			(xy 82.376143 -385.614202) (xy 82.3392 -385.566485) (xy 82.308846 -385.514328) (xy 82.285605 -385.458637)
			(xy 82.269879 -385.400375) (xy 82.261943 -385.340553) (xy 82.261456 -385.31038) (xy 82.261974 -385.279492)
			(xy 82.27028 -385.218276) (xy 82.286739 -385.158732) (xy 82.311052 -385.10194) (xy 82.32648 -385.075176)
			(xy 82.332322 -385.06527) (xy 82.334608 -385.042918) (xy 82.301334 -384.947668) (xy 82.285586 -384.931666)
			(xy 82.274918 -384.927602) (xy 82.251541 -384.918406) (xy 82.207644 -384.89399) (xy 82.167946 -384.863212)
			(xy 82.133364 -384.826781) (xy 82.104694 -384.785535) (xy 82.082595 -384.740426) (xy 82.067578 -384.692492)
			(xy 82.059988 -384.642838) (xy 82.059526 -384.617722) (xy 81.520792 -384.617722) (xy 81.52026 -384.644824)
			(xy 81.511452 -384.698306) (xy 81.503266 -384.724148) (xy 81.499456 -384.73507) (xy 81.501996 -384.757422)
			(xy 81.554574 -384.843274) (xy 81.573624 -384.85572) (xy 81.5848 -384.857498) (xy 81.614114 -384.862229)
			(xy 81.671284 -384.878274) (xy 81.725898 -384.90158) (xy 81.777038 -384.931756) (xy 81.823845 -384.968295)
			(xy 81.865531 -385.010582) (xy 81.901395 -385.057906) (xy 81.930836 -385.109473) (xy 81.953358 -385.164415)
			(xy 81.968583 -385.221809) (xy 81.976255 -385.28069) (xy 81.976722 -385.31038) (xy 81.976196 -385.341443)
			(xy 81.967784 -385.402996) (xy 81.959958 -385.433062) (xy 81.957164 -385.443222) (xy 81.959704 -385.463034)
			(xy 82.007202 -385.54533) (xy 82.023204 -385.557522) (xy 82.033364 -385.560062) (xy 82.062476 -385.568054)
			(xy 82.118442 -385.590689) (xy 82.170947 -385.620485) (xy 82.21908 -385.656924) (xy 82.262006 -385.699373)
			(xy 82.29898 -385.747097) (xy 82.32936 -385.799266) (xy 82.352618 -385.854976) (xy 82.368352 -385.91326)
			(xy 82.376289 -385.973107) (xy 82.376772 -386.003292) (xy 82.376646 -386.017427) (xy 82.374865 -386.045641)
			(xy 82.373216 -386.05968) (xy 82.372461 -386.068287) (xy 82.376098 -386.085166) (xy 82.380328 -386.0927)
			(xy 82.396076 -386.1181) (xy 82.40079 -386.125156) (xy 82.413893 -386.135927) (xy 82.42173 -386.139182)
			(xy 82.445111 -386.148365) (xy 82.489007 -386.172786) (xy 82.528702 -386.203567) (xy 82.563283 -386.240001)
			(xy 82.591952 -386.281248) (xy 82.61405 -386.326357) (xy 82.629067 -386.374292) (xy 82.636659 -386.423946)
			(xy 82.637122 -386.449062) (xy 82.636693 -386.473264) (xy 82.62962 -386.521148) (xy 82.615635 -386.567488)
			(xy 82.595036 -386.61129) (xy 82.582004 -386.631688) (xy 82.577218 -386.639646) (xy 82.573182 -386.657756)
			(xy 82.57413 -386.666994) (xy 82.578448 -386.697982) (xy 82.580145 -386.707274) (xy 82.589417 -386.723716)
			(xy 82.596482 -386.729986) (xy 82.618574 -386.748663) (xy 82.658345 -386.790677) (xy 82.692506 -386.837365)
			(xy 82.720513 -386.887986) (xy 82.741919 -386.941732) (xy 82.756384 -386.997746) (xy 82.763677 -387.055136)
			(xy 82.764122 -387.084062) (xy 82.763534 -387.117383) (xy 82.753871 -387.183322) (xy 82.734744 -387.247161)
			(xy 82.721196 -387.27761) (xy 82.716942 -387.288073) (xy 82.717056 -387.310634) (xy 82.726793 -387.330986)
			(xy 82.735166 -387.33857) (xy 82.757389 -387.357271) (xy 82.797455 -387.399321) (xy 82.831879 -387.446102)
			(xy 82.860107 -387.496862) (xy 82.881687 -387.550786) (xy 82.89627 -387.607007) (xy 82.903623 -387.664621)
			(xy 82.904076 -387.693662) (xy 82.90359 -387.722667) (xy 82.89628 -387.780213) (xy 82.881759 -387.836375)
			(xy 82.86026 -387.890253) (xy 82.832127 -387.940983) (xy 82.797811 -387.987754) (xy 82.757862 -388.029815)
			(xy 82.735674 -388.0485) (xy 82.728562 -388.054088) (xy 82.719418 -388.069328) (xy 82.704178 -388.152132)
			(xy 82.706972 -388.169404) (xy 82.711544 -388.177532) (xy 82.724119 -388.200718) (xy 82.741993 -388.25034)
			(xy 82.751094 -388.302291) (xy 82.751676 -388.328662) (xy 82.751572 -388.339943) (xy 82.749921 -388.362445)
			(xy 82.748374 -388.37362) (xy 82.747104 -388.382764) (xy 82.750406 -388.400036) (xy 82.794094 -388.471156)
			(xy 82.80781 -388.482078) (xy 82.816446 -388.484872) (xy 82.844608 -388.495077) (xy 82.896555 -388.524883)
			(xy 82.91957 -388.544054) (xy 82.941051 -388.563638) (xy 82.976867 -388.609415) (xy 82.99069 -388.634986)
			(xy 82.991452 -388.636256) (xy 83.383628 -389.314944) (xy 83.396363 -389.338309) (xy 83.414477 -389.388337)
			(xy 83.423686 -389.440741) (xy 83.424268 -389.467344) (xy 83.423878 -389.491338) (xy 83.416364 -389.538735)
			(xy 83.401528 -389.584374) (xy 83.379736 -389.627129) (xy 83.351523 -389.665949) (xy 83.317585 -389.699878)
			(xy 83.278757 -389.728079) (xy 83.235996 -389.74986) (xy 83.190354 -389.764684) (xy 83.142955 -389.772184)
			(xy 83.11896 -389.772652) (xy 83.095428 -389.772201) (xy 83.048921 -389.764994) (xy 83.004073 -389.750728)
			(xy 82.961949 -389.72974) (xy 82.92355 -389.702529) (xy 82.889788 -389.669741) (xy 82.861465 -389.632156)
			(xy 82.849974 -389.611616) (xy 82.84972 -389.611108) (xy 82.849212 -389.610346) (xy 82.451702 -388.921752)
			(xy 82.441129 -388.901826) (xy 82.425326 -388.859576) (xy 82.415919 -388.815459) (xy 82.41411 -388.792974)
			(xy 82.413602 -388.781798) (xy 82.413348 -388.774432) (xy 82.413506 -388.763083) (xy 82.415282 -388.740454)
			(xy 82.416904 -388.72922) (xy 82.418174 -388.72033) (xy 82.414618 -388.703058) (xy 82.371184 -388.631938)
			(xy 82.357468 -388.620762) (xy 82.348832 -388.617968) (xy 82.326422 -388.609994) (xy 82.284252 -388.587985)
			(xy 82.246005 -388.559704) (xy 82.212607 -388.525834) (xy 82.184865 -388.487194) (xy 82.163451 -388.44472)
			(xy 82.148882 -388.399438) (xy 82.141511 -388.352446) (xy 82.14106 -388.328662) (xy 82.141631 -388.302289)
			(xy 82.150713 -388.250331) (xy 82.168599 -388.200711) (xy 82.181192 -388.177532) (xy 82.185764 -388.169404)
			(xy 82.188558 -388.152132) (xy 82.173318 -388.069328) (xy 82.164174 -388.054088) (xy 82.157062 -388.0485)
			(xy 82.134883 -388.029803) (xy 82.094938 -387.987739) (xy 82.060623 -387.940969) (xy 82.032485 -387.890241)
			(xy 82.010977 -387.836368) (xy 81.996441 -387.78021) (xy 81.989111 -387.722666) (xy 81.98866 -387.693662)
			(xy 81.989258 -387.660341) (xy 81.998917 -387.594403) (xy 82.01804 -387.530563) (xy 82.031586 -387.500114)
			(xy 82.035823 -387.489645) (xy 82.035718 -387.467087) (xy 82.025986 -387.446737) (xy 82.017616 -387.439154)
			(xy 81.995352 -387.420499) (xy 81.955289 -387.378441) (xy 81.92087 -387.331651) (xy 81.892647 -387.280883)
			(xy 81.871074 -387.226952) (xy 81.856498 -387.170725) (xy 81.849154 -387.113105) (xy 81.848706 -387.084062)
			(xy 81.849174 -387.055136) (xy 81.856457 -386.997745) (xy 81.870914 -386.94173) (xy 81.892316 -386.887983)
			(xy 81.92032 -386.837361) (xy 81.95448 -386.790672) (xy 81.994252 -386.748661) (xy 82.016346 -386.729986)
			(xy 82.023315 -386.723636) (xy 82.032575 -386.707234) (xy 82.03438 -386.697982) (xy 82.038698 -386.666994)
			(xy 82.039594 -386.657757) (xy 82.035574 -386.639659) (xy 82.030824 -386.631688) (xy 82.014518 -386.605841)
			(xy 81.990613 -386.549607) (xy 81.983326 -386.519928) (xy 81.98126 -386.511768) (xy 81.972564 -386.497366)
			(xy 81.966308 -386.491734) (xy 81.943194 -386.472684) (xy 81.93631 -386.467443) (xy 81.920083 -386.461475)
			(xy 81.911444 -386.461) (xy 81.881807 -386.460007) (xy 81.823141 -386.451356) (xy 81.766084 -386.435203)
			(xy 81.71159 -386.411818) (xy 81.660571 -386.381594) (xy 81.613881 -386.345035) (xy 81.572302 -386.302754)
			(xy 81.53653 -386.255459) (xy 81.507164 -386.203942) (xy 81.484695 -386.149063) (xy 81.469499 -386.091744)
			(xy 81.461831 -386.032942) (xy 81.461356 -386.003292) (xy 81.461877 -385.972229) (xy 81.470293 -385.910675)
			(xy 81.47812 -385.88061) (xy 81.480914 -385.87045) (xy 81.478374 -385.850638) (xy 81.430876 -385.768342)
			(xy 81.414874 -385.75615) (xy 81.404714 -385.75361) (xy 81.37559 -385.745658) (xy 81.319623 -385.723018)
			(xy 81.267117 -385.693218) (xy 81.218984 -385.656774) (xy 81.176059 -385.61432) (xy 81.139086 -385.566592)
			(xy 81.108708 -385.514418) (xy 81.085452 -385.458704) (xy 81.069721 -385.400416) (xy 81.061787 -385.340567)
			(xy 81.061306 -385.31038) (xy 81.061831 -385.279492) (xy 81.070136 -385.218276) (xy 81.086593 -385.158733)
			(xy 81.110903 -385.101941) (xy 81.12633 -385.075176) (xy 81.132172 -385.06527) (xy 81.134458 -385.042918)
			(xy 81.101184 -384.947668) (xy 81.085436 -384.931666) (xy 81.074768 -384.927602) (xy 81.051381 -384.918433)
			(xy 81.007484 -384.894011) (xy 80.967789 -384.863227) (xy 80.933209 -384.826792) (xy 80.90454 -384.785543)
			(xy 80.882443 -384.740431) (xy 80.867427 -384.692495) (xy 80.859838 -384.642839) (xy 80.859376 -384.617722)
			(xy 80.320896 -384.617722) (xy 80.320364 -384.644824) (xy 80.311556 -384.698306) (xy 80.30337 -384.724148)
			(xy 80.29956 -384.73507) (xy 80.3021 -384.757422) (xy 80.354678 -384.843274) (xy 80.373728 -384.85572)
			(xy 80.384904 -384.857498) (xy 80.414219 -384.862226) (xy 80.471389 -384.878272) (xy 80.526003 -384.901578)
			(xy 80.577143 -384.931755) (xy 80.623949 -384.968293) (xy 80.665635 -385.010581) (xy 80.701499 -385.057905)
			(xy 80.73094 -385.109472) (xy 80.753462 -385.164414) (xy 80.768687 -385.221809) (xy 80.776359 -385.28069)
			(xy 80.776826 -385.31038) (xy 80.7763 -385.341443) (xy 80.767888 -385.402996) (xy 80.760062 -385.433062)
			(xy 80.757268 -385.443222) (xy 80.759808 -385.463034) (xy 80.807306 -385.54533) (xy 80.823308 -385.557522)
			(xy 80.833468 -385.560062) (xy 80.862581 -385.568051) (xy 80.918547 -385.590687) (xy 80.971052 -385.620483)
			(xy 81.019185 -385.656922) (xy 81.062111 -385.699372) (xy 81.099084 -385.747096) (xy 81.129464 -385.799266)
			(xy 81.152722 -385.854976) (xy 81.168456 -385.91326) (xy 81.176393 -385.973107) (xy 81.176876 -386.003292)
			(xy 81.17675 -386.017427) (xy 81.174969 -386.045641) (xy 81.17332 -386.05968) (xy 81.172564 -386.068287)
			(xy 81.176201 -386.085166) (xy 81.180432 -386.0927) (xy 81.19618 -386.1181) (xy 81.20088 -386.12517)
			(xy 81.213986 -386.135945) (xy 81.221834 -386.139182) (xy 81.245183 -386.148408) (xy 81.289026 -386.172863)
			(xy 81.32867 -386.203663) (xy 81.363205 -386.2401) (xy 81.391836 -386.281338) (xy 81.413907 -386.326428)
			(xy 81.428911 -386.374336) (xy 81.436503 -386.423961) (xy 81.436972 -386.449062) (xy 81.436551 -386.473264)
			(xy 81.429477 -386.521149) (xy 81.41549 -386.567489) (xy 81.394888 -386.611291) (xy 81.381854 -386.631688)
			(xy 81.377065 -386.639644) (xy 81.373032 -386.657756) (xy 81.37398 -386.666994) (xy 81.378298 -386.697982)
			(xy 81.379981 -386.707278) (xy 81.389261 -386.72372) (xy 81.396332 -386.729986) (xy 81.418413 -386.748676)
			(xy 81.458187 -386.790686) (xy 81.49235 -386.837372) (xy 81.520359 -386.88799) (xy 81.541767 -386.941734)
			(xy 81.556233 -386.997747) (xy 81.563527 -387.055137) (xy 81.563972 -387.084062) (xy 81.563379 -387.117383)
			(xy 81.553718 -387.183322) (xy 81.534593 -387.247161) (xy 81.521046 -387.27761) (xy 81.516776 -387.288069)
			(xy 81.516889 -387.310636) (xy 81.526637 -387.33099) (xy 81.535016 -387.33857) (xy 81.55725 -387.357259)
			(xy 81.597313 -387.399312) (xy 81.631734 -387.446096) (xy 81.659961 -387.496858) (xy 81.681538 -387.550784)
			(xy 81.696121 -387.607006) (xy 81.703473 -387.664621) (xy 81.703926 -387.693662) (xy 81.703459 -387.722667)
			(xy 81.696147 -387.780215) (xy 81.681625 -387.836378) (xy 81.660123 -387.890257) (xy 81.631987 -387.940987)
			(xy 81.597667 -387.987757) (xy 81.557714 -388.029816) (xy 81.535524 -388.0485) (xy 81.528412 -388.054088)
			(xy 81.519268 -388.069328) (xy 81.504028 -388.152132) (xy 81.506822 -388.169404) (xy 81.511394 -388.177532)
			(xy 81.523965 -388.200721) (xy 81.541842 -388.250341) (xy 81.550944 -388.302292) (xy 81.551526 -388.328662)
			(xy 81.551423 -388.339943) (xy 81.549771 -388.362445) (xy 81.548224 -388.37362) (xy 81.546954 -388.38251)
			(xy 81.55051 -388.400036) (xy 81.593944 -388.470902) (xy 81.60766 -388.482078) (xy 81.616296 -388.484872)
			(xy 81.638548 -388.492788) (xy 81.680469 -388.514544) (xy 81.718541 -388.542494) (xy 81.751857 -388.57597)
			(xy 81.779624 -388.614175) (xy 81.790794 -388.634986) (xy 81.791302 -388.636002) (xy 82.183732 -389.314944)
			(xy 82.196467 -389.338308) (xy 82.214581 -389.388337) (xy 82.22379 -389.440741) (xy 82.224372 -389.467344)
			(xy 82.223978 -389.491338) (xy 82.216464 -389.538735) (xy 82.201628 -389.584373) (xy 82.179836 -389.627128)
			(xy 82.151624 -389.665948) (xy 82.117687 -389.699876) (xy 82.078859 -389.728078) (xy 82.036099 -389.749859)
			(xy 81.990457 -389.764683) (xy 81.943058 -389.772184) (xy 81.919064 -389.772652) (xy 81.895533 -389.772198)
			(xy 81.849025 -389.764992) (xy 81.804177 -389.750726) (xy 81.762053 -389.729738) (xy 81.723655 -389.702528)
			(xy 81.689892 -389.669741) (xy 81.661569 -389.632155) (xy 81.650078 -389.611616) (xy 81.649824 -389.611108)
			(xy 81.649316 -389.610346) (xy 81.251552 -388.922006) (xy 81.239641 -388.899336) (xy 81.222701 -388.851012)
			(xy 81.21404 -388.800542) (xy 81.213452 -388.77494) (xy 81.213452 -388.774432) (xy 81.21361 -388.763083)
			(xy 81.215386 -388.740454) (xy 81.217008 -388.72922) (xy 81.218278 -388.72033) (xy 81.214722 -388.703058)
			(xy 81.171288 -388.631938) (xy 81.157318 -388.621016) (xy 81.148936 -388.617968) (xy 81.126532 -388.609939)
			(xy 81.084314 -388.587979) (xy 81.046018 -388.55973) (xy 81.012572 -388.525878) (xy 80.984788 -388.487243)
			(xy 80.963339 -388.444763) (xy 80.948746 -388.399468) (xy 80.941363 -388.352456) (xy 80.94091 -388.328662)
			(xy 80.941474 -388.302289) (xy 80.950558 -388.25033) (xy 80.968447 -388.20071) (xy 80.981042 -388.177532)
			(xy 80.985614 -388.169404) (xy 80.988408 -388.152132) (xy 80.973168 -388.069328) (xy 80.964024 -388.054088)
			(xy 80.956912 -388.0485) (xy 80.934744 -388.029791) (xy 80.894796 -387.98773) (xy 80.860478 -387.940963)
			(xy 80.832339 -387.890238) (xy 80.810829 -387.836365) (xy 80.796292 -387.780209) (xy 80.788961 -387.722666)
			(xy 80.78851 -387.693662) (xy 80.789113 -387.660341) (xy 80.798771 -387.594403) (xy 80.817891 -387.530564)
			(xy 80.831436 -387.500114) (xy 80.835657 -387.489641) (xy 80.835551 -387.467089) (xy 80.82583 -387.44674)
			(xy 80.817466 -387.439154) (xy 80.795192 -387.420512) (xy 80.755131 -387.37845) (xy 80.720714 -387.331657)
			(xy 80.692493 -387.280887) (xy 80.670922 -387.226954) (xy 80.656348 -387.170726) (xy 80.649004 -387.113105)
			(xy 80.648556 -387.084062) (xy 80.649006 -387.055136) (xy 80.65629 -386.997743) (xy 80.670749 -386.941726)
			(xy 80.692153 -386.887979) (xy 80.72016 -386.837357) (xy 80.754324 -386.790669) (xy 80.7941 -386.74866)
			(xy 80.816196 -386.729986) (xy 80.823173 -386.723644) (xy 80.832427 -386.707236) (xy 80.83423 -386.697982)
			(xy 80.838548 -386.666994) (xy 80.839452 -386.657757) (xy 80.835427 -386.639658) (xy 80.830674 -386.631688)
			(xy 80.814364 -386.605844) (xy 80.790462 -386.549607) (xy 80.783176 -386.519928) (xy 80.781123 -386.511764)
			(xy 80.772418 -386.497363) (xy 80.766158 -386.491734) (xy 80.743044 -386.472684) (xy 80.736205 -386.46749)
			(xy 80.720119 -386.461513) (xy 80.711548 -386.461) (xy 80.681911 -386.460003) (xy 80.623246 -386.451353)
			(xy 80.566188 -386.4352) (xy 80.511694 -386.411816) (xy 80.460675 -386.381592) (xy 80.413985 -386.345034)
			(xy 80.372406 -386.302753) (xy 80.336634 -386.255458) (xy 80.307268 -386.203941) (xy 80.284799 -386.149063)
			(xy 80.269603 -386.091743) (xy 80.261935 -386.032942) (xy 80.26146 -386.003292) (xy 80.261981 -385.972229)
			(xy 80.270397 -385.910675) (xy 80.278224 -385.88061) (xy 80.281018 -385.87045) (xy 80.278478 -385.850638)
			(xy 80.23098 -385.768342) (xy 80.214978 -385.75615) (xy 80.204818 -385.75361) (xy 80.193097 -385.750462)
			(xy 80.169971 -385.743093) (xy 80.15859 -385.738878) (xy 80.146144 -385.734306) (xy 80.120236 -385.738116)
			(xy 80.030828 -385.806696) (xy 80.020414 -385.830826) (xy 80.021684 -385.84378) (xy 80.023208 -385.87553)
			(xy 80.02282 -385.899206) (xy 80.016088 -385.946077) (xy 80.002725 -385.991503) (xy 79.993236 -386.013198)
			(xy 79.988918 -386.022596) (xy 79.988156 -386.042662) (xy 80.020414 -386.129022) (xy 80.03413 -386.143754)
			(xy 80.043528 -386.148072) (xy 80.067892 -386.159773) (xy 80.112763 -386.189897) (xy 80.152142 -386.226913)
			(xy 80.184981 -386.269836) (xy 80.210408 -386.317526) (xy 80.227747 -386.368714) (xy 80.236536 -386.42204)
			(xy 80.237076 -386.449062) (xy 80.236655 -386.473264) (xy 80.229581 -386.521149) (xy 80.215593 -386.567489)
			(xy 80.194992 -386.611291) (xy 80.181958 -386.631688) (xy 80.177169 -386.639644) (xy 80.173136 -386.657756)
			(xy 80.174084 -386.666994) (xy 80.178402 -386.697982) (xy 80.180083 -386.707278) (xy 80.189365 -386.72372)
			(xy 80.196436 -386.729986) (xy 80.218518 -386.748675) (xy 80.258291 -386.790685) (xy 80.292454 -386.837371)
			(xy 80.320463 -386.88799) (xy 80.341871 -386.941734) (xy 80.356337 -386.997747) (xy 80.363631 -387.055137)
			(xy 80.364076 -387.084062) (xy 80.363483 -387.117383) (xy 80.353821 -387.183322) (xy 80.334697 -387.247161)
			(xy 80.32115 -387.27761) (xy 80.316878 -387.288069) (xy 80.316992 -387.310636) (xy 80.32674 -387.33099)
			(xy 80.33512 -387.33857) (xy 80.357354 -387.357258) (xy 80.397418 -387.399312) (xy 80.431839 -387.446096)
			(xy 80.460065 -387.496858) (xy 80.481643 -387.550784) (xy 80.496225 -387.607006) (xy 80.503577 -387.664621)
			(xy 80.50403 -387.693662) (xy 80.503561 -387.722667) (xy 80.49625 -387.780215) (xy 80.481727 -387.836378)
			(xy 80.460226 -387.890257) (xy 80.43209 -387.940987) (xy 80.397771 -387.987757) (xy 80.357818 -388.029816)
			(xy 80.335628 -388.0485) (xy 80.328516 -388.054088) (xy 80.319372 -388.069328) (xy 80.304132 -388.152132)
			(xy 80.306926 -388.169404) (xy 80.311498 -388.177532) (xy 80.32407 -388.20072) (xy 80.341946 -388.250341)
			(xy 80.351048 -388.302292) (xy 80.35163 -388.328662) (xy 80.351527 -388.339943) (xy 80.349875 -388.362445)
			(xy 80.348328 -388.37362) (xy 80.347058 -388.38251) (xy 80.350614 -388.400036) (xy 80.394048 -388.470902)
			(xy 80.407764 -388.482078) (xy 80.4164 -388.484872) (xy 80.438653 -388.492786) (xy 80.480573 -388.514543)
			(xy 80.518645 -388.542493) (xy 80.551962 -388.575969) (xy 80.579729 -388.614175) (xy 80.590898 -388.634986)
			(xy 80.591406 -388.636002) (xy 80.983836 -389.314944) (xy 80.996571 -389.338308) (xy 81.014685 -389.388337)
			(xy 81.023894 -389.440741) (xy 81.024476 -389.467344) (xy 81.024078 -389.491338) (xy 81.016564 -389.538734)
			(xy 81.001729 -389.584372) (xy 80.979937 -389.627127) (xy 80.951725 -389.665946) (xy 80.917788 -389.699875)
			(xy 80.878962 -389.728077) (xy 80.836201 -389.749858) (xy 80.79056 -389.764682) (xy 80.743162 -389.772184)
			(xy 80.719168 -389.772652) (xy 80.695637 -389.772194) (xy 80.649129 -389.764989) (xy 80.604281 -389.750724)
			(xy 80.562158 -389.729737) (xy 80.523759 -389.702527) (xy 80.489997 -389.66974) (xy 80.461673 -389.632155)
			(xy 80.450182 -389.611616) (xy 80.449928 -389.611108) (xy 80.44942 -389.610346) (xy 80.051656 -388.922006)
			(xy 80.039745 -388.899335) (xy 80.022805 -388.851011) (xy 80.014144 -388.800542) (xy 80.013556 -388.77494)
			(xy 80.013556 -388.774432) (xy 80.013714 -388.763083) (xy 80.01549 -388.740454) (xy 80.017112 -388.72922)
			(xy 80.018382 -388.72033) (xy 80.014826 -388.703058) (xy 79.971392 -388.631938) (xy 79.957422 -388.621016)
			(xy 79.94904 -388.617968) (xy 79.926637 -388.609937) (xy 79.884419 -388.587977) (xy 79.846122 -388.559729)
			(xy 79.812676 -388.525877) (xy 79.784892 -388.487243) (xy 79.763443 -388.444763) (xy 79.74885 -388.399467)
			(xy 79.741467 -388.352456) (xy 79.741014 -388.328662) (xy 79.741578 -388.302289) (xy 79.750661 -388.25033)
			(xy 79.768551 -388.20071) (xy 79.781146 -388.177532) (xy 79.785718 -388.169404) (xy 79.788512 -388.152132)
			(xy 79.773272 -388.069328) (xy 79.764128 -388.054088) (xy 79.757016 -388.0485) (xy 79.734849 -388.02979)
			(xy 79.694901 -387.98773) (xy 79.660583 -387.940963) (xy 79.632443 -387.890237) (xy 79.610933 -387.836365)
			(xy 79.596396 -387.780208) (xy 79.589065 -387.722666) (xy 79.588614 -387.693662) (xy 79.589216 -387.660341)
			(xy 79.598874 -387.594403) (xy 79.617995 -387.530564) (xy 79.63154 -387.500114) (xy 79.635792 -387.489649)
			(xy 79.635687 -387.467086) (xy 79.625947 -387.446734) (xy 79.61757 -387.439154) (xy 79.595297 -387.420511)
			(xy 79.555236 -387.378449) (xy 79.520819 -387.331657) (xy 79.492598 -387.280887) (xy 79.471027 -387.226954)
			(xy 79.456452 -387.170726) (xy 79.449108 -387.113105) (xy 79.44866 -387.084062) (xy 79.449109 -387.055135)
			(xy 79.456392 -386.997743) (xy 79.470852 -386.941726) (xy 79.492256 -386.887978) (xy 79.520263 -386.837357)
			(xy 79.554428 -386.790669) (xy 79.594204 -386.748659) (xy 79.6163 -386.729986) (xy 79.623278 -386.723645)
			(xy 79.632531 -386.707236) (xy 79.634334 -386.697982) (xy 79.638652 -386.666994) (xy 79.639555 -386.657757)
			(xy 79.635531 -386.639658) (xy 79.630778 -386.631688) (xy 79.617788 -386.611267) (xy 79.597209 -386.567464)
			(xy 79.583222 -386.521133) (xy 79.576127 -386.47326) (xy 79.57566 -386.449062) (xy 79.57604 -386.425386)
			(xy 79.582774 -386.378515) (xy 79.596141 -386.333088) (xy 79.605632 -386.311394) (xy 79.60995 -386.301996)
			(xy 79.610712 -386.28193) (xy 79.578454 -386.19557) (xy 79.564738 -386.180838) (xy 79.55534 -386.17652)
			(xy 79.530966 -386.16484) (xy 79.486096 -386.134711) (xy 79.446719 -386.097691) (xy 79.413881 -386.054764)
			(xy 79.388456 -386.007071) (xy 79.371119 -385.955881) (xy 79.362331 -385.902553) (xy 79.361792 -385.87553)
			(xy 77.874744 -385.87553) (xy 77.845327 -385.912288) (xy 77.823314 -385.93395) (xy 77.814678 -385.942332)
			(xy 77.80655 -385.964684) (xy 77.818488 -386.069078) (xy 77.831442 -386.08889) (xy 77.841856 -386.09524)
			(xy 77.867194 -386.110751) (xy 77.914047 -386.147276) (xy 77.955779 -386.189558) (xy 77.991688 -386.236885)
			(xy 78.021169 -386.288462) (xy 78.043727 -386.343421) (xy 78.058982 -386.400837) (xy 78.066677 -386.459744)
			(xy 78.067154 -386.489448) (xy 78.06668 -386.520107) (xy 78.058488 -386.580875) (xy 78.042258 -386.640005)
			(xy 78.018279 -386.69644) (xy 77.986982 -386.749169) (xy 77.948926 -386.797248) (xy 77.9272 -386.818886)
			(xy 77.919463 -386.827199) (xy 77.911465 -386.84842) (xy 77.913372 -386.871017) (xy 77.918564 -386.881116)
			(xy 77.9327 -386.906586) (xy 77.952771 -386.961264) (xy 77.962934 -387.018617) (xy 77.963522 -387.04774)
			(xy 77.963012 -387.073727) (xy 77.954882 -387.125062) (xy 77.938821 -387.174492) (xy 77.915225 -387.220802)
			(xy 77.884675 -387.26285) (xy 77.847924 -387.299601) (xy 77.805876 -387.330151) (xy 77.759566 -387.353747)
			(xy 77.710136 -387.369808) (xy 77.658801 -387.377938) (xy 77.606827 -387.377938) (xy 77.555492 -387.369808)
			(xy 77.506062 -387.353747) (xy 77.459752 -387.330151) (xy 77.417704 -387.299601) (xy 77.380953 -387.26285)
			(xy 77.350403 -387.220802) (xy 77.326807 -387.174492) (xy 77.310746 -387.125062) (xy 77.302616 -387.073727)
			(xy 77.302106 -387.04774) (xy 77.302526 -387.023227) (xy 77.30971 -386.97473) (xy 77.323987 -386.927829)
			(xy 77.33411 -386.9055) (xy 77.338485 -386.895032) (xy 77.338531 -386.872371) (xy 77.328805 -386.851903)
			(xy 77.320394 -386.844286) (xy 77.298182 -386.825611) (xy 77.258171 -386.783577) (xy 77.223798 -386.736821)
			(xy 77.195613 -386.686093) (xy 77.174071 -386.632208) (xy 77.159517 -386.576031) (xy 77.152184 -386.518464)
			(xy 77.151738 -386.489448) (xy 77.152227 -386.458567) (xy 77.160545 -386.397369) (xy 77.177022 -386.337847)
			(xy 77.20136 -386.281083) (xy 77.233114 -386.22811) (xy 77.271708 -386.179893) (xy 77.293724 -386.158232)
			(xy 77.30236 -386.14985) (xy 77.310488 -386.127498) (xy 77.29855 -386.023104) (xy 77.285596 -386.003292)
			(xy 77.275182 -385.996942) (xy 77.251793 -385.982726) (xy 77.208283 -385.949519) (xy 77.169051 -385.911354)
			(xy 77.134656 -385.868776) (xy 77.105593 -385.822395) (xy 77.093572 -385.797806) (xy 77.087476 -385.785106)
			(xy 77.064616 -385.769612) (xy 76.947776 -385.762246) (xy 76.923392 -385.774692) (xy 76.915772 -385.78663)
			(xy 76.900682 -385.809509) (xy 76.864991 -385.851102) (xy 76.823716 -385.887159) (xy 76.777706 -385.916937)
			(xy 76.727907 -385.939825) (xy 76.675346 -385.95535) (xy 76.621103 -385.963194) (xy 76.5937 -385.963668)
			(xy 76.566446 -385.963262) (xy 76.512493 -385.955505) (xy 76.460192 -385.940148) (xy 76.41061 -385.917505)
			(xy 76.364755 -385.888035) (xy 76.32356 -385.85234) (xy 76.287865 -385.811145) (xy 76.258395 -385.76529)
			(xy 76.235752 -385.715708) (xy 76.220395 -385.663407) (xy 76.212638 -385.609454) (xy 69.764491 -385.609454)
			(xy 69.772276 -385.61518) (xy 69.798364 -385.63285) (xy 69.84639 -385.673642) (xy 69.889013 -385.72005)
			(xy 69.925581 -385.771365) (xy 69.955534 -385.826802) (xy 69.978415 -385.885512) (xy 69.993874 -385.946598)
			(xy 70.001673 -386.009124) (xy 70.002146 -386.04063) (xy 70.001681 -386.071361) (xy 69.994269 -386.132374)
			(xy 69.979558 -386.192048) (xy 69.957762 -386.249515) (xy 69.929199 -386.303936) (xy 69.894284 -386.354518)
			(xy 69.853528 -386.400522) (xy 69.807524 -386.441279) (xy 69.756943 -386.476195) (xy 69.702523 -386.504759)
			(xy 69.645056 -386.526556) (xy 69.585381 -386.541268) (xy 69.524369 -386.54868) (xy 69.493638 -386.549138)
			(xy 69.462135 -386.548666) (xy 69.399611 -386.540881) (xy 69.33853 -386.525426) (xy 69.279828 -386.502537)
			(xy 69.224406 -386.472567) (xy 69.19849 -386.45465) (xy 69.187568 -386.44703) (xy 69.16166 -386.444236)
			(xy 69.057266 -386.488178) (xy 69.041264 -386.508752) (xy 69.039232 -386.52196) (xy 69.033748 -386.554301)
			(xy 69.015536 -386.61732) (xy 68.98937 -386.677473) (xy 68.955685 -386.733761) (xy 68.91504 -386.78525)
			(xy 68.86811 -386.831083) (xy 68.815676 -386.870499) (xy 68.758607 -386.902844) (xy 68.697852 -386.927581)
			(xy 68.63442 -386.944298) (xy 68.569365 -386.952717) (xy 68.536566 -386.953252) (xy 68.505162 -386.952783)
			(xy 68.442833 -386.945042) (xy 68.381931 -386.929684) (xy 68.323386 -386.906941) (xy 68.268087 -386.87716)
			(xy 68.216877 -386.840795) (xy 68.170537 -386.798399) (xy 68.129771 -386.750618) (xy 68.095201 -386.69818)
			(xy 68.067353 -386.641883) (xy 68.046651 -386.582585) (xy 68.033411 -386.521189) (xy 68.03009 -386.489956)
			(xy 68.029074 -386.479796) (xy 68.020438 -386.462778) (xy 67.952366 -386.403342) (xy 67.934078 -386.396992)
			(xy 67.923918 -386.3975) (xy 67.899788 -386.398008) (xy 67.869057 -386.397543) (xy 67.808045 -386.390134)
			(xy 67.74837 -386.375424) (xy 67.690903 -386.353628) (xy 67.636483 -386.325065) (xy 67.585902 -386.29015)
			(xy 67.539898 -386.249394) (xy 67.499142 -386.203389) (xy 67.464229 -386.152807) (xy 67.435667 -386.098386)
			(xy 67.413873 -386.040919) (xy 67.399164 -385.981243) (xy 67.391756 -385.920231) (xy 67.39128 -385.8895)
			(xy 67.391711 -385.858718) (xy 67.399112 -385.797602) (xy 67.413841 -385.737827) (xy 67.435683 -385.680269)
			(xy 67.464317 -385.625771) (xy 67.48145 -385.600194) (xy 67.486525 -385.592203) (xy 67.490945 -385.573809)
			(xy 67.490086 -385.56438) (xy 67.485768 -385.533646) (xy 67.484029 -385.524411) (xy 67.474913 -385.507995)
			(xy 67.467988 -385.501642) (xy 67.446146 -385.482969) (xy 67.406828 -385.44106) (xy 67.37307 -385.394556)
			(xy 67.345404 -385.344189) (xy 67.324265 -385.290753) (xy 67.309988 -385.23509) (xy 67.302796 -385.178077)
			(xy 67.30238 -385.149344) (xy 67.302821 -385.120708) (xy 67.30996 -385.063883) (xy 67.324133 -385.008392)
			(xy 67.345119 -384.955103) (xy 67.372588 -384.904849) (xy 67.388994 -384.881374) (xy 67.394579 -384.872823)
			(xy 67.399124 -384.852929) (xy 67.395608 -384.832827) (xy 67.390518 -384.82397) (xy 67.373021 -384.795997)
			(xy 67.345378 -384.736087) (xy 67.326627 -384.672828) (xy 67.317158 -384.607532) (xy 67.316604 -384.574542)
			(xy 67.31707 -384.545303) (xy 67.324522 -384.487303) (xy 67.339299 -384.430723) (xy 67.361158 -384.376485)
			(xy 67.389746 -384.325472) (xy 67.424595 -384.278513) (xy 67.46514 -384.236373) (xy 67.51072 -384.199739)
			(xy 67.560593 -384.169206) (xy 67.613948 -384.145271) (xy 67.669915 -384.128323) (xy 67.727585 -384.11864)
			(xy 67.756786 -384.117088) (xy 67.766438 -384.116834) (xy 67.783964 -384.109214) (xy 67.846448 -384.046222)
			(xy 67.854068 -384.02895) (xy 67.854322 -384.019044) (xy 67.855929 -383.986493) (xy 67.866408 -383.922168)
			(xy 67.885021 -383.859709) (xy 67.911462 -383.800141) (xy 67.945298 -383.74444) (xy 67.985974 -383.693519)
			(xy 68.032824 -383.648213) (xy 68.085079 -383.609265) (xy 68.141882 -383.577314) (xy 68.202303 -383.552883)
			(xy 68.26535 -383.536373) (xy 68.329989 -383.528055) (xy 68.362576 -383.527554) (xy 68.396157 -383.528099)
			(xy 68.462732 -383.536951) (xy 68.527563 -383.554491) (xy 68.58952 -383.580414) (xy 68.647525 -383.614269)
			(xy 68.700568 -383.655465) (xy 68.747725 -383.703287) (xy 68.788176 -383.7569) (xy 68.821216 -383.815373)
			(xy 68.834254 -383.846324) (xy 68.839842 -383.86004) (xy 68.863464 -383.877058) (xy 68.984622 -383.884678)
			(xy 69.010276 -383.870454) (xy 69.017388 -383.8575) (xy 69.034295 -383.828149) (xy 69.074704 -383.773786)
			(xy 69.121971 -383.725268) (xy 69.175259 -383.683452) (xy 69.233625 -383.649078) (xy 69.296036 -383.622754)
			(xy 69.361389 -383.604946) (xy 69.428528 -383.595969) (xy 69.462396 -383.595372) (xy 69.501649 -383.596122)
			(xy 69.579215 -383.608248) (xy 69.616828 -383.619502) (xy 69.629274 -383.623312) (xy 69.655182 -383.618232)
			(xy 69.74078 -383.545334) (xy 69.750178 -383.520696) (xy 69.748146 -383.507742) (xy 69.746235 -383.493915)
			(xy 69.744203 -383.466074) (xy 69.744082 -383.452116) (xy 69.744442 -383.42732) (xy 69.75081 -383.37814)
			(xy 69.756782 -383.354072) (xy 69.760084 -383.342388) (xy 69.755512 -383.319528) (xy 69.699124 -383.246122)
			(xy 69.691522 -383.237175) (xy 69.670466 -383.226858) (xy 69.658738 -383.22631) (xy 46.558708 -383.22631)
			(xy 46.552358 -383.228088) (xy 46.531767 -383.233099) (xy 46.489728 -383.238452) (xy 46.468538 -383.238756)
			(xy 46.447348 -383.238452) (xy 46.405308 -383.233104) (xy 46.384718 -383.228088) (xy 46.378368 -383.22631)
			(xy 46.005496 -383.22631) (xy 45.9994 -383.227834) (xy 45.979416 -383.232581) (xy 45.938658 -383.237678)
			(xy 45.91812 -383.237994) (xy 45.897582 -383.237682) (xy 45.856824 -383.232581) (xy 45.83684 -383.227834)
			(xy 45.830744 -383.22631) (xy 45.446696 -383.22631) (xy 45.4406 -383.227834) (xy 45.420616 -383.232581)
			(xy 45.379858 -383.237678) (xy 45.35932 -383.237994) (xy 45.338782 -383.237682) (xy 45.298024 -383.232581)
			(xy 45.27804 -383.227834) (xy 45.271944 -383.22631) (xy 41.783508 -383.22631) (xy 41.771344 -383.226999)
			(xy 41.749713 -383.238132) (xy 41.742106 -383.247646) (xy 41.725519 -383.270266) (xy 41.686795 -383.310845)
			(xy 41.642542 -383.345311) (xy 41.593717 -383.372922) (xy 41.541374 -383.393081) (xy 41.486642 -383.405353)
			(xy 41.430702 -383.409474) (xy 41.374762 -383.405353) (xy 41.32003 -383.393081) (xy 41.267687 -383.372922)
			(xy 41.218862 -383.345311) (xy 41.174609 -383.310845) (xy 41.135885 -383.270266) (xy 41.119298 -383.247646)
			(xy 41.111681 -383.238138) (xy 41.09006 -383.226987) (xy 41.077896 -383.22631) (xy 40.329358 -383.22631)
			(xy 40.319291 -383.226741) (xy 40.300699 -383.234467) (xy 40.29329 -383.241296) (xy 39.791386 -383.7432)
			(xy 43.683934 -383.7432) (xy 43.688005 -383.687578) (xy 43.700131 -383.633141) (xy 43.720054 -383.58105)
			(xy 43.74735 -383.532415) (xy 43.781436 -383.488272) (xy 43.821585 -383.449563) (xy 43.866943 -383.417112)
			(xy 43.916543 -383.391611) (xy 43.969327 -383.373604) (xy 44.02417 -383.363474) (xy 44.079904 -383.361437)
			(xy 44.135341 -383.367537) (xy 44.189298 -383.381643) (xy 44.240627 -383.403455) (xy 44.288233 -383.432509)
			(xy 44.331101 -383.468184) (xy 44.368318 -383.509721) (xy 44.399091 -383.556234) (xy 44.422763 -383.606731)
			(xy 44.438831 -383.660138) (xy 44.446951 -383.715314) (xy 44.44746 -383.7432) (xy 44.446951 -383.771086)
			(xy 44.438831 -383.826262) (xy 44.422763 -383.879669) (xy 44.399091 -383.930166) (xy 44.368318 -383.976679)
			(xy 44.331101 -384.018216) (xy 44.288233 -384.053891) (xy 44.240627 -384.082945) (xy 44.189298 -384.104757)
			(xy 44.135341 -384.118863) (xy 44.079904 -384.124963) (xy 44.02417 -384.122926) (xy 43.969327 -384.112796)
			(xy 43.916543 -384.094789) (xy 43.866943 -384.069288) (xy 43.821585 -384.036837) (xy 43.781436 -383.998128)
			(xy 43.74735 -383.953985) (xy 43.720054 -383.90535) (xy 43.700131 -383.853259) (xy 43.688005 -383.798822)
			(xy 43.683934 -383.7432) (xy 39.791386 -383.7432) (xy 39.533576 -384.00101) (xy 39.526723 -384.008405)
			(xy 39.51898 -384.027004) (xy 39.51859 -384.037078) (xy 39.51859 -384.66268) (xy 43.683934 -384.66268)
			(xy 43.688005 -384.607058) (xy 43.700131 -384.552621) (xy 43.720054 -384.50053) (xy 43.74735 -384.451895)
			(xy 43.781436 -384.407752) (xy 43.821585 -384.369043) (xy 43.866943 -384.336592) (xy 43.916543 -384.311091)
			(xy 43.969327 -384.293084) (xy 44.02417 -384.282954) (xy 44.079904 -384.280917) (xy 44.135341 -384.287017)
			(xy 44.189298 -384.301123) (xy 44.240627 -384.322935) (xy 44.288233 -384.351989) (xy 44.330712 -384.38734)
			(xy 44.944012 -384.38734) (xy 44.944012 -384.327404) (xy 44.951835 -384.267982) (xy 44.967348 -384.210089)
			(xy 44.990284 -384.154716) (xy 45.020251 -384.10281) (xy 45.056738 -384.05526) (xy 45.099118 -384.01288)
			(xy 45.146668 -383.976393) (xy 45.198574 -383.946426) (xy 45.253947 -383.92349) (xy 45.31184 -383.907977)
			(xy 45.371262 -383.900154) (xy 45.431198 -383.900154) (xy 45.49062 -383.907977) (xy 45.548513 -383.92349)
			(xy 45.603886 -383.946426) (xy 45.655792 -383.976393) (xy 45.703342 -384.01288) (xy 45.745722 -384.05526)
			(xy 45.782209 -384.10281) (xy 45.812176 -384.154716) (xy 45.835112 -384.210089) (xy 45.850625 -384.267982)
			(xy 45.858448 -384.327404) (xy 45.858938 -384.357372) (xy 45.858448 -384.38734) (xy 45.850625 -384.446762)
			(xy 45.835112 -384.504655) (xy 45.812176 -384.560028) (xy 45.782209 -384.611934) (xy 45.745722 -384.659484)
			(xy 45.703342 -384.701864) (xy 45.655792 -384.738351) (xy 45.603886 -384.768318) (xy 45.548513 -384.791254)
			(xy 45.49062 -384.806767) (xy 45.431198 -384.81459) (xy 45.371262 -384.81459) (xy 45.31184 -384.806767)
			(xy 45.253947 -384.791254) (xy 45.198574 -384.768318) (xy 45.146668 -384.738351) (xy 45.099118 -384.701864)
			(xy 45.056738 -384.659484) (xy 45.020251 -384.611934) (xy 44.990284 -384.560028) (xy 44.967348 -384.504655)
			(xy 44.951835 -384.446762) (xy 44.944012 -384.38734) (xy 44.330712 -384.38734) (xy 44.331101 -384.387664)
			(xy 44.368318 -384.429201) (xy 44.399091 -384.475714) (xy 44.422763 -384.526211) (xy 44.438831 -384.579618)
			(xy 44.446951 -384.634794) (xy 44.44746 -384.66268) (xy 44.446951 -384.690566) (xy 44.438831 -384.745742)
			(xy 44.422763 -384.799149) (xy 44.399091 -384.849646) (xy 44.368318 -384.896159) (xy 44.331101 -384.937696)
			(xy 44.288233 -384.973371) (xy 44.240627 -385.002425) (xy 44.189298 -385.024237) (xy 44.135341 -385.038343)
			(xy 44.079904 -385.044443) (xy 44.02417 -385.042406) (xy 43.969327 -385.032276) (xy 43.916543 -385.014269)
			(xy 43.866943 -384.988768) (xy 43.821585 -384.956317) (xy 43.781436 -384.917608) (xy 43.74735 -384.873465)
			(xy 43.720054 -384.82483) (xy 43.700131 -384.772739) (xy 43.688005 -384.718302) (xy 43.683934 -384.66268)
			(xy 39.51859 -384.66268) (xy 39.51859 -385.609452) (xy 43.684938 -385.609452) (xy 43.684938 -385.554948)
			(xy 43.692694 -385.500999) (xy 43.708048 -385.448703) (xy 43.730688 -385.399123) (xy 43.760153 -385.35327)
			(xy 43.795843 -385.312077) (xy 43.837032 -385.276382) (xy 43.882881 -385.246911) (xy 43.932457 -385.224265)
			(xy 43.984752 -385.208904) (xy 44.0387 -385.201141) (xy 44.065952 -385.200652) (xy 44.094586 -385.20116)
			(xy 44.151211 -385.209726) (xy 44.205919 -385.226659) (xy 44.257482 -385.251578) (xy 44.304742 -385.283923)
			(xy 44.346638 -385.322968) (xy 44.382227 -385.367836) (xy 44.396914 -385.392422) (xy 44.404026 -385.404614)
			(xy 44.427902 -385.41833) (xy 44.544996 -385.416044) (xy 44.568364 -385.40182) (xy 44.574968 -385.389374)
			(xy 44.589932 -385.362137) (xy 44.626059 -385.311572) (xy 44.668698 -385.266364) (xy 44.717065 -385.227344)
			(xy 44.770269 -385.19523) (xy 44.82733 -385.170615) (xy 44.887199 -385.15395) (xy 44.948772 -385.145544)
			(xy 44.979844 -385.145026) (xy 45.009814 -385.145441) (xy 45.069241 -385.15327) (xy 45.127137 -385.168789)
			(xy 45.182513 -385.191733) (xy 45.23442 -385.221707) (xy 45.28197 -385.258201) (xy 45.324351 -385.300588)
			(xy 45.360836 -385.348145) (xy 45.390802 -385.400057) (xy 45.413736 -385.455437) (xy 45.429245 -385.513336)
			(xy 45.437064 -385.572764) (xy 45.437552 -385.602734) (xy 45.437054 -385.633614) (xy 45.428738 -385.694812)
			(xy 45.412263 -385.754335) (xy 45.387927 -385.811099) (xy 45.356174 -385.864071) (xy 45.347002 -385.87553)
			(xy 46.834044 -385.87553) (xy 46.834629 -385.849546) (xy 46.842754 -385.798217) (xy 46.858808 -385.748791)
			(xy 46.882396 -385.702485) (xy 46.912937 -385.660439) (xy 46.949679 -385.623687) (xy 46.991718 -385.593136)
			(xy 47.038019 -385.569537) (xy 47.087441 -385.553472) (xy 47.138768 -385.545335) (xy 47.164752 -385.544822)
			(xy 47.181185 -385.545046) (xy 47.213885 -385.548355) (xy 47.23003 -385.551426) (xy 47.242984 -385.553966)
			(xy 47.26813 -385.546092) (xy 47.345346 -385.464304) (xy 47.35195 -385.438904) (xy 47.348648 -385.426204)
			(xy 47.341641 -385.397762) (xy 47.334124 -385.339669) (xy 47.333662 -385.31038) (xy 47.334179 -385.279492)
			(xy 47.342485 -385.218276) (xy 47.358944 -385.158732) (xy 47.383258 -385.10194) (xy 47.398686 -385.075176)
			(xy 47.404528 -385.06527) (xy 47.406814 -385.042918) (xy 47.37354 -384.947668) (xy 47.357792 -384.931666)
			(xy 47.347124 -384.927602) (xy 47.323727 -384.918457) (xy 47.279832 -384.894029) (xy 47.240138 -384.863241)
			(xy 47.20556 -384.826801) (xy 47.176893 -384.78555) (xy 47.154798 -384.740435) (xy 47.139783 -384.692497)
			(xy 47.132194 -384.642839) (xy 47.131732 -384.617722) (xy 47.132242 -384.591735) (xy 47.140372 -384.5404)
			(xy 47.156433 -384.49097) (xy 47.180029 -384.44466) (xy 47.210579 -384.402612) (xy 47.24733 -384.365861)
			(xy 47.289378 -384.335311) (xy 47.335688 -384.311715) (xy 47.385118 -384.295654) (xy 47.436453 -384.287524)
			(xy 47.488427 -384.287524) (xy 47.539762 -384.295654) (xy 47.589192 -384.311715) (xy 47.635502 -384.335311)
			(xy 47.67755 -384.365861) (xy 47.714301 -384.402612) (xy 47.744851 -384.44466) (xy 47.768447 -384.49097)
			(xy 47.784508 -384.5404) (xy 47.792638 -384.591735) (xy 47.793148 -384.617722) (xy 48.331628 -384.617722)
			(xy 48.332138 -384.591735) (xy 48.340268 -384.5404) (xy 48.356329 -384.49097) (xy 48.379925 -384.44466)
			(xy 48.410475 -384.402612) (xy 48.447226 -384.365861) (xy 48.489274 -384.335311) (xy 48.535584 -384.311715)
			(xy 48.585014 -384.295654) (xy 48.636349 -384.287524) (xy 48.688323 -384.287524) (xy 48.739658 -384.295654)
			(xy 48.789088 -384.311715) (xy 48.835398 -384.335311) (xy 48.877446 -384.365861) (xy 48.914197 -384.402612)
			(xy 48.944747 -384.44466) (xy 48.968343 -384.49097) (xy 48.984404 -384.5404) (xy 48.992534 -384.591735)
			(xy 48.993044 -384.617722) (xy 49.531778 -384.617722) (xy 49.532288 -384.591735) (xy 49.540418 -384.5404)
			(xy 49.556479 -384.49097) (xy 49.580075 -384.44466) (xy 49.610625 -384.402612) (xy 49.647376 -384.365861)
			(xy 49.689424 -384.335311) (xy 49.735734 -384.311715) (xy 49.785164 -384.295654) (xy 49.836499 -384.287524)
			(xy 49.888473 -384.287524) (xy 49.939808 -384.295654) (xy 49.989238 -384.311715) (xy 50.035548 -384.335311)
			(xy 50.077596 -384.365861) (xy 50.114347 -384.402612) (xy 50.144897 -384.44466) (xy 50.168493 -384.49097)
			(xy 50.184554 -384.5404) (xy 50.192684 -384.591735) (xy 50.193194 -384.617722) (xy 50.731674 -384.617722)
			(xy 50.732184 -384.591735) (xy 50.740314 -384.5404) (xy 50.756375 -384.49097) (xy 50.779971 -384.44466)
			(xy 50.810521 -384.402612) (xy 50.847272 -384.365861) (xy 50.88932 -384.335311) (xy 50.93563 -384.311715)
			(xy 50.98506 -384.295654) (xy 51.036395 -384.287524) (xy 51.088369 -384.287524) (xy 51.139704 -384.295654)
			(xy 51.189134 -384.311715) (xy 51.235444 -384.335311) (xy 51.277492 -384.365861) (xy 51.314243 -384.402612)
			(xy 51.344793 -384.44466) (xy 51.368389 -384.49097) (xy 51.38445 -384.5404) (xy 51.39258 -384.591735)
			(xy 51.39309 -384.617722) (xy 51.931824 -384.617722) (xy 51.932334 -384.591735) (xy 51.940464 -384.5404)
			(xy 51.956525 -384.49097) (xy 51.980121 -384.44466) (xy 52.010671 -384.402612) (xy 52.047422 -384.365861)
			(xy 52.08947 -384.335311) (xy 52.13578 -384.311715) (xy 52.18521 -384.295654) (xy 52.236545 -384.287524)
			(xy 52.288519 -384.287524) (xy 52.339854 -384.295654) (xy 52.389284 -384.311715) (xy 52.435594 -384.335311)
			(xy 52.477642 -384.365861) (xy 52.514393 -384.402612) (xy 52.544943 -384.44466) (xy 52.568539 -384.49097)
			(xy 52.5846 -384.5404) (xy 52.59273 -384.591735) (xy 52.59324 -384.617722) (xy 53.13172 -384.617722)
			(xy 53.13223 -384.591735) (xy 53.14036 -384.5404) (xy 53.156421 -384.49097) (xy 53.180017 -384.44466)
			(xy 53.210567 -384.402612) (xy 53.247318 -384.365861) (xy 53.289366 -384.335311) (xy 53.335676 -384.311715)
			(xy 53.385106 -384.295654) (xy 53.436441 -384.287524) (xy 53.488415 -384.287524) (xy 53.53975 -384.295654)
			(xy 53.58918 -384.311715) (xy 53.63549 -384.335311) (xy 53.677538 -384.365861) (xy 53.714289 -384.402612)
			(xy 53.744839 -384.44466) (xy 53.768435 -384.49097) (xy 53.784496 -384.5404) (xy 53.792626 -384.591735)
			(xy 53.793136 -384.617722) (xy 54.331616 -384.617722) (xy 54.332126 -384.591735) (xy 54.340256 -384.5404)
			(xy 54.356317 -384.49097) (xy 54.379913 -384.44466) (xy 54.410463 -384.402612) (xy 54.447214 -384.365861)
			(xy 54.489262 -384.335311) (xy 54.535572 -384.311715) (xy 54.585002 -384.295654) (xy 54.636337 -384.287524)
			(xy 54.688311 -384.287524) (xy 54.739646 -384.295654) (xy 54.789076 -384.311715) (xy 54.835386 -384.335311)
			(xy 54.877434 -384.365861) (xy 54.914185 -384.402612) (xy 54.944735 -384.44466) (xy 54.968331 -384.49097)
			(xy 54.984392 -384.5404) (xy 54.992522 -384.591735) (xy 54.993032 -384.617722) (xy 55.531766 -384.617722)
			(xy 55.532276 -384.591735) (xy 55.540406 -384.5404) (xy 55.556467 -384.49097) (xy 55.580063 -384.44466)
			(xy 55.610613 -384.402612) (xy 55.647364 -384.365861) (xy 55.689412 -384.335311) (xy 55.735722 -384.311715)
			(xy 55.785152 -384.295654) (xy 55.836487 -384.287524) (xy 55.888461 -384.287524) (xy 55.939796 -384.295654)
			(xy 55.989226 -384.311715) (xy 56.035536 -384.335311) (xy 56.077584 -384.365861) (xy 56.114335 -384.402612)
			(xy 56.144885 -384.44466) (xy 56.168481 -384.49097) (xy 56.184542 -384.5404) (xy 56.192672 -384.591735)
			(xy 56.193182 -384.617722) (xy 56.731662 -384.617722) (xy 56.732172 -384.591735) (xy 56.740302 -384.5404)
			(xy 56.756363 -384.49097) (xy 56.779959 -384.44466) (xy 56.810509 -384.402612) (xy 56.84726 -384.365861)
			(xy 56.889308 -384.335311) (xy 56.935618 -384.311715) (xy 56.985048 -384.295654) (xy 57.036383 -384.287524)
			(xy 57.088357 -384.287524) (xy 57.139692 -384.295654) (xy 57.189122 -384.311715) (xy 57.235432 -384.335311)
			(xy 57.27748 -384.365861) (xy 57.314231 -384.402612) (xy 57.344781 -384.44466) (xy 57.368377 -384.49097)
			(xy 57.384438 -384.5404) (xy 57.392568 -384.591735) (xy 57.393078 -384.617722) (xy 57.931812 -384.617722)
			(xy 57.932322 -384.591735) (xy 57.940452 -384.5404) (xy 57.956513 -384.49097) (xy 57.980109 -384.44466)
			(xy 58.010659 -384.402612) (xy 58.04741 -384.365861) (xy 58.089458 -384.335311) (xy 58.135768 -384.311715)
			(xy 58.185198 -384.295654) (xy 58.236533 -384.287524) (xy 58.288507 -384.287524) (xy 58.339842 -384.295654)
			(xy 58.389272 -384.311715) (xy 58.435582 -384.335311) (xy 58.47763 -384.365861) (xy 58.514381 -384.402612)
			(xy 58.544931 -384.44466) (xy 58.568527 -384.49097) (xy 58.584588 -384.5404) (xy 58.592718 -384.591735)
			(xy 58.593228 -384.617722) (xy 59.131708 -384.617722) (xy 59.132218 -384.591735) (xy 59.140348 -384.5404)
			(xy 59.156409 -384.49097) (xy 59.180005 -384.44466) (xy 59.210555 -384.402612) (xy 59.247306 -384.365861)
			(xy 59.289354 -384.335311) (xy 59.335664 -384.311715) (xy 59.385094 -384.295654) (xy 59.436429 -384.287524)
			(xy 59.488403 -384.287524) (xy 59.539738 -384.295654) (xy 59.589168 -384.311715) (xy 59.635478 -384.335311)
			(xy 59.677526 -384.365861) (xy 59.714277 -384.402612) (xy 59.744827 -384.44466) (xy 59.768423 -384.49097)
			(xy 59.784484 -384.5404) (xy 59.792614 -384.591735) (xy 59.793124 -384.617722) (xy 60.331604 -384.617722)
			(xy 60.332114 -384.591735) (xy 60.340244 -384.5404) (xy 60.356305 -384.49097) (xy 60.379901 -384.44466)
			(xy 60.410451 -384.402612) (xy 60.447202 -384.365861) (xy 60.48925 -384.335311) (xy 60.53556 -384.311715)
			(xy 60.58499 -384.295654) (xy 60.636325 -384.287524) (xy 60.688299 -384.287524) (xy 60.739634 -384.295654)
			(xy 60.789064 -384.311715) (xy 60.835374 -384.335311) (xy 60.877422 -384.365861) (xy 60.914173 -384.402612)
			(xy 60.944723 -384.44466) (xy 60.968319 -384.49097) (xy 60.98438 -384.5404) (xy 60.99251 -384.591735)
			(xy 60.99302 -384.617722) (xy 61.531754 -384.617722) (xy 61.532264 -384.591735) (xy 61.540394 -384.5404)
			(xy 61.556455 -384.49097) (xy 61.580051 -384.44466) (xy 61.610601 -384.402612) (xy 61.647352 -384.365861)
			(xy 61.6894 -384.335311) (xy 61.73571 -384.311715) (xy 61.78514 -384.295654) (xy 61.836475 -384.287524)
			(xy 61.888449 -384.287524) (xy 61.939784 -384.295654) (xy 61.989214 -384.311715) (xy 62.035524 -384.335311)
			(xy 62.077572 -384.365861) (xy 62.114323 -384.402612) (xy 62.144873 -384.44466) (xy 62.168469 -384.49097)
			(xy 62.18453 -384.5404) (xy 62.19266 -384.591735) (xy 62.19317 -384.617722) (xy 62.73165 -384.617722)
			(xy 62.73216 -384.591735) (xy 62.74029 -384.5404) (xy 62.756351 -384.49097) (xy 62.779947 -384.44466)
			(xy 62.810497 -384.402612) (xy 62.847248 -384.365861) (xy 62.889296 -384.335311) (xy 62.935606 -384.311715)
			(xy 62.985036 -384.295654) (xy 63.036371 -384.287524) (xy 63.088345 -384.287524) (xy 63.13968 -384.295654)
			(xy 63.18911 -384.311715) (xy 63.23542 -384.335311) (xy 63.277468 -384.365861) (xy 63.314219 -384.402612)
			(xy 63.344769 -384.44466) (xy 63.368365 -384.49097) (xy 63.384426 -384.5404) (xy 63.392556 -384.591735)
			(xy 63.393066 -384.617722) (xy 63.9318 -384.617722) (xy 63.93231 -384.591735) (xy 63.94044 -384.5404)
			(xy 63.956501 -384.49097) (xy 63.980097 -384.44466) (xy 64.010647 -384.402612) (xy 64.047398 -384.365861)
			(xy 64.089446 -384.335311) (xy 64.135756 -384.311715) (xy 64.185186 -384.295654) (xy 64.236521 -384.287524)
			(xy 64.288495 -384.287524) (xy 64.33983 -384.295654) (xy 64.38926 -384.311715) (xy 64.43557 -384.335311)
			(xy 64.477618 -384.365861) (xy 64.514369 -384.402612) (xy 64.544919 -384.44466) (xy 64.568515 -384.49097)
			(xy 64.584576 -384.5404) (xy 64.592706 -384.591735) (xy 64.593216 -384.617722) (xy 65.131696 -384.617722)
			(xy 65.132206 -384.591735) (xy 65.140336 -384.5404) (xy 65.156397 -384.49097) (xy 65.179993 -384.44466)
			(xy 65.210543 -384.402612) (xy 65.247294 -384.365861) (xy 65.289342 -384.335311) (xy 65.335652 -384.311715)
			(xy 65.385082 -384.295654) (xy 65.436417 -384.287524) (xy 65.488391 -384.287524) (xy 65.539726 -384.295654)
			(xy 65.589156 -384.311715) (xy 65.635466 -384.335311) (xy 65.677514 -384.365861) (xy 65.714265 -384.402612)
			(xy 65.744815 -384.44466) (xy 65.768411 -384.49097) (xy 65.784472 -384.5404) (xy 65.792602 -384.591735)
			(xy 65.793112 -384.617722) (xy 65.792579 -384.644824) (xy 65.783771 -384.698306) (xy 65.775586 -384.724148)
			(xy 65.771776 -384.73507) (xy 65.774316 -384.757422) (xy 65.826894 -384.843274) (xy 65.845944 -384.85572)
			(xy 65.85712 -384.857498) (xy 65.886437 -384.862214) (xy 65.943607 -384.878261) (xy 65.998221 -384.90157)
			(xy 66.049361 -384.931747) (xy 66.096167 -384.968288) (xy 66.137852 -385.010576) (xy 66.173716 -385.057902)
			(xy 66.203157 -385.10947) (xy 66.225679 -385.164413) (xy 66.240903 -385.221808) (xy 66.248575 -385.28069)
			(xy 66.249042 -385.31038) (xy 66.248515 -385.341443) (xy 66.240103 -385.402996) (xy 66.232278 -385.433062)
			(xy 66.229484 -385.443222) (xy 66.232024 -385.463034) (xy 66.279522 -385.54533) (xy 66.295524 -385.557522)
			(xy 66.305684 -385.560062) (xy 66.3348 -385.56804) (xy 66.390765 -385.590678) (xy 66.44327 -385.620476)
			(xy 66.491403 -385.656917) (xy 66.534328 -385.699368) (xy 66.571301 -385.747093) (xy 66.60168 -385.799263)
			(xy 66.624939 -385.854975) (xy 66.640673 -385.913259) (xy 66.648609 -385.973106) (xy 66.649092 -386.003292)
			(xy 66.64899 -386.017042) (xy 66.647338 -386.044493) (xy 66.64579 -386.058156) (xy 66.645077 -386.066844)
			(xy 66.648847 -386.083852) (xy 66.653156 -386.09143) (xy 66.669158 -386.11683) (xy 66.673941 -386.123856)
			(xy 66.687174 -386.134504) (xy 66.695066 -386.137658) (xy 66.718832 -386.146605) (xy 66.763482 -386.170793)
			(xy 66.803909 -386.201522) (xy 66.839162 -386.238072) (xy 66.868412 -386.279583) (xy 66.890971 -386.325078)
			(xy 66.906308 -386.373487) (xy 66.914063 -386.423672) (xy 66.914522 -386.449062) (xy 66.91399 -386.47505)
			(xy 66.905865 -386.526385) (xy 66.889809 -386.575818) (xy 66.866217 -386.62213) (xy 66.83567 -386.664182)
			(xy 66.798921 -386.700936) (xy 66.756875 -386.73149) (xy 66.710566 -386.755089) (xy 66.661136 -386.771153)
			(xy 66.609801 -386.779286) (xy 66.583814 -386.77977) (xy 66.558905 -386.779306) (xy 66.50965 -386.77185)
			(xy 66.46207 -386.757089) (xy 66.417244 -386.735357) (xy 66.376184 -386.707146) (xy 66.339821 -386.673096)
			(xy 66.308978 -386.633975) (xy 66.284353 -386.59067) (xy 66.266503 -386.544161) (xy 66.260726 -386.519928)
			(xy 66.258573 -386.511705) (xy 66.249756 -386.497185) (xy 66.243454 -386.49148) (xy 66.220086 -386.47243)
			(xy 66.213207 -386.46721) (xy 66.196964 -386.461375) (xy 66.188336 -386.461) (xy 66.158498 -386.460332)
			(xy 66.099375 -386.452179) (xy 66.041813 -386.43641) (xy 65.986788 -386.413294) (xy 65.935235 -386.383222)
			(xy 65.888028 -386.346704) (xy 65.845968 -386.30436) (xy 65.809768 -386.256909) (xy 65.780042 -386.205155)
			(xy 65.757295 -386.149977) (xy 65.741913 -386.09231) (xy 65.734157 -386.033134) (xy 65.733676 -386.003292)
			(xy 65.734196 -385.972229) (xy 65.742613 -385.910675) (xy 65.75044 -385.88061) (xy 65.753234 -385.87045)
			(xy 65.750694 -385.850638) (xy 65.703196 -385.768342) (xy 65.687194 -385.75615) (xy 65.677034 -385.75361)
			(xy 65.647914 -385.745645) (xy 65.591947 -385.723007) (xy 65.53944 -385.693209) (xy 65.491307 -385.656767)
			(xy 65.448381 -385.614315) (xy 65.411408 -385.566588) (xy 65.381029 -385.514415) (xy 65.357772 -385.458702)
			(xy 65.342041 -385.400415) (xy 65.334107 -385.340566) (xy 65.333626 -385.31038) (xy 65.334148 -385.279492)
			(xy 65.342454 -385.218276) (xy 65.358911 -385.158732) (xy 65.383223 -385.101941) (xy 65.39865 -385.075176)
			(xy 65.404492 -385.06527) (xy 65.406778 -385.042918) (xy 65.373504 -384.947668) (xy 65.357756 -384.931666)
			(xy 65.347088 -384.927602) (xy 65.323705 -384.918422) (xy 65.279808 -384.894003) (xy 65.240112 -384.863221)
			(xy 65.205531 -384.826787) (xy 65.176861 -384.78554) (xy 65.154764 -384.740429) (xy 65.139748 -384.692494)
			(xy 65.132158 -384.642838) (xy 65.131696 -384.617722) (xy 64.593216 -384.617722) (xy 64.592683 -384.644824)
			(xy 64.583875 -384.698306) (xy 64.57569 -384.724148) (xy 64.57188 -384.73507) (xy 64.57442 -384.757422)
			(xy 64.626998 -384.843274) (xy 64.646048 -384.85572) (xy 64.657224 -384.857498) (xy 64.686541 -384.862211)
			(xy 64.743712 -384.878258) (xy 64.798326 -384.901567) (xy 64.849465 -384.931746) (xy 64.896271 -384.968286)
			(xy 64.937956 -385.010575) (xy 64.973821 -385.057901) (xy 65.003261 -385.109469) (xy 65.025783 -385.164412)
			(xy 65.041007 -385.221807) (xy 65.048679 -385.28069) (xy 65.049146 -385.31038) (xy 65.048623 -385.341506)
			(xy 65.040217 -385.403188) (xy 65.032382 -385.433316) (xy 65.029588 -385.443476) (xy 65.032128 -385.463542)
			(xy 65.079372 -385.54533) (xy 65.095374 -385.557522) (xy 65.105534 -385.560062) (xy 65.13464 -385.568074)
			(xy 65.190606 -385.590706) (xy 65.243112 -385.620499) (xy 65.291246 -385.656934) (xy 65.334173 -385.699382)
			(xy 65.371147 -385.747103) (xy 65.401528 -385.799271) (xy 65.424787 -385.854979) (xy 65.440522 -385.913262)
			(xy 65.448458 -385.973107) (xy 65.448942 -386.003292) (xy 65.448817 -386.017427) (xy 65.447035 -386.045641)
			(xy 65.445386 -386.05968) (xy 65.444621 -386.068287) (xy 65.448263 -386.085168) (xy 65.452498 -386.0927)
			(xy 65.468246 -386.1181) (xy 65.472938 -386.125174) (xy 65.486056 -386.135935) (xy 65.4939 -386.139182)
			(xy 65.517275 -386.148381) (xy 65.561172 -386.172798) (xy 65.600868 -386.203577) (xy 65.635449 -386.240008)
			(xy 65.66412 -386.281252) (xy 65.686219 -386.32636) (xy 65.701237 -386.374293) (xy 65.708829 -386.423947)
			(xy 65.709292 -386.449062) (xy 65.708868 -386.473264) (xy 65.701794 -386.521149) (xy 65.687808 -386.567489)
			(xy 65.667207 -386.611291) (xy 65.654174 -386.631688) (xy 65.649386 -386.639645) (xy 65.645352 -386.657756)
			(xy 65.6463 -386.666994) (xy 65.650618 -386.697982) (xy 65.652294 -386.70728) (xy 65.661579 -386.723721)
			(xy 65.668652 -386.729986) (xy 65.690738 -386.748671) (xy 65.73051 -386.790682) (xy 65.764673 -386.837369)
			(xy 65.792681 -386.887988) (xy 65.814088 -386.941733) (xy 65.828554 -386.997747) (xy 65.835847 -387.055136)
			(xy 65.836292 -387.084062) (xy 69.88378 -387.084062) (xy 69.887851 -387.02844) (xy 69.899977 -386.974003)
			(xy 69.9199 -386.921912) (xy 69.947196 -386.873277) (xy 69.981282 -386.829134) (xy 70.021431 -386.790425)
			(xy 70.066789 -386.757974) (xy 70.116389 -386.732473) (xy 70.169173 -386.714466) (xy 70.224016 -386.704336)
			(xy 70.27975 -386.702299) (xy 70.335187 -386.708399) (xy 70.389144 -386.722505) (xy 70.440473 -386.744317)
			(xy 70.488079 -386.773371) (xy 70.530947 -386.809046) (xy 70.568164 -386.850583) (xy 70.598937 -386.897096)
			(xy 70.622609 -386.947593) (xy 70.638677 -387.001) (xy 70.646797 -387.056176) (xy 70.647306 -387.084062)
			(xy 70.646797 -387.111948) (xy 70.638677 -387.167124) (xy 70.622609 -387.220531) (xy 70.598937 -387.271028)
			(xy 70.568164 -387.317541) (xy 70.530947 -387.359078) (xy 70.488079 -387.394753) (xy 70.440473 -387.423807)
			(xy 70.389144 -387.445619) (xy 70.335187 -387.459725) (xy 70.27975 -387.465825) (xy 70.224016 -387.463788)
			(xy 70.169173 -387.453658) (xy 70.116389 -387.435651) (xy 70.066789 -387.41015) (xy 70.021431 -387.377699)
			(xy 69.981282 -387.33899) (xy 69.947196 -387.294847) (xy 69.9199 -387.246212) (xy 69.899977 -387.194121)
			(xy 69.887851 -387.139684) (xy 69.88378 -387.084062) (xy 65.836292 -387.084062) (xy 65.835697 -387.117383)
			(xy 65.826036 -387.183321) (xy 65.806912 -387.247161) (xy 65.793366 -387.27761) (xy 65.789122 -387.288076)
			(xy 65.789236 -387.310633) (xy 65.798968 -387.330984) (xy 65.807336 -387.33857) (xy 65.829574 -387.357254)
			(xy 65.869636 -387.399309) (xy 65.904057 -387.446094) (xy 65.932282 -387.496857) (xy 65.953859 -387.550783)
			(xy 65.968441 -387.607005) (xy 65.975793 -387.664621) (xy 65.976246 -387.693662) (xy 65.975771 -387.722667)
			(xy 65.96846 -387.780214) (xy 65.964766 -387.7945) (xy 71.957182 -387.7945) (xy 71.961253 -387.738878)
			(xy 71.973379 -387.684441) (xy 71.993302 -387.63235) (xy 72.020598 -387.583715) (xy 72.054684 -387.539572)
			(xy 72.094833 -387.500863) (xy 72.140191 -387.468412) (xy 72.189791 -387.442911) (xy 72.242575 -387.424904)
			(xy 72.297418 -387.414774) (xy 72.353152 -387.412737) (xy 72.408589 -387.418837) (xy 72.462546 -387.432943)
			(xy 72.513875 -387.454755) (xy 72.561481 -387.483809) (xy 72.604349 -387.519484) (xy 72.641566 -387.561021)
			(xy 72.672339 -387.607534) (xy 72.696011 -387.658031) (xy 72.712079 -387.711438) (xy 72.720199 -387.766614)
			(xy 72.72062 -387.789674) (xy 73.302114 -387.789674) (xy 73.302678 -387.754718) (xy 73.312243 -387.685464)
			(xy 73.331204 -387.618173) (xy 73.359203 -387.554113) (xy 73.395713 -387.494491) (xy 73.41743 -387.467094)
			(xy 73.422706 -387.460099) (xy 73.428549 -387.443593) (xy 73.42886 -387.434836) (xy 73.42886 -387.280912)
			(xy 73.428498 -387.272165) (xy 73.422661 -387.255673) (xy 73.41743 -387.248654) (xy 73.395746 -387.221233)
			(xy 73.359243 -387.161613) (xy 73.331244 -387.097559) (xy 73.312277 -387.030274) (xy 73.302698 -386.961027)
			(xy 73.302114 -386.926074) (xy 73.302532 -386.895342) (xy 73.309944 -386.834325) (xy 73.324656 -386.774647)
			(xy 73.346455 -386.717178) (xy 73.375021 -386.662755) (xy 73.40994 -386.612172) (xy 73.450701 -386.566167)
			(xy 73.49671 -386.52541) (xy 73.547296 -386.490497) (xy 73.601722 -386.461935) (xy 73.659193 -386.440142)
			(xy 73.718873 -386.425435) (xy 73.77989 -386.418029) (xy 73.810622 -386.417566) (xy 73.831547 -386.417766)
			(xy 73.873257 -386.421204) (xy 73.893934 -386.424424) (xy 73.903078 -386.425948) (xy 73.920858 -386.422646)
			(xy 73.992994 -386.378958) (xy 74.00417 -386.364988) (xy 74.007218 -386.356352) (xy 74.016011 -386.331342)
			(xy 74.039496 -386.283814) (xy 74.069338 -386.239998) (xy 74.104963 -386.200738) (xy 74.145682 -386.166792)
			(xy 74.190711 -386.138813) (xy 74.239182 -386.117342) (xy 74.29016 -386.102792) (xy 74.342661 -386.095444)
			(xy 74.369168 -386.094986) (xy 74.39642 -386.095485) (xy 74.450369 -386.103238) (xy 74.502666 -386.118589)
			(xy 74.552246 -386.141228) (xy 74.598099 -386.170692) (xy 74.639291 -386.206382) (xy 74.674986 -386.247571)
			(xy 74.704454 -386.293421) (xy 74.727098 -386.342998) (xy 74.742454 -386.395294) (xy 74.750212 -386.449242)
			(xy 74.750676 -386.476494) (xy 74.750108 -386.504464) (xy 74.741967 -386.559807) (xy 74.725828 -386.613368)
			(xy 74.702039 -386.663996) (xy 74.671109 -386.710607) (xy 74.633703 -386.752199) (xy 74.590622 -386.787882)
			(xy 74.542791 -386.816888) (xy 74.491236 -386.838596) (xy 74.437063 -386.852541) (xy 74.4093 -386.85597)
			(xy 74.400156 -386.856732) (xy 74.3839 -386.86486) (xy 74.325988 -386.926074) (xy 74.318876 -386.942584)
			(xy 74.318368 -386.951728) (xy 74.316278 -386.984047) (xy 74.304867 -387.047799) (xy 74.285445 -387.109584)
			(xy 74.258328 -387.1684) (xy 74.223955 -387.223292) (xy 74.203814 -387.248654) (xy 74.198564 -387.255667)
			(xy 74.192705 -387.272159) (xy 74.192384 -387.280912) (xy 74.192384 -387.434836) (xy 74.192735 -387.443584)
			(xy 74.198581 -387.460075) (xy 74.203814 -387.467094) (xy 74.225526 -387.494494) (xy 74.262024 -387.554119)
			(xy 74.290016 -387.61818) (xy 74.308977 -387.685469) (xy 74.318549 -387.754719) (xy 74.31913 -387.789674)
			(xy 74.318679 -387.820891) (xy 74.311063 -387.88286) (xy 74.295918 -387.943429) (xy 74.273472 -388.001689)
			(xy 74.259186 -388.02945) (xy 74.254614 -388.037578) (xy 74.252328 -388.055612) (xy 74.271378 -388.138924)
			(xy 74.281284 -388.15391) (xy 74.288904 -388.159498) (xy 74.30943 -388.174952) (xy 74.346567 -388.210457)
			(xy 74.378602 -388.250627) (xy 74.404954 -388.294733) (xy 74.406211 -388.297674) (xy 76.33665 -388.297674)
			(xy 76.340721 -388.242052) (xy 76.352847 -388.187615) (xy 76.37277 -388.135524) (xy 76.400066 -388.086889)
			(xy 76.434152 -388.042746) (xy 76.474301 -388.004037) (xy 76.519659 -387.971586) (xy 76.569259 -387.946085)
			(xy 76.622043 -387.928078) (xy 76.676886 -387.917948) (xy 76.73262 -387.915911) (xy 76.788057 -387.922011)
			(xy 76.842014 -387.936117) (xy 76.893343 -387.957929) (xy 76.940949 -387.986983) (xy 76.983817 -388.022658)
			(xy 77.021034 -388.064195) (xy 77.051807 -388.110708) (xy 77.075479 -388.161205) (xy 77.091547 -388.214612)
			(xy 77.099667 -388.269788) (xy 77.100176 -388.297674) (xy 77.099729 -388.322137) (xy 77.302616 -388.322137)
			(xy 77.302616 -388.270163) (xy 77.310746 -388.218828) (xy 77.326807 -388.169398) (xy 77.350403 -388.123088)
			(xy 77.380953 -388.08104) (xy 77.417704 -388.044289) (xy 77.459752 -388.013739) (xy 77.506062 -387.990143)
			(xy 77.555492 -387.974082) (xy 77.606827 -387.965952) (xy 77.658801 -387.965952) (xy 77.710136 -387.974082)
			(xy 77.759566 -387.990143) (xy 77.805876 -388.013739) (xy 77.847924 -388.044289) (xy 77.884675 -388.08104)
			(xy 77.915225 -388.123088) (xy 77.938821 -388.169398) (xy 77.954882 -388.218828) (xy 77.963012 -388.270163)
			(xy 77.963522 -388.29615) (xy 77.963012 -388.322137) (xy 77.954882 -388.373472) (xy 77.938821 -388.422902)
			(xy 77.915225 -388.469212) (xy 77.884675 -388.51126) (xy 77.847924 -388.548011) (xy 77.805876 -388.578561)
			(xy 77.759566 -388.602157) (xy 77.710136 -388.618218) (xy 77.658801 -388.626348) (xy 77.606827 -388.626348)
			(xy 77.555492 -388.618218) (xy 77.506062 -388.602157) (xy 77.459752 -388.578561) (xy 77.417704 -388.548011)
			(xy 77.380953 -388.51126) (xy 77.350403 -388.469212) (xy 77.326807 -388.422902) (xy 77.310746 -388.373472)
			(xy 77.302616 -388.322137) (xy 77.099729 -388.322137) (xy 77.099667 -388.32556) (xy 77.091547 -388.380736)
			(xy 77.075479 -388.434143) (xy 77.051807 -388.48464) (xy 77.021034 -388.531153) (xy 76.983817 -388.57269)
			(xy 76.940949 -388.608365) (xy 76.893343 -388.637419) (xy 76.842014 -388.659231) (xy 76.788057 -388.673337)
			(xy 76.73262 -388.679437) (xy 76.676886 -388.6774) (xy 76.622043 -388.66727) (xy 76.569259 -388.649263)
			(xy 76.519659 -388.623762) (xy 76.474301 -388.591311) (xy 76.434152 -388.552602) (xy 76.400066 -388.508459)
			(xy 76.37277 -388.459824) (xy 76.352847 -388.407733) (xy 76.340721 -388.353296) (xy 76.33665 -388.297674)
			(xy 74.406211 -388.297674) (xy 74.425147 -388.341977) (xy 74.438815 -388.391505) (xy 74.445711 -388.442419)
			(xy 74.44613 -388.468108) (xy 74.445686 -388.495479) (xy 74.437865 -388.54966) (xy 74.422372 -388.602164)
			(xy 74.399525 -388.651911) (xy 74.369794 -388.697876) (xy 74.35215 -388.718806) (xy 74.346054 -388.725918)
			(xy 74.339704 -388.742936) (xy 74.339704 -388.82828) (xy 74.346054 -388.845298) (xy 74.35215 -388.85241)
			(xy 74.369799 -388.873334) (xy 74.399511 -388.919308) (xy 74.422346 -388.969058) (xy 74.437835 -389.02156)
			(xy 74.445659 -389.075738) (xy 74.44613 -389.103108) (xy 74.445644 -389.130359) (xy 74.437888 -389.184307)
			(xy 74.422533 -389.236602) (xy 74.399891 -389.286179) (xy 74.370425 -389.332029) (xy 74.334734 -389.37322)
			(xy 74.293543 -389.408911) (xy 74.247693 -389.438377) (xy 74.198116 -389.461019) (xy 74.145821 -389.476374)
			(xy 74.091873 -389.48413) (xy 74.037371 -389.48413) (xy 73.983423 -389.476374) (xy 73.931128 -389.461019)
			(xy 73.881551 -389.438377) (xy 73.835701 -389.408911) (xy 73.79451 -389.37322) (xy 73.758819 -389.332029)
			(xy 73.729353 -389.286179) (xy 73.706711 -389.236602) (xy 73.691356 -389.184307) (xy 73.6836 -389.130359)
			(xy 73.683114 -389.103108) (xy 73.683581 -389.075738) (xy 73.691398 -389.021559) (xy 73.706887 -388.969055)
			(xy 73.729728 -388.919308) (xy 73.759453 -388.873342) (xy 73.777094 -388.85241) (xy 73.78319 -388.845298)
			(xy 73.78954 -388.82828) (xy 73.78954 -388.742936) (xy 73.78319 -388.725918) (xy 73.777094 -388.718806)
			(xy 73.759443 -388.697883) (xy 73.729733 -388.651908) (xy 73.7069 -388.602158) (xy 73.691411 -388.549655)
			(xy 73.683586 -388.495478) (xy 73.683114 -388.468108) (xy 73.683401 -388.446584) (xy 73.688238 -388.403809)
			(xy 73.692766 -388.382764) (xy 73.694798 -388.37362) (xy 73.692512 -388.355586) (xy 73.652126 -388.280148)
			(xy 73.638664 -388.26821) (xy 73.629774 -388.264908) (xy 73.601252 -388.253536) (xy 73.546906 -388.224955)
			(xy 73.496399 -388.190037) (xy 73.450465 -388.149289) (xy 73.409774 -388.103304) (xy 73.374918 -388.052754)
			(xy 73.346405 -387.998373) (xy 73.324649 -387.940954) (xy 73.309968 -387.881332) (xy 73.302575 -387.820375)
			(xy 73.302114 -387.789674) (xy 72.72062 -387.789674) (xy 72.720708 -387.7945) (xy 72.720199 -387.822386)
			(xy 72.712079 -387.877562) (xy 72.696011 -387.930969) (xy 72.672339 -387.981466) (xy 72.641566 -388.027979)
			(xy 72.604349 -388.069516) (xy 72.561481 -388.105191) (xy 72.513875 -388.134245) (xy 72.462546 -388.156057)
			(xy 72.408589 -388.170163) (xy 72.353152 -388.176263) (xy 72.297418 -388.174226) (xy 72.242575 -388.164096)
			(xy 72.189791 -388.146089) (xy 72.140191 -388.120588) (xy 72.094833 -388.088137) (xy 72.054684 -388.049428)
			(xy 72.020598 -388.005285) (xy 71.993302 -387.95665) (xy 71.973379 -387.904559) (xy 71.961253 -387.850122)
			(xy 71.957182 -387.7945) (xy 65.964766 -387.7945) (xy 65.953938 -387.836377) (xy 65.932438 -387.890255)
			(xy 65.904303 -387.940986) (xy 65.869985 -387.987756) (xy 65.830034 -388.029815) (xy 65.807844 -388.0485)
			(xy 65.800732 -388.054088) (xy 65.791588 -388.069328) (xy 65.776348 -388.152132) (xy 65.779142 -388.169404)
			(xy 65.783714 -388.177532) (xy 65.796287 -388.20072) (xy 65.814162 -388.25034) (xy 65.820987 -388.289292)
			(xy 67.369182 -388.289292) (xy 67.369672 -388.259324) (xy 67.377495 -388.199902) (xy 67.393008 -388.142009)
			(xy 67.415944 -388.086636) (xy 67.445911 -388.03473) (xy 67.482398 -387.98718) (xy 67.524778 -387.9448)
			(xy 67.572328 -387.908313) (xy 67.624234 -387.878346) (xy 67.679607 -387.85541) (xy 67.7375 -387.839897)
			(xy 67.796922 -387.832074) (xy 67.856858 -387.832074) (xy 67.91628 -387.839897) (xy 67.974173 -387.85541)
			(xy 68.029546 -387.878346) (xy 68.081452 -387.908313) (xy 68.129002 -387.9448) (xy 68.171382 -387.98718)
			(xy 68.207869 -388.03473) (xy 68.237836 -388.086636) (xy 68.260772 -388.142009) (xy 68.276285 -388.199902)
			(xy 68.284108 -388.259324) (xy 68.284598 -388.289292) (xy 68.284046 -388.321117) (xy 68.275228 -388.384152)
			(xy 68.25776 -388.445358) (xy 68.231981 -388.503553) (xy 68.198386 -388.557615) (xy 68.178426 -388.582408)
			(xy 68.172584 -388.58952) (xy 68.166488 -388.607046) (xy 68.169028 -388.693152) (xy 68.17614 -388.71017)
			(xy 68.18249 -388.717028) (xy 68.194974 -388.730558) (xy 68.21799 -388.759293) (xy 68.228464 -388.774432)
			(xy 68.236592 -388.786116) (xy 68.262246 -388.798054) (xy 68.379848 -388.784846) (xy 68.4022 -388.767574)
			(xy 68.40728 -388.754366) (xy 68.418162 -388.727878) (xy 68.44664 -388.678199) (xy 68.482224 -388.633336)
			(xy 68.524114 -388.594295) (xy 68.571369 -388.561953) (xy 68.622927 -388.537039) (xy 68.67763 -388.52011)
			(xy 68.734249 -388.511548) (xy 68.76288 -388.511034) (xy 68.79025 -388.511504) (xy 68.844429 -388.519319)
			(xy 68.896933 -388.534807) (xy 68.94668 -388.557648) (xy 68.992647 -388.587373) (xy 69.013578 -388.605014)
			(xy 69.02069 -388.61111) (xy 69.037708 -388.61746) (xy 69.123052 -388.61746) (xy 69.14007 -388.61111)
			(xy 69.147182 -388.605014) (xy 69.168115 -388.587373) (xy 69.214083 -388.557649) (xy 69.263829 -388.534803)
			(xy 69.316331 -388.519307) (xy 69.370509 -388.511478) (xy 69.425251 -388.511478) (xy 69.479429 -388.519307)
			(xy 69.531931 -388.534803) (xy 69.581677 -388.557649) (xy 69.627645 -388.587373) (xy 69.648578 -388.605014)
			(xy 69.65569 -388.61111) (xy 69.672708 -388.61746) (xy 69.758052 -388.61746) (xy 69.77507 -388.61111)
			(xy 69.782182 -388.605014) (xy 69.803112 -388.587372) (xy 69.849085 -388.55766) (xy 69.898833 -388.534825)
			(xy 69.951334 -388.519334) (xy 70.005511 -388.511507) (xy 70.03288 -388.511034) (xy 70.060137 -388.511412)
			(xy 70.114096 -388.519167) (xy 70.166402 -388.534523) (xy 70.21599 -388.557167) (xy 70.261851 -388.586638)
			(xy 70.30305 -388.622335) (xy 70.33875 -388.663533) (xy 70.368223 -388.709392) (xy 70.39087 -388.758979)
			(xy 70.40243 -388.798348) (xy 71.741308 -388.798348) (xy 71.741308 -388.743852) (xy 71.749064 -388.68991)
			(xy 71.764417 -388.63762) (xy 71.787055 -388.588048) (xy 71.816517 -388.542202) (xy 71.852204 -388.501016)
			(xy 71.893389 -388.465327) (xy 71.939234 -388.435863) (xy 71.988805 -388.413222) (xy 72.041094 -388.397867)
			(xy 72.095036 -388.390109) (xy 72.122284 -388.389622) (xy 72.149654 -388.390092) (xy 72.203833 -388.397908)
			(xy 72.256337 -388.413396) (xy 72.306083 -388.436237) (xy 72.35205 -388.465961) (xy 72.372982 -388.483602)
			(xy 72.380094 -388.489698) (xy 72.397112 -388.496048) (xy 72.482456 -388.496048) (xy 72.499474 -388.489698)
			(xy 72.506586 -388.483602) (xy 72.527513 -388.465956) (xy 72.573487 -388.436245) (xy 72.623236 -388.413411)
			(xy 72.675738 -388.397921) (xy 72.729914 -388.390095) (xy 72.757284 -388.389622) (xy 72.78454 -388.390024)
			(xy 72.838497 -388.39778) (xy 72.890801 -388.413135) (xy 72.940387 -388.435779) (xy 72.986246 -388.465249)
			(xy 73.027443 -388.500945) (xy 73.063142 -388.542142) (xy 73.092613 -388.587999) (xy 73.115259 -388.637584)
			(xy 73.130617 -388.689888) (xy 73.138375 -388.743844) (xy 73.138375 -388.798356) (xy 73.130617 -388.852312)
			(xy 73.115259 -388.904616) (xy 73.092613 -388.954201) (xy 73.063142 -389.000058) (xy 73.027443 -389.041255)
			(xy 72.986246 -389.076951) (xy 72.940387 -389.106421) (xy 72.890801 -389.129065) (xy 72.838497 -389.14442)
			(xy 72.78454 -389.152176) (xy 72.757284 -389.152638) (xy 72.729913 -389.152196) (xy 72.675732 -389.144375)
			(xy 72.623228 -389.128881) (xy 72.573481 -389.106033) (xy 72.527516 -389.076303) (xy 72.506586 -389.058658)
			(xy 72.499474 -389.052562) (xy 72.482456 -389.046212) (xy 72.397112 -389.046212) (xy 72.380094 -389.052562)
			(xy 72.372982 -389.058658) (xy 72.352024 -389.076266) (xy 72.306059 -389.105984) (xy 72.256318 -389.128826)
			(xy 72.203823 -389.144325) (xy 72.149652 -389.15216) (xy 72.122284 -389.152638) (xy 72.095036 -389.152091)
			(xy 72.041094 -389.144333) (xy 71.988805 -389.128978) (xy 71.939234 -389.106337) (xy 71.893389 -389.076873)
			(xy 71.852204 -389.041184) (xy 71.816517 -388.999998) (xy 71.787055 -388.954152) (xy 71.764417 -388.90458)
			(xy 71.749064 -388.85229) (xy 71.741308 -388.798348) (xy 70.40243 -388.798348) (xy 70.406229 -388.811285)
			(xy 70.413987 -388.865243) (xy 70.413987 -388.919757) (xy 70.406229 -388.973715) (xy 70.39087 -389.026021)
			(xy 70.368223 -389.075608) (xy 70.33875 -389.121467) (xy 70.30305 -389.162665) (xy 70.261851 -389.198362)
			(xy 70.21599 -389.227833) (xy 70.166402 -389.250477) (xy 70.114096 -389.265833) (xy 70.060137 -389.273588)
			(xy 70.03288 -389.27405) (xy 70.005509 -389.273608) (xy 69.951328 -389.265786) (xy 69.898824 -389.250292)
			(xy 69.849078 -389.227445) (xy 69.803112 -389.197714) (xy 69.782182 -389.18007) (xy 69.77507 -389.173974)
			(xy 69.758052 -389.167624) (xy 69.672708 -389.167624) (xy 69.65569 -389.173974) (xy 69.648578 -389.18007)
			(xy 69.627645 -389.197711) (xy 69.581677 -389.227435) (xy 69.531931 -389.250281) (xy 69.479429 -389.265777)
			(xy 69.425251 -389.273606) (xy 69.370509 -389.273606) (xy 69.316331 -389.265777) (xy 69.263829 -389.250281)
			(xy 69.214083 -389.227435) (xy 69.168115 -389.197711) (xy 69.147182 -389.18007) (xy 69.14007 -389.173974)
			(xy 69.123052 -389.167624) (xy 69.037708 -389.167624) (xy 69.02069 -389.173974) (xy 69.013578 -389.18007)
			(xy 68.992623 -389.197681) (xy 68.946657 -389.227398) (xy 68.896916 -389.25024) (xy 68.84442 -389.265738)
			(xy 68.790248 -389.273573) (xy 68.76288 -389.27405) (xy 68.734278 -389.273565) (xy 68.677713 -389.265027)
			(xy 68.623056 -389.248145) (xy 68.571529 -389.223297) (xy 68.524287 -389.19104) (xy 68.482385 -389.152095)
			(xy 68.464176 -389.130032) (xy 68.45554 -389.118856) (xy 68.42887 -389.10895) (xy 68.312538 -389.131302)
			(xy 68.29171 -389.150098) (xy 68.287646 -389.163814) (xy 68.27754 -389.195157) (xy 68.249571 -389.254777)
			(xy 68.213335 -389.309765) (xy 68.191888 -389.334756) (xy 68.185538 -389.341868) (xy 68.178934 -389.35914)
			(xy 68.178934 -389.445246) (xy 68.185538 -389.462518) (xy 68.191888 -389.46963) (xy 68.213475 -389.494858)
			(xy 68.249845 -389.550409) (xy 68.277809 -389.61063) (xy 68.296781 -389.674259) (xy 68.306363 -389.739961)
			(xy 68.30695 -389.77316) (xy 68.306438 -389.804762) (xy 68.297733 -389.867364) (xy 68.280484 -389.928169)
			(xy 68.25502 -389.986016) (xy 68.238878 -390.01319) (xy 68.234359 -390.021423) (xy 68.230922 -390.039866)
			(xy 68.234334 -390.058313) (xy 68.238878 -390.06653) (xy 68.255009 -390.093707) (xy 68.280434 -390.151565)
			(xy 68.297672 -390.212368) (xy 68.306398 -390.274961) (xy 68.30695 -390.30656) (xy 68.306378 -390.338173)
			(xy 68.302637 -390.365051) (xy 70.12228 -390.365051) (xy 70.12228 -390.310549) (xy 70.130036 -390.256603)
			(xy 70.14539 -390.20431) (xy 70.16803 -390.154733) (xy 70.197496 -390.108884) (xy 70.233186 -390.067694)
			(xy 70.274374 -390.032003) (xy 70.320223 -390.002536) (xy 70.369798 -389.979895) (xy 70.422091 -389.964538)
			(xy 70.476037 -389.956781) (xy 70.503288 -389.956294) (xy 70.530658 -389.956769) (xy 70.584837 -389.964585)
			(xy 70.63734 -389.980072) (xy 70.687087 -390.002912) (xy 70.733054 -390.032634) (xy 70.753986 -390.050274)
			(xy 70.761098 -390.05637) (xy 70.778116 -390.06272) (xy 70.86346 -390.06272) (xy 70.880478 -390.05637)
			(xy 70.88759 -390.050274) (xy 70.908512 -390.032622) (xy 70.954488 -390.002913) (xy 71.004238 -389.98008)
			(xy 71.056741 -389.964592) (xy 71.110918 -389.956767) (xy 71.138288 -389.956294) (xy 71.165542 -389.956753)
			(xy 71.219494 -389.964508) (xy 71.271794 -389.979863) (xy 71.321376 -390.002505) (xy 71.36723 -390.031973)
			(xy 71.408425 -390.067667) (xy 71.44412 -390.10886) (xy 71.473589 -390.154714) (xy 71.496233 -390.204295)
			(xy 71.511589 -390.256594) (xy 71.519347 -390.310546) (xy 71.519347 -390.365054) (xy 71.511589 -390.419006)
			(xy 71.496233 -390.471305) (xy 71.473589 -390.520886) (xy 71.44412 -390.56674) (xy 71.408425 -390.607933)
			(xy 71.36723 -390.643627) (xy 71.321376 -390.673095) (xy 71.271794 -390.695737) (xy 71.219494 -390.711092)
			(xy 71.165542 -390.718847) (xy 71.138288 -390.71931) (xy 71.110918 -390.718849) (xy 71.056738 -390.711029)
			(xy 71.004235 -390.695539) (xy 70.954489 -390.672696) (xy 70.908522 -390.642971) (xy 70.88759 -390.62533)
			(xy 70.880478 -390.619234) (xy 70.86346 -390.612884) (xy 70.778116 -390.612884) (xy 70.761098 -390.619234)
			(xy 70.753986 -390.62533) (xy 70.733036 -390.642947) (xy 70.687068 -390.672661) (xy 70.637325 -390.695501)
			(xy 70.584828 -390.710997) (xy 70.530656 -390.718832) (xy 70.503288 -390.71931) (xy 70.476037 -390.718819)
			(xy 70.422091 -390.711062) (xy 70.369798 -390.695705) (xy 70.320223 -390.673064) (xy 70.274374 -390.643597)
			(xy 70.233186 -390.607906) (xy 70.197496 -390.566716) (xy 70.16803 -390.520867) (xy 70.14539 -390.47129)
			(xy 70.130036 -390.418997) (xy 70.12228 -390.365051) (xy 68.302637 -390.365051) (xy 68.297661 -390.400794)
			(xy 68.280416 -390.461622) (xy 68.254971 -390.519501) (xy 68.221807 -390.573331) (xy 68.181557 -390.622089)
			(xy 68.134984 -390.664849) (xy 68.082973 -390.700798) (xy 68.054982 -390.7155) (xy 68.045684 -390.720789)
			(xy 68.032162 -390.737334) (xy 68.026504 -390.757939) (xy 68.02755 -390.768586) (xy 68.029355 -390.781144)
			(xy 68.031261 -390.806445) (xy 68.03136 -390.819132) (xy 68.03085 -390.845119) (xy 68.02272 -390.896454)
			(xy 68.006659 -390.945884) (xy 67.983063 -390.992194) (xy 67.952513 -391.034242) (xy 67.915762 -391.070993)
			(xy 67.873714 -391.101543) (xy 67.827404 -391.125139) (xy 67.777974 -391.1412) (xy 67.726639 -391.14933)
			(xy 67.674665 -391.14933) (xy 67.62333 -391.1412) (xy 67.5739 -391.125139) (xy 67.52759 -391.101543)
			(xy 67.485542 -391.070993) (xy 67.448791 -391.034242) (xy 67.418241 -390.992194) (xy 67.394645 -390.945884)
			(xy 67.378584 -390.896454) (xy 67.370454 -390.845119) (xy 67.369944 -390.819132) (xy 67.370336 -390.795394)
			(xy 67.377133 -390.748406) (xy 67.390579 -390.702873) (xy 67.410396 -390.659729) (xy 67.436178 -390.619863)
			(xy 67.451478 -390.601708) (xy 67.458189 -390.59331) (xy 67.46453 -390.572789) (xy 67.461937 -390.551467)
			(xy 67.456812 -390.542018) (xy 67.441309 -390.515247) (xy 67.416891 -390.458407) (xy 67.400367 -390.398792)
			(xy 67.392038 -390.337492) (xy 67.391534 -390.30656) (xy 67.392058 -390.274958) (xy 67.40076 -390.212357)
			(xy 67.418005 -390.151552) (xy 67.443466 -390.093704) (xy 67.459606 -390.06653) (xy 67.464191 -390.058328)
			(xy 67.467607 -390.039866) (xy 67.464166 -390.021407) (xy 67.459606 -390.01319) (xy 67.443482 -389.98601)
			(xy 67.418055 -389.928152) (xy 67.400815 -389.867351) (xy 67.392087 -389.804759) (xy 67.391534 -389.77316)
			(xy 67.392106 -389.739926) (xy 67.401714 -389.674156) (xy 67.420737 -389.610468) (xy 67.448774 -389.550203)
			(xy 67.485236 -389.494628) (xy 67.50685 -389.469376) (xy 67.5132 -389.462264) (xy 67.519804 -389.444992)
			(xy 67.519804 -389.358886) (xy 67.5132 -389.341614) (xy 67.50685 -389.334502) (xy 67.485284 -389.309257)
			(xy 67.44891 -389.253711) (xy 67.420941 -389.193495) (xy 67.401964 -389.129869) (xy 67.392377 -389.06417)
			(xy 67.391788 -389.030972) (xy 67.392323 -388.999147) (xy 67.401145 -388.93611) (xy 67.418617 -388.874905)
			(xy 67.444401 -388.81671) (xy 67.477998 -388.762649) (xy 67.49796 -388.737856) (xy 67.503802 -388.730744)
			(xy 67.509898 -388.713218) (xy 67.507358 -388.627112) (xy 67.500246 -388.610094) (xy 67.493896 -388.603236)
			(xy 67.474416 -388.58196) (xy 67.440421 -388.535353) (xy 67.412554 -388.484843) (xy 67.391258 -388.43123)
			(xy 67.37687 -388.375366) (xy 67.36962 -388.318136) (xy 67.369182 -388.289292) (xy 65.820987 -388.289292)
			(xy 65.823264 -388.302291) (xy 65.823846 -388.328662) (xy 65.823743 -388.339943) (xy 65.822091 -388.362445)
			(xy 65.820544 -388.37362) (xy 65.819274 -388.38251) (xy 65.82283 -388.400036) (xy 65.866264 -388.470902)
			(xy 65.87998 -388.482078) (xy 65.888616 -388.484872) (xy 65.910872 -388.492779) (xy 65.952792 -388.514538)
			(xy 65.990863 -388.542489) (xy 66.024179 -388.575967) (xy 66.051945 -388.614174) (xy 66.063114 -388.634986)
			(xy 66.063622 -388.636002) (xy 66.456052 -389.314944) (xy 66.468789 -389.338308) (xy 66.486902 -389.388337)
			(xy 66.49611 -389.440741) (xy 66.496692 -389.467344) (xy 66.496278 -389.491337) (xy 66.488765 -389.538732)
			(xy 66.47393 -389.584368) (xy 66.45214 -389.627122) (xy 66.42393 -389.665941) (xy 66.389995 -389.699869)
			(xy 66.351171 -389.728071) (xy 66.308412 -389.749853) (xy 66.262774 -389.764679) (xy 66.215377 -389.772183)
			(xy 66.191384 -389.772652) (xy 66.167853 -389.772182) (xy 66.121346 -389.764979) (xy 66.076499 -389.750715)
			(xy 66.034375 -389.729731) (xy 65.995976 -389.702523) (xy 65.962213 -389.669738) (xy 65.933889 -389.632154)
			(xy 65.922398 -389.611616) (xy 65.922144 -389.611108) (xy 65.921636 -389.610346) (xy 65.523872 -388.922006)
			(xy 65.511954 -388.899339) (xy 65.495018 -388.851013) (xy 65.486359 -388.800542) (xy 65.485772 -388.77494)
			(xy 65.485772 -388.774432) (xy 65.48593 -388.763083) (xy 65.487706 -388.740454) (xy 65.489328 -388.72922)
			(xy 65.490598 -388.72033) (xy 65.487042 -388.703058) (xy 65.443608 -388.631938) (xy 65.429638 -388.621016)
			(xy 65.421256 -388.617968) (xy 65.398857 -388.609927) (xy 65.356638 -388.58797) (xy 65.318341 -388.559724)
			(xy 65.284894 -388.525873) (xy 65.257109 -388.48724) (xy 65.23566 -388.444761) (xy 65.221067 -388.399467)
			(xy 65.213683 -388.352456) (xy 65.21323 -388.328662) (xy 65.213792 -388.302289) (xy 65.222876 -388.25033)
			(xy 65.240766 -388.20071) (xy 65.253362 -388.177532) (xy 65.257934 -388.169404) (xy 65.260728 -388.152132)
			(xy 65.245488 -388.069328) (xy 65.236344 -388.054088) (xy 65.229232 -388.0485) (xy 65.207068 -388.029786)
			(xy 65.167119 -387.987727) (xy 65.1328 -387.940961) (xy 65.10466 -387.890236) (xy 65.083149 -387.836364)
			(xy 65.068612 -387.780208) (xy 65.061281 -387.722666) (xy 65.06083 -387.693662) (xy 65.061431 -387.660341)
			(xy 65.071089 -387.594403) (xy 65.090211 -387.530563) (xy 65.103756 -387.500114) (xy 65.108003 -387.489647)
			(xy 65.107898 -387.467086) (xy 65.098161 -387.446735) (xy 65.089786 -387.439154) (xy 65.067516 -387.420507)
			(xy 65.027455 -387.378446) (xy 64.993037 -387.331655) (xy 64.964815 -387.280885) (xy 64.943243 -387.226953)
			(xy 64.928668 -387.170725) (xy 64.921324 -387.113105) (xy 64.920876 -387.084062) (xy 64.921319 -387.055135)
			(xy 64.928603 -386.997742) (xy 64.943063 -386.941725) (xy 64.964467 -386.887977) (xy 64.992476 -386.837356)
			(xy 65.026642 -386.790668) (xy 65.066419 -386.748659) (xy 65.088516 -386.729986) (xy 65.095481 -386.723631)
			(xy 65.104744 -386.707233) (xy 65.10655 -386.697982) (xy 65.110868 -386.666994) (xy 65.111769 -386.657757)
			(xy 65.107746 -386.639658) (xy 65.102994 -386.631688) (xy 65.086685 -386.605843) (xy 65.062782 -386.549607)
			(xy 65.055496 -386.519928) (xy 65.053438 -386.511766) (xy 65.044736 -386.497365) (xy 65.038478 -386.491734)
			(xy 65.015364 -386.472684) (xy 65.008488 -386.467431) (xy 64.992255 -386.46147) (xy 64.983614 -386.461)
			(xy 64.953979 -386.459943) (xy 64.895316 -386.4513) (xy 64.83826 -386.435155) (xy 64.783766 -386.411778)
			(xy 64.732746 -386.381561) (xy 64.686056 -386.345008) (xy 64.644476 -386.302733) (xy 64.608703 -386.255443)
			(xy 64.579336 -386.203929) (xy 64.556866 -386.149055) (xy 64.541669 -386.091739) (xy 64.534001 -386.03294)
			(xy 64.533526 -386.003292) (xy 64.534048 -385.972229) (xy 64.542463 -385.910675) (xy 64.55029 -385.88061)
			(xy 64.553084 -385.87045) (xy 64.550544 -385.850638) (xy 64.503046 -385.768342) (xy 64.487044 -385.75615)
			(xy 64.476884 -385.75361) (xy 64.447805 -385.745544) (xy 64.391878 -385.722884) (xy 64.339412 -385.693073)
			(xy 64.291316 -385.656629) (xy 64.248424 -385.614183) (xy 64.21148 -385.56647) (xy 64.181123 -385.514318)
			(xy 64.15788 -385.45863) (xy 64.142154 -385.400371) (xy 64.134217 -385.340552) (xy 64.13373 -385.31038)
			(xy 64.134252 -385.279492) (xy 64.142557 -385.218276) (xy 64.159015 -385.158732) (xy 64.183327 -385.10194)
			(xy 64.198754 -385.075176) (xy 64.204596 -385.06527) (xy 64.206882 -385.042918) (xy 64.173608 -384.947668)
			(xy 64.15786 -384.931666) (xy 64.147192 -384.927602) (xy 64.12381 -384.91842) (xy 64.079913 -384.894001)
			(xy 64.040216 -384.86322) (xy 64.005635 -384.826786) (xy 63.976966 -384.785539) (xy 63.954868 -384.740429)
			(xy 63.939852 -384.692494) (xy 63.932262 -384.642838) (xy 63.9318 -384.617722) (xy 63.393066 -384.617722)
			(xy 63.392535 -384.644824) (xy 63.383726 -384.698307) (xy 63.37554 -384.724148) (xy 63.37173 -384.73507)
			(xy 63.37427 -384.757422) (xy 63.426848 -384.843274) (xy 63.445898 -384.85572) (xy 63.457074 -384.857498)
			(xy 63.486398 -384.862172) (xy 63.543569 -384.878225) (xy 63.598182 -384.90154) (xy 63.649321 -384.931723)
			(xy 63.696126 -384.968268) (xy 63.73781 -385.010561) (xy 63.773674 -385.05789) (xy 63.803113 -385.109461)
			(xy 63.825634 -385.164407) (xy 63.840858 -385.221804) (xy 63.848529 -385.280689) (xy 63.848996 -385.31038)
			(xy 63.848471 -385.341443) (xy 63.840058 -385.402997) (xy 63.832232 -385.433062) (xy 63.829438 -385.443222)
			(xy 63.831978 -385.463034) (xy 63.879476 -385.54533) (xy 63.895478 -385.557522) (xy 63.905638 -385.560062)
			(xy 63.934745 -385.568071) (xy 63.990711 -385.590704) (xy 64.043217 -385.620497) (xy 64.091351 -385.656933)
			(xy 64.134277 -385.69938) (xy 64.171251 -385.747102) (xy 64.201632 -385.79927) (xy 64.224891 -385.854979)
			(xy 64.240626 -385.913262) (xy 64.248562 -385.973107) (xy 64.249046 -386.003292) (xy 64.248921 -386.017427)
			(xy 64.247139 -386.045641) (xy 64.24549 -386.05968) (xy 64.244724 -386.068287) (xy 64.248367 -386.085168)
			(xy 64.252602 -386.0927) (xy 64.26835 -386.1181) (xy 64.273072 -386.12515) (xy 64.286169 -386.135925)
			(xy 64.294004 -386.139182) (xy 64.31738 -386.148379) (xy 64.361276 -386.172797) (xy 64.400972 -386.203575)
			(xy 64.435554 -386.240007) (xy 64.464224 -386.281252) (xy 64.486323 -386.32636) (xy 64.501341 -386.374293)
			(xy 64.508933 -386.423947) (xy 64.509396 -386.449062) (xy 64.508971 -386.473264) (xy 64.501898 -386.521149)
			(xy 64.487911 -386.567488) (xy 64.467311 -386.61129) (xy 64.454278 -386.631688) (xy 64.449491 -386.639645)
			(xy 64.445456 -386.657756) (xy 64.446404 -386.666994) (xy 64.450722 -386.697982) (xy 64.452397 -386.70728)
			(xy 64.461682 -386.723721) (xy 64.468756 -386.729986) (xy 64.490843 -386.74867) (xy 64.530615 -386.790681)
			(xy 64.564777 -386.837369) (xy 64.592785 -386.887988) (xy 64.614192 -386.941733) (xy 64.628658 -386.997747)
			(xy 64.635951 -387.055136) (xy 64.636396 -387.084062) (xy 64.635801 -387.117383) (xy 64.62614 -387.183321)
			(xy 64.607016 -387.247161) (xy 64.59347 -387.27761) (xy 64.589225 -387.288075) (xy 64.589339 -387.310634)
			(xy 64.599071 -387.330985) (xy 64.60744 -387.33857) (xy 64.629658 -387.357278) (xy 64.669725 -387.399326)
			(xy 64.70415 -387.446105) (xy 64.732379 -387.496864) (xy 64.75396 -387.550788) (xy 64.768544 -387.607008)
			(xy 64.775897 -387.664622) (xy 64.77635 -387.693662) (xy 64.775874 -387.722667) (xy 64.768563 -387.780214)
			(xy 64.754041 -387.836377) (xy 64.732541 -387.890255) (xy 64.704406 -387.940985) (xy 64.670088 -387.987755)
			(xy 64.630137 -388.029815) (xy 64.607948 -388.0485) (xy 64.600836 -388.054088) (xy 64.591692 -388.069328)
			(xy 64.576452 -388.152132) (xy 64.579246 -388.169404) (xy 64.583818 -388.177532) (xy 64.596391 -388.20072)
			(xy 64.614266 -388.25034) (xy 64.623368 -388.302291) (xy 64.62395 -388.328662) (xy 64.623847 -388.339943)
			(xy 64.622195 -388.362445) (xy 64.620648 -388.37362) (xy 64.619378 -388.382764) (xy 64.62268 -388.400036)
			(xy 64.666368 -388.471156) (xy 64.680084 -388.482078) (xy 64.68872 -388.484872) (xy 64.716888 -388.49506)
			(xy 64.768832 -388.524878) (xy 64.791844 -388.544054) (xy 64.813334 -388.56363) (xy 64.849143 -388.609412)
			(xy 64.862964 -388.634986) (xy 64.863726 -388.636256) (xy 65.255902 -389.314944) (xy 65.268705 -389.338288)
			(xy 65.286934 -389.388305) (xy 65.296203 -389.440727) (xy 65.296796 -389.467344) (xy 65.296401 -389.491352)
			(xy 65.28888 -389.538774) (xy 65.274029 -389.584435) (xy 65.252215 -389.627209) (xy 65.223975 -389.666042)
			(xy 65.190006 -389.699977) (xy 65.151145 -389.728177) (xy 65.108348 -389.749948) (xy 65.062672 -389.764752)
			(xy 65.015242 -389.772226) (xy 64.991234 -389.772652) (xy 64.967702 -389.772222) (xy 64.921193 -389.765011)
			(xy 64.876344 -389.750741) (xy 64.834221 -389.729749) (xy 64.795822 -389.702535) (xy 64.762061 -389.669745)
			(xy 64.733738 -389.632157) (xy 64.722248 -389.611616) (xy 64.721994 -389.611108) (xy 64.721486 -389.610346)
			(xy 64.323976 -388.921752) (xy 64.313401 -388.901827) (xy 64.297599 -388.859576) (xy 64.288193 -388.815459)
			(xy 64.286384 -388.792974) (xy 64.285876 -388.781798) (xy 64.285876 -388.774432) (xy 64.285968 -388.763087)
			(xy 64.287622 -388.740458) (xy 64.289178 -388.72922) (xy 64.290448 -388.72033) (xy 64.286892 -388.703058)
			(xy 64.243458 -388.631938) (xy 64.229742 -388.620762) (xy 64.221106 -388.617968) (xy 64.198711 -388.609951)
			(xy 64.15654 -388.587953) (xy 64.11829 -388.55968) (xy 64.084889 -388.525816) (xy 64.057144 -388.487182)
			(xy 64.035727 -388.444712) (xy 64.021157 -388.399434) (xy 64.013785 -388.352444) (xy 64.013334 -388.328662)
			(xy 64.013895 -388.302289) (xy 64.022979 -388.25033) (xy 64.04087 -388.20071) (xy 64.053466 -388.177532)
			(xy 64.058038 -388.169404) (xy 64.060832 -388.152132) (xy 64.045592 -388.069328) (xy 64.036448 -388.054088)
			(xy 64.029336 -388.0485) (xy 64.007173 -388.029785) (xy 63.967224 -387.987726) (xy 63.932905 -387.94096)
			(xy 63.904764 -387.890236) (xy 63.883253 -387.836364) (xy 63.868716 -387.780208) (xy 63.861385 -387.722666)
			(xy 63.860934 -387.693662) (xy 63.861535 -387.660341) (xy 63.871193 -387.594403) (xy 63.890315 -387.530563)
			(xy 63.90386 -387.500114) (xy 63.908106 -387.489647) (xy 63.908001 -387.467087) (xy 63.898264 -387.446735)
			(xy 63.88989 -387.439154) (xy 63.867621 -387.420506) (xy 63.827559 -387.378445) (xy 63.793141 -387.331654)
			(xy 63.764919 -387.280885) (xy 63.743347 -387.226953) (xy 63.728772 -387.170725) (xy 63.721428 -387.113105)
			(xy 63.72098 -387.084062) (xy 63.721421 -387.055135) (xy 63.728705 -386.997742) (xy 63.743165 -386.941725)
			(xy 63.76457 -386.887977) (xy 63.792579 -386.837355) (xy 63.826745 -386.790668) (xy 63.866523 -386.748659)
			(xy 63.88862 -386.729986) (xy 63.895585 -386.723632) (xy 63.904848 -386.707234) (xy 63.906654 -386.697982)
			(xy 63.910972 -386.666994) (xy 63.911872 -386.657757) (xy 63.90785 -386.639658) (xy 63.903098 -386.631688)
			(xy 63.886789 -386.605843) (xy 63.862886 -386.549607) (xy 63.8556 -386.519928) (xy 63.853541 -386.511766)
			(xy 63.84484 -386.497365) (xy 63.838582 -386.491734) (xy 63.815468 -386.472684) (xy 63.808591 -386.467433)
			(xy 63.792358 -386.46147) (xy 63.783718 -386.461) (xy 63.754083 -386.459939) (xy 63.69542 -386.451297)
			(xy 63.638364 -386.435153) (xy 63.58387 -386.411776) (xy 63.532851 -386.381559) (xy 63.48616 -386.345007)
			(xy 63.44458 -386.302732) (xy 63.408807 -386.255442) (xy 63.37944 -386.203929) (xy 63.35697 -386.149055)
			(xy 63.341773 -386.091739) (xy 63.334105 -386.03294) (xy 63.33363 -386.003292) (xy 63.334151 -385.972229)
			(xy 63.342567 -385.910675) (xy 63.350394 -385.88061) (xy 63.353188 -385.87045) (xy 63.350648 -385.850638)
			(xy 63.30315 -385.768342) (xy 63.287148 -385.75615) (xy 63.276988 -385.75361) (xy 63.247878 -385.745609)
			(xy 63.19191 -385.722978) (xy 63.139403 -385.693185) (xy 63.091268 -385.656749) (xy 63.048341 -385.6143)
			(xy 63.011366 -385.566577) (xy 62.980986 -385.514408) (xy 62.957728 -385.458697) (xy 62.941996 -385.400412)
			(xy 62.934062 -385.340565) (xy 62.93358 -385.31038) (xy 62.934109 -385.279492) (xy 62.942413 -385.218277)
			(xy 62.958869 -385.158733) (xy 62.983178 -385.101941) (xy 62.998604 -385.075176) (xy 63.004446 -385.06527)
			(xy 63.006732 -385.042918) (xy 62.973458 -384.947668) (xy 62.95771 -384.931666) (xy 62.947042 -384.927602)
			(xy 62.923649 -384.918447) (xy 62.879753 -384.894022) (xy 62.840059 -384.863235) (xy 62.80548 -384.826797)
			(xy 62.776812 -384.785547) (xy 62.754716 -384.740434) (xy 62.739701 -384.692496) (xy 62.732112 -384.642839)
			(xy 62.73165 -384.617722) (xy 62.19317 -384.617722) (xy 62.192639 -384.644824) (xy 62.18383 -384.698307)
			(xy 62.175644 -384.724148) (xy 62.171834 -384.73507) (xy 62.174374 -384.757422) (xy 62.226952 -384.843274)
			(xy 62.246002 -384.85572) (xy 62.257178 -384.857498) (xy 62.286502 -384.862168) (xy 62.343673 -384.878223)
			(xy 62.398287 -384.901538) (xy 62.449426 -384.931722) (xy 62.496231 -384.968267) (xy 62.537915 -385.01056)
			(xy 62.573778 -385.057889) (xy 62.603217 -385.109461) (xy 62.625738 -385.164407) (xy 62.640962 -385.221804)
			(xy 62.648633 -385.280689) (xy 62.6491 -385.31038) (xy 62.648576 -385.341506) (xy 62.640171 -385.403188)
			(xy 62.632336 -385.433316) (xy 62.629542 -385.443476) (xy 62.632082 -385.463542) (xy 62.679326 -385.54533)
			(xy 62.695328 -385.557522) (xy 62.705488 -385.560062) (xy 62.734604 -385.568038) (xy 62.79057 -385.590676)
			(xy 62.843075 -385.620475) (xy 62.891207 -385.656916) (xy 62.934133 -385.699367) (xy 62.971106 -385.747092)
			(xy 63.001485 -385.799263) (xy 63.024743 -385.854974) (xy 63.040477 -385.913259) (xy 63.048413 -385.973106)
			(xy 63.048896 -386.003292) (xy 63.048771 -386.017427) (xy 63.046989 -386.045641) (xy 63.04534 -386.05968)
			(xy 63.044582 -386.068287) (xy 63.04822 -386.085167) (xy 63.052452 -386.0927) (xy 63.0682 -386.1181)
			(xy 63.072907 -386.125162) (xy 63.086014 -386.13593) (xy 63.093854 -386.139182) (xy 63.117241 -386.148352)
			(xy 63.161136 -386.172776) (xy 63.20083 -386.20356) (xy 63.235409 -386.239996) (xy 63.264078 -386.281244)
			(xy 63.286175 -386.326355) (xy 63.301192 -386.37429) (xy 63.308783 -386.423946) (xy 63.309246 -386.449062)
			(xy 63.30883 -386.473265) (xy 63.301755 -386.52115) (xy 63.287766 -386.56749) (xy 63.267163 -386.611291)
			(xy 63.254128 -386.631688) (xy 63.249337 -386.639643) (xy 63.245306 -386.657756) (xy 63.246254 -386.666994)
			(xy 63.250572 -386.697982) (xy 63.252262 -386.707276) (xy 63.261538 -386.723718) (xy 63.268606 -386.729986)
			(xy 63.290682 -386.748682) (xy 63.330457 -386.79069) (xy 63.364621 -386.837375) (xy 63.392631 -386.887992)
			(xy 63.41404 -386.941735) (xy 63.428507 -386.997748) (xy 63.435801 -387.055137) (xy 63.436246 -387.084062)
			(xy 63.435656 -387.117383) (xy 63.425993 -387.183322) (xy 63.406867 -387.247161) (xy 63.39332 -387.27761)
			(xy 63.389058 -387.288071) (xy 63.389172 -387.310635) (xy 63.398914 -387.330988) (xy 63.40729 -387.33857)
			(xy 63.429518 -387.357265) (xy 63.469583 -387.399317) (xy 63.504005 -387.446099) (xy 63.532233 -387.49686)
			(xy 63.553811 -387.550785) (xy 63.568394 -387.607007) (xy 63.575747 -387.664621) (xy 63.5762 -387.693662)
			(xy 63.575742 -387.722668) (xy 63.56843 -387.780216) (xy 63.553906 -387.83638) (xy 63.532403 -387.890259)
			(xy 63.504266 -387.940989) (xy 63.469944 -387.987758) (xy 63.429989 -388.029816) (xy 63.407798 -388.0485)
			(xy 63.400686 -388.054088) (xy 63.391542 -388.069328) (xy 63.376302 -388.152132) (xy 63.379096 -388.169404)
			(xy 63.383668 -388.177532) (xy 63.396237 -388.200722) (xy 63.414115 -388.250341) (xy 63.423218 -388.302292)
			(xy 63.4238 -388.328662) (xy 63.423696 -388.339943) (xy 63.422045 -388.362445) (xy 63.420498 -388.37362)
			(xy 63.419228 -388.38251) (xy 63.422784 -388.400036) (xy 63.466218 -388.470902) (xy 63.479934 -388.482078)
			(xy 63.48857 -388.484872) (xy 63.510818 -388.492801) (xy 63.552739 -388.514553) (xy 63.590812 -388.5425)
			(xy 63.624129 -388.575973) (xy 63.651897 -388.614176) (xy 63.663068 -388.634986) (xy 63.663576 -388.636002)
			(xy 64.056006 -389.314944) (xy 64.06881 -389.338287) (xy 64.087038 -389.388304) (xy 64.096307 -389.440727)
			(xy 64.0969 -389.467344) (xy 64.096501 -389.491351) (xy 64.08898 -389.538774) (xy 64.07413 -389.584434)
			(xy 64.052316 -389.627208) (xy 64.024077 -389.666041) (xy 63.990108 -389.699976) (xy 63.951247 -389.728176)
			(xy 63.908451 -389.749947) (xy 63.862776 -389.764752) (xy 63.815346 -389.772225) (xy 63.791338 -389.772652)
			(xy 63.767806 -389.772219) (xy 63.721297 -389.765009) (xy 63.676449 -389.750739) (xy 63.634325 -389.729748)
			(xy 63.595927 -389.702534) (xy 63.562165 -389.669744) (xy 63.533842 -389.632157) (xy 63.522352 -389.611616)
			(xy 63.522098 -389.611108) (xy 63.52159 -389.610346) (xy 63.123826 -388.922006) (xy 63.111947 -388.89933)
			(xy 63.095098 -388.850996) (xy 63.086526 -388.800533) (xy 63.08598 -388.77494) (xy 63.08598 -388.774432)
			(xy 63.086072 -388.763087) (xy 63.087726 -388.740458) (xy 63.089282 -388.72922) (xy 63.090552 -388.72033)
			(xy 63.086996 -388.703058) (xy 63.043562 -388.631938) (xy 63.029592 -388.621016) (xy 63.02121 -388.617968)
			(xy 62.998801 -388.609954) (xy 62.956584 -388.58799) (xy 62.918288 -388.559739) (xy 62.884843 -388.525884)
			(xy 62.85706 -388.487247) (xy 62.835612 -388.444766) (xy 62.82102 -388.399469) (xy 62.813637 -388.352456)
			(xy 62.813184 -388.328662) (xy 62.813752 -388.302289) (xy 62.822834 -388.250331) (xy 62.840722 -388.20071)
			(xy 62.853316 -388.177532) (xy 62.857888 -388.169404) (xy 62.860682 -388.152132) (xy 62.845442 -388.069328)
			(xy 62.836298 -388.054088) (xy 62.829186 -388.0485) (xy 62.807012 -388.029797) (xy 62.767066 -387.987735)
			(xy 62.732749 -387.940966) (xy 62.704611 -387.89024) (xy 62.683102 -387.836367) (xy 62.668565 -387.780209)
			(xy 62.661235 -387.722666) (xy 62.660784 -387.693662) (xy 62.66138 -387.660341) (xy 62.67104 -387.594402)
			(xy 62.690163 -387.530563) (xy 62.70371 -387.500114) (xy 62.707939 -387.489643) (xy 62.707834 -387.467088)
			(xy 62.698107 -387.446739) (xy 62.68974 -387.439154) (xy 62.667481 -387.420493) (xy 62.627417 -387.378437)
			(xy 62.592997 -387.331648) (xy 62.564773 -387.280881) (xy 62.543199 -387.226951) (xy 62.528623 -387.170724)
			(xy 62.521278 -387.113105) (xy 62.52083 -387.084062) (xy 62.521289 -387.055136) (xy 62.528573 -386.997744)
			(xy 62.543031 -386.941728) (xy 62.564433 -386.887981) (xy 62.592439 -386.837359) (xy 62.626601 -386.790671)
			(xy 62.666375 -386.74866) (xy 62.68847 -386.729986) (xy 62.695443 -386.72364) (xy 62.7047 -386.707235)
			(xy 62.706504 -386.697982) (xy 62.710822 -386.666994) (xy 62.71173 -386.657757) (xy 62.707704 -386.639657)
			(xy 62.702948 -386.631688) (xy 62.686635 -386.605845) (xy 62.662735 -386.549608) (xy 62.65545 -386.519928)
			(xy 62.653378 -386.51177) (xy 62.644685 -386.497368) (xy 62.638432 -386.491734) (xy 62.615318 -386.472684)
			(xy 62.608428 -386.467453) (xy 62.592205 -386.461478) (xy 62.583568 -386.461) (xy 62.553932 -386.459985)
			(xy 62.495267 -386.451337) (xy 62.43821 -386.435187) (xy 62.383716 -386.411805) (xy 62.332697 -386.381582)
			(xy 62.286007 -386.345026) (xy 62.244427 -386.302747) (xy 62.208655 -386.255454) (xy 62.179288 -386.203937)
			(xy 62.156819 -386.149061) (xy 62.141623 -386.091742) (xy 62.133955 -386.032941) (xy 62.13348 -386.003292)
			(xy 62.134 -385.972229) (xy 62.142417 -385.910675) (xy 62.150244 -385.88061) (xy 62.153038 -385.87045)
			(xy 62.150498 -385.850638) (xy 62.103 -385.768342) (xy 62.086998 -385.75615) (xy 62.076838 -385.75361)
			(xy 62.047751 -385.745575) (xy 61.991824 -385.722909) (xy 61.939358 -385.693093) (xy 61.891264 -385.656645)
			(xy 61.848373 -385.614195) (xy 61.81143 -385.566479) (xy 61.781075 -385.514325) (xy 61.757833 -385.458634)
			(xy 61.742108 -385.400374) (xy 61.734171 -385.340553) (xy 61.733684 -385.31038) (xy 61.734212 -385.279492)
			(xy 61.742517 -385.218277) (xy 61.758973 -385.158733) (xy 61.783282 -385.101941) (xy 61.798708 -385.075176)
			(xy 61.80455 -385.06527) (xy 61.806836 -385.042918) (xy 61.773562 -384.947668) (xy 61.757814 -384.931666)
			(xy 61.747146 -384.927602) (xy 61.723754 -384.918445) (xy 61.679858 -384.89402) (xy 61.640164 -384.863234)
			(xy 61.605584 -384.826797) (xy 61.576917 -384.785546) (xy 61.554821 -384.740433) (xy 61.539805 -384.692496)
			(xy 61.532216 -384.642839) (xy 61.531754 -384.617722) (xy 60.99302 -384.617722) (xy 60.992487 -384.644824)
			(xy 60.983679 -384.698306) (xy 60.975494 -384.724148) (xy 60.971684 -384.73507) (xy 60.974224 -384.757422)
			(xy 61.026802 -384.843274) (xy 61.045852 -384.85572) (xy 61.057028 -384.857498) (xy 61.086346 -384.862208)
			(xy 61.143516 -384.878256) (xy 61.19813 -384.901565) (xy 61.24927 -384.931744) (xy 61.296076 -384.968285)
			(xy 61.337761 -385.010574) (xy 61.373625 -385.0579) (xy 61.403065 -385.109468) (xy 61.425587 -385.164412)
			(xy 61.440811 -385.221807) (xy 61.448483 -385.28069) (xy 61.44895 -385.31038) (xy 61.448423 -385.341443)
			(xy 61.440011 -385.402996) (xy 61.432186 -385.433062) (xy 61.429392 -385.443222) (xy 61.431932 -385.463034)
			(xy 61.47943 -385.54533) (xy 61.495432 -385.557522) (xy 61.505592 -385.560062) (xy 61.534709 -385.568035)
			(xy 61.590675 -385.590674) (xy 61.64318 -385.620473) (xy 61.691312 -385.656914) (xy 61.734237 -385.699366)
			(xy 61.77121 -385.747091) (xy 61.801589 -385.799262) (xy 61.824847 -385.854974) (xy 61.840581 -385.913259)
			(xy 61.848517 -385.973106) (xy 61.849 -386.003292) (xy 61.848875 -386.017427) (xy 61.847093 -386.045641)
			(xy 61.845444 -386.05968) (xy 61.844685 -386.068287) (xy 61.848324 -386.085167) (xy 61.852556 -386.0927)
			(xy 61.868304 -386.1181) (xy 61.873009 -386.125163) (xy 61.886118 -386.13593) (xy 61.893958 -386.139182)
			(xy 61.917345 -386.14835) (xy 61.96124 -386.172774) (xy 62.000935 -386.203559) (xy 62.035514 -386.239995)
			(xy 62.064182 -386.281243) (xy 62.086279 -386.326355) (xy 62.101296 -386.37429) (xy 62.108887 -386.423946)
			(xy 62.10935 -386.449062) (xy 62.108933 -386.473264) (xy 62.101858 -386.52115) (xy 62.08787 -386.56749)
			(xy 62.067267 -386.611291) (xy 62.054232 -386.631688) (xy 62.049441 -386.639643) (xy 62.04541 -386.657756)
			(xy 62.046358 -386.666994) (xy 62.050676 -386.697982) (xy 62.052365 -386.707276) (xy 62.061642 -386.723718)
			(xy 62.06871 -386.729986) (xy 62.090787 -386.748681) (xy 62.130561 -386.790689) (xy 62.164726 -386.837374)
			(xy 62.192735 -386.887992) (xy 62.214144 -386.941735) (xy 62.228611 -386.997748) (xy 62.235905 -387.055137)
			(xy 62.23635 -387.084062) (xy 62.235759 -387.117383) (xy 62.226097 -387.183322) (xy 62.206971 -387.247161)
			(xy 62.193424 -387.27761) (xy 62.189161 -387.288071) (xy 62.189275 -387.310635) (xy 62.199018 -387.330988)
			(xy 62.207394 -387.33857) (xy 62.229623 -387.357264) (xy 62.269687 -387.399316) (xy 62.30411 -387.446099)
			(xy 62.332337 -387.49686) (xy 62.353916 -387.550785) (xy 62.368498 -387.607006) (xy 62.375851 -387.664621)
			(xy 62.376304 -387.693662) (xy 62.375845 -387.722668) (xy 62.368533 -387.780216) (xy 62.354009 -387.83638)
			(xy 62.332507 -387.890259) (xy 62.304369 -387.940989) (xy 62.270048 -387.987758) (xy 62.230093 -388.029817)
			(xy 62.207902 -388.0485) (xy 62.20079 -388.054088) (xy 62.191646 -388.069328) (xy 62.176406 -388.152132)
			(xy 62.1792 -388.169404) (xy 62.183772 -388.177532) (xy 62.196342 -388.200722) (xy 62.214219 -388.250341)
			(xy 62.223322 -388.302292) (xy 62.223904 -388.328662) (xy 62.2238 -388.339943) (xy 62.222149 -388.362445)
			(xy 62.220602 -388.37362) (xy 62.219332 -388.382764) (xy 62.222634 -388.400036) (xy 62.266322 -388.471156)
			(xy 62.280038 -388.482078) (xy 62.288674 -388.484872) (xy 62.316838 -388.495071) (xy 62.368784 -388.524881)
			(xy 62.391798 -388.544054) (xy 62.413283 -388.563635) (xy 62.449096 -388.609414) (xy 62.462918 -388.634986)
			(xy 62.46368 -388.636256) (xy 62.855856 -389.314944) (xy 62.868593 -389.338307) (xy 62.886706 -389.388337)
			(xy 62.895914 -389.440741) (xy 62.896496 -389.467344) (xy 62.896078 -389.491337) (xy 62.888565 -389.538731)
			(xy 62.873731 -389.584367) (xy 62.851941 -389.627121) (xy 62.823731 -389.665939) (xy 62.789797 -389.699868)
			(xy 62.750973 -389.72807) (xy 62.708215 -389.749852) (xy 62.662577 -389.764678) (xy 62.615181 -389.772182)
			(xy 62.591188 -389.772652) (xy 62.567657 -389.772178) (xy 62.521151 -389.764976) (xy 62.476303 -389.750713)
			(xy 62.434179 -389.729729) (xy 62.39578 -389.702522) (xy 62.362018 -389.669737) (xy 62.333693 -389.632154)
			(xy 62.322202 -389.611616) (xy 62.321948 -389.611108) (xy 62.32144 -389.610346) (xy 61.92393 -388.921752)
			(xy 61.913359 -388.901824) (xy 61.897555 -388.859575) (xy 61.888147 -388.815459) (xy 61.886338 -388.792974)
			(xy 61.88583 -388.781798) (xy 61.885576 -388.774432) (xy 61.885734 -388.763083) (xy 61.88751 -388.740454)
			(xy 61.889132 -388.72922) (xy 61.890402 -388.72033) (xy 61.886846 -388.703058) (xy 61.843412 -388.631938)
			(xy 61.829696 -388.620762) (xy 61.82106 -388.617968) (xy 61.798655 -388.609978) (xy 61.756485 -388.587973)
			(xy 61.718237 -388.559695) (xy 61.684838 -388.525827) (xy 61.657095 -388.48719) (xy 61.63568 -388.444717)
			(xy 61.62111 -388.399437) (xy 61.613739 -388.352445) (xy 61.613288 -388.328662) (xy 61.613855 -388.302289)
			(xy 61.622938 -388.250331) (xy 61.640826 -388.20071) (xy 61.65342 -388.177532) (xy 61.657992 -388.169404)
			(xy 61.660786 -388.152132) (xy 61.645546 -388.069328) (xy 61.636402 -388.054088) (xy 61.62929 -388.0485)
			(xy 61.607117 -388.029796) (xy 61.567171 -387.987734) (xy 61.532854 -387.940966) (xy 61.504715 -387.890239)
			(xy 61.483206 -387.836366) (xy 61.468669 -387.780209) (xy 61.461339 -387.722666) (xy 61.460888 -387.693662)
			(xy 61.461484 -387.660341) (xy 61.471143 -387.594402) (xy 61.490267 -387.530563) (xy 61.503814 -387.500114)
			(xy 61.508042 -387.489642) (xy 61.507937 -387.467088) (xy 61.498211 -387.446739) (xy 61.489844 -387.439154)
			(xy 61.467586 -387.420492) (xy 61.427522 -387.378436) (xy 61.393101 -387.331648) (xy 61.364877 -387.280881)
			(xy 61.343303 -387.22695) (xy 61.328727 -387.170724) (xy 61.321382 -387.113105) (xy 61.320934 -387.084062)
			(xy 61.321392 -387.055136) (xy 61.328675 -386.997744) (xy 61.343134 -386.941728) (xy 61.364536 -386.88798)
			(xy 61.392542 -386.837359) (xy 61.426705 -386.790671) (xy 61.466479 -386.74866) (xy 61.488574 -386.729986)
			(xy 61.495548 -386.723641) (xy 61.504804 -386.707235) (xy 61.506608 -386.697982) (xy 61.510926 -386.666994)
			(xy 61.511833 -386.657757) (xy 61.507807 -386.639657) (xy 61.503052 -386.631688) (xy 61.48674 -386.605845)
			(xy 61.462839 -386.549608) (xy 61.455554 -386.519928) (xy 61.453481 -386.511771) (xy 61.444789 -386.497368)
			(xy 61.438536 -386.491734) (xy 61.415422 -386.472684) (xy 61.408531 -386.467455) (xy 61.392309 -386.461479)
			(xy 61.383672 -386.461) (xy 61.354036 -386.459981) (xy 61.295371 -386.451334) (xy 61.238314 -386.435184)
			(xy 61.18382 -386.411802) (xy 61.132801 -386.381581) (xy 61.086111 -386.345024) (xy 61.044532 -386.302746)
			(xy 61.008759 -386.255453) (xy 60.979393 -386.203937) (xy 60.956923 -386.14906) (xy 60.941727 -386.091742)
			(xy 60.934059 -386.032941) (xy 60.933584 -386.003292) (xy 60.934104 -385.972229) (xy 60.942521 -385.910675)
			(xy 60.950348 -385.88061) (xy 60.953142 -385.87045) (xy 60.950602 -385.850638) (xy 60.903104 -385.768342)
			(xy 60.887102 -385.75615) (xy 60.876942 -385.75361) (xy 60.847824 -385.74564) (xy 60.791856 -385.723003)
			(xy 60.73935 -385.693206) (xy 60.691216 -385.656765) (xy 60.64829 -385.614313) (xy 60.611316 -385.566587)
			(xy 60.580938 -385.514414) (xy 60.557681 -385.458701) (xy 60.541949 -385.400415) (xy 60.534015 -385.340566)
			(xy 60.533534 -385.31038) (xy 60.534055 -385.279492) (xy 60.542361 -385.218276) (xy 60.558819 -385.158732)
			(xy 60.58313 -385.10194) (xy 60.598558 -385.075176) (xy 60.6044 -385.06527) (xy 60.606686 -385.042918)
			(xy 60.573412 -384.947668) (xy 60.557664 -384.931666) (xy 60.546996 -384.927602) (xy 60.523615 -384.918418)
			(xy 60.479717 -384.893999) (xy 60.440021 -384.863219) (xy 60.40544 -384.826785) (xy 60.37677 -384.785539)
			(xy 60.354672 -384.740428) (xy 60.339656 -384.692493) (xy 60.332066 -384.642838) (xy 60.331604 -384.617722)
			(xy 59.793124 -384.617722) (xy 59.792595 -384.644824) (xy 59.783785 -384.698307) (xy 59.775598 -384.724148)
			(xy 59.771788 -384.73507) (xy 59.774328 -384.757422) (xy 59.826906 -384.843274) (xy 59.845956 -384.85572)
			(xy 59.857132 -384.857498) (xy 59.88645 -384.862204) (xy 59.943621 -384.878253) (xy 59.998235 -384.901563)
			(xy 60.049374 -384.931742) (xy 60.09618 -384.968283) (xy 60.137865 -385.010573) (xy 60.173729 -385.057899)
			(xy 60.203169 -385.109468) (xy 60.225691 -385.164411) (xy 60.240915 -385.221807) (xy 60.248587 -385.28069)
			(xy 60.249054 -385.31038) (xy 60.248527 -385.341443) (xy 60.240115 -385.402996) (xy 60.23229 -385.433062)
			(xy 60.229496 -385.443222) (xy 60.232036 -385.463034) (xy 60.279534 -385.54533) (xy 60.295536 -385.557522)
			(xy 60.305696 -385.560062) (xy 60.334814 -385.568032) (xy 60.39078 -385.590672) (xy 60.443284 -385.620471)
			(xy 60.491417 -385.656913) (xy 60.534341 -385.699365) (xy 60.571314 -385.747091) (xy 60.601693 -385.799262)
			(xy 60.624951 -385.854973) (xy 60.640685 -385.913259) (xy 60.648621 -385.973106) (xy 60.649104 -386.003292)
			(xy 60.648979 -386.017427) (xy 60.647197 -386.045641) (xy 60.645548 -386.05968) (xy 60.644789 -386.068287)
			(xy 60.648428 -386.085167) (xy 60.65266 -386.0927) (xy 60.668408 -386.1181) (xy 60.673099 -386.125177)
			(xy 60.686211 -386.135949) (xy 60.694062 -386.139182) (xy 60.717417 -386.148393) (xy 60.76126 -386.172852)
			(xy 60.800902 -386.203655) (xy 60.835436 -386.240094) (xy 60.864066 -386.281333) (xy 60.886136 -386.326425)
			(xy 60.90114 -386.374334) (xy 60.908731 -386.42396) (xy 60.9092 -386.449062) (xy 60.908775 -386.473264)
			(xy 60.901701 -386.521149) (xy 60.887715 -386.567488) (xy 60.867115 -386.61129) (xy 60.854082 -386.631688)
			(xy 60.849295 -386.639645) (xy 60.84526 -386.657756) (xy 60.846208 -386.666994) (xy 60.850526 -386.697982)
			(xy 60.8522 -386.70728) (xy 60.861486 -386.723721) (xy 60.86856 -386.729986) (xy 60.890648 -386.748669)
			(xy 60.930419 -386.79068) (xy 60.964581 -386.837368) (xy 60.992589 -386.887988) (xy 61.013997 -386.941733)
			(xy 61.028462 -386.997746) (xy 61.035755 -387.055136) (xy 61.0362 -387.084062) (xy 61.035614 -387.117384)
			(xy 61.025951 -387.183322) (xy 61.006823 -387.247161) (xy 60.993274 -387.27761) (xy 60.989027 -387.288075)
			(xy 60.989141 -387.310634) (xy 60.998875 -387.330985) (xy 61.007244 -387.33857) (xy 61.029463 -387.357277)
			(xy 61.06953 -387.399325) (xy 61.103954 -387.446105) (xy 61.132184 -387.496864) (xy 61.153764 -387.550787)
			(xy 61.168348 -387.607008) (xy 61.175701 -387.664621) (xy 61.176154 -387.693662) (xy 61.175676 -387.722667)
			(xy 61.168366 -387.780214) (xy 61.153844 -387.836377) (xy 61.132344 -387.890255) (xy 61.104209 -387.940985)
			(xy 61.069892 -387.987755) (xy 61.029941 -388.029815) (xy 61.007752 -388.0485) (xy 61.00064 -388.054088)
			(xy 60.991496 -388.069328) (xy 60.976256 -388.152132) (xy 60.97905 -388.169404) (xy 60.983622 -388.177532)
			(xy 60.996196 -388.200719) (xy 61.014071 -388.25034) (xy 61.023172 -388.302291) (xy 61.023754 -388.328662)
			(xy 61.023651 -388.339943) (xy 61.021999 -388.362445) (xy 61.020452 -388.37362) (xy 61.019182 -388.38251)
			(xy 61.022738 -388.400036) (xy 61.066172 -388.470902) (xy 61.079888 -388.482078) (xy 61.088524 -388.484872)
			(xy 61.110781 -388.492775) (xy 61.152701 -388.514535) (xy 61.190772 -388.542488) (xy 61.224087 -388.575967)
			(xy 61.251853 -388.614174) (xy 61.263022 -388.634986) (xy 61.26353 -388.636002) (xy 61.65596 -389.314944)
			(xy 61.668697 -389.338307) (xy 61.68681 -389.388337) (xy 61.696018 -389.440741) (xy 61.6966 -389.467344)
			(xy 61.696178 -389.491337) (xy 61.688665 -389.538731) (xy 61.673831 -389.584366) (xy 61.652041 -389.627119)
			(xy 61.623832 -389.665938) (xy 61.589898 -389.699866) (xy 61.551075 -389.728069) (xy 61.508318 -389.749851)
			(xy 61.46268 -389.764677) (xy 61.415285 -389.772182) (xy 61.391292 -389.772652) (xy 61.367761 -389.772175)
			(xy 61.321255 -389.764973) (xy 61.276407 -389.750711) (xy 61.234284 -389.729728) (xy 61.195885 -389.702521)
			(xy 61.162122 -389.669737) (xy 61.133797 -389.632154) (xy 61.122306 -389.611616) (xy 61.122052 -389.611108)
			(xy 61.121544 -389.610346) (xy 60.72378 -388.922006) (xy 60.711863 -388.899339) (xy 60.694927 -388.851013)
			(xy 60.686267 -388.800542) (xy 60.68568 -388.77494) (xy 60.68568 -388.774432) (xy 60.685838 -388.763083)
			(xy 60.687614 -388.740454) (xy 60.689236 -388.72922) (xy 60.690506 -388.72033) (xy 60.68695 -388.703058)
			(xy 60.643516 -388.631938) (xy 60.629546 -388.621016) (xy 60.621164 -388.617968) (xy 60.598766 -388.609923)
			(xy 60.556547 -388.587967) (xy 60.51825 -388.559721) (xy 60.484803 -388.525871) (xy 60.457018 -388.487239)
			(xy 60.435568 -388.44476) (xy 60.420975 -388.399466) (xy 60.413591 -388.352455) (xy 60.413138 -388.328662)
			(xy 60.413699 -388.302289) (xy 60.422783 -388.25033) (xy 60.440674 -388.20071) (xy 60.45327 -388.177532)
			(xy 60.457842 -388.169404) (xy 60.460636 -388.152132) (xy 60.445396 -388.069328) (xy 60.436252 -388.054088)
			(xy 60.42914 -388.0485) (xy 60.406978 -388.029784) (xy 60.367029 -387.987726) (xy 60.332709 -387.94096)
			(xy 60.304569 -387.890235) (xy 60.283058 -387.836364) (xy 60.26852 -387.780208) (xy 60.261189 -387.722666)
			(xy 60.260738 -387.693662) (xy 60.261338 -387.660341) (xy 60.270997 -387.594403) (xy 60.290119 -387.530563)
			(xy 60.303664 -387.500114) (xy 60.307908 -387.489647) (xy 60.307804 -387.467087) (xy 60.298067 -387.446736)
			(xy 60.289694 -387.439154) (xy 60.267426 -387.420505) (xy 60.227364 -387.378445) (xy 60.192945 -387.331654)
			(xy 60.164723 -387.280885) (xy 60.143151 -387.226953) (xy 60.128576 -387.170725) (xy 60.121232 -387.113105)
			(xy 60.120784 -387.084062) (xy 60.121224 -387.055135) (xy 60.128508 -386.997742) (xy 60.142968 -386.941725)
			(xy 60.164373 -386.887976) (xy 60.192382 -386.837355) (xy 60.226549 -386.790668) (xy 60.266327 -386.748659)
			(xy 60.288424 -386.729986) (xy 60.29539 -386.723633) (xy 60.304652 -386.707234) (xy 60.306458 -386.697982)
			(xy 60.310776 -386.666994) (xy 60.311676 -386.657757) (xy 60.307654 -386.639658) (xy 60.302902 -386.631688)
			(xy 60.286594 -386.605843) (xy 60.26269 -386.549607) (xy 60.255404 -386.519928) (xy 60.253344 -386.511766)
			(xy 60.244644 -386.497365) (xy 60.238386 -386.491734) (xy 60.215272 -386.472684) (xy 60.208452 -386.467462)
			(xy 60.192352 -386.461501) (xy 60.183776 -386.461) (xy 60.15414 -386.459978) (xy 60.095475 -386.45133)
			(xy 60.038419 -386.435181) (xy 59.983924 -386.4118) (xy 59.932905 -386.381579) (xy 59.886215 -386.345023)
			(xy 59.844636 -386.302745) (xy 59.808863 -386.255452) (xy 59.779497 -386.203936) (xy 59.757027 -386.14906)
			(xy 59.741831 -386.091741) (xy 59.734163 -386.032941) (xy 59.733688 -386.003292) (xy 59.734208 -385.972229)
			(xy 59.742624 -385.910675) (xy 59.750452 -385.88061) (xy 59.753246 -385.87045) (xy 59.750706 -385.850638)
			(xy 59.703208 -385.768342) (xy 59.687206 -385.75615) (xy 59.677046 -385.75361) (xy 59.647928 -385.745637)
			(xy 59.591961 -385.723001) (xy 59.539454 -385.693204) (xy 59.49132 -385.656763) (xy 59.448394 -385.614312)
			(xy 59.411421 -385.566586) (xy 59.381042 -385.514414) (xy 59.357785 -385.458701) (xy 59.342053 -385.400415)
			(xy 59.334119 -385.340566) (xy 59.333638 -385.31038) (xy 59.334158 -385.279492) (xy 59.342464 -385.218276)
			(xy 59.358922 -385.158732) (xy 59.383234 -385.10194) (xy 59.398662 -385.075176) (xy 59.404504 -385.06527)
			(xy 59.40679 -385.042918) (xy 59.373516 -384.947668) (xy 59.357768 -384.931666) (xy 59.3471 -384.927602)
			(xy 59.32372 -384.918416) (xy 59.279822 -384.893998) (xy 59.240126 -384.863217) (xy 59.205544 -384.826785)
			(xy 59.176874 -384.785538) (xy 59.154777 -384.740428) (xy 59.13976 -384.692493) (xy 59.13217 -384.642838)
			(xy 59.131708 -384.617722) (xy 58.593228 -384.617722) (xy 58.592699 -384.644824) (xy 58.583889 -384.698307)
			(xy 58.575702 -384.724148) (xy 58.571892 -384.73507) (xy 58.574432 -384.757422) (xy 58.62701 -384.843528)
			(xy 58.645806 -384.85572) (xy 58.657236 -384.857498) (xy 58.686524 -384.862311) (xy 58.743658 -384.878384)
			(xy 58.798235 -384.901708) (xy 58.849338 -384.931893) (xy 58.896109 -384.968432) (xy 58.937764 -385.010711)
			(xy 58.973603 -385.05802) (xy 59.003024 -385.109566) (xy 59.025534 -385.164484) (xy 59.040755 -385.221851)
			(xy 59.048431 -385.280704) (xy 59.048904 -385.31038) (xy 59.048379 -385.341443) (xy 59.039966 -385.402997)
			(xy 59.03214 -385.433062) (xy 59.029346 -385.443222) (xy 59.031886 -385.463034) (xy 59.079384 -385.54533)
			(xy 59.095386 -385.557522) (xy 59.105546 -385.560062) (xy 59.134654 -385.568066) (xy 59.190621 -385.590699)
			(xy 59.243126 -385.620493) (xy 59.29126 -385.65693) (xy 59.334186 -385.699378) (xy 59.37116 -385.7471)
			(xy 59.401541 -385.799269) (xy 59.4248 -385.854978) (xy 59.440534 -385.913261) (xy 59.448471 -385.973107)
			(xy 59.448954 -386.003292) (xy 59.448829 -386.017427) (xy 59.447047 -386.045641) (xy 59.445398 -386.05968)
			(xy 59.444632 -386.068287) (xy 59.448274 -386.085168) (xy 59.45251 -386.0927) (xy 59.468258 -386.1181)
			(xy 59.472978 -386.125152) (xy 59.486076 -386.135926) (xy 59.493912 -386.139182) (xy 59.517289 -386.148375)
			(xy 59.561186 -386.172793) (xy 59.600882 -386.203573) (xy 59.635463 -386.240005) (xy 59.664133 -386.28125)
			(xy 59.686231 -386.326359) (xy 59.701249 -386.374293) (xy 59.708841 -386.423946) (xy 59.709304 -386.449062)
			(xy 59.708878 -386.473264) (xy 59.701805 -386.521149) (xy 59.687818 -386.567488) (xy 59.667219 -386.61129)
			(xy 59.654186 -386.631688) (xy 59.649399 -386.639645) (xy 59.645364 -386.657756) (xy 59.646312 -386.666994)
			(xy 59.65063 -386.697982) (xy 59.652303 -386.707281) (xy 59.661589 -386.723722) (xy 59.668664 -386.729986)
			(xy 59.690752 -386.748668) (xy 59.730524 -386.79068) (xy 59.764686 -386.837368) (xy 59.792694 -386.887987)
			(xy 59.814101 -386.941733) (xy 59.828566 -386.997746) (xy 59.835859 -387.055136) (xy 59.836304 -387.084062)
			(xy 59.835718 -387.117384) (xy 59.826054 -387.183322) (xy 59.806927 -387.247161) (xy 59.793378 -387.27761)
			(xy 59.78913 -387.288075) (xy 59.789244 -387.310634) (xy 59.798978 -387.330985) (xy 59.807348 -387.33857)
			(xy 59.829567 -387.357276) (xy 59.869634 -387.399324) (xy 59.904059 -387.446104) (xy 59.932288 -387.496864)
			(xy 59.953868 -387.550787) (xy 59.968452 -387.607008) (xy 59.975805 -387.664621) (xy 59.976258 -387.693662)
			(xy 59.975779 -387.722667) (xy 59.968468 -387.780214) (xy 59.953947 -387.836376) (xy 59.932446 -387.890254)
			(xy 59.904313 -387.940985) (xy 59.869995 -387.987755) (xy 59.830045 -388.029815) (xy 59.807856 -388.0485)
			(xy 59.800744 -388.054088) (xy 59.7916 -388.069328) (xy 59.77636 -388.152132) (xy 59.779154 -388.169404)
			(xy 59.783726 -388.177532) (xy 59.7963 -388.200719) (xy 59.814175 -388.25034) (xy 59.823276 -388.302291)
			(xy 59.823858 -388.328662) (xy 59.823755 -388.339943) (xy 59.822103 -388.362445) (xy 59.820556 -388.37362)
			(xy 59.819286 -388.38251) (xy 59.822842 -388.400036) (xy 59.866276 -388.470902) (xy 59.879992 -388.482078)
			(xy 59.888628 -388.484872) (xy 59.910868 -388.49282) (xy 59.95279 -388.514567) (xy 59.990865 -388.542509)
			(xy 60.024184 -388.575978) (xy 60.051954 -388.614178) (xy 60.063126 -388.634986) (xy 60.063634 -388.636002)
			(xy 60.456064 -389.314944) (xy 60.468802 -389.338307) (xy 60.486914 -389.388336) (xy 60.496122 -389.440741)
			(xy 60.496704 -389.467344) (xy 60.496278 -389.491337) (xy 60.488765 -389.53873) (xy 60.473931 -389.584365)
			(xy 60.452142 -389.627118) (xy 60.423933 -389.665937) (xy 60.39 -389.699865) (xy 60.351177 -389.728067)
			(xy 60.308421 -389.74985) (xy 60.262783 -389.764676) (xy 60.215389 -389.772182) (xy 60.191396 -389.772652)
			(xy 60.167865 -389.772172) (xy 60.121359 -389.764971) (xy 60.076512 -389.750709) (xy 60.034388 -389.729726)
			(xy 59.995989 -389.70252) (xy 59.962226 -389.669736) (xy 59.933902 -389.632154) (xy 59.92241 -389.611616)
			(xy 59.922156 -389.611108) (xy 59.921648 -389.610346) (xy 59.523884 -388.922006) (xy 59.511967 -388.899338)
			(xy 59.495031 -388.851013) (xy 59.486371 -388.800542) (xy 59.485784 -388.77494) (xy 59.485784 -388.774432)
			(xy 59.485942 -388.763083) (xy 59.487718 -388.740454) (xy 59.48934 -388.72922) (xy 59.49061 -388.72033)
			(xy 59.487054 -388.703058) (xy 59.44362 -388.631938) (xy 59.42965 -388.621016) (xy 59.421268 -388.617968)
			(xy 59.398871 -388.609921) (xy 59.356652 -388.587965) (xy 59.318355 -388.55972) (xy 59.284907 -388.52587)
			(xy 59.257122 -388.487238) (xy 59.235672 -388.44476) (xy 59.221079 -388.399466) (xy 59.213695 -388.352455)
			(xy 59.213242 -388.328662) (xy 59.213802 -388.302289) (xy 59.222887 -388.25033) (xy 59.240778 -388.20071)
			(xy 59.253374 -388.177532) (xy 59.257946 -388.169404) (xy 59.26074 -388.152132) (xy 59.2455 -388.069328)
			(xy 59.236356 -388.054088) (xy 59.229244 -388.0485) (xy 59.207083 -388.029783) (xy 59.167133 -387.987725)
			(xy 59.132814 -387.940959) (xy 59.104673 -387.890235) (xy 59.083162 -387.836364) (xy 59.068624 -387.780208)
			(xy 59.061293 -387.722666) (xy 59.060842 -387.693662) (xy 59.061442 -387.660341) (xy 59.0711 -387.594403)
			(xy 59.090222 -387.530563) (xy 59.103768 -387.500114) (xy 59.108011 -387.489646) (xy 59.107906 -387.467087)
			(xy 59.098171 -387.446736) (xy 59.089798 -387.439154) (xy 59.067531 -387.420504) (xy 59.027469 -387.378444)
			(xy 58.99305 -387.331654) (xy 58.964828 -387.280884) (xy 58.943256 -387.226953) (xy 58.92868 -387.170725)
			(xy 58.921336 -387.113105) (xy 58.920888 -387.084062) (xy 58.921326 -387.055135) (xy 58.928611 -386.997742)
			(xy 58.943071 -386.941724) (xy 58.964476 -386.887976) (xy 58.992486 -386.837355) (xy 59.026652 -386.790667)
			(xy 59.066431 -386.748659) (xy 59.088528 -386.729986) (xy 59.095494 -386.723633) (xy 59.104756 -386.707234)
			(xy 59.106562 -386.697982) (xy 59.11088 -386.666994) (xy 59.111779 -386.657757) (xy 59.107757 -386.639658)
			(xy 59.103006 -386.631688) (xy 59.086698 -386.605842) (xy 59.062795 -386.549607) (xy 59.055508 -386.519928)
			(xy 59.053447 -386.511767) (xy 59.044747 -386.497365) (xy 59.03849 -386.491734) (xy 59.015376 -386.472684)
			(xy 59.008497 -386.467436) (xy 58.992266 -386.461472) (xy 58.983626 -386.461) (xy 58.953988 -386.460024)
			(xy 58.895322 -386.45137) (xy 58.838265 -386.435215) (xy 58.78377 -386.411829) (xy 58.732751 -386.381602)
			(xy 58.686062 -386.345042) (xy 58.644483 -386.30276) (xy 58.608711 -386.255464) (xy 58.579345 -386.203945)
			(xy 58.556876 -386.149066) (xy 58.541681 -386.091745) (xy 58.534013 -386.032942) (xy 58.533538 -386.003292)
			(xy 58.534059 -385.972229) (xy 58.542475 -385.910675) (xy 58.550302 -385.88061) (xy 58.553096 -385.87045)
			(xy 58.550556 -385.850638) (xy 58.503058 -385.768342) (xy 58.487056 -385.75615) (xy 58.476896 -385.75361)
			(xy 58.447788 -385.745604) (xy 58.39182 -385.722973) (xy 58.339312 -385.693182) (xy 58.291177 -385.656746)
			(xy 58.248249 -385.614298) (xy 58.211275 -385.566576) (xy 58.180895 -385.514406) (xy 58.157636 -385.458696)
			(xy 58.141904 -385.400412) (xy 58.13397 -385.340565) (xy 58.133488 -385.31038) (xy 58.133954 -385.279457)
			(xy 58.142238 -385.21817) (xy 58.158705 -385.158558) (xy 58.183055 -385.101709) (xy 58.198512 -385.074922)
			(xy 58.204608 -385.06527) (xy 58.206894 -385.042918) (xy 58.173366 -384.947668) (xy 58.157618 -384.931666)
			(xy 58.14695 -384.927602) (xy 58.123592 -384.918398) (xy 58.079748 -384.893939) (xy 58.040105 -384.863136)
			(xy 58.005571 -384.826695) (xy 57.976941 -384.785455) (xy 57.954871 -384.740362) (xy 57.939869 -384.692451)
			(xy 57.93228 -384.642824) (xy 57.931812 -384.617722) (xy 57.393078 -384.617722) (xy 57.392547 -384.644824)
			(xy 57.383738 -384.698307) (xy 57.375552 -384.724148) (xy 57.371742 -384.73507) (xy 57.374282 -384.757422)
			(xy 57.42686 -384.843274) (xy 57.44591 -384.85572) (xy 57.457086 -384.857498) (xy 57.486411 -384.862162)
			(xy 57.543582 -384.878218) (xy 57.598196 -384.901533) (xy 57.649335 -384.931718) (xy 57.696139 -384.968264)
			(xy 57.737823 -385.010558) (xy 57.773686 -385.057888) (xy 57.803125 -385.109459) (xy 57.825646 -385.164406)
			(xy 57.84087 -385.221804) (xy 57.848541 -385.280689) (xy 57.849008 -385.31038) (xy 57.848483 -385.341443)
			(xy 57.84007 -385.402997) (xy 57.832244 -385.433062) (xy 57.82945 -385.443222) (xy 57.83199 -385.463034)
			(xy 57.879488 -385.54533) (xy 57.89549 -385.557522) (xy 57.90565 -385.560062) (xy 57.934759 -385.568063)
			(xy 57.990725 -385.590697) (xy 58.043231 -385.620491) (xy 58.091364 -385.656929) (xy 58.134291 -385.699377)
			(xy 58.171265 -385.7471) (xy 58.201645 -385.799268) (xy 58.224904 -385.854978) (xy 58.240638 -385.913261)
			(xy 58.248575 -385.973107) (xy 58.249058 -386.003292) (xy 58.248933 -386.017427) (xy 58.247151 -386.045641)
			(xy 58.245502 -386.05968) (xy 58.244735 -386.068287) (xy 58.248378 -386.085168) (xy 58.252614 -386.0927)
			(xy 58.268362 -386.1181) (xy 58.273068 -386.125165) (xy 58.28617 -386.135943) (xy 58.294016 -386.139182)
			(xy 58.317361 -386.148417) (xy 58.361205 -386.172871) (xy 58.400849 -386.203669) (xy 58.435385 -386.240104)
			(xy 58.464017 -386.28134) (xy 58.486089 -386.32643) (xy 58.501093 -386.374337) (xy 58.508685 -386.423961)
			(xy 58.509154 -386.449062) (xy 58.508736 -386.473264) (xy 58.501662 -386.52115) (xy 58.487673 -386.567489)
			(xy 58.467071 -386.611291) (xy 58.454036 -386.631688) (xy 58.449246 -386.639643) (xy 58.445214 -386.657756)
			(xy 58.446162 -386.666994) (xy 58.45048 -386.697982) (xy 58.452168 -386.707276) (xy 58.461445 -386.723718)
			(xy 58.468514 -386.729986) (xy 58.490592 -386.74868) (xy 58.530366 -386.790689) (xy 58.56453 -386.837374)
			(xy 58.59254 -386.887992) (xy 58.613948 -386.941735) (xy 58.628415 -386.997748) (xy 58.635709 -387.055137)
			(xy 58.636154 -387.084062) (xy 58.635563 -387.117383) (xy 58.625901 -387.183322) (xy 58.606775 -387.247161)
			(xy 58.593228 -387.27761) (xy 58.588964 -387.288071) (xy 58.589077 -387.310635) (xy 58.598821 -387.330988)
			(xy 58.607198 -387.33857) (xy 58.629428 -387.357263) (xy 58.669492 -387.399315) (xy 58.703914 -387.446098)
			(xy 58.732141 -387.49686) (xy 58.75372 -387.550785) (xy 58.768302 -387.607006) (xy 58.775655 -387.664621)
			(xy 58.776108 -387.693662) (xy 58.775647 -387.722668) (xy 58.768336 -387.780216) (xy 58.753812 -387.83638)
			(xy 58.73231 -387.890258) (xy 58.704172 -387.940989) (xy 58.669852 -387.987758) (xy 58.629897 -388.029816)
			(xy 58.607706 -388.0485) (xy 58.600594 -388.054088) (xy 58.59145 -388.069328) (xy 58.57621 -388.152132)
			(xy 58.579004 -388.169404) (xy 58.583576 -388.177532) (xy 58.596146 -388.200721) (xy 58.614023 -388.250341)
			(xy 58.623126 -388.302292) (xy 58.623708 -388.328662) (xy 58.623604 -388.339943) (xy 58.621953 -388.362445)
			(xy 58.620406 -388.37362) (xy 58.619136 -388.38251) (xy 58.622692 -388.400036) (xy 58.666126 -388.470902)
			(xy 58.679842 -388.482078) (xy 58.688478 -388.484872) (xy 58.710727 -388.492796) (xy 58.752648 -388.51455)
			(xy 58.790721 -388.542497) (xy 58.824038 -388.575972) (xy 58.851806 -388.614176) (xy 58.862976 -388.634986)
			(xy 58.863484 -388.636002) (xy 59.255914 -389.314944) (xy 59.268718 -389.338287) (xy 59.286947 -389.388304)
			(xy 59.296215 -389.440727) (xy 59.296808 -389.467344) (xy 59.296401 -389.491351) (xy 59.28888 -389.538772)
			(xy 59.27403 -389.584432) (xy 59.252217 -389.627206) (xy 59.223979 -389.666038) (xy 59.190011 -389.699973)
			(xy 59.151151 -389.728173) (xy 59.108357 -389.749944) (xy 59.062682 -389.76475) (xy 59.015253 -389.772225)
			(xy 58.991246 -389.772652) (xy 58.967714 -389.772212) (xy 58.921206 -389.765003) (xy 58.876357 -389.750735)
			(xy 58.834234 -389.729745) (xy 58.795835 -389.702532) (xy 58.762074 -389.669743) (xy 58.733751 -389.632156)
			(xy 58.72226 -389.611616) (xy 58.722006 -389.611108) (xy 58.721498 -389.610346) (xy 58.323734 -388.922006)
			(xy 58.311856 -388.89933) (xy 58.295006 -388.850996) (xy 58.286434 -388.800533) (xy 58.285888 -388.77494)
			(xy 58.285888 -388.774432) (xy 58.285979 -388.763087) (xy 58.287634 -388.740458) (xy 58.28919 -388.72922)
			(xy 58.29046 -388.72033) (xy 58.286904 -388.703058) (xy 58.24347 -388.631938) (xy 58.2295 -388.621016)
			(xy 58.221118 -388.617968) (xy 58.198711 -388.609949) (xy 58.156493 -388.587987) (xy 58.118197 -388.559736)
			(xy 58.084752 -388.525882) (xy 58.056968 -388.487246) (xy 58.03552 -388.444765) (xy 58.020928 -388.399469)
			(xy 58.013545 -388.352456) (xy 58.013092 -388.328662) (xy 58.013659 -388.302289) (xy 58.022742 -388.250331)
			(xy 58.04063 -388.20071) (xy 58.053224 -388.177532) (xy 58.057796 -388.169404) (xy 58.06059 -388.152132)
			(xy 58.04535 -388.069328) (xy 58.036206 -388.054088) (xy 58.029094 -388.0485) (xy 58.006922 -388.029795)
			(xy 57.966975 -387.987734) (xy 57.932658 -387.940965) (xy 57.90452 -387.890239) (xy 57.88301 -387.836366)
			(xy 57.868473 -387.780209) (xy 57.861143 -387.722666) (xy 57.860692 -387.693662) (xy 57.861287 -387.660341)
			(xy 57.870947 -387.594402) (xy 57.890071 -387.530563) (xy 57.903618 -387.500114) (xy 57.907845 -387.489642)
			(xy 57.907739 -387.467088) (xy 57.898014 -387.446739) (xy 57.889648 -387.439154) (xy 57.867391 -387.420491)
			(xy 57.827326 -387.378435) (xy 57.792905 -387.331647) (xy 57.764681 -387.28088) (xy 57.743107 -387.22695)
			(xy 57.728531 -387.170724) (xy 57.721186 -387.113105) (xy 57.720738 -387.084062) (xy 57.721195 -387.055136)
			(xy 57.728478 -386.997744) (xy 57.742936 -386.941728) (xy 57.764339 -386.88798) (xy 57.792346 -386.837359)
			(xy 57.826508 -386.79067) (xy 57.866283 -386.74866) (xy 57.888378 -386.729986) (xy 57.895353 -386.723641)
			(xy 57.904608 -386.707236) (xy 57.906412 -386.697982) (xy 57.91073 -386.666994) (xy 57.911637 -386.657757)
			(xy 57.907611 -386.639657) (xy 57.902856 -386.631688) (xy 57.886544 -386.605845) (xy 57.862643 -386.549607)
			(xy 57.855358 -386.519928) (xy 57.85331 -386.511762) (xy 57.844602 -386.497362) (xy 57.83834 -386.491734)
			(xy 57.815226 -386.472684) (xy 57.808392 -386.467483) (xy 57.792302 -386.46151) (xy 57.78373 -386.461)
			(xy 57.754092 -386.46002) (xy 57.695426 -386.451367) (xy 57.638369 -386.435212) (xy 57.583875 -386.411826)
			(xy 57.532856 -386.3816) (xy 57.486166 -386.345041) (xy 57.444587 -386.302759) (xy 57.408816 -386.255463)
			(xy 57.379449 -386.203944) (xy 57.356981 -386.149065) (xy 57.341785 -386.091745) (xy 57.334117 -386.032942)
			(xy 57.333642 -386.003292) (xy 57.334163 -385.972229) (xy 57.342579 -385.910675) (xy 57.350406 -385.88061)
			(xy 57.3532 -385.87045) (xy 57.35066 -385.850638) (xy 57.303162 -385.768342) (xy 57.28716 -385.75615)
			(xy 57.277 -385.75361) (xy 57.247874 -385.745668) (xy 57.191907 -385.723026) (xy 57.139401 -385.693224)
			(xy 57.091268 -385.656779) (xy 57.048343 -385.614324) (xy 57.011371 -385.566595) (xy 56.980994 -385.51442)
			(xy 56.957737 -385.458705) (xy 56.942006 -385.400417) (xy 56.934073 -385.340567) (xy 56.933592 -385.31038)
			(xy 56.934119 -385.279492) (xy 56.942424 -385.218277) (xy 56.95888 -385.158733) (xy 56.98319 -385.101941)
			(xy 56.998616 -385.075176) (xy 57.004458 -385.06527) (xy 57.006744 -385.042918) (xy 56.97347 -384.947668)
			(xy 56.957722 -384.931666) (xy 56.947054 -384.927602) (xy 56.923664 -384.918441) (xy 56.879768 -384.894017)
			(xy 56.840073 -384.863232) (xy 56.805493 -384.826795) (xy 56.776825 -384.785545) (xy 56.754729 -384.740432)
			(xy 56.739713 -384.692496) (xy 56.732124 -384.642839) (xy 56.731662 -384.617722) (xy 56.193182 -384.617722)
			(xy 56.19265 -384.644824) (xy 56.183842 -384.698307) (xy 56.175656 -384.724148) (xy 56.171846 -384.73507)
			(xy 56.174386 -384.757422) (xy 56.226964 -384.843274) (xy 56.246014 -384.85572) (xy 56.25719 -384.857498)
			(xy 56.286503 -384.862237) (xy 56.343673 -384.878281) (xy 56.398287 -384.901586) (xy 56.449427 -384.931761)
			(xy 56.496234 -384.968298) (xy 56.53792 -385.010584) (xy 56.573785 -385.057908) (xy 56.603226 -385.109474)
			(xy 56.625748 -385.164416) (xy 56.640973 -385.22181) (xy 56.648645 -385.280691) (xy 56.649112 -385.31038)
			(xy 56.648587 -385.341506) (xy 56.640182 -385.403188) (xy 56.632348 -385.433316) (xy 56.629554 -385.443476)
			(xy 56.632094 -385.463542) (xy 56.679338 -385.54533) (xy 56.69534 -385.557522) (xy 56.7055 -385.560062)
			(xy 56.734619 -385.56803) (xy 56.790584 -385.59067) (xy 56.843089 -385.620469) (xy 56.891221 -385.656911)
			(xy 56.934146 -385.699364) (xy 56.971118 -385.74709) (xy 57.001497 -385.799261) (xy 57.024755 -385.854973)
			(xy 57.040489 -385.913258) (xy 57.048425 -385.973106) (xy 57.048908 -386.003292) (xy 57.048783 -386.017427)
			(xy 57.047001 -386.045641) (xy 57.045352 -386.05968) (xy 57.044592 -386.068287) (xy 57.048231 -386.085167)
			(xy 57.052464 -386.0927) (xy 57.068212 -386.1181) (xy 57.072915 -386.125165) (xy 57.086025 -386.135931)
			(xy 57.093866 -386.139182) (xy 57.117255 -386.148346) (xy 57.16115 -386.172771) (xy 57.200844 -386.203556)
			(xy 57.235423 -386.239993) (xy 57.264091 -386.281242) (xy 57.286187 -386.326354) (xy 57.301204 -386.37429)
			(xy 57.308795 -386.423946) (xy 57.309258 -386.449062) (xy 57.30884 -386.473264) (xy 57.301765 -386.52115)
			(xy 57.287777 -386.567489) (xy 57.267175 -386.611291) (xy 57.25414 -386.631688) (xy 57.24935 -386.639643)
			(xy 57.245318 -386.657756) (xy 57.246266 -386.666994) (xy 57.250584 -386.697982) (xy 57.252271 -386.707277)
			(xy 57.261549 -386.723719) (xy 57.268618 -386.729986) (xy 57.290697 -386.748679) (xy 57.33047 -386.790688)
			(xy 57.364634 -386.837373) (xy 57.392644 -386.887991) (xy 57.414053 -386.941735) (xy 57.428519 -386.997748)
			(xy 57.435813 -387.055137) (xy 57.436258 -387.084062) (xy 57.435667 -387.117383) (xy 57.426004 -387.183322)
			(xy 57.406879 -387.247161) (xy 57.393332 -387.27761) (xy 57.389066 -387.28807) (xy 57.38918 -387.310636)
			(xy 57.398925 -387.330989) (xy 57.407302 -387.33857) (xy 57.429533 -387.357262) (xy 57.469597 -387.399315)
			(xy 57.504019 -387.446098) (xy 57.532246 -387.49686) (xy 57.553824 -387.550785) (xy 57.568406 -387.607006)
			(xy 57.575759 -387.664621) (xy 57.576212 -387.693662) (xy 57.57575 -387.722668) (xy 57.568438 -387.780216)
			(xy 57.553915 -387.836379) (xy 57.532413 -387.890258) (xy 57.504276 -387.940988) (xy 57.469955 -387.987758)
			(xy 57.430001 -388.029816) (xy 57.40781 -388.0485) (xy 57.400698 -388.054088) (xy 57.391554 -388.069328)
			(xy 57.376314 -388.152132) (xy 57.379108 -388.169404) (xy 57.38368 -388.177532) (xy 57.39625 -388.200721)
			(xy 57.414127 -388.250341) (xy 57.42323 -388.302292) (xy 57.423812 -388.328662) (xy 57.423708 -388.339943)
			(xy 57.422057 -388.362445) (xy 57.42051 -388.37362) (xy 57.41924 -388.38251) (xy 57.422796 -388.400036)
			(xy 57.46623 -388.470902) (xy 57.479946 -388.482078) (xy 57.488582 -388.484872) (xy 57.510832 -388.492795)
			(xy 57.552753 -388.514549) (xy 57.590825 -388.542497) (xy 57.624142 -388.575971) (xy 57.65191 -388.614176)
			(xy 57.66308 -388.634986) (xy 57.663588 -388.636002) (xy 58.056018 -389.314944) (xy 58.068823 -389.338287)
			(xy 58.087051 -389.388304) (xy 58.096319 -389.440727) (xy 58.096912 -389.467344) (xy 58.096502 -389.491351)
			(xy 58.08898 -389.538772) (xy 58.074131 -389.584432) (xy 58.052318 -389.627205) (xy 58.02408 -389.666037)
			(xy 57.990113 -389.699971) (xy 57.951253 -389.728172) (xy 57.908459 -389.749943) (xy 57.862786 -389.764749)
			(xy 57.815357 -389.772225) (xy 57.79135 -389.772652) (xy 57.767818 -389.772209) (xy 57.72131 -389.765001)
			(xy 57.676462 -389.750733) (xy 57.634338 -389.729743) (xy 57.59594 -389.702531) (xy 57.562178 -389.669743)
			(xy 57.533855 -389.632156) (xy 57.522364 -389.611616) (xy 57.52211 -389.611108) (xy 57.521602 -389.610346)
			(xy 57.123838 -388.922006) (xy 57.11196 -388.89933) (xy 57.095111 -388.850996) (xy 57.086538 -388.800533)
			(xy 57.085992 -388.77494) (xy 57.085992 -388.774432) (xy 57.086083 -388.763087) (xy 57.087738 -388.740458)
			(xy 57.089294 -388.72922) (xy 57.090564 -388.72033) (xy 57.087008 -388.703058) (xy 57.043574 -388.631938)
			(xy 57.029604 -388.621016) (xy 57.021222 -388.617968) (xy 56.998815 -388.609947) (xy 56.956598 -388.587985)
			(xy 56.918302 -388.559735) (xy 56.884856 -388.525881) (xy 56.857073 -388.487245) (xy 56.835625 -388.444764)
			(xy 56.821032 -388.399469) (xy 56.813649 -388.352456) (xy 56.813196 -388.328662) (xy 56.813762 -388.302289)
			(xy 56.822845 -388.250331) (xy 56.840733 -388.20071) (xy 56.853328 -388.177532) (xy 56.8579 -388.169404)
			(xy 56.860694 -388.152132) (xy 56.845454 -388.069328) (xy 56.83631 -388.054088) (xy 56.829198 -388.0485)
			(xy 56.807027 -388.029794) (xy 56.76708 -387.987733) (xy 56.732763 -387.940965) (xy 56.704624 -387.890239)
			(xy 56.683114 -387.836366) (xy 56.668577 -387.780209) (xy 56.661247 -387.722666) (xy 56.660796 -387.693662)
			(xy 56.661391 -387.660341) (xy 56.671051 -387.594402) (xy 56.690175 -387.530563) (xy 56.703722 -387.500114)
			(xy 56.707947 -387.489642) (xy 56.707842 -387.467089) (xy 56.698118 -387.446739) (xy 56.689752 -387.439154)
			(xy 56.667496 -387.420491) (xy 56.627431 -387.378434) (xy 56.59301 -387.331647) (xy 56.564785 -387.28088)
			(xy 56.543212 -387.22695) (xy 56.528635 -387.170724) (xy 56.52129 -387.113105) (xy 56.520842 -387.084062)
			(xy 56.521297 -387.055136) (xy 56.528581 -386.997744) (xy 56.543039 -386.941727) (xy 56.564442 -386.88798)
			(xy 56.592449 -386.837358) (xy 56.626612 -386.79067) (xy 56.666387 -386.74866) (xy 56.688482 -386.729986)
			(xy 56.695457 -386.723642) (xy 56.704713 -386.707236) (xy 56.706516 -386.697982) (xy 56.710834 -386.666994)
			(xy 56.71174 -386.657757) (xy 56.707715 -386.639657) (xy 56.70296 -386.631688) (xy 56.686648 -386.605845)
			(xy 56.662748 -386.549607) (xy 56.655462 -386.519928) (xy 56.653413 -386.511762) (xy 56.644706 -386.497362)
			(xy 56.638444 -386.491734) (xy 56.61533 -386.472684) (xy 56.608437 -386.467458) (xy 56.592216 -386.46148)
			(xy 56.58358 -386.461) (xy 56.553944 -386.459974) (xy 56.49528 -386.451327) (xy 56.438223 -386.435178)
			(xy 56.383729 -386.411798) (xy 56.33271 -386.381577) (xy 56.28602 -386.345021) (xy 56.24444 -386.302743)
			(xy 56.208668 -386.255451) (xy 56.179301 -386.203935) (xy 56.156831 -386.149059) (xy 56.141635 -386.091741)
			(xy 56.133967 -386.032941) (xy 56.133492 -386.003292) (xy 56.134012 -385.972229) (xy 56.142428 -385.910675)
			(xy 56.150256 -385.88061) (xy 56.15305 -385.87045) (xy 56.15051 -385.850638) (xy 56.103012 -385.768342)
			(xy 56.08701 -385.75615) (xy 56.07685 -385.75361) (xy 56.047765 -385.745567) (xy 55.991838 -385.722902)
			(xy 55.939372 -385.693088) (xy 55.891277 -385.656641) (xy 55.848387 -385.614192) (xy 55.811443 -385.566477)
			(xy 55.781088 -385.514323) (xy 55.757846 -385.458633) (xy 55.74212 -385.400373) (xy 55.734183 -385.340552)
			(xy 55.733696 -385.31038) (xy 55.734222 -385.279492) (xy 55.742527 -385.218277) (xy 55.758984 -385.158733)
			(xy 55.783294 -385.101941) (xy 55.79872 -385.075176) (xy 55.804562 -385.06527) (xy 55.806848 -385.042918)
			(xy 55.773574 -384.947668) (xy 55.757826 -384.931666) (xy 55.747158 -384.927602) (xy 55.723768 -384.918439)
			(xy 55.679872 -384.894015) (xy 55.640177 -384.86323) (xy 55.605598 -384.826794) (xy 55.576929 -384.785544)
			(xy 55.554833 -384.740432) (xy 55.539817 -384.692495) (xy 55.532228 -384.642839) (xy 55.531766 -384.617722)
			(xy 54.993032 -384.617722) (xy 54.992503 -384.644824) (xy 54.983693 -384.698307) (xy 54.975506 -384.724148)
			(xy 54.971696 -384.73507) (xy 54.974236 -384.757422) (xy 55.026814 -384.843274) (xy 55.045864 -384.85572)
			(xy 55.05704 -384.857498) (xy 55.086359 -384.862198) (xy 55.14353 -384.878248) (xy 55.198144 -384.901559)
			(xy 55.249283 -384.931739) (xy 55.296089 -384.968281) (xy 55.337774 -385.01057) (xy 55.373638 -385.057898)
			(xy 55.403078 -385.109466) (xy 55.425599 -385.164411) (xy 55.440823 -385.221806) (xy 55.448495 -385.28069)
			(xy 55.448962 -385.31038) (xy 55.448435 -385.341443) (xy 55.440023 -385.402996) (xy 55.432198 -385.433062)
			(xy 55.429404 -385.443222) (xy 55.431944 -385.463034) (xy 55.479442 -385.54533) (xy 55.495444 -385.557522)
			(xy 55.505604 -385.560062) (xy 55.534704 -385.568094) (xy 55.590671 -385.590722) (xy 55.643177 -385.620512)
			(xy 55.691312 -385.656945) (xy 55.73424 -385.699389) (xy 55.771215 -385.747109) (xy 55.801596 -385.799275)
			(xy 55.824856 -385.854982) (xy 55.840591 -385.913264) (xy 55.848528 -385.973108) (xy 55.849012 -386.003292)
			(xy 55.848887 -386.017427) (xy 55.847105 -386.045641) (xy 55.845456 -386.05968) (xy 55.844695 -386.068287)
			(xy 55.848335 -386.085167) (xy 55.852568 -386.0927) (xy 55.868316 -386.1181) (xy 55.873018 -386.125166)
			(xy 55.886129 -386.135932) (xy 55.89397 -386.139182) (xy 55.91736 -386.148344) (xy 55.961255 -386.172769)
			(xy 56.000948 -386.203555) (xy 56.035527 -386.239992) (xy 56.064195 -386.281241) (xy 56.086291 -386.326353)
			(xy 56.101308 -386.374289) (xy 56.108899 -386.423945) (xy 56.109362 -386.449062) (xy 56.108943 -386.473264)
			(xy 56.101869 -386.52115) (xy 56.087881 -386.567489) (xy 56.067278 -386.611291) (xy 56.054244 -386.631688)
			(xy 56.049454 -386.639644) (xy 56.045422 -386.657756) (xy 56.04637 -386.666994) (xy 56.050688 -386.697982)
			(xy 56.052374 -386.707277) (xy 56.061652 -386.723719) (xy 56.068722 -386.729986) (xy 56.090801 -386.748678)
			(xy 56.130575 -386.790687) (xy 56.164739 -386.837373) (xy 56.192748 -386.887991) (xy 56.214157 -386.941735)
			(xy 56.228623 -386.997748) (xy 56.235917 -387.055137) (xy 56.236362 -387.084062) (xy 56.23577 -387.117383)
			(xy 56.226108 -387.183322) (xy 56.206983 -387.247161) (xy 56.193436 -387.27761) (xy 56.189169 -387.28807)
			(xy 56.189282 -387.310636) (xy 56.199028 -387.330989) (xy 56.207406 -387.33857) (xy 56.229638 -387.357261)
			(xy 56.269701 -387.399314) (xy 56.304123 -387.446097) (xy 56.33235 -387.496859) (xy 56.353928 -387.550784)
			(xy 56.368511 -387.607006) (xy 56.375863 -387.664621) (xy 56.376316 -387.693662) (xy 56.375852 -387.722668)
			(xy 56.368541 -387.780216) (xy 56.354018 -387.836379) (xy 56.332516 -387.890258) (xy 56.304379 -387.940988)
			(xy 56.270059 -387.987757) (xy 56.230105 -388.029816) (xy 56.207914 -388.0485) (xy 56.200802 -388.054088)
			(xy 56.191658 -388.069328) (xy 56.176418 -388.152132) (xy 56.179212 -388.169404) (xy 56.183784 -388.177532)
			(xy 56.196355 -388.200721) (xy 56.214231 -388.250341) (xy 56.223334 -388.302292) (xy 56.223916 -388.328662)
			(xy 56.223812 -388.339943) (xy 56.222161 -388.362445) (xy 56.220614 -388.37362) (xy 56.219344 -388.382764)
			(xy 56.222646 -388.400036) (xy 56.266334 -388.471156) (xy 56.28005 -388.482078) (xy 56.288686 -388.484872)
			(xy 56.316851 -388.495068) (xy 56.368797 -388.52488) (xy 56.39181 -388.544054) (xy 56.413296 -388.563634)
			(xy 56.449108 -388.609414) (xy 56.46293 -388.634986) (xy 56.463692 -388.636256) (xy 56.855868 -389.314944)
			(xy 56.868606 -389.338307) (xy 56.886718 -389.388336) (xy 56.895926 -389.440741) (xy 56.896508 -389.467344)
			(xy 56.896078 -389.491336) (xy 56.888565 -389.53873) (xy 56.873732 -389.584364) (xy 56.851943 -389.627117)
			(xy 56.823735 -389.665935) (xy 56.789802 -389.699863) (xy 56.750979 -389.728066) (xy 56.708224 -389.749849)
			(xy 56.662587 -389.764676) (xy 56.615192 -389.772181) (xy 56.5912 -389.772652) (xy 56.56767 -389.772169)
			(xy 56.521163 -389.764968) (xy 56.476316 -389.750707) (xy 56.434192 -389.729725) (xy 56.395793 -389.702519)
			(xy 56.36203 -389.669735) (xy 56.333706 -389.632154) (xy 56.322214 -389.611616) (xy 56.32196 -389.611108)
			(xy 56.321452 -389.610346) (xy 55.923942 -388.921752) (xy 55.913372 -388.901824) (xy 55.897567 -388.859575)
			(xy 55.888159 -388.815459) (xy 55.88635 -388.792974) (xy 55.885842 -388.781798) (xy 55.885588 -388.774432)
			(xy 55.885745 -388.763083) (xy 55.887522 -388.740454) (xy 55.889144 -388.72922) (xy 55.890414 -388.72033)
			(xy 55.886858 -388.703058) (xy 55.843424 -388.631938) (xy 55.829708 -388.620762) (xy 55.821072 -388.617968)
			(xy 55.79867 -388.609971) (xy 55.756499 -388.587968) (xy 55.718251 -388.559691) (xy 55.684851 -388.525824)
			(xy 55.657108 -388.487188) (xy 55.635692 -388.444716) (xy 55.621122 -388.399436) (xy 55.613751 -388.352445)
			(xy 55.6133 -388.328662) (xy 55.613866 -388.302289) (xy 55.622949 -388.250331) (xy 55.640837 -388.20071)
			(xy 55.653432 -388.177532) (xy 55.658004 -388.169404) (xy 55.660798 -388.152132) (xy 55.645558 -388.069328)
			(xy 55.636414 -388.054088) (xy 55.629302 -388.0485) (xy 55.607132 -388.029793) (xy 55.567185 -387.987732)
			(xy 55.532867 -387.940964) (xy 55.504728 -387.890238) (xy 55.483218 -387.836366) (xy 55.468682 -387.780209)
			(xy 55.461351 -387.722666) (xy 55.4609 -387.693662) (xy 55.461495 -387.660341) (xy 55.471154 -387.594402)
			(xy 55.490279 -387.530563) (xy 55.503826 -387.500114) (xy 55.50805 -387.489641) (xy 55.507945 -387.467089)
			(xy 55.498221 -387.446739) (xy 55.489856 -387.439154) (xy 55.467601 -387.42049) (xy 55.427536 -387.378434)
			(xy 55.393114 -387.331647) (xy 55.36489 -387.28088) (xy 55.343316 -387.22695) (xy 55.328739 -387.170723)
			(xy 55.321394 -387.113105) (xy 55.320946 -387.084062) (xy 55.3214 -387.055136) (xy 55.328683 -386.997744)
			(xy 55.343142 -386.941727) (xy 55.364545 -386.887979) (xy 55.392552 -386.837358) (xy 55.426715 -386.79067)
			(xy 55.466491 -386.74866) (xy 55.488586 -386.729986) (xy 55.495562 -386.723643) (xy 55.504817 -386.707236)
			(xy 55.50662 -386.697982) (xy 55.510938 -386.666994) (xy 55.511843 -386.657757) (xy 55.507818 -386.639657)
			(xy 55.503064 -386.631688) (xy 55.486753 -386.605844) (xy 55.462852 -386.549607) (xy 55.455566 -386.519928)
			(xy 55.453516 -386.511763) (xy 55.444809 -386.497363) (xy 55.438548 -386.491734) (xy 55.415434 -386.472684)
			(xy 55.40854 -386.467459) (xy 55.39232 -386.461481) (xy 55.383684 -386.461) (xy 55.354048 -386.45997)
			(xy 55.295384 -386.451324) (xy 55.238327 -386.435176) (xy 55.183833 -386.411796) (xy 55.132814 -386.381575)
			(xy 55.086124 -386.34502) (xy 55.044544 -386.302742) (xy 55.008772 -386.25545) (xy 54.979405 -386.203935)
			(xy 54.956935 -386.149059) (xy 54.941739 -386.091741) (xy 54.934071 -386.032941) (xy 54.933596 -386.003292)
			(xy 54.934116 -385.972229) (xy 54.942532 -385.910675) (xy 54.95036 -385.88061) (xy 54.953154 -385.87045)
			(xy 54.950614 -385.850638) (xy 54.903116 -385.768342) (xy 54.887114 -385.75615) (xy 54.876954 -385.75361)
			(xy 54.847838 -385.745632) (xy 54.79187 -385.722997) (xy 54.739363 -385.6932) (xy 54.691229 -385.656761)
			(xy 54.648303 -385.61431) (xy 54.611329 -385.566584) (xy 54.58095 -385.514413) (xy 54.557693 -385.4587)
			(xy 54.541961 -385.400414) (xy 54.534027 -385.340566) (xy 54.533546 -385.31038) (xy 54.534065 -385.279492)
			(xy 54.542371 -385.218276) (xy 54.55883 -385.158732) (xy 54.583142 -385.10194) (xy 54.59857 -385.075176)
			(xy 54.604412 -385.06527) (xy 54.606698 -385.042918) (xy 54.573424 -384.947668) (xy 54.557676 -384.931666)
			(xy 54.547008 -384.927602) (xy 54.523629 -384.918412) (xy 54.479732 -384.893994) (xy 54.440035 -384.863215)
			(xy 54.405453 -384.826783) (xy 54.376783 -384.785537) (xy 54.354685 -384.740427) (xy 54.339668 -384.692493)
			(xy 54.332078 -384.642838) (xy 54.331616 -384.617722) (xy 53.793136 -384.617722) (xy 53.792607 -384.644824)
			(xy 53.783797 -384.698307) (xy 53.77561 -384.724148) (xy 53.7718 -384.73507) (xy 53.77434 -384.757422)
			(xy 53.826918 -384.843274) (xy 53.845968 -384.85572) (xy 53.857144 -384.857498) (xy 53.886464 -384.862195)
			(xy 53.943634 -384.878245) (xy 53.998248 -384.901556) (xy 54.049388 -384.931737) (xy 54.096193 -384.968279)
			(xy 54.137878 -385.010569) (xy 54.173742 -385.057897) (xy 54.203182 -385.109466) (xy 54.225703 -385.16441)
			(xy 54.240927 -385.221806) (xy 54.248599 -385.280689) (xy 54.249066 -385.31038) (xy 54.248539 -385.341443)
			(xy 54.240127 -385.402996) (xy 54.232302 -385.433062) (xy 54.229508 -385.443222) (xy 54.232048 -385.463034)
			(xy 54.279546 -385.54533) (xy 54.295548 -385.557522) (xy 54.305708 -385.560062) (xy 54.334809 -385.568091)
			(xy 54.390776 -385.59072) (xy 54.443282 -385.62051) (xy 54.491417 -385.656943) (xy 54.534344 -385.699388)
			(xy 54.571319 -385.747108) (xy 54.6017 -385.799274) (xy 54.62496 -385.854982) (xy 54.640695 -385.913263)
			(xy 54.648632 -385.973108) (xy 54.649116 -386.003292) (xy 54.648991 -386.017427) (xy 54.647209 -386.045641)
			(xy 54.64556 -386.05968) (xy 54.644799 -386.068287) (xy 54.648439 -386.085167) (xy 54.652672 -386.0927)
			(xy 54.66842 -386.1181) (xy 54.67314 -386.125155) (xy 54.686232 -386.135938) (xy 54.694074 -386.139182)
			(xy 54.717432 -386.148386) (xy 54.761274 -386.172846) (xy 54.800917 -386.203651) (xy 54.835449 -386.240091)
			(xy 54.864079 -386.281331) (xy 54.886149 -386.326424) (xy 54.901152 -386.374334) (xy 54.908744 -386.42396)
			(xy 54.909212 -386.449062) (xy 54.908785 -386.473264) (xy 54.901712 -386.521148) (xy 54.887726 -386.567488)
			(xy 54.867127 -386.61129) (xy 54.854094 -386.631688) (xy 54.849308 -386.639646) (xy 54.845272 -386.657756)
			(xy 54.84622 -386.666994) (xy 54.850538 -386.697982) (xy 54.852209 -386.707281) (xy 54.861497 -386.723722)
			(xy 54.868572 -386.729986) (xy 54.890662 -386.748666) (xy 54.930433 -386.790678) (xy 54.964595 -386.837367)
			(xy 54.992602 -386.887987) (xy 55.014009 -386.941732) (xy 55.028474 -386.997746) (xy 55.035767 -387.055136)
			(xy 55.036212 -387.084062) (xy 55.035625 -387.117384) (xy 55.025962 -387.183322) (xy 55.006834 -387.247161)
			(xy 54.993286 -387.27761) (xy 54.989035 -387.288074) (xy 54.989149 -387.310634) (xy 54.998885 -387.330986)
			(xy 55.007256 -387.33857) (xy 55.029477 -387.357274) (xy 55.069543 -387.399323) (xy 55.103968 -387.446103)
			(xy 55.132196 -387.496863) (xy 55.153776 -387.550787) (xy 55.16836 -387.607007) (xy 55.175713 -387.664621)
			(xy 55.176166 -387.693662) (xy 55.175684 -387.722667) (xy 55.168373 -387.780214) (xy 55.153852 -387.836376)
			(xy 55.132352 -387.890254) (xy 55.104219 -387.940984) (xy 55.069902 -387.987754) (xy 55.029953 -388.029815)
			(xy 55.007764 -388.0485) (xy 55.000652 -388.054088) (xy 54.991508 -388.069328) (xy 54.976268 -388.152132)
			(xy 54.979062 -388.169404) (xy 54.983634 -388.177532) (xy 54.996209 -388.200719) (xy 55.014083 -388.25034)
			(xy 55.023184 -388.302291) (xy 55.023766 -388.328662) (xy 55.023663 -388.339943) (xy 55.022011 -388.362445)
			(xy 55.020464 -388.37362) (xy 55.019194 -388.38251) (xy 55.02275 -388.400036) (xy 55.066184 -388.470902)
			(xy 55.0799 -388.482078) (xy 55.088536 -388.484872) (xy 55.110778 -388.492817) (xy 55.152699 -388.514565)
			(xy 55.190774 -388.542507) (xy 55.224093 -388.575977) (xy 55.251863 -388.614177) (xy 55.263034 -388.634986)
			(xy 55.263542 -388.636002) (xy 55.655972 -389.314944) (xy 55.66871 -389.338307) (xy 55.686822 -389.388336)
			(xy 55.69603 -389.440741) (xy 55.696612 -389.467344) (xy 55.696178 -389.491336) (xy 55.688665 -389.538729)
			(xy 55.673832 -389.584363) (xy 55.652044 -389.627116) (xy 55.623836 -389.665934) (xy 55.589903 -389.699862)
			(xy 55.551082 -389.728065) (xy 55.508326 -389.749848) (xy 55.46269 -389.764675) (xy 55.415296 -389.772181)
			(xy 55.391304 -389.772652) (xy 55.367774 -389.772165) (xy 55.321268 -389.764965) (xy 55.27642 -389.750705)
			(xy 55.234297 -389.729723) (xy 55.195897 -389.702518) (xy 55.162134 -389.669735) (xy 55.13381 -389.632154)
			(xy 55.122318 -389.611616) (xy 55.122064 -389.611108) (xy 55.121556 -389.610346) (xy 54.723792 -388.922006)
			(xy 54.711876 -388.899338) (xy 54.694939 -388.851012) (xy 54.686279 -388.800542) (xy 54.685692 -388.77494)
			(xy 54.685692 -388.774432) (xy 54.685849 -388.763083) (xy 54.687626 -388.740454) (xy 54.689248 -388.72922)
			(xy 54.690518 -388.72033) (xy 54.686962 -388.703058) (xy 54.643528 -388.631938) (xy 54.629558 -388.621016)
			(xy 54.621176 -388.617968) (xy 54.598781 -388.609916) (xy 54.556562 -388.587961) (xy 54.518264 -388.559717)
			(xy 54.484816 -388.525868) (xy 54.45703 -388.487237) (xy 54.435581 -388.444759) (xy 54.420987 -388.399465)
			(xy 54.413603 -388.352455) (xy 54.41315 -388.328662) (xy 54.413722 -388.302289) (xy 54.422804 -388.250331)
			(xy 54.440689 -388.200711) (xy 54.453282 -388.177532) (xy 54.457854 -388.169404) (xy 54.460648 -388.152132)
			(xy 54.445408 -388.069328) (xy 54.436264 -388.054088) (xy 54.429152 -388.0485) (xy 54.406971 -388.029806)
			(xy 54.367027 -387.987741) (xy 54.332711 -387.94097) (xy 54.304575 -387.890242) (xy 54.283066 -387.836368)
			(xy 54.268531 -387.78021) (xy 54.2612 -387.722666) (xy 54.26075 -387.693662) (xy 54.261349 -387.660341)
			(xy 54.271008 -387.594403) (xy 54.29013 -387.530563) (xy 54.303676 -387.500114) (xy 54.307916 -387.489646)
			(xy 54.307811 -387.467087) (xy 54.298078 -387.446736) (xy 54.289706 -387.439154) (xy 54.26744 -387.420502)
			(xy 54.227378 -387.378443) (xy 54.192959 -387.331653) (xy 54.164736 -387.280884) (xy 54.143164 -387.226952)
			(xy 54.128588 -387.170725) (xy 54.121244 -387.113105) (xy 54.120796 -387.084062) (xy 54.121231 -387.055135)
			(xy 54.128516 -386.997741) (xy 54.142976 -386.941724) (xy 54.164382 -386.887975) (xy 54.192392 -386.837354)
			(xy 54.226559 -386.790667) (xy 54.266338 -386.748659) (xy 54.288436 -386.729986) (xy 54.295404 -386.723634)
			(xy 54.304665 -386.707234) (xy 54.30647 -386.697982) (xy 54.310788 -386.666994) (xy 54.311686 -386.657757)
			(xy 54.307665 -386.639658) (xy 54.302914 -386.631688) (xy 54.286607 -386.605842) (xy 54.262703 -386.549607)
			(xy 54.255416 -386.519928) (xy 54.253353 -386.511767) (xy 54.244655 -386.497366) (xy 54.238398 -386.491734)
			(xy 54.215284 -386.472684) (xy 54.208461 -386.467467) (xy 54.192363 -386.461503) (xy 54.183788 -386.461)
			(xy 54.154152 -386.459967) (xy 54.095488 -386.451321) (xy 54.038432 -386.435173) (xy 53.983937 -386.411793)
			(xy 53.932918 -386.381573) (xy 53.886228 -386.345018) (xy 53.844649 -386.302741) (xy 53.808876 -386.255449)
			(xy 53.779509 -386.203934) (xy 53.757039 -386.149058) (xy 53.741843 -386.091741) (xy 53.734175 -386.032941)
			(xy 53.7337 -386.003292) (xy 53.73422 -385.972229) (xy 53.742636 -385.910675) (xy 53.750464 -385.88061)
			(xy 53.753258 -385.87045) (xy 53.750718 -385.850638) (xy 53.70322 -385.768342) (xy 53.687218 -385.75615)
			(xy 53.677058 -385.75361) (xy 53.647943 -385.745629) (xy 53.591975 -385.722994) (xy 53.539468 -385.693198)
			(xy 53.491334 -385.656759) (xy 53.448408 -385.614308) (xy 53.411434 -385.566583) (xy 53.381055 -385.514412)
			(xy 53.357797 -385.4587) (xy 53.342065 -385.400414) (xy 53.334132 -385.340566) (xy 53.33365 -385.31038)
			(xy 53.334169 -385.279492) (xy 53.342475 -385.218276) (xy 53.358933 -385.158732) (xy 53.383246 -385.10194)
			(xy 53.398674 -385.075176) (xy 53.404516 -385.06527) (xy 53.406802 -385.042918) (xy 53.373528 -384.947668)
			(xy 53.35778 -384.931666) (xy 53.347112 -384.927602) (xy 53.323734 -384.918409) (xy 53.279836 -384.893993)
			(xy 53.240139 -384.863214) (xy 53.205557 -384.826782) (xy 53.176887 -384.785536) (xy 53.154789 -384.740427)
			(xy 53.139772 -384.692492) (xy 53.132182 -384.642838) (xy 53.13172 -384.617722) (xy 52.59324 -384.617722)
			(xy 52.59271 -384.644824) (xy 52.583901 -384.698307) (xy 52.575714 -384.724148) (xy 52.571904 -384.73507)
			(xy 52.574444 -384.757422) (xy 52.627022 -384.843528) (xy 52.645818 -384.85572) (xy 52.657248 -384.857498)
			(xy 52.686538 -384.862302) (xy 52.743672 -384.878376) (xy 52.798248 -384.901702) (xy 52.849351 -384.931888)
			(xy 52.896122 -384.968427) (xy 52.937777 -385.010707) (xy 52.973616 -385.058018) (xy 53.003037 -385.109565)
			(xy 53.025547 -385.164483) (xy 53.040767 -385.22185) (xy 53.048443 -385.280704) (xy 53.048916 -385.31038)
			(xy 53.04839 -385.341443) (xy 53.039978 -385.402996) (xy 53.032152 -385.433062) (xy 53.029358 -385.443222)
			(xy 53.031898 -385.463034) (xy 53.079396 -385.54533) (xy 53.095398 -385.557522) (xy 53.105558 -385.560062)
			(xy 53.134669 -385.568058) (xy 53.190635 -385.590693) (xy 53.24314 -385.620488) (xy 53.291274 -385.656926)
			(xy 53.3342 -385.699375) (xy 53.371173 -385.747098) (xy 53.401553 -385.799267) (xy 53.424812 -385.854977)
			(xy 53.440546 -385.913261) (xy 53.448483 -385.973107) (xy 53.448966 -386.003292) (xy 53.448841 -386.017427)
			(xy 53.447059 -386.045641) (xy 53.44541 -386.05968) (xy 53.444656 -386.068287) (xy 53.448292 -386.085166)
			(xy 53.452522 -386.0927) (xy 53.46827 -386.1181) (xy 53.472986 -386.125155) (xy 53.486087 -386.135927)
			(xy 53.493924 -386.139182) (xy 53.517304 -386.148368) (xy 53.5612 -386.172788) (xy 53.600895 -386.203569)
			(xy 53.635476 -386.240002) (xy 53.664146 -386.281249) (xy 53.686244 -386.326358) (xy 53.701261 -386.374292)
			(xy 53.708853 -386.423946) (xy 53.709316 -386.449062) (xy 53.708888 -386.473264) (xy 53.701815 -386.521148)
			(xy 53.687829 -386.567488) (xy 53.667231 -386.61129) (xy 53.654198 -386.631688) (xy 53.649412 -386.639646)
			(xy 53.645376 -386.657756) (xy 53.646324 -386.666994) (xy 53.650642 -386.697982) (xy 53.652312 -386.707281)
			(xy 53.6616 -386.723722) (xy 53.668676 -386.729986) (xy 53.690767 -386.748665) (xy 53.730538 -386.790678)
			(xy 53.764699 -386.837366) (xy 53.792706 -386.887987) (xy 53.814113 -386.941732) (xy 53.828578 -386.997746)
			(xy 53.835871 -387.055136) (xy 53.836316 -387.084062) (xy 53.835728 -387.117384) (xy 53.826065 -387.183322)
			(xy 53.806938 -387.247161) (xy 53.79339 -387.27761) (xy 53.789138 -387.288074) (xy 53.789252 -387.310634)
			(xy 53.798988 -387.330986) (xy 53.80736 -387.33857) (xy 53.829582 -387.357273) (xy 53.869648 -387.399322)
			(xy 53.904072 -387.446103) (xy 53.932301 -387.496863) (xy 53.95388 -387.550787) (xy 53.968464 -387.607007)
			(xy 53.975817 -387.664621) (xy 53.97627 -387.693662) (xy 53.975787 -387.722667) (xy 53.968476 -387.780213)
			(xy 53.953955 -387.836376) (xy 53.932455 -387.890253) (xy 53.904322 -387.940984) (xy 53.870006 -387.987754)
			(xy 53.830057 -388.029815) (xy 53.807868 -388.0485) (xy 53.800756 -388.054088) (xy 53.791612 -388.069328)
			(xy 53.776372 -388.152132) (xy 53.779166 -388.169404) (xy 53.783738 -388.177532) (xy 53.796313 -388.200719)
			(xy 53.814187 -388.25034) (xy 53.823288 -388.302291) (xy 53.82387 -388.328662) (xy 53.823766 -388.339943)
			(xy 53.822115 -388.362445) (xy 53.820568 -388.37362) (xy 53.819298 -388.38251) (xy 53.822854 -388.400036)
			(xy 53.866288 -388.470902) (xy 53.880004 -388.482078) (xy 53.88864 -388.484872) (xy 53.910882 -388.492815)
			(xy 53.952804 -388.514563) (xy 53.990878 -388.542506) (xy 54.024197 -388.575977) (xy 54.051967 -388.614177)
			(xy 54.063138 -388.634986) (xy 54.063646 -388.636002) (xy 54.456076 -389.314944) (xy 54.468806 -389.338311)
			(xy 54.486923 -389.388338) (xy 54.496134 -389.440741) (xy 54.496716 -389.467344) (xy 54.496278 -389.491336)
			(xy 54.488766 -389.538728) (xy 54.473933 -389.584362) (xy 54.452144 -389.627115) (xy 54.423937 -389.665932)
			(xy 54.390005 -389.69986) (xy 54.351184 -389.728063) (xy 54.308429 -389.749846) (xy 54.262793 -389.764674)
			(xy 54.2154 -389.772181) (xy 54.191408 -389.772652) (xy 54.167878 -389.772162) (xy 54.121372 -389.764963)
			(xy 54.076525 -389.750703) (xy 54.034401 -389.729721) (xy 53.996002 -389.702517) (xy 53.962239 -389.669734)
			(xy 53.933914 -389.632153) (xy 53.922422 -389.611616) (xy 53.922168 -389.611108) (xy 53.92166 -389.610346)
			(xy 53.523896 -388.922006) (xy 53.51198 -388.899338) (xy 53.495043 -388.851012) (xy 53.486383 -388.800542)
			(xy 53.485796 -388.77494) (xy 53.485796 -388.774432) (xy 53.485953 -388.763083) (xy 53.48773 -388.740454)
			(xy 53.489352 -388.72922) (xy 53.490622 -388.72033) (xy 53.487066 -388.703058) (xy 53.443632 -388.631938)
			(xy 53.429662 -388.621016) (xy 53.42128 -388.617968) (xy 53.398886 -388.609914) (xy 53.356666 -388.58796)
			(xy 53.318368 -388.559716) (xy 53.284921 -388.525867) (xy 53.257135 -388.487236) (xy 53.235685 -388.444758)
			(xy 53.221091 -388.399465) (xy 53.213707 -388.352455) (xy 53.213254 -388.328662) (xy 53.213826 -388.302289)
			(xy 53.222907 -388.250331) (xy 53.240793 -388.200711) (xy 53.253386 -388.177532) (xy 53.257958 -388.169404)
			(xy 53.260752 -388.152132) (xy 53.245512 -388.069328) (xy 53.236368 -388.054088) (xy 53.229256 -388.0485)
			(xy 53.207076 -388.029805) (xy 53.167131 -387.98774) (xy 53.132816 -387.94097) (xy 53.104679 -387.890242)
			(xy 53.083171 -387.836368) (xy 53.068635 -387.78021) (xy 53.061305 -387.722666) (xy 53.060854 -387.693662)
			(xy 53.061453 -387.660341) (xy 53.071112 -387.594403) (xy 53.090234 -387.530563) (xy 53.10378 -387.500114)
			(xy 53.108019 -387.489645) (xy 53.107914 -387.467087) (xy 53.098181 -387.446737) (xy 53.08981 -387.439154)
			(xy 53.067545 -387.420501) (xy 53.027482 -387.378442) (xy 52.993063 -387.331652) (xy 52.96484 -387.280883)
			(xy 52.943268 -387.226952) (xy 52.928692 -387.170725) (xy 52.921348 -387.113105) (xy 52.9209 -387.084062)
			(xy 52.921334 -387.055135) (xy 52.928618 -386.997741) (xy 52.943079 -386.941723) (xy 52.964485 -386.887975)
			(xy 52.992495 -386.837354) (xy 53.026663 -386.790667) (xy 53.066442 -386.748658) (xy 53.08854 -386.729986)
			(xy 53.095508 -386.723635) (xy 53.104769 -386.707234) (xy 53.106574 -386.697982) (xy 53.110892 -386.666994)
			(xy 53.111789 -386.657757) (xy 53.107768 -386.639658) (xy 53.103018 -386.631688) (xy 53.086711 -386.605842)
			(xy 53.062807 -386.549607) (xy 53.05552 -386.519928) (xy 53.053456 -386.511768) (xy 53.044758 -386.497366)
			(xy 53.038502 -386.491734) (xy 53.015388 -386.472684) (xy 53.008506 -386.467441) (xy 52.992277 -386.461474)
			(xy 52.983638 -386.461) (xy 52.954 -386.460013) (xy 52.895335 -386.451361) (xy 52.838278 -386.435207)
			(xy 52.783783 -386.411822) (xy 52.732764 -386.381597) (xy 52.686075 -386.345037) (xy 52.644496 -386.302756)
			(xy 52.608724 -386.255461) (xy 52.579358 -386.203943) (xy 52.556889 -386.149064) (xy 52.541693 -386.091744)
			(xy 52.534025 -386.032942) (xy 52.53355 -386.003292) (xy 52.534071 -385.972229) (xy 52.542487 -385.910675)
			(xy 52.550314 -385.88061) (xy 52.553108 -385.87045) (xy 52.550568 -385.850638) (xy 52.50307 -385.768342)
			(xy 52.487068 -385.75615) (xy 52.476908 -385.75361) (xy 52.447783 -385.745662) (xy 52.391816 -385.723021)
			(xy 52.33931 -385.69322) (xy 52.291177 -385.656776) (xy 52.248252 -385.614322) (xy 52.21128 -385.566593)
			(xy 52.180902 -385.514419) (xy 52.157646 -385.458705) (xy 52.141914 -385.400417) (xy 52.133981 -385.340567)
			(xy 52.1335 -385.31038) (xy 52.133965 -385.279457) (xy 52.142248 -385.21817) (xy 52.158716 -385.158558)
			(xy 52.183067 -385.101709) (xy 52.198524 -385.074922) (xy 52.20462 -385.06527) (xy 52.206906 -385.042918)
			(xy 52.173378 -384.947668) (xy 52.15763 -384.931666) (xy 52.146962 -384.927602) (xy 52.123606 -384.918392)
			(xy 52.079763 -384.893934) (xy 52.040119 -384.863132) (xy 52.005585 -384.826693) (xy 51.976954 -384.785453)
			(xy 51.954884 -384.740361) (xy 51.939882 -384.692451) (xy 51.932292 -384.642824) (xy 51.931824 -384.617722)
			(xy 51.39309 -384.617722) (xy 51.392558 -384.644824) (xy 51.38375 -384.698306) (xy 51.375564 -384.724148)
			(xy 51.371754 -384.73507) (xy 51.374294 -384.757422) (xy 51.426872 -384.843274) (xy 51.445922 -384.85572)
			(xy 51.457098 -384.857498) (xy 51.486412 -384.862231) (xy 51.543582 -384.878276) (xy 51.598196 -384.901582)
			(xy 51.649336 -384.931757) (xy 51.696142 -384.968296) (xy 51.737828 -385.010582) (xy 51.773693 -385.057906)
			(xy 51.803134 -385.109473) (xy 51.825656 -385.164415) (xy 51.840881 -385.221809) (xy 51.848553 -385.28069)
			(xy 51.84902 -385.31038) (xy 51.848494 -385.341443) (xy 51.840082 -385.402996) (xy 51.832256 -385.433062)
			(xy 51.829462 -385.443222) (xy 51.832002 -385.463034) (xy 51.8795 -385.54533) (xy 51.895502 -385.557522)
			(xy 51.905662 -385.560062) (xy 51.934773 -385.568055) (xy 51.99074 -385.59069) (xy 52.043245 -385.620486)
			(xy 52.091378 -385.656924) (xy 52.134304 -385.699374) (xy 52.171278 -385.747097) (xy 52.201657 -385.799267)
			(xy 52.224916 -385.854977) (xy 52.24065 -385.91326) (xy 52.248587 -385.973107) (xy 52.24907 -386.003292)
			(xy 52.248944 -386.017427) (xy 52.247163 -386.045641) (xy 52.245514 -386.05968) (xy 52.244759 -386.068287)
			(xy 52.248396 -386.085166) (xy 52.252626 -386.0927) (xy 52.268374 -386.1181) (xy 52.273076 -386.125168)
			(xy 52.28618 -386.135945) (xy 52.294028 -386.139182) (xy 52.317376 -386.148411) (xy 52.361219 -386.172866)
			(xy 52.400863 -386.203665) (xy 52.435398 -386.240102) (xy 52.46403 -386.281339) (xy 52.486101 -386.326429)
			(xy 52.501105 -386.374336) (xy 52.508697 -386.423961) (xy 52.509166 -386.449062) (xy 52.508746 -386.473264)
			(xy 52.501672 -386.521149) (xy 52.487684 -386.567489) (xy 52.467082 -386.611291) (xy 52.454048 -386.631688)
			(xy 52.449258 -386.639644) (xy 52.445226 -386.657756) (xy 52.446174 -386.666994) (xy 52.450492 -386.697982)
			(xy 52.452176 -386.707277) (xy 52.461456 -386.723719) (xy 52.468526 -386.729986) (xy 52.490606 -386.748677)
			(xy 52.53038 -386.790687) (xy 52.564543 -386.837372) (xy 52.592552 -386.887991) (xy 52.613961 -386.941735)
			(xy 52.628427 -386.997747) (xy 52.635721 -387.055137) (xy 52.636166 -387.084062) (xy 52.635574 -387.117383)
			(xy 52.625912 -387.183322) (xy 52.606787 -387.247161) (xy 52.59324 -387.27761) (xy 52.588972 -387.28807)
			(xy 52.589085 -387.310636) (xy 52.598832 -387.330989) (xy 52.60721 -387.33857) (xy 52.629442 -387.35726)
			(xy 52.669506 -387.399313) (xy 52.703928 -387.446097) (xy 52.732154 -387.496859) (xy 52.753732 -387.550784)
			(xy 52.768315 -387.607006) (xy 52.775667 -387.664621) (xy 52.77612 -387.693662) (xy 52.775655 -387.722667)
			(xy 52.768343 -387.780216) (xy 52.75382 -387.836379) (xy 52.732318 -387.890257) (xy 52.704182 -387.940988)
			(xy 52.669862 -387.987757) (xy 52.629909 -388.029816) (xy 52.607718 -388.0485) (xy 52.600606 -388.054088)
			(xy 52.591462 -388.069328) (xy 52.576222 -388.152132) (xy 52.579016 -388.169404) (xy 52.583588 -388.177532)
			(xy 52.596159 -388.200721) (xy 52.614036 -388.250341) (xy 52.623138 -388.302292) (xy 52.62372 -388.328662)
			(xy 52.623616 -388.339943) (xy 52.621965 -388.362445) (xy 52.620418 -388.37362) (xy 52.619148 -388.38251)
			(xy 52.622704 -388.400036) (xy 52.666138 -388.470902) (xy 52.679854 -388.482078) (xy 52.68849 -388.484872)
			(xy 52.710741 -388.492791) (xy 52.752662 -388.514546) (xy 52.790734 -388.542495) (xy 52.824051 -388.57597)
			(xy 52.851818 -388.614175) (xy 52.862988 -388.634986) (xy 52.863496 -388.636002) (xy 53.255926 -389.314944)
			(xy 53.268731 -389.338286) (xy 53.286959 -389.388304) (xy 53.296227 -389.440727) (xy 53.29682 -389.467344)
			(xy 53.296402 -389.49135) (xy 53.288881 -389.538771) (xy 53.274031 -389.58443) (xy 53.252219 -389.627202)
			(xy 53.223982 -389.666034) (xy 53.190016 -389.699969) (xy 53.151158 -389.728169) (xy 53.108365 -389.749941)
			(xy 53.062692 -389.764748) (xy 53.015265 -389.772224) (xy 52.991258 -389.772652) (xy 52.967726 -389.772202)
			(xy 52.921219 -389.764996) (xy 52.87637 -389.750729) (xy 52.834247 -389.72974) (xy 52.795848 -389.702529)
			(xy 52.762086 -389.669741) (xy 52.733763 -389.632156) (xy 52.722272 -389.611616) (xy 52.722018 -389.611108)
			(xy 52.72151 -389.610346) (xy 52.323746 -388.922006) (xy 52.311869 -388.89933) (xy 52.295019 -388.850996)
			(xy 52.286446 -388.800533) (xy 52.2859 -388.77494) (xy 52.2859 -388.774432) (xy 52.285991 -388.763087)
			(xy 52.287646 -388.740458) (xy 52.289202 -388.72922) (xy 52.290472 -388.72033) (xy 52.286916 -388.703058)
			(xy 52.243482 -388.631938) (xy 52.229512 -388.621016) (xy 52.22113 -388.617968) (xy 52.198725 -388.609942)
			(xy 52.156507 -388.587982) (xy 52.118211 -388.559732) (xy 52.084765 -388.525879) (xy 52.056981 -388.487244)
			(xy 52.035533 -388.444764) (xy 52.02094 -388.399468) (xy 52.013557 -388.352456) (xy 52.013104 -388.328662)
			(xy 52.013669 -388.302289) (xy 52.022752 -388.25033) (xy 52.040641 -388.20071) (xy 52.053236 -388.177532)
			(xy 52.057808 -388.169404) (xy 52.060602 -388.152132) (xy 52.045362 -388.069328) (xy 52.036218 -388.054088)
			(xy 52.029106 -388.0485) (xy 52.006937 -388.029792) (xy 51.966989 -387.987731) (xy 51.932671 -387.940964)
			(xy 51.904532 -387.890238) (xy 51.883022 -387.836366) (xy 51.868486 -387.780209) (xy 51.861155 -387.722666)
			(xy 51.860704 -387.693662) (xy 51.861307 -387.660341) (xy 51.870965 -387.594403) (xy 51.890086 -387.530564)
			(xy 51.90363 -387.500114) (xy 51.907853 -387.489641) (xy 51.907747 -387.467089) (xy 51.898024 -387.44674)
			(xy 51.88966 -387.439154) (xy 51.867405 -387.420489) (xy 51.82734 -387.378433) (xy 51.792919 -387.331646)
			(xy 51.764694 -387.28088) (xy 51.74312 -387.22695) (xy 51.728543 -387.170723) (xy 51.721198 -387.113105)
			(xy 51.72075 -387.084062) (xy 51.721202 -387.055136) (xy 51.728486 -386.997743) (xy 51.742945 -386.941727)
			(xy 51.764348 -386.887979) (xy 51.792355 -386.837358) (xy 51.826519 -386.79067) (xy 51.866294 -386.74866)
			(xy 51.88839 -386.729986) (xy 51.895367 -386.723643) (xy 51.904621 -386.707236) (xy 51.906424 -386.697982)
			(xy 51.910742 -386.666994) (xy 51.911647 -386.657757) (xy 51.907622 -386.639657) (xy 51.902868 -386.631688)
			(xy 51.886557 -386.605844) (xy 51.862656 -386.549607) (xy 51.85537 -386.519928) (xy 51.853319 -386.511763)
			(xy 51.844613 -386.497363) (xy 51.838352 -386.491734) (xy 51.815238 -386.472684) (xy 51.808401 -386.467488)
			(xy 51.792314 -386.461512) (xy 51.783742 -386.461) (xy 51.754105 -386.460009) (xy 51.695439 -386.451357)
			(xy 51.638382 -386.435204) (xy 51.583888 -386.411819) (xy 51.532869 -386.381595) (xy 51.486179 -386.345036)
			(xy 51.4446 -386.302755) (xy 51.408828 -386.25546) (xy 51.379462 -386.203942) (xy 51.356993 -386.149064)
			(xy 51.341797 -386.091744) (xy 51.334129 -386.032942) (xy 51.333654 -386.003292) (xy 51.334175 -385.972229)
			(xy 51.342591 -385.910675) (xy 51.350418 -385.88061) (xy 51.353212 -385.87045) (xy 51.350672 -385.850638)
			(xy 51.303174 -385.768342) (xy 51.287172 -385.75615) (xy 51.277012 -385.75361) (xy 51.247888 -385.74566)
			(xy 51.191921 -385.723019) (xy 51.139415 -385.693219) (xy 51.091282 -385.656775) (xy 51.048356 -385.614321)
			(xy 51.011384 -385.566593) (xy 50.981006 -385.514419) (xy 50.95775 -385.458704) (xy 50.942019 -385.400417)
			(xy 50.934085 -385.340567) (xy 50.933604 -385.31038) (xy 50.934129 -385.279492) (xy 50.942434 -385.218277)
			(xy 50.958891 -385.158733) (xy 50.983201 -385.101941) (xy 50.998628 -385.075176) (xy 51.00447 -385.06527)
			(xy 51.006756 -385.042918) (xy 50.973482 -384.947668) (xy 50.957734 -384.931666) (xy 50.947066 -384.927602)
			(xy 50.923678 -384.918434) (xy 50.879782 -384.894012) (xy 50.840086 -384.863228) (xy 50.805506 -384.826792)
			(xy 50.776838 -384.785543) (xy 50.754741 -384.740431) (xy 50.739725 -384.692495) (xy 50.732136 -384.642839)
			(xy 50.731674 -384.617722) (xy 50.193194 -384.617722) (xy 50.192662 -384.644824) (xy 50.183854 -384.698306)
			(xy 50.175668 -384.724148) (xy 50.171858 -384.73507) (xy 50.174398 -384.757422) (xy 50.226976 -384.843274)
			(xy 50.246026 -384.85572) (xy 50.257202 -384.857498) (xy 50.286516 -384.862228) (xy 50.343687 -384.878273)
			(xy 50.398301 -384.901579) (xy 50.449441 -384.931756) (xy 50.496247 -384.968294) (xy 50.537933 -385.010581)
			(xy 50.573797 -385.057906) (xy 50.603238 -385.109472) (xy 50.62576 -385.164415) (xy 50.640985 -385.221809)
			(xy 50.648657 -385.28069) (xy 50.649124 -385.31038) (xy 50.648602 -385.341506) (xy 50.640195 -385.403188)
			(xy 50.63236 -385.433316) (xy 50.629566 -385.443476) (xy 50.632106 -385.463542) (xy 50.67935 -385.54533)
			(xy 50.695352 -385.557522) (xy 50.705512 -385.560062) (xy 50.734614 -385.568089) (xy 50.790581 -385.590718)
			(xy 50.843087 -385.620508) (xy 50.891221 -385.656942) (xy 50.934148 -385.699387) (xy 50.971124 -385.747107)
			(xy 51.001505 -385.799274) (xy 51.024765 -385.854981) (xy 51.040499 -385.913263) (xy 51.048436 -385.973108)
			(xy 51.04892 -386.003292) (xy 51.048795 -386.017427) (xy 51.047013 -386.045641) (xy 51.045364 -386.05968)
			(xy 51.044602 -386.068287) (xy 51.048243 -386.085167) (xy 51.052476 -386.0927) (xy 51.068224 -386.1181)
			(xy 51.072923 -386.125168) (xy 51.086036 -386.135933) (xy 51.093878 -386.139182) (xy 51.117248 -386.148393)
			(xy 51.161145 -386.172807) (xy 51.200843 -386.203583) (xy 51.235425 -386.240013) (xy 51.264096 -386.281256)
			(xy 51.286196 -386.326362) (xy 51.301215 -386.374294) (xy 51.308807 -386.423947) (xy 51.30927 -386.449062)
			(xy 51.30885 -386.473264) (xy 51.301776 -386.521149) (xy 51.287788 -386.567489) (xy 51.267186 -386.611291)
			(xy 51.254152 -386.631688) (xy 51.249363 -386.639644) (xy 51.24533 -386.657756) (xy 51.246278 -386.666994)
			(xy 51.250596 -386.697982) (xy 51.252279 -386.707278) (xy 51.261559 -386.723719) (xy 51.26863 -386.729986)
			(xy 51.290711 -386.748676) (xy 51.330484 -386.790686) (xy 51.364648 -386.837372) (xy 51.392657 -386.88799)
			(xy 51.414065 -386.941734) (xy 51.428531 -386.997747) (xy 51.435825 -387.055137) (xy 51.43627 -387.084062)
			(xy 51.435678 -387.117383) (xy 51.426016 -387.183322) (xy 51.406891 -387.247161) (xy 51.393344 -387.27761)
			(xy 51.389074 -387.288069) (xy 51.389188 -387.310636) (xy 51.398935 -387.330989) (xy 51.407314 -387.33857)
			(xy 51.429547 -387.357259) (xy 51.469611 -387.399313) (xy 51.504032 -387.446096) (xy 51.532259 -387.496859)
			(xy 51.553836 -387.550784) (xy 51.568419 -387.607006) (xy 51.575771 -387.664621) (xy 51.576224 -387.693662)
			(xy 51.575757 -387.722667) (xy 51.568446 -387.780215) (xy 51.553923 -387.836379) (xy 51.532421 -387.890257)
			(xy 51.504285 -387.940988) (xy 51.469966 -387.987757) (xy 51.430012 -388.029816) (xy 51.407822 -388.0485)
			(xy 51.40071 -388.054088) (xy 51.391566 -388.069328) (xy 51.376326 -388.152132) (xy 51.37912 -388.169404)
			(xy 51.383692 -388.177532) (xy 51.396263 -388.200721) (xy 51.41414 -388.250341) (xy 51.423242 -388.302292)
			(xy 51.423824 -388.328662) (xy 51.423721 -388.339943) (xy 51.422069 -388.362445) (xy 51.420522 -388.37362)
			(xy 51.419252 -388.38251) (xy 51.422808 -388.400036) (xy 51.466242 -388.470902) (xy 51.479958 -388.482078)
			(xy 51.488594 -388.484872) (xy 51.510846 -388.492789) (xy 51.552766 -388.514545) (xy 51.590839 -388.542494)
			(xy 51.624155 -388.57597) (xy 51.651922 -388.614175) (xy 51.663092 -388.634986) (xy 51.6636 -388.636002)
			(xy 52.05603 -389.314944) (xy 52.068836 -389.338286) (xy 52.087063 -389.388304) (xy 52.096331 -389.440727)
			(xy 52.096924 -389.467344) (xy 52.096502 -389.49135) (xy 52.088981 -389.53877) (xy 52.074132 -389.584429)
			(xy 52.05232 -389.627201) (xy 52.024084 -389.666033) (xy 51.990118 -389.699967) (xy 51.95126 -389.728168)
			(xy 51.908468 -389.74994) (xy 51.862795 -389.764747) (xy 51.815369 -389.772224) (xy 51.791362 -389.772652)
			(xy 51.76783 -389.772199) (xy 51.721323 -389.764993) (xy 51.676475 -389.750727) (xy 51.634351 -389.729739)
			(xy 51.595952 -389.702528) (xy 51.56219 -389.669741) (xy 51.533867 -389.632155) (xy 51.522376 -389.611616)
			(xy 51.522122 -389.611108) (xy 51.521614 -389.610346) (xy 51.12385 -388.922006) (xy 51.111973 -388.899329)
			(xy 51.095123 -388.850996) (xy 51.08655 -388.800533) (xy 51.086004 -388.77494) (xy 51.086004 -388.774432)
			(xy 51.086095 -388.763087) (xy 51.08775 -388.740458) (xy 51.089306 -388.72922) (xy 51.090576 -388.72033)
			(xy 51.08702 -388.703058) (xy 51.043586 -388.631938) (xy 51.029616 -388.621016) (xy 51.021234 -388.617968)
			(xy 50.99883 -388.60994) (xy 50.956612 -388.58798) (xy 50.918316 -388.559731) (xy 50.88487 -388.525878)
			(xy 50.857086 -388.487244) (xy 50.835637 -388.444763) (xy 50.821044 -388.399468) (xy 50.813661 -388.352456)
			(xy 50.813208 -388.328662) (xy 50.813773 -388.302289) (xy 50.822856 -388.25033) (xy 50.840745 -388.20071)
			(xy 50.85334 -388.177532) (xy 50.857912 -388.169404) (xy 50.860706 -388.152132) (xy 50.845466 -388.069328)
			(xy 50.836322 -388.054088) (xy 50.82921 -388.0485) (xy 50.807041 -388.029791) (xy 50.767094 -387.987731)
			(xy 50.732776 -387.940963) (xy 50.704637 -387.890238) (xy 50.683127 -387.836365) (xy 50.66859 -387.780209)
			(xy 50.661259 -387.722666) (xy 50.660808 -387.693662) (xy 50.661411 -387.660341) (xy 50.671069 -387.594403)
			(xy 50.690189 -387.530564) (xy 50.703734 -387.500114) (xy 50.707955 -387.489641) (xy 50.70785 -387.467089)
			(xy 50.698128 -387.44674) (xy 50.689764 -387.439154) (xy 50.667489 -387.420512) (xy 50.627429 -387.37845)
			(xy 50.593012 -387.331658) (xy 50.564791 -387.280887) (xy 50.54322 -387.226954) (xy 50.528646 -387.170726)
			(xy 50.521302 -387.113105) (xy 50.520854 -387.084062) (xy 50.521305 -387.055136) (xy 50.528588 -386.997743)
			(xy 50.543047 -386.941726) (xy 50.564451 -386.887979) (xy 50.592458 -386.837357) (xy 50.626622 -386.790669)
			(xy 50.666398 -386.74866) (xy 50.688494 -386.729986) (xy 50.695471 -386.723644) (xy 50.704725 -386.707236)
			(xy 50.706528 -386.697982) (xy 50.710846 -386.666994) (xy 50.71175 -386.657757) (xy 50.707726 -386.639658)
			(xy 50.702972 -386.631688) (xy 50.686661 -386.605844) (xy 50.66276 -386.549607) (xy 50.655474 -386.519928)
			(xy 50.653422 -386.511764) (xy 50.644717 -386.497363) (xy 50.638456 -386.491734) (xy 50.615342 -386.472684)
			(xy 50.608446 -386.467463) (xy 50.592228 -386.461482) (xy 50.583592 -386.461) (xy 50.553956 -386.459963)
			(xy 50.495293 -386.451318) (xy 50.438236 -386.43517) (xy 50.383742 -386.411791) (xy 50.332723 -386.381571)
			(xy 50.286032 -386.345017) (xy 50.244453 -386.30274) (xy 50.20868 -386.255448) (xy 50.179313 -386.203933)
			(xy 50.156843 -386.149058) (xy 50.141647 -386.09174) (xy 50.133979 -386.032941) (xy 50.133504 -386.003292)
			(xy 50.134023 -385.972229) (xy 50.14244 -385.910675) (xy 50.150268 -385.88061) (xy 50.153062 -385.87045)
			(xy 50.150522 -385.850638) (xy 50.103024 -385.768342) (xy 50.087022 -385.75615) (xy 50.076862 -385.75361)
			(xy 50.047779 -385.745559) (xy 49.991852 -385.722896) (xy 49.939386 -385.693083) (xy 49.891291 -385.656637)
			(xy 49.8484 -385.614189) (xy 49.811456 -385.566475) (xy 49.7811 -385.514321) (xy 49.757858 -385.458632)
			(xy 49.742132 -385.400373) (xy 49.734195 -385.340552) (xy 49.733708 -385.31038) (xy 49.734233 -385.279492)
			(xy 49.742538 -385.218276) (xy 49.758995 -385.158733) (xy 49.783305 -385.101941) (xy 49.798732 -385.075176)
			(xy 49.804574 -385.06527) (xy 49.80686 -385.042918) (xy 49.773586 -384.947668) (xy 49.757838 -384.931666)
			(xy 49.74717 -384.927602) (xy 49.723783 -384.918432) (xy 49.679887 -384.89401) (xy 49.640191 -384.863227)
			(xy 49.605611 -384.826791) (xy 49.576942 -384.785543) (xy 49.554845 -384.740431) (xy 49.539829 -384.692495)
			(xy 49.53224 -384.642839) (xy 49.531778 -384.617722) (xy 48.993044 -384.617722) (xy 48.992514 -384.644824)
			(xy 48.983705 -384.698307) (xy 48.975518 -384.724148) (xy 48.971708 -384.73507) (xy 48.974248 -384.757422)
			(xy 49.026826 -384.843274) (xy 49.045876 -384.85572) (xy 49.057052 -384.857498) (xy 49.086373 -384.862189)
			(xy 49.143544 -384.87824) (xy 49.198157 -384.901552) (xy 49.249297 -384.931733) (xy 49.296102 -384.968276)
			(xy 49.337787 -385.010567) (xy 49.37365 -385.057895) (xy 49.40309 -385.109465) (xy 49.425611 -385.164409)
			(xy 49.440836 -385.221806) (xy 49.448507 -385.280689) (xy 49.448974 -385.31038) (xy 49.448447 -385.341443)
			(xy 49.440035 -385.402996) (xy 49.43221 -385.433062) (xy 49.429416 -385.443222) (xy 49.431956 -385.463034)
			(xy 49.479454 -385.54533) (xy 49.495456 -385.557522) (xy 49.505616 -385.560062) (xy 49.534719 -385.568086)
			(xy 49.590685 -385.590716) (xy 49.643191 -385.620506) (xy 49.691326 -385.656941) (xy 49.734253 -385.699386)
			(xy 49.771228 -385.747107) (xy 49.801609 -385.799273) (xy 49.824869 -385.854981) (xy 49.840603 -385.913263)
			(xy 49.84854 -385.973108) (xy 49.849024 -386.003292) (xy 49.848899 -386.017427) (xy 49.847117 -386.045641)
			(xy 49.845468 -386.05968) (xy 49.844706 -386.068287) (xy 49.848346 -386.085167) (xy 49.85258 -386.0927)
			(xy 49.868328 -386.1181) (xy 49.873026 -386.125169) (xy 49.88614 -386.135933) (xy 49.893982 -386.139182)
			(xy 49.917353 -386.148391) (xy 49.96125 -386.172806) (xy 50.000947 -386.203582) (xy 50.03553 -386.240012)
			(xy 50.064201 -386.281255) (xy 50.0863 -386.326362) (xy 50.101319 -386.374294) (xy 50.108911 -386.423947)
			(xy 50.109374 -386.449062) (xy 50.108953 -386.473264) (xy 50.101879 -386.521149) (xy 50.087891 -386.567489)
			(xy 50.06729 -386.611291) (xy 50.054256 -386.631688) (xy 50.049467 -386.639644) (xy 50.045434 -386.657756)
			(xy 50.046382 -386.666994) (xy 50.0507 -386.697982) (xy 50.052382 -386.707278) (xy 50.061663 -386.72372)
			(xy 50.068734 -386.729986) (xy 50.090816 -386.748675) (xy 50.130589 -386.790685) (xy 50.164752 -386.837371)
			(xy 50.192761 -386.88799) (xy 50.214169 -386.941734) (xy 50.228635 -386.997747) (xy 50.235929 -387.055137)
			(xy 50.236374 -387.084062) (xy 50.235781 -387.117383) (xy 50.226119 -387.183322) (xy 50.206995 -387.247161)
			(xy 50.193448 -387.27761) (xy 50.189177 -387.288069) (xy 50.18929 -387.310636) (xy 50.199038 -387.33099)
			(xy 50.207418 -387.33857) (xy 50.229652 -387.357258) (xy 50.269715 -387.399312) (xy 50.304137 -387.446096)
			(xy 50.332363 -387.496858) (xy 50.35394 -387.550784) (xy 50.368523 -387.607006) (xy 50.375875 -387.664621)
			(xy 50.376328 -387.693662) (xy 50.37586 -387.722667) (xy 50.368549 -387.780215) (xy 50.354026 -387.836378)
			(xy 50.332524 -387.890257) (xy 50.304388 -387.940987) (xy 50.270069 -387.987757) (xy 50.230116 -388.029816)
			(xy 50.207926 -388.0485) (xy 50.200814 -388.054088) (xy 50.19167 -388.069328) (xy 50.17643 -388.152132)
			(xy 50.179224 -388.169404) (xy 50.183796 -388.177532) (xy 50.196368 -388.200721) (xy 50.214244 -388.250341)
			(xy 50.223346 -388.302292) (xy 50.223928 -388.328662) (xy 50.223825 -388.339943) (xy 50.222173 -388.362445)
			(xy 50.220626 -388.37362) (xy 50.219356 -388.382764) (xy 50.222658 -388.400036) (xy 50.266346 -388.471156)
			(xy 50.280062 -388.482078) (xy 50.288698 -388.484872) (xy 50.316864 -388.495065) (xy 50.368809 -388.524879)
			(xy 50.391822 -388.544054) (xy 50.413309 -388.563632) (xy 50.44912 -388.609413) (xy 50.462942 -388.634986)
			(xy 50.463704 -388.636256) (xy 50.85588 -389.314944) (xy 50.868611 -389.338311) (xy 50.886727 -389.388338)
			(xy 50.895938 -389.440741) (xy 50.89652 -389.467344) (xy 50.896078 -389.491336) (xy 50.888566 -389.538728)
			(xy 50.873733 -389.584362) (xy 50.851945 -389.627113) (xy 50.823738 -389.665931) (xy 50.789807 -389.699859)
			(xy 50.750986 -389.728062) (xy 50.708232 -389.749845) (xy 50.662597 -389.764673) (xy 50.615204 -389.772181)
			(xy 50.591212 -389.772652) (xy 50.567679 -389.77224) (xy 50.52117 -389.765026) (xy 50.476321 -389.750752)
			(xy 50.434197 -389.729758) (xy 50.395799 -389.702541) (xy 50.362038 -389.669748) (xy 50.333716 -389.632158)
			(xy 50.322226 -389.611616) (xy 50.321972 -389.611108) (xy 50.321464 -389.610346) (xy 49.923954 -388.921752)
			(xy 49.913377 -388.901828) (xy 49.897576 -388.859577) (xy 49.888171 -388.815459) (xy 49.886362 -388.792974)
			(xy 49.885854 -388.781798) (xy 49.8856 -388.774432) (xy 49.885757 -388.763083) (xy 49.887534 -388.740454)
			(xy 49.889156 -388.72922) (xy 49.890426 -388.72033) (xy 49.88687 -388.703058) (xy 49.843436 -388.631938)
			(xy 49.82972 -388.620762) (xy 49.821084 -388.617968) (xy 49.798685 -388.609964) (xy 49.756513 -388.587963)
			(xy 49.718265 -388.559687) (xy 49.684865 -388.525822) (xy 49.657121 -388.487186) (xy 49.635705 -388.444714)
			(xy 49.621135 -388.399435) (xy 49.613763 -388.352445) (xy 49.613312 -388.328662) (xy 49.613876 -388.302289)
			(xy 49.62296 -388.25033) (xy 49.640849 -388.20071) (xy 49.653444 -388.177532) (xy 49.658016 -388.169404)
			(xy 49.66081 -388.152132) (xy 49.64557 -388.069328) (xy 49.636426 -388.054088) (xy 49.629314 -388.0485)
			(xy 49.607146 -388.029791) (xy 49.567198 -387.98773) (xy 49.53288 -387.940963) (xy 49.504741 -387.890237)
			(xy 49.483231 -387.836365) (xy 49.468694 -387.780209) (xy 49.461363 -387.722666) (xy 49.460912 -387.693662)
			(xy 49.461515 -387.660341) (xy 49.471173 -387.594403) (xy 49.490293 -387.530564) (xy 49.503838 -387.500114)
			(xy 49.508091 -387.489649) (xy 49.507986 -387.467086) (xy 49.498245 -387.446734) (xy 49.489868 -387.439154)
			(xy 49.467594 -387.420511) (xy 49.427534 -387.378449) (xy 49.393117 -387.331657) (xy 49.364896 -387.280887)
			(xy 49.343324 -387.226954) (xy 49.32875 -387.170726) (xy 49.321406 -387.113105) (xy 49.320958 -387.084062)
			(xy 49.321407 -387.055136) (xy 49.328691 -386.997743) (xy 49.34315 -386.941726) (xy 49.364554 -386.887978)
			(xy 49.392562 -386.837357) (xy 49.426726 -386.790669) (xy 49.466502 -386.74866) (xy 49.488598 -386.729986)
			(xy 49.495576 -386.723645) (xy 49.504829 -386.707236) (xy 49.506632 -386.697982) (xy 49.51095 -386.666994)
			(xy 49.511853 -386.657757) (xy 49.507829 -386.639658) (xy 49.503076 -386.631688) (xy 49.486766 -386.605844)
			(xy 49.462864 -386.549607) (xy 49.455578 -386.519928) (xy 49.453525 -386.511764) (xy 49.44482 -386.497363)
			(xy 49.43856 -386.491734) (xy 49.415446 -386.472684) (xy 49.408549 -386.467464) (xy 49.392331 -386.461483)
			(xy 49.383696 -386.461) (xy 49.354061 -386.459959) (xy 49.295397 -386.451315) (xy 49.23834 -386.435168)
			(xy 49.183846 -386.411789) (xy 49.132827 -386.381569) (xy 49.086137 -386.345015) (xy 49.044557 -386.302738)
			(xy 49.008784 -386.255447) (xy 48.979417 -386.203932) (xy 48.956947 -386.149057) (xy 48.941751 -386.09174)
			(xy 48.934083 -386.032941) (xy 48.933608 -386.003292) (xy 48.93413 -385.972229) (xy 48.942545 -385.910675)
			(xy 48.950372 -385.88061) (xy 48.953166 -385.87045) (xy 48.950626 -385.850638) (xy 48.903128 -385.768342)
			(xy 48.887126 -385.75615) (xy 48.876966 -385.75361) (xy 48.847852 -385.745624) (xy 48.791884 -385.72299)
			(xy 48.739378 -385.693195) (xy 48.691243 -385.656756) (xy 48.648316 -385.614306) (xy 48.611342 -385.566582)
			(xy 48.580963 -385.514411) (xy 48.557706 -385.458699) (xy 48.541974 -385.400414) (xy 48.53404 -385.340566)
			(xy 48.533558 -385.31038) (xy 48.534076 -385.279492) (xy 48.542382 -385.218276) (xy 48.558841 -385.158732)
			(xy 48.583154 -385.10194) (xy 48.598582 -385.075176) (xy 48.604424 -385.06527) (xy 48.60671 -385.042918)
			(xy 48.573436 -384.947668) (xy 48.557688 -384.931666) (xy 48.54702 -384.927602) (xy 48.523644 -384.918405)
			(xy 48.479746 -384.893989) (xy 48.440049 -384.863211) (xy 48.405466 -384.82678) (xy 48.376796 -384.785535)
			(xy 48.354697 -384.740426) (xy 48.33968 -384.692492) (xy 48.33209 -384.642838) (xy 48.331628 -384.617722)
			(xy 47.793148 -384.617722) (xy 47.792618 -384.644824) (xy 47.783809 -384.698307) (xy 47.775622 -384.724148)
			(xy 47.771812 -384.73507) (xy 47.774352 -384.757422) (xy 47.82693 -384.843274) (xy 47.84598 -384.85572)
			(xy 47.857156 -384.857498) (xy 47.886477 -384.862186) (xy 47.943648 -384.878237) (xy 47.998262 -384.90155)
			(xy 48.049401 -384.931731) (xy 48.096206 -384.968275) (xy 48.137891 -385.010566) (xy 48.173754 -385.057894)
			(xy 48.203194 -385.109464) (xy 48.225715 -385.164409) (xy 48.24094 -385.221805) (xy 48.248611 -385.280689)
			(xy 48.249078 -385.31038) (xy 48.248551 -385.341443) (xy 48.240139 -385.402996) (xy 48.232314 -385.433062)
			(xy 48.22952 -385.443222) (xy 48.23206 -385.463034) (xy 48.279558 -385.54533) (xy 48.29556 -385.557522)
			(xy 48.30572 -385.560062) (xy 48.334823 -385.568083) (xy 48.39079 -385.590714) (xy 48.443296 -385.620505)
			(xy 48.49143 -385.656939) (xy 48.534357 -385.699385) (xy 48.571332 -385.747106) (xy 48.601713 -385.799273)
			(xy 48.624973 -385.854981) (xy 48.640707 -385.913263) (xy 48.648644 -385.973108) (xy 48.649128 -386.003292)
			(xy 48.649003 -386.017427) (xy 48.647221 -386.045641) (xy 48.645572 -386.05968) (xy 48.644809 -386.068287)
			(xy 48.64845 -386.085167) (xy 48.652684 -386.0927) (xy 48.668432 -386.1181) (xy 48.673148 -386.125158)
			(xy 48.686243 -386.13594) (xy 48.694086 -386.139182) (xy 48.717425 -386.148434) (xy 48.761269 -386.172883)
			(xy 48.800915 -386.203678) (xy 48.835451 -386.240111) (xy 48.864085 -386.281345) (xy 48.886157 -386.326433)
			(xy 48.901163 -386.374338) (xy 48.908755 -386.423962) (xy 48.909224 -386.449062) (xy 48.908795 -386.473264)
			(xy 48.901722 -386.521148) (xy 48.887737 -386.567488) (xy 48.867138 -386.61129) (xy 48.854106 -386.631688)
			(xy 48.84932 -386.639646) (xy 48.845284 -386.657756) (xy 48.846232 -386.666994) (xy 48.85055 -386.697982)
			(xy 48.852247 -386.707274) (xy 48.861518 -386.723717) (xy 48.868584 -386.729986) (xy 48.890677 -386.748663)
			(xy 48.930447 -386.790676) (xy 48.964608 -386.837365) (xy 48.992615 -386.887986) (xy 49.014021 -386.941732)
			(xy 49.028486 -386.997746) (xy 49.035779 -387.055136) (xy 49.036224 -387.084062) (xy 49.035636 -387.117383)
			(xy 49.025973 -387.183322) (xy 49.006846 -387.247161) (xy 48.993298 -387.27761) (xy 48.989043 -387.288073)
			(xy 48.989157 -387.310635) (xy 48.998895 -387.330987) (xy 49.007268 -387.33857) (xy 49.029492 -387.357271)
			(xy 49.069557 -387.399321) (xy 49.103981 -387.446102) (xy 49.132209 -387.496862) (xy 49.153789 -387.550786)
			(xy 49.168372 -387.607007) (xy 49.175725 -387.664621) (xy 49.176178 -387.693662) (xy 49.175692 -387.722667)
			(xy 49.168381 -387.780213) (xy 49.15386 -387.836375) (xy 49.132361 -387.890253) (xy 49.104229 -387.940983)
			(xy 49.069913 -387.987754) (xy 49.029964 -388.029815) (xy 49.007776 -388.0485) (xy 49.000664 -388.054088)
			(xy 48.99152 -388.069328) (xy 48.97628 -388.152132) (xy 48.979074 -388.169404) (xy 48.983646 -388.177532)
			(xy 48.996222 -388.200718) (xy 49.014095 -388.25034) (xy 49.023196 -388.302291) (xy 49.023778 -388.328662)
			(xy 49.023674 -388.339943) (xy 49.022023 -388.362445) (xy 49.020476 -388.37362) (xy 49.019206 -388.38251)
			(xy 49.022762 -388.400036) (xy 49.066196 -388.470902) (xy 49.079912 -388.482078) (xy 49.088548 -388.484872)
			(xy 49.110792 -388.492811) (xy 49.152713 -388.514561) (xy 49.190787 -388.542504) (xy 49.224106 -388.575976)
			(xy 49.251875 -388.614177) (xy 49.263046 -388.634986) (xy 49.263554 -388.636002) (xy 49.655984 -389.314944)
			(xy 49.668715 -389.338311) (xy 49.686832 -389.388338) (xy 49.696042 -389.440741) (xy 49.696624 -389.467344)
			(xy 49.696178 -389.491336) (xy 49.688666 -389.538727) (xy 49.673833 -389.584361) (xy 49.652046 -389.627112)
			(xy 49.623839 -389.66593) (xy 49.589908 -389.699858) (xy 49.551088 -389.72806) (xy 49.508335 -389.749844)
			(xy 49.4627 -389.764672) (xy 49.415308 -389.77218) (xy 49.391316 -389.772652) (xy 49.367783 -389.772236)
			(xy 49.321274 -389.765023) (xy 49.276425 -389.75075) (xy 49.234301 -389.729756) (xy 49.195903 -389.70254)
			(xy 49.162142 -389.669748) (xy 49.13382 -389.632158) (xy 49.12233 -389.611616) (xy 49.122076 -389.611108)
			(xy 49.121568 -389.610346) (xy 48.723804 -388.922006) (xy 48.711889 -388.899338) (xy 48.694951 -388.851012)
			(xy 48.686292 -388.800542) (xy 48.685704 -388.77494) (xy 48.685704 -388.774432) (xy 48.685861 -388.763083)
			(xy 48.687638 -388.740454) (xy 48.68926 -388.72922) (xy 48.69053 -388.72033) (xy 48.686974 -388.703058)
			(xy 48.64354 -388.631938) (xy 48.62957 -388.621016) (xy 48.621188 -388.617968) (xy 48.598795 -388.609909)
			(xy 48.556576 -388.587956) (xy 48.518278 -388.559713) (xy 48.48483 -388.525866) (xy 48.457043 -388.487235)
			(xy 48.435593 -388.444757) (xy 48.420999 -388.399465) (xy 48.413615 -388.352455) (xy 48.413162 -388.328662)
			(xy 48.413733 -388.302289) (xy 48.422814 -388.250331) (xy 48.440701 -388.200711) (xy 48.453294 -388.177532)
			(xy 48.457866 -388.169404) (xy 48.46066 -388.152132) (xy 48.44542 -388.069328) (xy 48.436276 -388.054088)
			(xy 48.429164 -388.0485) (xy 48.406986 -388.029803) (xy 48.367041 -387.987739) (xy 48.332725 -387.940969)
			(xy 48.304587 -387.890241) (xy 48.283079 -387.836368) (xy 48.268543 -387.78021) (xy 48.261213 -387.722666)
			(xy 48.260762 -387.693662) (xy 48.26136 -387.660341) (xy 48.271019 -387.594403) (xy 48.290142 -387.530563)
			(xy 48.303688 -387.500114) (xy 48.307924 -387.489645) (xy 48.307819 -387.467087) (xy 48.298088 -387.446737)
			(xy 48.289718 -387.439154) (xy 48.267455 -387.420499) (xy 48.227392 -387.37844) (xy 48.192972 -387.331651)
			(xy 48.164749 -387.280883) (xy 48.143176 -387.226952) (xy 48.128601 -387.170724) (xy 48.121256 -387.113105)
			(xy 48.120808 -387.084062) (xy 48.121275 -387.055136) (xy 48.128558 -386.997745) (xy 48.143016 -386.94173)
			(xy 48.164417 -386.887982) (xy 48.192422 -386.837361) (xy 48.226582 -386.790672) (xy 48.266354 -386.748661)
			(xy 48.288448 -386.729986) (xy 48.295418 -386.723636) (xy 48.304677 -386.707234) (xy 48.306482 -386.697982)
			(xy 48.3108 -386.666994) (xy 48.311712 -386.657758) (xy 48.307683 -386.639656) (xy 48.302926 -386.631688)
			(xy 48.28662 -386.605841) (xy 48.262715 -386.549607) (xy 48.255428 -386.519928) (xy 48.253362 -386.511768)
			(xy 48.244666 -386.497366) (xy 48.23841 -386.491734) (xy 48.215296 -386.472684) (xy 48.20847 -386.467471)
			(xy 48.192374 -386.461505) (xy 48.1838 -386.461) (xy 48.154165 -386.459956) (xy 48.095501 -386.451311)
			(xy 48.038445 -386.435165) (xy 47.98395 -386.411786) (xy 47.932931 -386.381567) (xy 47.886241 -386.345014)
			(xy 47.844661 -386.302737) (xy 47.808888 -386.255446) (xy 47.779521 -386.203932) (xy 47.757052 -386.149057)
			(xy 47.741855 -386.09174) (xy 47.734187 -386.03294) (xy 47.733712 -386.003292) (xy 47.734234 -385.972229)
			(xy 47.742649 -385.910675) (xy 47.750476 -385.88061) (xy 47.75327 -385.87045) (xy 47.75073 -385.850638)
			(xy 47.703232 -385.768342) (xy 47.68723 -385.75615) (xy 47.67707 -385.75361) (xy 47.665348 -385.750466)
			(xy 47.642223 -385.743094) (xy 47.630842 -385.738878) (xy 47.618396 -385.734306) (xy 47.592488 -385.738116)
			(xy 47.50308 -385.806696) (xy 47.492666 -385.830826) (xy 47.493936 -385.84378) (xy 47.49546 -385.87553)
			(xy 47.495076 -385.899206) (xy 47.488343 -385.946077) (xy 47.474978 -385.991503) (xy 47.465488 -386.013198)
			(xy 47.46117 -386.022596) (xy 47.460408 -386.042662) (xy 47.492666 -386.129022) (xy 47.506382 -386.143754)
			(xy 47.51578 -386.148072) (xy 47.540156 -386.159749) (xy 47.585024 -386.189879) (xy 47.624401 -386.2269)
			(xy 47.657238 -386.269828) (xy 47.682663 -386.317521) (xy 47.7 -386.368711) (xy 47.708789 -386.422039)
			(xy 47.709328 -386.449062) (xy 47.708898 -386.473264) (xy 47.701825 -386.521148) (xy 47.68784 -386.567488)
			(xy 47.667242 -386.61129) (xy 47.65421 -386.631688) (xy 47.649418 -386.639642) (xy 47.645388 -386.657755)
			(xy 47.646336 -386.666994) (xy 47.650654 -386.697982) (xy 47.652349 -386.707274) (xy 47.661622 -386.723717)
			(xy 47.668688 -386.729986) (xy 47.690781 -386.748662) (xy 47.730552 -386.790676) (xy 47.764713 -386.837365)
			(xy 47.792719 -386.887986) (xy 47.814126 -386.941731) (xy 47.82859 -386.997746) (xy 47.835883 -387.055136)
			(xy 47.836328 -387.084062) (xy 47.835739 -387.117383) (xy 47.826077 -387.183322) (xy 47.80695 -387.247161)
			(xy 47.793402 -387.27761) (xy 47.789146 -387.288073) (xy 47.78926 -387.310635) (xy 47.798999 -387.330987)
			(xy 47.807372 -387.33857) (xy 47.829596 -387.35727) (xy 47.869662 -387.39932) (xy 47.904085 -387.446101)
			(xy 47.932314 -387.496862) (xy 47.953893 -387.550786) (xy 47.968476 -387.607007) (xy 47.975829 -387.664621)
			(xy 47.976282 -387.693662) (xy 47.975794 -387.722667) (xy 47.968484 -387.780213) (xy 47.953963 -387.836375)
			(xy 47.932464 -387.890252) (xy 47.904332 -387.940983) (xy 47.870016 -387.987753) (xy 47.830068 -388.029815)
			(xy 47.80788 -388.0485) (xy 47.800768 -388.054088) (xy 47.791624 -388.069328) (xy 47.776384 -388.152132)
			(xy 47.779178 -388.169404) (xy 47.78375 -388.177532) (xy 47.796326 -388.200718) (xy 47.814199 -388.25034)
			(xy 47.8233 -388.302291) (xy 47.823882 -388.328662) (xy 47.823778 -388.339943) (xy 47.822127 -388.362445)
			(xy 47.82058 -388.37362) (xy 47.81931 -388.38251) (xy 47.822866 -388.400036) (xy 47.8663 -388.470902)
			(xy 47.880016 -388.482078) (xy 47.888652 -388.484872) (xy 47.910896 -388.492809) (xy 47.952818 -388.514559)
			(xy 47.990892 -388.542503) (xy 48.02421 -388.575975) (xy 48.051979 -388.614177) (xy 48.06315 -388.634986)
			(xy 48.063658 -388.636002) (xy 48.456088 -389.314944) (xy 48.468819 -389.33831) (xy 48.486936 -389.388338)
			(xy 48.496146 -389.440741) (xy 48.496728 -389.467344) (xy 48.496278 -389.491335) (xy 48.488766 -389.538727)
			(xy 48.473934 -389.58436) (xy 48.452147 -389.627111) (xy 48.423941 -389.665928) (xy 48.39001 -389.699856)
			(xy 48.351191 -389.728059) (xy 48.308437 -389.749843) (xy 48.262803 -389.764672) (xy 48.215411 -389.77218)
			(xy 48.19142 -389.772652) (xy 48.167887 -389.772233) (xy 48.121378 -389.76502) (xy 48.076529 -389.750748)
			(xy 48.034406 -389.729755) (xy 47.996007 -389.702539) (xy 47.962246 -389.669747) (xy 47.933924 -389.632157)
			(xy 47.922434 -389.611616) (xy 47.92218 -389.611108) (xy 47.921672 -389.610346) (xy 47.523908 -388.922006)
			(xy 47.511993 -388.899337) (xy 47.495055 -388.851012) (xy 47.486396 -388.800542) (xy 47.485808 -388.77494)
			(xy 47.485808 -388.774432) (xy 47.485965 -388.763083) (xy 47.487742 -388.740454) (xy 47.489364 -388.72922)
			(xy 47.490634 -388.72033) (xy 47.487078 -388.703058) (xy 47.443644 -388.631938) (xy 47.429674 -388.621016)
			(xy 47.421292 -388.617968) (xy 47.398879 -388.609965) (xy 47.356662 -388.587999) (xy 47.318367 -388.559745)
			(xy 47.284923 -388.525889) (xy 47.25714 -388.487251) (xy 47.235693 -388.444768) (xy 47.221101 -388.39947)
			(xy 47.213719 -388.352457) (xy 47.213266 -388.328662) (xy 47.213836 -388.302289) (xy 47.222918 -388.250331)
			(xy 47.240805 -388.200711) (xy 47.253398 -388.177532) (xy 47.25797 -388.169404) (xy 47.260764 -388.152132)
			(xy 47.245524 -388.069328) (xy 47.23638 -388.054088) (xy 47.229268 -388.0485) (xy 47.207091 -388.029802)
			(xy 47.167145 -387.987738) (xy 47.132829 -387.940968) (xy 47.104692 -387.890241) (xy 47.083183 -387.836367)
			(xy 47.068647 -387.78021) (xy 47.061317 -387.722666) (xy 47.060866 -387.693662) (xy 47.061464 -387.660341)
			(xy 47.071123 -387.594403) (xy 47.090246 -387.530563) (xy 47.103792 -387.500114) (xy 47.108027 -387.489644)
			(xy 47.107922 -387.467088) (xy 47.098191 -387.446738) (xy 47.089822 -387.439154) (xy 47.06756 -387.420498)
			(xy 47.027496 -387.37844) (xy 46.993077 -387.331651) (xy 46.964853 -387.280883) (xy 46.94328 -387.226951)
			(xy 46.928705 -387.170724) (xy 46.92136 -387.113105) (xy 46.920912 -387.084062) (xy 46.921378 -387.055136)
			(xy 46.928661 -386.997745) (xy 46.943119 -386.941729) (xy 46.96452 -386.887982) (xy 46.992525 -386.837361)
			(xy 47.026686 -386.790672) (xy 47.066458 -386.748661) (xy 47.088552 -386.729986) (xy 47.095522 -386.723637)
			(xy 47.104781 -386.707235) (xy 47.106586 -386.697982) (xy 47.110904 -386.666994) (xy 47.111815 -386.657758)
			(xy 47.107787 -386.639657) (xy 47.10303 -386.631688) (xy 47.090046 -386.611263) (xy 47.069464 -386.567462)
			(xy 47.055475 -386.521132) (xy 47.048379 -386.473259) (xy 47.047912 -386.449062) (xy 47.048296 -386.425386)
			(xy 47.055029 -386.378515) (xy 47.068394 -386.333089) (xy 47.077884 -386.311394) (xy 47.082202 -386.301996)
			(xy 47.082964 -386.28193) (xy 47.050706 -386.19557) (xy 47.03699 -386.180838) (xy 47.027592 -386.17652)
			(xy 47.00323 -386.164816) (xy 46.958358 -386.134694) (xy 46.918978 -386.097679) (xy 46.886138 -386.054756)
			(xy 46.86071 -386.007066) (xy 46.843372 -385.955878) (xy 46.834583 -385.902552) (xy 46.834044 -385.87553)
			(xy 45.347002 -385.87553) (xy 45.317581 -385.912289) (xy 45.295566 -385.93395) (xy 45.28693 -385.942332)
			(xy 45.278802 -385.964684) (xy 45.29074 -386.069078) (xy 45.303694 -386.08889) (xy 45.314108 -386.09524)
			(xy 45.339458 -386.110732) (xy 45.386309 -386.147261) (xy 45.428038 -386.189547) (xy 45.463945 -386.236877)
			(xy 45.493424 -386.288457) (xy 45.515981 -386.343417) (xy 45.531234 -386.400835) (xy 45.53893 -386.459743)
			(xy 45.539406 -386.489448) (xy 45.538947 -386.520107) (xy 45.530754 -386.580877) (xy 45.514522 -386.640008)
			(xy 45.49054 -386.696443) (xy 45.45924 -386.749172) (xy 45.42118 -386.797249) (xy 45.399452 -386.818886)
			(xy 45.391716 -386.827201) (xy 45.383711 -386.84842) (xy 45.38562 -386.871018) (xy 45.390816 -386.881116)
			(xy 45.404956 -386.906584) (xy 45.425024 -386.961263) (xy 45.435186 -387.018616) (xy 45.435774 -387.04774)
			(xy 45.435264 -387.073727) (xy 45.427134 -387.125062) (xy 45.411073 -387.174492) (xy 45.387477 -387.220802)
			(xy 45.356927 -387.26285) (xy 45.320176 -387.299601) (xy 45.278128 -387.330151) (xy 45.231818 -387.353747)
			(xy 45.182388 -387.369808) (xy 45.131053 -387.377938) (xy 45.079079 -387.377938) (xy 45.027744 -387.369808)
			(xy 44.978314 -387.353747) (xy 44.932004 -387.330151) (xy 44.889956 -387.299601) (xy 44.853205 -387.26285)
			(xy 44.822655 -387.220802) (xy 44.799059 -387.174492) (xy 44.782998 -387.125062) (xy 44.774868 -387.073727)
			(xy 44.774358 -387.04774) (xy 44.774782 -387.023227) (xy 44.781966 -386.974731) (xy 44.79624 -386.92783)
			(xy 44.806362 -386.9055) (xy 44.810752 -386.895036) (xy 44.810799 -386.872369) (xy 44.801063 -386.8519)
			(xy 44.792646 -386.844286) (xy 44.770424 -386.825623) (xy 44.730416 -386.783586) (xy 44.696044 -386.736827)
			(xy 44.667862 -386.686097) (xy 44.646321 -386.63221) (xy 44.631768 -386.576032) (xy 44.624436 -386.518464)
			(xy 44.62399 -386.489448) (xy 44.624494 -386.458568) (xy 44.632811 -386.397371) (xy 44.649286 -386.337849)
			(xy 44.673621 -386.281086) (xy 44.705372 -386.228113) (xy 44.743963 -386.179894) (xy 44.765976 -386.158232)
			(xy 44.774612 -386.14985) (xy 44.78274 -386.127498) (xy 44.770802 -386.023104) (xy 44.757848 -386.003292)
			(xy 44.747434 -385.996942) (xy 44.724055 -385.982711) (xy 44.680543 -385.949509) (xy 44.641308 -385.911347)
			(xy 44.606912 -385.868772) (xy 44.577846 -385.822394) (xy 44.565824 -385.797806) (xy 44.559728 -385.785106)
			(xy 44.536868 -385.769612) (xy 44.420028 -385.762246) (xy 44.395644 -385.774692) (xy 44.388024 -385.78663)
			(xy 44.372965 -385.809531) (xy 44.33727 -385.851123) (xy 44.295989 -385.887179) (xy 44.249973 -385.916955)
			(xy 44.200169 -385.939839) (xy 44.147603 -385.95536) (xy 44.093357 -385.963197) (xy 44.065952 -385.963668)
			(xy 44.0387 -385.963259) (xy 43.984752 -385.955496) (xy 43.932457 -385.940135) (xy 43.882881 -385.917489)
			(xy 43.837032 -385.888018) (xy 43.795843 -385.852323) (xy 43.760153 -385.81113) (xy 43.730688 -385.765277)
			(xy 43.708048 -385.715697) (xy 43.692694 -385.663401) (xy 43.684938 -385.609452) (xy 39.51859 -385.609452)
			(xy 39.51859 -387.4719) (xy 39.87701 -387.4719) (xy 39.881023 -387.408107) (xy 39.893 -387.345319)
			(xy 39.912753 -387.284528) (xy 39.939968 -387.226692) (xy 39.974218 -387.172723) (xy 40.014962 -387.123472)
			(xy 40.061557 -387.079716) (xy 40.113269 -387.042145) (xy 40.169282 -387.011352) (xy 40.228713 -386.987821)
			(xy 40.290625 -386.971925) (xy 40.35404 -386.963914) (xy 40.386 -386.963412) (xy 40.417114 -386.963875)
			(xy 40.478876 -386.971478) (xy 40.539249 -386.986558) (xy 40.597332 -387.00889) (xy 40.625014 -387.023102)
			(xy 40.636952 -387.029452) (xy 40.663876 -387.02869) (xy 40.761412 -386.969254) (xy 40.77462 -386.945632)
			(xy 40.774366 -386.93217) (xy 40.774366 -386.926074) (xy 40.774832 -386.895343) (xy 40.782243 -386.834331)
			(xy 40.796953 -386.774656) (xy 40.818749 -386.71719) (xy 40.847313 -386.662769) (xy 40.882227 -386.612188)
			(xy 40.922984 -386.566184) (xy 40.968988 -386.525427) (xy 41.019569 -386.490513) (xy 41.07399 -386.461949)
			(xy 41.131456 -386.440153) (xy 41.191131 -386.425443) (xy 41.252143 -386.418032) (xy 41.282874 -386.417566)
			(xy 41.303799 -386.417772) (xy 41.345509 -386.421206) (xy 41.366186 -386.424424) (xy 41.37533 -386.425948)
			(xy 41.39311 -386.422646) (xy 41.465246 -386.378958) (xy 41.476422 -386.364988) (xy 41.47947 -386.356352)
			(xy 41.488218 -386.331325) (xy 41.511707 -386.283795) (xy 41.541555 -386.239977) (xy 41.577185 -386.200717)
			(xy 41.61791 -386.166772) (xy 41.662945 -386.138795) (xy 41.711422 -386.117328) (xy 41.762405 -386.102782)
			(xy 41.814911 -386.095441) (xy 41.84142 -386.094986) (xy 41.868671 -386.095459) (xy 41.922619 -386.103218)
			(xy 41.974914 -386.118576) (xy 42.024491 -386.141219) (xy 42.070341 -386.170686) (xy 42.111531 -386.206379)
			(xy 42.147222 -386.24757) (xy 42.176688 -386.293421) (xy 42.199329 -386.342999) (xy 42.214685 -386.395294)
			(xy 42.222442 -386.449243) (xy 42.222928 -386.476494) (xy 42.222403 -386.504466) (xy 42.21426 -386.559813)
			(xy 42.198119 -386.613377) (xy 42.174326 -386.664008) (xy 42.143392 -386.710621) (xy 42.105981 -386.752214)
			(xy 42.062894 -386.787895) (xy 42.015057 -386.8169) (xy 41.963496 -386.838605) (xy 41.909317 -386.852544)
			(xy 41.881552 -386.85597) (xy 41.872408 -386.856732) (xy 41.856152 -386.86486) (xy 41.79824 -386.926074)
			(xy 41.791128 -386.942584) (xy 41.79062 -386.951728) (xy 41.788519 -386.984046) (xy 41.777108 -387.047798)
			(xy 41.757689 -387.109582) (xy 41.730574 -387.168398) (xy 41.696206 -387.223291) (xy 41.676066 -387.248654)
			(xy 41.670811 -387.255663) (xy 41.664956 -387.272158) (xy 41.664636 -387.280912) (xy 41.664636 -387.434836)
			(xy 41.664977 -387.443585) (xy 41.670828 -387.460077) (xy 41.676066 -387.467094) (xy 41.697771 -387.494499)
			(xy 41.734271 -387.554123) (xy 41.762266 -387.618182) (xy 41.781228 -387.685469) (xy 41.790801 -387.75472)
			(xy 41.791382 -387.789674) (xy 41.790643 -387.828651) (xy 41.778786 -387.905698) (xy 41.76776 -387.94309)
			(xy 41.764204 -387.954266) (xy 41.767252 -387.976872) (xy 41.824148 -388.062216) (xy 41.843706 -388.0739)
			(xy 41.85539 -388.074916) (xy 41.883488 -388.077986) (xy 41.938415 -388.091315) (xy 41.990775 -388.112603)
			(xy 42.03942 -388.141383) (xy 42.083287 -388.177024) (xy 42.121415 -388.218748) (xy 42.15297 -388.265641)
			(xy 42.168217 -388.297674) (xy 43.808902 -388.297674) (xy 43.812973 -388.242052) (xy 43.825099 -388.187615)
			(xy 43.845022 -388.135524) (xy 43.872318 -388.086889) (xy 43.906404 -388.042746) (xy 43.946553 -388.004037)
			(xy 43.991911 -387.971586) (xy 44.041511 -387.946085) (xy 44.094295 -387.928078) (xy 44.149138 -387.917948)
			(xy 44.204872 -387.915911) (xy 44.260309 -387.922011) (xy 44.314266 -387.936117) (xy 44.365595 -387.957929)
			(xy 44.413201 -387.986983) (xy 44.456069 -388.022658) (xy 44.493286 -388.064195) (xy 44.524059 -388.110708)
			(xy 44.547731 -388.161205) (xy 44.563799 -388.214612) (xy 44.571919 -388.269788) (xy 44.572428 -388.297674)
			(xy 44.571981 -388.322137) (xy 44.774868 -388.322137) (xy 44.774868 -388.270163) (xy 44.782998 -388.218828)
			(xy 44.799059 -388.169398) (xy 44.822655 -388.123088) (xy 44.853205 -388.08104) (xy 44.889956 -388.044289)
			(xy 44.932004 -388.013739) (xy 44.978314 -387.990143) (xy 45.027744 -387.974082) (xy 45.079079 -387.965952)
			(xy 45.131053 -387.965952) (xy 45.182388 -387.974082) (xy 45.231818 -387.990143) (xy 45.278128 -388.013739)
			(xy 45.320176 -388.044289) (xy 45.356927 -388.08104) (xy 45.387477 -388.123088) (xy 45.411073 -388.169398)
			(xy 45.427134 -388.218828) (xy 45.435264 -388.270163) (xy 45.435774 -388.29615) (xy 45.435264 -388.322137)
			(xy 45.427134 -388.373472) (xy 45.411073 -388.422902) (xy 45.387477 -388.469212) (xy 45.356927 -388.51126)
			(xy 45.320176 -388.548011) (xy 45.278128 -388.578561) (xy 45.231818 -388.602157) (xy 45.182388 -388.618218)
			(xy 45.131053 -388.626348) (xy 45.079079 -388.626348) (xy 45.027744 -388.618218) (xy 44.978314 -388.602157)
			(xy 44.932004 -388.578561) (xy 44.889956 -388.548011) (xy 44.853205 -388.51126) (xy 44.822655 -388.469212)
			(xy 44.799059 -388.422902) (xy 44.782998 -388.373472) (xy 44.774868 -388.322137) (xy 44.571981 -388.322137)
			(xy 44.571919 -388.32556) (xy 44.563799 -388.380736) (xy 44.547731 -388.434143) (xy 44.524059 -388.48464)
			(xy 44.493286 -388.531153) (xy 44.456069 -388.57269) (xy 44.413201 -388.608365) (xy 44.365595 -388.637419)
			(xy 44.314266 -388.659231) (xy 44.260309 -388.673337) (xy 44.204872 -388.679437) (xy 44.149138 -388.6774)
			(xy 44.094295 -388.66727) (xy 44.041511 -388.649263) (xy 43.991911 -388.623762) (xy 43.946553 -388.591311)
			(xy 43.906404 -388.552602) (xy 43.872318 -388.508459) (xy 43.845022 -388.459824) (xy 43.825099 -388.407733)
			(xy 43.812973 -388.353296) (xy 43.808902 -388.297674) (xy 42.168217 -388.297674) (xy 42.177262 -388.316676)
			(xy 42.193757 -388.370737) (xy 42.202096 -388.426639) (xy 42.202608 -388.4549) (xy 42.202122 -388.482151)
			(xy 42.194366 -388.536099) (xy 42.179011 -388.588394) (xy 42.156369 -388.637971) (xy 42.126903 -388.683821)
			(xy 42.091212 -388.725012) (xy 42.050021 -388.760703) (xy 42.004171 -388.790169) (xy 41.954594 -388.812811)
			(xy 41.902299 -388.828166) (xy 41.848351 -388.835922) (xy 41.793849 -388.835922) (xy 41.739901 -388.828166)
			(xy 41.687606 -388.812811) (xy 41.638029 -388.790169) (xy 41.592179 -388.760703) (xy 41.550988 -388.725012)
			(xy 41.515297 -388.683821) (xy 41.485831 -388.637971) (xy 41.463189 -388.588394) (xy 41.447834 -388.536099)
			(xy 41.440078 -388.482151) (xy 41.439592 -388.4549) (xy 41.439694 -388.443441) (xy 41.441092 -388.420566)
			(xy 41.442386 -388.40918) (xy 41.443656 -388.397496) (xy 41.43629 -388.375906) (xy 41.364916 -388.3025)
			(xy 41.343326 -388.294626) (xy 41.331642 -388.295896) (xy 41.319479 -388.296977) (xy 41.295085 -388.29812)
			(xy 41.282874 -388.298182) (xy 41.251469 -388.297669) (xy 41.189139 -388.289931) (xy 41.128236 -388.274575)
			(xy 41.069687 -388.251836) (xy 41.014385 -388.22206) (xy 40.963171 -388.1857) (xy 40.916824 -388.143309)
			(xy 40.87605 -388.095533) (xy 40.841471 -388.0431) (xy 40.813612 -387.986807) (xy 40.802814 -387.957314)
			(xy 40.799004 -387.946392) (xy 40.782748 -387.930136) (xy 40.686228 -387.895846) (xy 40.663368 -387.898386)
			(xy 40.653462 -387.904482) (xy 40.623187 -387.92248) (xy 40.558729 -387.95087) (xy 40.490975 -387.970107)
			(xy 40.421216 -387.979826) (xy 40.386 -387.980428) (xy 40.35404 -387.979886) (xy 40.290625 -387.971875)
			(xy 40.228713 -387.955979) (xy 40.169282 -387.932448) (xy 40.113269 -387.901655) (xy 40.061557 -387.864084)
			(xy 40.014962 -387.820328) (xy 39.974218 -387.771077) (xy 39.939968 -387.717108) (xy 39.912753 -387.659272)
			(xy 39.893 -387.598481) (xy 39.881023 -387.535693) (xy 39.87701 -387.4719) (xy 39.51859 -387.4719)
			(xy 39.51859 -390.626092) (xy 44.635674 -390.626092) (xy 44.636236 -390.5928) (xy 44.645856 -390.526916)
			(xy 44.664933 -390.463124) (xy 44.693065 -390.402776) (xy 44.710858 -390.374632) (xy 44.715916 -390.366114)
			(xy 44.719729 -390.346693) (xy 44.715911 -390.327273) (xy 44.710858 -390.318752) (xy 44.693077 -390.290604)
			(xy 44.664985 -390.230244) (xy 44.645918 -390.166456) (xy 44.636276 -390.10058) (xy 44.635674 -390.067292)
			(xy 44.636164 -390.037324) (xy 44.643987 -389.977902) (xy 44.6595 -389.920009) (xy 44.682436 -389.864636)
			(xy 44.712403 -389.81273) (xy 44.74889 -389.76518) (xy 44.79127 -389.7228) (xy 44.83882 -389.686313)
			(xy 44.890726 -389.656346) (xy 44.946099 -389.63341) (xy 45.003992 -389.617897) (xy 45.063414 -389.610074)
			(xy 45.12335 -389.610074) (xy 45.182772 -389.617897) (xy 45.240665 -389.63341) (xy 45.296038 -389.656346)
			(xy 45.347944 -389.686313) (xy 45.395494 -389.7228) (xy 45.437874 -389.76518) (xy 45.474361 -389.81273)
			(xy 45.504328 -389.864636) (xy 45.527264 -389.920009) (xy 45.542777 -389.977902) (xy 45.5506 -390.037324)
			(xy 45.55109 -390.067292) (xy 45.550525 -390.100584) (xy 45.541852 -390.160002) (xy 47.085262 -390.160002)
			(xy 47.089222 -390.110948) (xy 47.100999 -390.063164) (xy 47.12029 -390.017888) (xy 47.146593 -389.976292)
			(xy 47.179228 -389.939455) (xy 47.217349 -389.90833) (xy 47.25997 -389.883723) (xy 47.305986 -389.866271)
			(xy 47.354205 -389.856427) (xy 47.40338 -389.854446) (xy 47.452235 -389.860378) (xy 47.499506 -389.87407)
			(xy 47.543968 -389.895168) (xy 47.584471 -389.923124) (xy 47.619964 -389.957216) (xy 47.649529 -389.99656)
			(xy 47.6724 -390.040137) (xy 47.687984 -390.086818) (xy 47.695879 -390.135395) (xy 47.696374 -390.160002)
			(xy 48.285412 -390.160002) (xy 48.289372 -390.110948) (xy 48.301149 -390.063164) (xy 48.32044 -390.017888)
			(xy 48.346743 -389.976292) (xy 48.379378 -389.939455) (xy 48.417499 -389.90833) (xy 48.46012 -389.883723)
			(xy 48.506136 -389.866271) (xy 48.554355 -389.856427) (xy 48.60353 -389.854446) (xy 48.652385 -389.860378)
			(xy 48.699656 -389.87407) (xy 48.744118 -389.895168) (xy 48.784621 -389.923124) (xy 48.820114 -389.957216)
			(xy 48.849679 -389.99656) (xy 48.87255 -390.040137) (xy 48.888134 -390.086818) (xy 48.896029 -390.135395)
			(xy 48.896524 -390.160002) (xy 49.485562 -390.160002) (xy 49.489522 -390.110948) (xy 49.501299 -390.063164)
			(xy 49.52059 -390.017888) (xy 49.546893 -389.976292) (xy 49.579528 -389.939455) (xy 49.617649 -389.90833)
			(xy 49.66027 -389.883723) (xy 49.706286 -389.866271) (xy 49.754505 -389.856427) (xy 49.80368 -389.854446)
			(xy 49.852535 -389.860378) (xy 49.899806 -389.87407) (xy 49.944268 -389.895168) (xy 49.984771 -389.923124)
			(xy 50.020264 -389.957216) (xy 50.049829 -389.99656) (xy 50.0727 -390.040137) (xy 50.088284 -390.086818)
			(xy 50.096179 -390.135395) (xy 50.096674 -390.160002) (xy 50.685458 -390.160002) (xy 50.689418 -390.110948)
			(xy 50.701195 -390.063164) (xy 50.720486 -390.017888) (xy 50.746789 -389.976292) (xy 50.779424 -389.939455)
			(xy 50.817545 -389.90833) (xy 50.860166 -389.883723) (xy 50.906182 -389.866271) (xy 50.954401 -389.856427)
			(xy 51.003576 -389.854446) (xy 51.052431 -389.860378) (xy 51.099702 -389.87407) (xy 51.144164 -389.895168)
			(xy 51.184667 -389.923124) (xy 51.22016 -389.957216) (xy 51.249725 -389.99656) (xy 51.272596 -390.040137)
			(xy 51.28818 -390.086818) (xy 51.296075 -390.135395) (xy 51.29657 -390.160002) (xy 51.885608 -390.160002)
			(xy 51.889568 -390.110948) (xy 51.901345 -390.063164) (xy 51.920636 -390.017888) (xy 51.946939 -389.976292)
			(xy 51.979574 -389.939455) (xy 52.017695 -389.90833) (xy 52.060316 -389.883723) (xy 52.106332 -389.866271)
			(xy 52.154551 -389.856427) (xy 52.203726 -389.854446) (xy 52.252581 -389.860378) (xy 52.299852 -389.87407)
			(xy 52.344314 -389.895168) (xy 52.384817 -389.923124) (xy 52.42031 -389.957216) (xy 52.449875 -389.99656)
			(xy 52.472746 -390.040137) (xy 52.48833 -390.086818) (xy 52.496225 -390.135395) (xy 52.49672 -390.160002)
			(xy 53.085504 -390.160002) (xy 53.089464 -390.110948) (xy 53.101241 -390.063164) (xy 53.120532 -390.017888)
			(xy 53.146835 -389.976292) (xy 53.17947 -389.939455) (xy 53.217591 -389.90833) (xy 53.260212 -389.883723)
			(xy 53.306228 -389.866271) (xy 53.354447 -389.856427) (xy 53.403622 -389.854446) (xy 53.452477 -389.860378)
			(xy 53.499748 -389.87407) (xy 53.54421 -389.895168) (xy 53.584713 -389.923124) (xy 53.620206 -389.957216)
			(xy 53.649771 -389.99656) (xy 53.672642 -390.040137) (xy 53.688226 -390.086818) (xy 53.696121 -390.135395)
			(xy 53.696616 -390.160002) (xy 54.2854 -390.160002) (xy 54.28936 -390.110948) (xy 54.301137 -390.063164)
			(xy 54.320428 -390.017888) (xy 54.346731 -389.976292) (xy 54.379366 -389.939455) (xy 54.417487 -389.90833)
			(xy 54.460108 -389.883723) (xy 54.506124 -389.866271) (xy 54.554343 -389.856427) (xy 54.603518 -389.854446)
			(xy 54.652373 -389.860378) (xy 54.699644 -389.87407) (xy 54.744106 -389.895168) (xy 54.784609 -389.923124)
			(xy 54.820102 -389.957216) (xy 54.849667 -389.99656) (xy 54.872538 -390.040137) (xy 54.888122 -390.086818)
			(xy 54.896017 -390.135395) (xy 54.896512 -390.160002) (xy 55.48555 -390.160002) (xy 55.48951 -390.110948)
			(xy 55.501287 -390.063164) (xy 55.520578 -390.017888) (xy 55.546881 -389.976292) (xy 55.579516 -389.939455)
			(xy 55.617637 -389.90833) (xy 55.660258 -389.883723) (xy 55.706274 -389.866271) (xy 55.754493 -389.856427)
			(xy 55.803668 -389.854446) (xy 55.852523 -389.860378) (xy 55.899794 -389.87407) (xy 55.944256 -389.895168)
			(xy 55.984759 -389.923124) (xy 56.020252 -389.957216) (xy 56.049817 -389.99656) (xy 56.072688 -390.040137)
			(xy 56.088272 -390.086818) (xy 56.096167 -390.135395) (xy 56.096662 -390.160002) (xy 56.685446 -390.160002)
			(xy 56.689406 -390.110948) (xy 56.701183 -390.063164) (xy 56.720474 -390.017888) (xy 56.746777 -389.976292)
			(xy 56.779412 -389.939455) (xy 56.817533 -389.90833) (xy 56.860154 -389.883723) (xy 56.90617 -389.866271)
			(xy 56.954389 -389.856427) (xy 57.003564 -389.854446) (xy 57.052419 -389.860378) (xy 57.09969 -389.87407)
			(xy 57.144152 -389.895168) (xy 57.184655 -389.923124) (xy 57.220148 -389.957216) (xy 57.249713 -389.99656)
			(xy 57.272584 -390.040137) (xy 57.288168 -390.086818) (xy 57.296063 -390.135395) (xy 57.296558 -390.160002)
			(xy 57.885596 -390.160002) (xy 57.889556 -390.110948) (xy 57.901333 -390.063164) (xy 57.920624 -390.017888)
			(xy 57.946927 -389.976292) (xy 57.979562 -389.939455) (xy 58.017683 -389.90833) (xy 58.060304 -389.883723)
			(xy 58.10632 -389.866271) (xy 58.154539 -389.856427) (xy 58.203714 -389.854446) (xy 58.252569 -389.860378)
			(xy 58.29984 -389.87407) (xy 58.344302 -389.895168) (xy 58.384805 -389.923124) (xy 58.420298 -389.957216)
			(xy 58.449863 -389.99656) (xy 58.472734 -390.040137) (xy 58.488318 -390.086818) (xy 58.496213 -390.135395)
			(xy 58.496708 -390.160002) (xy 59.085492 -390.160002) (xy 59.089452 -390.110948) (xy 59.101229 -390.063164)
			(xy 59.12052 -390.017888) (xy 59.146823 -389.976292) (xy 59.179458 -389.939455) (xy 59.217579 -389.90833)
			(xy 59.2602 -389.883723) (xy 59.306216 -389.866271) (xy 59.354435 -389.856427) (xy 59.40361 -389.854446)
			(xy 59.452465 -389.860378) (xy 59.499736 -389.87407) (xy 59.544198 -389.895168) (xy 59.584701 -389.923124)
			(xy 59.620194 -389.957216) (xy 59.649759 -389.99656) (xy 59.67263 -390.040137) (xy 59.688214 -390.086818)
			(xy 59.696109 -390.135395) (xy 59.696604 -390.160002) (xy 60.285388 -390.160002) (xy 60.289348 -390.110948)
			(xy 60.301125 -390.063164) (xy 60.320416 -390.017888) (xy 60.346719 -389.976292) (xy 60.379354 -389.939455)
			(xy 60.417475 -389.90833) (xy 60.460096 -389.883723) (xy 60.506112 -389.866271) (xy 60.554331 -389.856427)
			(xy 60.603506 -389.854446) (xy 60.652361 -389.860378) (xy 60.699632 -389.87407) (xy 60.744094 -389.895168)
			(xy 60.784597 -389.923124) (xy 60.82009 -389.957216) (xy 60.849655 -389.99656) (xy 60.872526 -390.040137)
			(xy 60.88811 -390.086818) (xy 60.896005 -390.135395) (xy 60.8965 -390.160002) (xy 61.485538 -390.160002)
			(xy 61.489498 -390.110948) (xy 61.501275 -390.063164) (xy 61.520566 -390.017888) (xy 61.546869 -389.976292)
			(xy 61.579504 -389.939455) (xy 61.617625 -389.90833) (xy 61.660246 -389.883723) (xy 61.706262 -389.866271)
			(xy 61.754481 -389.856427) (xy 61.803656 -389.854446) (xy 61.852511 -389.860378) (xy 61.899782 -389.87407)
			(xy 61.944244 -389.895168) (xy 61.984747 -389.923124) (xy 62.02024 -389.957216) (xy 62.049805 -389.99656)
			(xy 62.072676 -390.040137) (xy 62.08826 -390.086818) (xy 62.096155 -390.135395) (xy 62.09665 -390.160002)
			(xy 62.685434 -390.160002) (xy 62.689394 -390.110948) (xy 62.701171 -390.063164) (xy 62.720462 -390.017888)
			(xy 62.746765 -389.976292) (xy 62.7794 -389.939455) (xy 62.817521 -389.90833) (xy 62.860142 -389.883723)
			(xy 62.906158 -389.866271) (xy 62.954377 -389.856427) (xy 63.003552 -389.854446) (xy 63.052407 -389.860378)
			(xy 63.099678 -389.87407) (xy 63.14414 -389.895168) (xy 63.184643 -389.923124) (xy 63.220136 -389.957216)
			(xy 63.249701 -389.99656) (xy 63.272572 -390.040137) (xy 63.288156 -390.086818) (xy 63.296051 -390.135395)
			(xy 63.296546 -390.160002) (xy 63.885584 -390.160002) (xy 63.889544 -390.110948) (xy 63.901321 -390.063164)
			(xy 63.920612 -390.017888) (xy 63.946915 -389.976292) (xy 63.97955 -389.939455) (xy 64.017671 -389.90833)
			(xy 64.060292 -389.883723) (xy 64.106308 -389.866271) (xy 64.154527 -389.856427) (xy 64.203702 -389.854446)
			(xy 64.252557 -389.860378) (xy 64.299828 -389.87407) (xy 64.34429 -389.895168) (xy 64.384793 -389.923124)
			(xy 64.420286 -389.957216) (xy 64.449851 -389.99656) (xy 64.472722 -390.040137) (xy 64.488306 -390.086818)
			(xy 64.496201 -390.135395) (xy 64.496696 -390.160002) (xy 65.08548 -390.160002) (xy 65.08944 -390.110948)
			(xy 65.101217 -390.063164) (xy 65.120508 -390.017888) (xy 65.146811 -389.976292) (xy 65.179446 -389.939455)
			(xy 65.217567 -389.90833) (xy 65.260188 -389.883723) (xy 65.306204 -389.866271) (xy 65.354423 -389.856427)
			(xy 65.403598 -389.854446) (xy 65.452453 -389.860378) (xy 65.499724 -389.87407) (xy 65.544186 -389.895168)
			(xy 65.584689 -389.923124) (xy 65.620182 -389.957216) (xy 65.649747 -389.99656) (xy 65.672618 -390.040137)
			(xy 65.688202 -390.086818) (xy 65.696097 -390.135395) (xy 65.696592 -390.160002) (xy 65.696097 -390.184609)
			(xy 65.695873 -390.185989) (xy 66.41516 -390.185989) (xy 66.41516 -390.134015) (xy 66.42329 -390.08268)
			(xy 66.439351 -390.03325) (xy 66.462947 -389.98694) (xy 66.493497 -389.944892) (xy 66.530248 -389.908141)
			(xy 66.572296 -389.877591) (xy 66.618606 -389.853995) (xy 66.668036 -389.837934) (xy 66.719371 -389.829804)
			(xy 66.771345 -389.829804) (xy 66.82268 -389.837934) (xy 66.87211 -389.853995) (xy 66.91842 -389.877591)
			(xy 66.960468 -389.908141) (xy 66.997219 -389.944892) (xy 67.027769 -389.98694) (xy 67.051365 -390.03325)
			(xy 67.067426 -390.08268) (xy 67.075556 -390.134015) (xy 67.076066 -390.160002) (xy 67.075556 -390.185989)
			(xy 67.067426 -390.237324) (xy 67.051365 -390.286754) (xy 67.027769 -390.333064) (xy 66.997219 -390.375112)
			(xy 66.960468 -390.411863) (xy 66.91842 -390.442413) (xy 66.87211 -390.466009) (xy 66.82268 -390.48207)
			(xy 66.771345 -390.4902) (xy 66.719371 -390.4902) (xy 66.668036 -390.48207) (xy 66.618606 -390.466009)
			(xy 66.572296 -390.442413) (xy 66.530248 -390.411863) (xy 66.493497 -390.375112) (xy 66.462947 -390.333064)
			(xy 66.439351 -390.286754) (xy 66.42329 -390.237324) (xy 66.41516 -390.185989) (xy 65.695873 -390.185989)
			(xy 65.688202 -390.233186) (xy 65.672618 -390.279867) (xy 65.649747 -390.323444) (xy 65.620182 -390.362788)
			(xy 65.584689 -390.39688) (xy 65.544186 -390.424836) (xy 65.499724 -390.445934) (xy 65.452453 -390.459626)
			(xy 65.403598 -390.465558) (xy 65.354423 -390.463577) (xy 65.306204 -390.453733) (xy 65.260188 -390.436281)
			(xy 65.217567 -390.411674) (xy 65.179446 -390.380549) (xy 65.146811 -390.343712) (xy 65.120508 -390.302116)
			(xy 65.101217 -390.25684) (xy 65.08944 -390.209056) (xy 65.08548 -390.160002) (xy 64.496696 -390.160002)
			(xy 64.496201 -390.184609) (xy 64.488306 -390.233186) (xy 64.472722 -390.279867) (xy 64.449851 -390.323444)
			(xy 64.420286 -390.362788) (xy 64.384793 -390.39688) (xy 64.34429 -390.424836) (xy 64.299828 -390.445934)
			(xy 64.252557 -390.459626) (xy 64.203702 -390.465558) (xy 64.154527 -390.463577) (xy 64.106308 -390.453733)
			(xy 64.060292 -390.436281) (xy 64.017671 -390.411674) (xy 63.97955 -390.380549) (xy 63.946915 -390.343712)
			(xy 63.920612 -390.302116) (xy 63.901321 -390.25684) (xy 63.889544 -390.209056) (xy 63.885584 -390.160002)
			(xy 63.296546 -390.160002) (xy 63.296051 -390.184609) (xy 63.288156 -390.233186) (xy 63.272572 -390.279867)
			(xy 63.249701 -390.323444) (xy 63.220136 -390.362788) (xy 63.184643 -390.39688) (xy 63.14414 -390.424836)
			(xy 63.099678 -390.445934) (xy 63.052407 -390.459626) (xy 63.003552 -390.465558) (xy 62.954377 -390.463577)
			(xy 62.906158 -390.453733) (xy 62.860142 -390.436281) (xy 62.817521 -390.411674) (xy 62.7794 -390.380549)
			(xy 62.746765 -390.343712) (xy 62.720462 -390.302116) (xy 62.701171 -390.25684) (xy 62.689394 -390.209056)
			(xy 62.685434 -390.160002) (xy 62.09665 -390.160002) (xy 62.096155 -390.184609) (xy 62.08826 -390.233186)
			(xy 62.072676 -390.279867) (xy 62.049805 -390.323444) (xy 62.02024 -390.362788) (xy 61.984747 -390.39688)
			(xy 61.944244 -390.424836) (xy 61.899782 -390.445934) (xy 61.852511 -390.459626) (xy 61.803656 -390.465558)
			(xy 61.754481 -390.463577) (xy 61.706262 -390.453733) (xy 61.660246 -390.436281) (xy 61.617625 -390.411674)
			(xy 61.579504 -390.380549) (xy 61.546869 -390.343712) (xy 61.520566 -390.302116) (xy 61.501275 -390.25684)
			(xy 61.489498 -390.209056) (xy 61.485538 -390.160002) (xy 60.8965 -390.160002) (xy 60.896005 -390.184609)
			(xy 60.88811 -390.233186) (xy 60.872526 -390.279867) (xy 60.849655 -390.323444) (xy 60.82009 -390.362788)
			(xy 60.784597 -390.39688) (xy 60.744094 -390.424836) (xy 60.699632 -390.445934) (xy 60.652361 -390.459626)
			(xy 60.603506 -390.465558) (xy 60.554331 -390.463577) (xy 60.506112 -390.453733) (xy 60.460096 -390.436281)
			(xy 60.417475 -390.411674) (xy 60.379354 -390.380549) (xy 60.346719 -390.343712) (xy 60.320416 -390.302116)
			(xy 60.301125 -390.25684) (xy 60.289348 -390.209056) (xy 60.285388 -390.160002) (xy 59.696604 -390.160002)
			(xy 59.696109 -390.184609) (xy 59.688214 -390.233186) (xy 59.67263 -390.279867) (xy 59.649759 -390.323444)
			(xy 59.620194 -390.362788) (xy 59.584701 -390.39688) (xy 59.544198 -390.424836) (xy 59.499736 -390.445934)
			(xy 59.452465 -390.459626) (xy 59.40361 -390.465558) (xy 59.354435 -390.463577) (xy 59.306216 -390.453733)
			(xy 59.2602 -390.436281) (xy 59.217579 -390.411674) (xy 59.179458 -390.380549) (xy 59.146823 -390.343712)
			(xy 59.12052 -390.302116) (xy 59.101229 -390.25684) (xy 59.089452 -390.209056) (xy 59.085492 -390.160002)
			(xy 58.496708 -390.160002) (xy 58.496213 -390.184609) (xy 58.488318 -390.233186) (xy 58.472734 -390.279867)
			(xy 58.449863 -390.323444) (xy 58.420298 -390.362788) (xy 58.384805 -390.39688) (xy 58.344302 -390.424836)
			(xy 58.29984 -390.445934) (xy 58.252569 -390.459626) (xy 58.203714 -390.465558) (xy 58.154539 -390.463577)
			(xy 58.10632 -390.453733) (xy 58.060304 -390.436281) (xy 58.017683 -390.411674) (xy 57.979562 -390.380549)
			(xy 57.946927 -390.343712) (xy 57.920624 -390.302116) (xy 57.901333 -390.25684) (xy 57.889556 -390.209056)
			(xy 57.885596 -390.160002) (xy 57.296558 -390.160002) (xy 57.296063 -390.184609) (xy 57.288168 -390.233186)
			(xy 57.272584 -390.279867) (xy 57.249713 -390.323444) (xy 57.220148 -390.362788) (xy 57.184655 -390.39688)
			(xy 57.144152 -390.424836) (xy 57.09969 -390.445934) (xy 57.052419 -390.459626) (xy 57.003564 -390.465558)
			(xy 56.954389 -390.463577) (xy 56.90617 -390.453733) (xy 56.860154 -390.436281) (xy 56.817533 -390.411674)
			(xy 56.779412 -390.380549) (xy 56.746777 -390.343712) (xy 56.720474 -390.302116) (xy 56.701183 -390.25684)
			(xy 56.689406 -390.209056) (xy 56.685446 -390.160002) (xy 56.096662 -390.160002) (xy 56.096167 -390.184609)
			(xy 56.088272 -390.233186) (xy 56.072688 -390.279867) (xy 56.049817 -390.323444) (xy 56.020252 -390.362788)
			(xy 55.984759 -390.39688) (xy 55.944256 -390.424836) (xy 55.899794 -390.445934) (xy 55.852523 -390.459626)
			(xy 55.803668 -390.465558) (xy 55.754493 -390.463577) (xy 55.706274 -390.453733) (xy 55.660258 -390.436281)
			(xy 55.617637 -390.411674) (xy 55.579516 -390.380549) (xy 55.546881 -390.343712) (xy 55.520578 -390.302116)
			(xy 55.501287 -390.25684) (xy 55.48951 -390.209056) (xy 55.48555 -390.160002) (xy 54.896512 -390.160002)
			(xy 54.896017 -390.184609) (xy 54.888122 -390.233186) (xy 54.872538 -390.279867) (xy 54.849667 -390.323444)
			(xy 54.820102 -390.362788) (xy 54.784609 -390.39688) (xy 54.744106 -390.424836) (xy 54.699644 -390.445934)
			(xy 54.652373 -390.459626) (xy 54.603518 -390.465558) (xy 54.554343 -390.463577) (xy 54.506124 -390.453733)
			(xy 54.460108 -390.436281) (xy 54.417487 -390.411674) (xy 54.379366 -390.380549) (xy 54.346731 -390.343712)
			(xy 54.320428 -390.302116) (xy 54.301137 -390.25684) (xy 54.28936 -390.209056) (xy 54.2854 -390.160002)
			(xy 53.696616 -390.160002) (xy 53.696121 -390.184609) (xy 53.688226 -390.233186) (xy 53.672642 -390.279867)
			(xy 53.649771 -390.323444) (xy 53.620206 -390.362788) (xy 53.584713 -390.39688) (xy 53.54421 -390.424836)
			(xy 53.499748 -390.445934) (xy 53.452477 -390.459626) (xy 53.403622 -390.465558) (xy 53.354447 -390.463577)
			(xy 53.306228 -390.453733) (xy 53.260212 -390.436281) (xy 53.217591 -390.411674) (xy 53.17947 -390.380549)
			(xy 53.146835 -390.343712) (xy 53.120532 -390.302116) (xy 53.101241 -390.25684) (xy 53.089464 -390.209056)
			(xy 53.085504 -390.160002) (xy 52.49672 -390.160002) (xy 52.496225 -390.184609) (xy 52.48833 -390.233186)
			(xy 52.472746 -390.279867) (xy 52.449875 -390.323444) (xy 52.42031 -390.362788) (xy 52.384817 -390.39688)
			(xy 52.344314 -390.424836) (xy 52.299852 -390.445934) (xy 52.252581 -390.459626) (xy 52.203726 -390.465558)
			(xy 52.154551 -390.463577) (xy 52.106332 -390.453733) (xy 52.060316 -390.436281) (xy 52.017695 -390.411674)
			(xy 51.979574 -390.380549) (xy 51.946939 -390.343712) (xy 51.920636 -390.302116) (xy 51.901345 -390.25684)
			(xy 51.889568 -390.209056) (xy 51.885608 -390.160002) (xy 51.29657 -390.160002) (xy 51.296075 -390.184609)
			(xy 51.28818 -390.233186) (xy 51.272596 -390.279867) (xy 51.249725 -390.323444) (xy 51.22016 -390.362788)
			(xy 51.184667 -390.39688) (xy 51.144164 -390.424836) (xy 51.099702 -390.445934) (xy 51.052431 -390.459626)
			(xy 51.003576 -390.465558) (xy 50.954401 -390.463577) (xy 50.906182 -390.453733) (xy 50.860166 -390.436281)
			(xy 50.817545 -390.411674) (xy 50.779424 -390.380549) (xy 50.746789 -390.343712) (xy 50.720486 -390.302116)
			(xy 50.701195 -390.25684) (xy 50.689418 -390.209056) (xy 50.685458 -390.160002) (xy 50.096674 -390.160002)
			(xy 50.096179 -390.184609) (xy 50.088284 -390.233186) (xy 50.0727 -390.279867) (xy 50.049829 -390.323444)
			(xy 50.020264 -390.362788) (xy 49.984771 -390.39688) (xy 49.944268 -390.424836) (xy 49.899806 -390.445934)
			(xy 49.852535 -390.459626) (xy 49.80368 -390.465558) (xy 49.754505 -390.463577) (xy 49.706286 -390.453733)
			(xy 49.66027 -390.436281) (xy 49.617649 -390.411674) (xy 49.579528 -390.380549) (xy 49.546893 -390.343712)
			(xy 49.52059 -390.302116) (xy 49.501299 -390.25684) (xy 49.489522 -390.209056) (xy 49.485562 -390.160002)
			(xy 48.896524 -390.160002) (xy 48.896029 -390.184609) (xy 48.888134 -390.233186) (xy 48.87255 -390.279867)
			(xy 48.849679 -390.323444) (xy 48.820114 -390.362788) (xy 48.784621 -390.39688) (xy 48.744118 -390.424836)
			(xy 48.699656 -390.445934) (xy 48.652385 -390.459626) (xy 48.60353 -390.465558) (xy 48.554355 -390.463577)
			(xy 48.506136 -390.453733) (xy 48.46012 -390.436281) (xy 48.417499 -390.411674) (xy 48.379378 -390.380549)
			(xy 48.346743 -390.343712) (xy 48.32044 -390.302116) (xy 48.301149 -390.25684) (xy 48.289372 -390.209056)
			(xy 48.285412 -390.160002) (xy 47.696374 -390.160002) (xy 47.695879 -390.184609) (xy 47.687984 -390.233186)
			(xy 47.6724 -390.279867) (xy 47.649529 -390.323444) (xy 47.619964 -390.362788) (xy 47.584471 -390.39688)
			(xy 47.543968 -390.424836) (xy 47.499506 -390.445934) (xy 47.452235 -390.459626) (xy 47.40338 -390.465558)
			(xy 47.354205 -390.463577) (xy 47.305986 -390.453733) (xy 47.25997 -390.436281) (xy 47.217349 -390.411674)
			(xy 47.179228 -390.380549) (xy 47.146593 -390.343712) (xy 47.12029 -390.302116) (xy 47.100999 -390.25684)
			(xy 47.089222 -390.209056) (xy 47.085262 -390.160002) (xy 45.541852 -390.160002) (xy 45.540908 -390.166468)
			(xy 45.521831 -390.23026) (xy 45.493699 -390.290608) (xy 45.475906 -390.318752) (xy 45.470856 -390.327275)
			(xy 45.467034 -390.346693) (xy 45.470851 -390.366112) (xy 45.475906 -390.374632) (xy 45.493676 -390.402786)
			(xy 45.521772 -390.463144) (xy 45.540842 -390.52693) (xy 45.550487 -390.592804) (xy 45.55109 -390.626092)
			(xy 45.550648 -390.655392) (xy 45.543201 -390.713516) (xy 45.528377 -390.770208) (xy 45.517816 -390.797542)
			(xy 45.513752 -390.807194) (xy 45.51426 -390.82726) (xy 45.552106 -390.913112) (xy 45.566584 -390.927082)
			(xy 45.57649 -390.930638) (xy 45.59985 -390.939841) (xy 45.643696 -390.964296) (xy 45.683343 -390.995098)
			(xy 45.717878 -391.031538) (xy 45.746509 -391.072779) (xy 45.768578 -391.117874) (xy 45.783578 -391.165786)
			(xy 45.791163 -391.215415) (xy 45.791628 -391.240518) (xy 45.791118 -391.266505) (xy 45.782988 -391.31784)
			(xy 45.766927 -391.36727) (xy 45.743331 -391.41358) (xy 45.712781 -391.455628) (xy 45.67603 -391.492379)
			(xy 45.633982 -391.522929) (xy 45.587672 -391.546525) (xy 45.538242 -391.562586) (xy 45.486907 -391.570716)
			(xy 45.434933 -391.570716) (xy 45.383598 -391.562586) (xy 45.334168 -391.546525) (xy 45.287858 -391.522929)
			(xy 45.24581 -391.492379) (xy 45.209059 -391.455628) (xy 45.178509 -391.41358) (xy 45.154913 -391.36727)
			(xy 45.138852 -391.31784) (xy 45.130722 -391.266505) (xy 45.130212 -391.240518) (xy 45.130314 -391.229307)
			(xy 45.13184 -391.206936) (xy 45.13326 -391.195814) (xy 45.134784 -391.1854) (xy 45.12945 -391.165842)
			(xy 45.071792 -391.091928) (xy 45.054012 -391.082276) (xy 45.043598 -391.081006) (xy 45.013419 -391.077136)
			(xy 44.954344 -391.062583) (xy 44.897719 -391.040329) (xy 44.844543 -391.010767) (xy 44.795754 -390.974417)
			(xy 44.752213 -390.931922) (xy 44.714689 -390.884031) (xy 44.683843 -390.831589) (xy 44.660219 -390.775521)
			(xy 44.644235 -390.716817) (xy 44.636173 -390.656513) (xy 44.635674 -390.626092) (xy 39.51859 -390.626092)
			(xy 39.51859 -391.2235) (xy 41.439082 -391.2235) (xy 41.443153 -391.167878) (xy 41.455279 -391.113441)
			(xy 41.475202 -391.06135) (xy 41.502498 -391.012715) (xy 41.536584 -390.968572) (xy 41.576733 -390.929863)
			(xy 41.622091 -390.897412) (xy 41.671691 -390.871911) (xy 41.724475 -390.853904) (xy 41.779318 -390.843774)
			(xy 41.835052 -390.841737) (xy 41.890489 -390.847837) (xy 41.944446 -390.861943) (xy 41.995775 -390.883755)
			(xy 42.043381 -390.912809) (xy 42.086249 -390.948484) (xy 42.123466 -390.990021) (xy 42.154239 -391.036534)
			(xy 42.177911 -391.087031) (xy 42.193979 -391.140438) (xy 42.202099 -391.195614) (xy 42.202608 -391.2235)
			(xy 42.202099 -391.251386) (xy 42.193979 -391.306562) (xy 42.177911 -391.359969) (xy 42.154239 -391.410466)
			(xy 42.123466 -391.456979) (xy 42.086249 -391.498516) (xy 42.043381 -391.534191) (xy 41.995775 -391.563245)
			(xy 41.944446 -391.585057) (xy 41.890489 -391.599163) (xy 41.835052 -391.605263) (xy 41.779318 -391.603226)
			(xy 41.724475 -391.593096) (xy 41.671691 -391.575089) (xy 41.622091 -391.549588) (xy 41.576733 -391.517137)
			(xy 41.536584 -391.478428) (xy 41.502498 -391.434285) (xy 41.475202 -391.38565) (xy 41.455279 -391.333559)
			(xy 41.443153 -391.279122) (xy 41.439082 -391.2235) (xy 39.51859 -391.2235) (xy 39.51859 -391.562844)
			(xy 39.537386 -391.589006) (xy 39.55288 -391.59434) (xy 39.582581 -391.605018) (xy 39.639302 -391.632704)
			(xy 39.692161 -391.667197) (xy 39.740344 -391.707967) (xy 39.78311 -391.754387) (xy 39.819803 -391.805743)
			(xy 39.849858 -391.861245) (xy 39.872812 -391.920041) (xy 39.888313 -391.981225) (xy 39.896123 -392.043857)
			(xy 39.896542 -392.075416) (xy 39.896449 -392.087245) (xy 39.895304 -392.110877) (xy 39.894256 -392.12266)
			(xy 39.89324 -392.13409) (xy 39.90086 -392.155172) (xy 40.539162 -392.793474) (xy 40.546563 -392.800313)
			(xy 40.565161 -392.808029) (xy 40.57523 -392.80846) (xy 42.929048 -392.80846) (xy 42.938998 -392.807922)
			(xy 42.95737 -392.800256) (xy 42.971468 -392.786201) (xy 42.975784 -392.777218) (xy 42.98188 -392.76274)
			(xy 42.975784 -392.732768) (xy 42.837608 -392.594592) (xy 42.815412 -392.5718) (xy 42.775732 -392.522067)
			(xy 42.741871 -392.468203) (xy 42.714255 -392.410887) (xy 42.69323 -392.350838) (xy 42.679062 -392.288813)
			(xy 42.671929 -392.225591) (xy 42.671492 -392.19378) (xy 42.671492 -391.91184) (xy 42.671986 -391.877576)
			(xy 42.680242 -391.809547) (xy 42.696639 -391.74301) (xy 42.720936 -391.678934) (xy 42.75278 -391.618255)
			(xy 42.791706 -391.561857) (xy 42.837148 -391.510562) (xy 42.888441 -391.465119) (xy 42.944838 -391.42619)
			(xy 43.005516 -391.394344) (xy 43.069591 -391.370044) (xy 43.136128 -391.353646) (xy 43.204156 -391.345388)
			(xy 43.23842 -391.344912) (xy 43.271398 -391.345392) (xy 43.336907 -391.35305) (xy 43.401085 -391.36826)
			(xy 43.463063 -391.390816) (xy 43.522005 -391.420414) (xy 43.549824 -391.43813) (xy 43.557569 -391.442744)
			(xy 43.575131 -391.446766) (xy 43.584114 -391.446004) (xy 43.614086 -391.442194) (xy 43.62299 -391.440702)
			(xy 43.638993 -391.432371) (xy 43.645328 -391.425938) (xy 43.668394 -391.401054) (xy 43.719481 -391.3564)
			(xy 43.775532 -391.318161) (xy 43.835746 -391.286883) (xy 43.899261 -391.263015) (xy 43.965172 -391.246897)
			(xy 44.032534 -391.23876) (xy 44.06646 -391.238232) (xy 44.100724 -391.238747) (xy 44.168753 -391.247002)
			(xy 44.235291 -391.263397) (xy 44.299367 -391.287693) (xy 44.360048 -391.319535) (xy 44.416448 -391.35846)
			(xy 44.467745 -391.403898) (xy 44.513191 -391.455189) (xy 44.552123 -391.511584) (xy 44.583974 -391.57226)
			(xy 44.608279 -391.636333) (xy 44.624683 -391.702868) (xy 44.632948 -391.770896) (xy 44.633388 -391.80516)
			(xy 44.633388 -392.136122) (xy 44.633866 -392.146088) (xy 44.641441 -392.164525) (xy 44.64812 -392.171936)
			(xy 44.810934 -392.33475) (xy 46.164246 -392.33475) (xy 46.164645 -392.311516) (xy 46.171144 -392.265506)
			(xy 46.18402 -392.220859) (xy 46.203021 -392.178454) (xy 46.227772 -392.139127) (xy 46.242478 -392.121136)
			(xy 46.248574 -392.114024) (xy 46.25467 -392.097514) (xy 46.25467 -392.013186) (xy 46.248574 -391.996676)
			(xy 46.242478 -391.989564) (xy 46.227797 -391.971553) (xy 46.203044 -391.932231) (xy 46.184038 -391.889831)
			(xy 46.171153 -391.845189) (xy 46.164643 -391.799182) (xy 46.164246 -391.77595) (xy 46.164756 -391.749963)
			(xy 46.172886 -391.698628) (xy 46.188947 -391.649198) (xy 46.212543 -391.602888) (xy 46.243093 -391.56084)
			(xy 46.279844 -391.524089) (xy 46.321892 -391.493539) (xy 46.368202 -391.469943) (xy 46.417632 -391.453882)
			(xy 46.468967 -391.445752) (xy 46.520941 -391.445752) (xy 46.572276 -391.453882) (xy 46.621706 -391.469943)
			(xy 46.668016 -391.493539) (xy 46.710064 -391.524089) (xy 46.746815 -391.56084) (xy 46.777365 -391.602888)
			(xy 46.800961 -391.649198) (xy 46.817022 -391.698628) (xy 46.825152 -391.749963) (xy 46.825662 -391.77595)
			(xy 46.825261 -391.799184) (xy 46.818763 -391.845194) (xy 46.805886 -391.889841) (xy 46.786886 -391.932246)
			(xy 46.762136 -391.971573) (xy 46.74743 -391.989564) (xy 46.741334 -391.996676) (xy 46.735238 -392.013186)
			(xy 46.735238 -392.097514) (xy 46.741334 -392.114024) (xy 46.74743 -392.121136) (xy 46.762113 -392.139146)
			(xy 46.786865 -392.178468) (xy 46.805871 -392.220869) (xy 46.818755 -392.265511) (xy 46.825265 -392.311518)
			(xy 46.825662 -392.33475) (xy 46.825152 -392.360737) (xy 46.817022 -392.412072) (xy 46.800961 -392.461502)
			(xy 46.777365 -392.507812) (xy 46.746815 -392.54986) (xy 46.710064 -392.586611) (xy 46.668016 -392.617161)
			(xy 46.621706 -392.640757) (xy 46.572276 -392.656818) (xy 46.520941 -392.664948) (xy 46.468967 -392.664948)
			(xy 46.417632 -392.656818) (xy 46.368202 -392.640757) (xy 46.321892 -392.617161) (xy 46.279844 -392.586611)
			(xy 46.243093 -392.54986) (xy 46.212543 -392.507812) (xy 46.188947 -392.461502) (xy 46.172886 -392.412072)
			(xy 46.164756 -392.360737) (xy 46.164246 -392.33475) (xy 44.810934 -392.33475) (xy 46.651164 -394.17498)
			(xy 46.658565 -394.181818) (xy 46.677163 -394.189533) (xy 46.687232 -394.189966)
		)
		(stroke
			(width 0)
			(type solid)
		)
		(fill yes)
		(layer "In4.Cu")
		(net "P1V8_CPU1_RT_1D")
	)
	(gr_poly
		(pts
			(xy 100.98659 -202.132438) (xy 100.994197 -202.130926) (xy 101.008036 -202.123945) (xy 101.013768 -202.118722)
			(xy 101.656642 -201.475848) (xy 101.664516 -201.465688) (xy 102.305866 -200.380346) (xy 102.313994 -200.366884)
			(xy 102.314248 -200.366376) (xy 102.314502 -200.366122) (xy 102.314502 -200.365868) (xy 102.35819 -200.291954)
			(xy 102.362762 -200.28789) (xy 102.364032 -200.286874) (xy 102.38867 -200.266808) (xy 102.398322 -200.258934)
			(xy 102.398576 -200.25868) (xy 102.426516 -200.23582) (xy 102.427278 -200.235058) (xy 102.429056 -200.233534)
			(xy 105.795318 -197.473316) (xy 105.795572 -197.473316) (xy 105.796842 -197.472046) (xy 105.799128 -197.470014)
			(xy 113.608358 -189.66053) (xy 113.615758 -189.65369) (xy 113.634357 -189.645972) (xy 113.644426 -189.645544)
			(xy 115.33886 -189.645544) (xy 115.347313 -189.645193) (xy 115.363276 -189.639618) (xy 115.370102 -189.634622)
			(xy 116.096796 -189.0395) (xy 116.097558 -189.038738) (xy 116.163344 -188.972952) (xy 116.166963 -188.96952)
			(xy 116.175282 -188.964022) (xy 116.179854 -188.96203) (xy 116.188744 -188.95822) (xy 116.196618 -188.954918)
			(xy 116.200026 -188.95343) (xy 116.206406 -188.94961) (xy 116.209318 -188.947298) (xy 133.606794 -174.69485)
			(xy 133.608318 -174.69358) (xy 133.610604 -174.691548) (xy 139.733782 -168.56837) (xy 139.739741 -168.561495)
			(xy 139.746777 -168.544731) (xy 139.747482 -168.526564) (xy 139.744958 -168.517824) (xy 139.711176 -168.428924)
			(xy 139.708363 -168.422105) (xy 139.699463 -168.41035) (xy 139.69365 -168.40581) (xy 139.687739 -168.401808)
			(xy 139.674332 -168.396922) (xy 139.667234 -168.396158) (xy 139.666726 -168.396158) (xy 139.638995 -168.394019)
			(xy 139.584536 -168.382722) (xy 139.532293 -168.36364) (xy 139.483372 -168.337179) (xy 139.438809 -168.303899)
			(xy 139.399548 -168.264504) (xy 139.36642 -168.219828) (xy 139.340126 -168.170817) (xy 139.321223 -168.118509)
			(xy 139.31519 -168.091358) (xy 139.31519 -168.09085) (xy 139.313062 -168.082517) (xy 139.304103 -168.06785)
			(xy 139.297664 -168.062148) (xy 139.29741 -168.061894) (xy 139.290447 -168.056691) (xy 139.274089 -168.050845)
			(xy 139.265406 -168.050464) (xy 139.071096 -168.050464) (xy 139.068556 -168.05021) (xy 139.009882 -168.05021)
			(xy 139.00023 -168.04513) (xy 138.999468 -168.044876) (xy 138.998452 -168.044114) (xy 138.95832 -168.023032)
			(xy 138.792204 -167.93464) (xy 138.789918 -167.933624) (xy 138.78814 -167.932608) (xy 138.787632 -167.9321)
			(xy 138.761978 -167.918892) (xy 138.759946 -167.917622) (xy 138.758676 -167.91686) (xy 138.754358 -167.912542)
			(xy 138.753596 -167.91178) (xy 138.735308 -167.893492) (xy 138.731752 -167.889936) (xy 136.512046 -165.67023)
			(xy 136.508236 -165.66642) (xy 136.487408 -165.645592) (xy 136.487408 -165.645338) (xy 136.45261 -165.61054)
			(xy 136.445808 -165.603192) (xy 136.438095 -165.584729) (xy 136.437624 -165.574726) (xy 136.437624 -157.216094)
			(xy 136.438163 -157.206108) (xy 136.445881 -157.187679) (xy 136.45261 -157.18028) (xy 136.487408 -157.145482)
			(xy 136.487408 -157.145228) (xy 136.508236 -157.1244) (xy 136.512046 -157.12059) (xy 137.192004 -156.440378)
			(xy 138.542776 -155.089606) (xy 138.548289 -155.083142) (xy 138.555054 -155.067569) (xy 138.555984 -155.059126)
			(xy 138.555984 -149.48535) (xy 138.555984 -149.484842) (xy 138.555634 -149.476626) (xy 138.550322 -149.461074)
			(xy 138.54557 -149.454362) (xy 138.540998 -149.449282) (xy 136.639046 -147.54733) (xy 136.635236 -147.54352)
			(xy 136.614408 -147.522692) (xy 136.614408 -147.522438) (xy 136.57961 -147.48764) (xy 136.572808 -147.480292)
			(xy 136.565095 -147.461829) (xy 136.564624 -147.451826) (xy 136.564624 -143.66367) (xy 136.564624 -143.663162)
			(xy 136.564278 -143.654944) (xy 136.558974 -143.639386) (xy 136.55421 -143.632682) (xy 136.549638 -143.627602)
			(xy 134.670546 -141.74851) (xy 134.665466 -141.743938) (xy 134.658738 -141.739219) (xy 134.643195 -141.733913)
			(xy 134.634986 -141.733524) (xy 131.103878 -141.733524) (xy 131.09575 -141.734032) (xy 131.087895 -141.735656)
			(xy 131.073659 -141.743023) (xy 131.06781 -141.74851) (xy 127.550672 -145.265648) (xy 127.547967 -145.268499)
			(xy 127.543376 -145.274879) (xy 127.541528 -145.278348) (xy 127.538944 -145.283775) (xy 127.53612 -145.295454)
			(xy 127.53594 -145.301462) (xy 127.53594 -145.855182) (xy 127.535823 -145.860137) (xy 127.533909 -145.86986)
			(xy 127.53213 -145.874486) (xy 127.52832 -145.88363) (xy 127.525018 -145.891504) (xy 127.52322 -145.896191)
			(xy 127.521301 -145.906043) (xy 127.521208 -145.911062) (xy 127.521208 -149.47646) (xy 127.520954 -149.483826)
			(xy 127.520954 -149.560788) (xy 127.520417 -149.570775) (xy 127.512702 -149.589206) (xy 127.505968 -149.596602)
			(xy 127.454152 -149.648418) (xy 127.453644 -149.64918) (xy 127.450342 -149.652736) (xy 127.447294 -149.65553)
			(xy 127.446532 -149.656292) (xy 121.739914 -155.363164) (xy 121.721818 -155.38042) (xy 121.680272 -155.408228)
			(xy 121.634101 -155.427401) (xy 121.585078 -155.437204) (xy 121.560082 -155.43784) (xy 108.4072 -155.43784)
			(xy 108.382202 -155.437208) (xy 108.333173 -155.427416) (xy 108.286997 -155.408247) (xy 108.245447 -155.380439)
			(xy 108.227368 -155.363164) (xy 102.301548 -149.437344) (xy 102.284329 -149.419233) (xy 102.256596 -149.377671)
			(xy 102.237494 -149.331501) (xy 102.227755 -149.282495) (xy 102.227126 -149.257512) (xy 102.227126 -147.304252)
			(xy 102.227732 -147.279266) (xy 102.237464 -147.230252) (xy 102.256565 -147.184075) (xy 102.284302 -147.142508)
			(xy 102.301548 -147.12442) (xy 102.631748 -146.79422) (xy 102.649843 -146.776962) (xy 102.691389 -146.74915)
			(xy 102.737559 -146.729971) (xy 102.786583 -146.720162) (xy 102.81158 -146.719544) (xy 103.079296 -146.719544)
			(xy 103.089194 -146.719024) (xy 103.107484 -146.711438) (xy 103.114856 -146.704812) (xy 103.119682 -146.699986)
			(xy 103.123119 -146.696371) (xy 103.128628 -146.688056) (xy 103.130604 -146.683476) (xy 103.134414 -146.674332)
			(xy 103.134414 -146.663918) (xy 103.134842 -146.636642) (xy 103.142539 -146.582636) (xy 103.15785 -146.530277)
			(xy 103.180464 -146.480633) (xy 103.209918 -146.434716) (xy 103.245612 -146.393463) (xy 103.286819 -146.357716)
			(xy 103.332697 -146.328202) (xy 103.382311 -146.305524) (xy 103.43465 -146.290144) (xy 103.488646 -146.282377)
			(xy 103.515922 -146.281902) (xy 103.543172 -146.28239) (xy 103.597117 -146.290149) (xy 103.649408 -146.305506)
			(xy 103.698982 -146.328149) (xy 103.744829 -146.357616) (xy 103.786016 -146.393307) (xy 103.821704 -146.434497)
			(xy 103.841002 -146.464528) (xy 115.805966 -146.464528) (xy 115.806432 -146.437158) (xy 115.814248 -146.382978)
			(xy 115.829736 -146.330474) (xy 115.852578 -146.280727) (xy 115.882304 -146.234761) (xy 115.899946 -146.21383)
			(xy 115.9002 -146.213576) (xy 115.905803 -146.2065) (xy 115.91204 -146.189575) (xy 115.912392 -146.180556)
			(xy 115.912392 -146.1135) (xy 115.912037 -146.104483) (xy 115.905788 -146.087566) (xy 115.9002 -146.08048)
			(xy 115.899946 -146.08048) (xy 115.899946 -146.080226) (xy 115.882332 -146.059271) (xy 115.852605 -146.013308)
			(xy 115.829756 -145.963565) (xy 115.814257 -145.911066) (xy 115.806426 -145.856891) (xy 115.806422 -145.802152)
			(xy 115.814248 -145.747975) (xy 115.829742 -145.695474) (xy 115.852584 -145.645729) (xy 115.882307 -145.599762)
			(xy 115.899946 -145.57883) (xy 115.9002 -145.578576) (xy 115.905803 -145.5715) (xy 115.91204 -145.554575)
			(xy 115.912392 -145.545556) (xy 115.912392 -145.4785) (xy 115.912037 -145.469483) (xy 115.905788 -145.452566)
			(xy 115.9002 -145.44548) (xy 115.899946 -145.44548) (xy 115.899946 -145.445226) (xy 115.882332 -145.424271)
			(xy 115.852605 -145.378308) (xy 115.829756 -145.328565) (xy 115.814257 -145.276066) (xy 115.806426 -145.221891)
			(xy 115.806422 -145.167152) (xy 115.814248 -145.112975) (xy 115.829742 -145.060474) (xy 115.852584 -145.010729)
			(xy 115.882307 -144.964762) (xy 115.899946 -144.94383) (xy 115.9002 -144.943576) (xy 115.905803 -144.9365)
			(xy 115.91204 -144.919575) (xy 115.912392 -144.910556) (xy 115.912392 -144.8435) (xy 115.912037 -144.834483)
			(xy 115.905788 -144.817566) (xy 115.9002 -144.81048) (xy 115.899946 -144.81048) (xy 115.899946 -144.810226)
			(xy 115.882332 -144.789271) (xy 115.852605 -144.743308) (xy 115.829756 -144.693565) (xy 115.814257 -144.641066)
			(xy 115.806426 -144.586891) (xy 115.806422 -144.532152) (xy 115.814248 -144.477975) (xy 115.829742 -144.425474)
			(xy 115.852584 -144.375729) (xy 115.882307 -144.329762) (xy 115.899946 -144.30883) (xy 115.9002 -144.308576)
			(xy 115.905803 -144.3015) (xy 115.91204 -144.284575) (xy 115.912392 -144.275556) (xy 115.912392 -144.2085)
			(xy 115.912037 -144.199483) (xy 115.905788 -144.182566) (xy 115.9002 -144.17548) (xy 115.899946 -144.17548)
			(xy 115.899946 -144.175226) (xy 115.882313 -144.154289) (xy 115.852598 -144.108318) (xy 115.829761 -144.058572)
			(xy 115.814268 -144.006072) (xy 115.80644 -143.951897) (xy 115.805966 -143.924528) (xy 115.806481 -143.897277)
			(xy 115.814234 -143.843329) (xy 115.829585 -143.791034) (xy 115.852222 -143.741456) (xy 115.881685 -143.695604)
			(xy 115.917373 -143.654411) (xy 115.95856 -143.618717) (xy 116.004408 -143.589248) (xy 116.053983 -143.566604)
			(xy 116.106276 -143.551245) (xy 116.160223 -143.543485) (xy 116.187474 -143.54302) (xy 116.214844 -143.543496)
			(xy 116.269023 -143.551311) (xy 116.321526 -143.566797) (xy 116.371273 -143.589637) (xy 116.41724 -143.61936)
			(xy 116.438172 -143.637) (xy 116.438426 -143.637254) (xy 116.445525 -143.642822) (xy 116.462432 -143.649079)
			(xy 116.471446 -143.649446) (xy 116.538502 -143.649446) (xy 116.54752 -143.649101) (xy 116.564438 -143.642846)
			(xy 116.571522 -143.637254) (xy 116.571522 -143.637) (xy 116.571776 -143.637) (xy 116.592706 -143.619359)
			(xy 116.63868 -143.589647) (xy 116.688428 -143.566812) (xy 116.740929 -143.551321) (xy 116.795105 -143.543494)
			(xy 116.822474 -143.54302) (xy 116.850048 -143.543497) (xy 116.904621 -143.551446) (xy 116.957481 -143.567168)
			(xy 117.007527 -143.590336) (xy 117.053717 -143.620467) (xy 117.095088 -143.656933) (xy 117.113304 -143.67764)
			(xy 117.120851 -143.685724) (xy 117.140869 -143.695072) (xy 117.151912 -143.695674) (xy 117.229636 -143.695674)
			(xy 117.240682 -143.695079) (xy 117.260704 -143.685733) (xy 117.268244 -143.67764) (xy 117.28649 -143.656961)
			(xy 117.32785 -143.620486) (xy 117.374033 -143.590349) (xy 117.424074 -143.567177) (xy 117.476931 -143.551455)
			(xy 117.531501 -143.543509) (xy 117.559074 -143.54302) (xy 117.586444 -143.543496) (xy 117.640623 -143.551311)
			(xy 117.693126 -143.566797) (xy 117.742873 -143.589637) (xy 117.78884 -143.61936) (xy 117.809772 -143.637)
			(xy 117.810026 -143.637254) (xy 117.817125 -143.642822) (xy 117.834032 -143.649079) (xy 117.843046 -143.649446)
			(xy 117.910102 -143.649446) (xy 117.91912 -143.649101) (xy 117.936038 -143.642846) (xy 117.943122 -143.637254)
			(xy 117.943122 -143.637) (xy 117.943376 -143.637) (xy 117.964309 -143.619359) (xy 118.010277 -143.589635)
			(xy 118.060023 -143.566789) (xy 118.112525 -143.551293) (xy 118.166703 -143.543464) (xy 118.221445 -143.543464)
			(xy 118.275623 -143.551293) (xy 118.328125 -143.566789) (xy 118.377871 -143.589635) (xy 118.423839 -143.619359)
			(xy 118.444772 -143.637) (xy 118.445026 -143.637254) (xy 118.452125 -143.642822) (xy 118.469032 -143.649079)
			(xy 118.478046 -143.649446) (xy 118.545102 -143.649446) (xy 118.55412 -143.649101) (xy 118.571038 -143.642846)
			(xy 118.578122 -143.637254) (xy 118.578122 -143.637) (xy 118.578376 -143.637) (xy 118.599309 -143.619359)
			(xy 118.645277 -143.589635) (xy 118.695023 -143.566789) (xy 118.747525 -143.551293) (xy 118.801703 -143.543464)
			(xy 118.856445 -143.543464) (xy 118.910623 -143.551293) (xy 118.963125 -143.566789) (xy 119.012871 -143.589635)
			(xy 119.058839 -143.619359) (xy 119.079772 -143.637) (xy 119.080026 -143.637254) (xy 119.087125 -143.642822)
			(xy 119.104032 -143.649079) (xy 119.113046 -143.649446) (xy 119.180102 -143.649446) (xy 119.18912 -143.649101)
			(xy 119.206038 -143.642846) (xy 119.213122 -143.637254) (xy 119.213122 -143.637) (xy 119.213376 -143.637)
			(xy 119.234306 -143.619359) (xy 119.28028 -143.589647) (xy 119.330028 -143.566812) (xy 119.382529 -143.551321)
			(xy 119.436705 -143.543494) (xy 119.464074 -143.54302) (xy 119.491648 -143.543497) (xy 119.546221 -143.551446)
			(xy 119.599081 -143.567168) (xy 119.649127 -143.590336) (xy 119.695317 -143.620467) (xy 119.736688 -143.656933)
			(xy 119.754904 -143.67764) (xy 119.762451 -143.685724) (xy 119.782469 -143.695072) (xy 119.793512 -143.695674)
			(xy 119.871236 -143.695674) (xy 119.882282 -143.695079) (xy 119.902304 -143.685733) (xy 119.909844 -143.67764)
			(xy 119.92809 -143.656961) (xy 119.96945 -143.620486) (xy 120.015633 -143.590349) (xy 120.065674 -143.567177)
			(xy 120.118531 -143.551455) (xy 120.173101 -143.543509) (xy 120.200674 -143.54302) (xy 120.228044 -143.543496)
			(xy 120.282223 -143.551311) (xy 120.334726 -143.566797) (xy 120.384473 -143.589637) (xy 120.43044 -143.61936)
			(xy 120.451372 -143.637) (xy 120.451626 -143.637254) (xy 120.458725 -143.642822) (xy 120.475632 -143.649079)
			(xy 120.484646 -143.649446) (xy 120.551702 -143.649446) (xy 120.56072 -143.649101) (xy 120.577638 -143.642846)
			(xy 120.584722 -143.637254) (xy 120.584722 -143.637) (xy 120.584976 -143.637) (xy 120.605906 -143.619359)
			(xy 120.65188 -143.589647) (xy 120.701628 -143.566812) (xy 120.754129 -143.551321) (xy 120.808305 -143.543494)
			(xy 120.835674 -143.54302) (xy 120.862927 -143.54348) (xy 120.91688 -143.551234) (xy 120.96918 -143.566588)
			(xy 121.018762 -143.589229) (xy 121.064616 -143.618697) (xy 121.10581 -143.654392) (xy 121.141504 -143.695585)
			(xy 121.170972 -143.74144) (xy 121.193613 -143.791022) (xy 121.208967 -143.843322) (xy 121.216721 -143.897275)
			(xy 121.217182 -143.924528) (xy 121.216737 -143.951899) (xy 121.208915 -144.006079) (xy 121.193421 -144.058583)
			(xy 121.170574 -144.108329) (xy 121.140845 -144.154295) (xy 121.123202 -144.175226) (xy 121.122948 -144.17548)
			(xy 121.117357 -144.182564) (xy 121.111114 -144.199483) (xy 121.110756 -144.2085) (xy 121.110756 -144.275556)
			(xy 121.111122 -144.284572) (xy 121.117362 -144.30149) (xy 121.122948 -144.308576) (xy 121.123202 -144.308576)
			(xy 121.123202 -144.30883) (xy 121.140869 -144.329741) (xy 121.17059 -144.375713) (xy 121.193432 -144.425463)
			(xy 121.208925 -144.477968) (xy 121.216751 -144.532149) (xy 121.216747 -144.586893) (xy 121.208916 -144.641073)
			(xy 121.193417 -144.693576) (xy 121.17057 -144.743324) (xy 121.140843 -144.789293) (xy 121.123202 -144.810226)
			(xy 121.122948 -144.81048) (xy 121.117357 -144.817564) (xy 121.111114 -144.834483) (xy 121.110756 -144.8435)
			(xy 121.110756 -144.910556) (xy 121.111122 -144.919572) (xy 121.117362 -144.93649) (xy 121.122948 -144.943576)
			(xy 121.123202 -144.943576) (xy 121.123202 -144.94383) (xy 121.140869 -144.964741) (xy 121.17059 -145.010713)
			(xy 121.193432 -145.060463) (xy 121.208925 -145.112968) (xy 121.216751 -145.167149) (xy 121.216747 -145.221893)
			(xy 121.208916 -145.276073) (xy 121.193417 -145.328576) (xy 121.17057 -145.378324) (xy 121.140843 -145.424293)
			(xy 121.123202 -145.445226) (xy 121.122948 -145.44548) (xy 121.117357 -145.452564) (xy 121.111114 -145.469483)
			(xy 121.110756 -145.4785) (xy 121.110756 -145.545556) (xy 121.111122 -145.554572) (xy 121.117362 -145.57149)
			(xy 121.122948 -145.578576) (xy 121.123202 -145.578576) (xy 121.123202 -145.57883) (xy 121.140869 -145.599741)
			(xy 121.17059 -145.645713) (xy 121.193432 -145.695463) (xy 121.208925 -145.747968) (xy 121.216751 -145.802149)
			(xy 121.216747 -145.856893) (xy 121.208916 -145.911073) (xy 121.193417 -145.963576) (xy 121.17057 -146.013324)
			(xy 121.140843 -146.059293) (xy 121.123202 -146.080226) (xy 121.122948 -146.08048) (xy 121.117357 -146.087564)
			(xy 121.111114 -146.104483) (xy 121.110756 -146.1135) (xy 121.110756 -146.180556) (xy 121.111122 -146.189572)
			(xy 121.117362 -146.20649) (xy 121.122948 -146.213576) (xy 121.123202 -146.213576) (xy 121.123202 -146.21383)
			(xy 121.140822 -146.234777) (xy 121.170537 -146.280746) (xy 121.193376 -146.33049) (xy 121.208872 -146.382987)
			(xy 121.216705 -146.43716) (xy 121.217182 -146.464528) (xy 121.216748 -146.491781) (xy 121.208987 -146.545732)
			(xy 121.193627 -146.598029) (xy 121.170981 -146.647608) (xy 121.141509 -146.69346) (xy 121.105812 -146.734651)
			(xy 121.064617 -146.770342) (xy 121.018761 -146.799807) (xy 120.969179 -146.822446) (xy 120.916879 -146.837799)
			(xy 120.862927 -146.845552) (xy 120.835674 -146.846036) (xy 120.808302 -146.845601) (xy 120.754121 -146.837778)
			(xy 120.701617 -146.822282) (xy 120.651871 -146.799433) (xy 120.605906 -146.769701) (xy 120.584976 -146.752056)
			(xy 120.584722 -146.751802) (xy 120.577633 -146.746219) (xy 120.560718 -146.73997) (xy 120.551702 -146.73961)
			(xy 120.484646 -146.73961) (xy 120.475631 -146.739987) (xy 120.458714 -146.746221) (xy 120.451626 -146.751802)
			(xy 120.451626 -146.752056) (xy 120.451372 -146.752056) (xy 120.430418 -146.769668) (xy 120.384452 -146.799385)
			(xy 120.33471 -146.822227) (xy 120.282214 -146.837725) (xy 120.228042 -146.845559) (xy 120.200674 -146.846036)
			(xy 120.173354 -146.845559) (xy 120.119273 -146.83776) (xy 120.066857 -146.822326) (xy 120.01718 -146.799573)
			(xy 119.971256 -146.769965) (xy 119.930026 -146.734109) (xy 119.894333 -146.692738) (xy 119.864907 -146.646698)
			(xy 119.853202 -146.622008) (xy 119.847106 -146.608292) (xy 119.82196 -146.592036) (xy 119.770144 -146.592036)
			(xy 119.760076 -146.592475) (xy 119.741478 -146.600185) (xy 119.734076 -146.607022) (xy 119.714472 -146.626004)
			(xy 119.670814 -146.658738) (xy 119.622937 -146.684918) (xy 119.571819 -146.704009) (xy 119.518502 -146.715621)
			(xy 119.464074 -146.719519) (xy 119.409646 -146.715621) (xy 119.356329 -146.704009) (xy 119.305211 -146.684918)
			(xy 119.257334 -146.658738) (xy 119.213676 -146.626004) (xy 119.194072 -146.607022) (xy 119.186673 -146.60018)
			(xy 119.168073 -146.592461) (xy 119.158004 -146.592036) (xy 119.135144 -146.592036) (xy 119.125076 -146.592475)
			(xy 119.106478 -146.600185) (xy 119.099076 -146.607022) (xy 119.079472 -146.626004) (xy 119.035814 -146.658738)
			(xy 118.987937 -146.684918) (xy 118.936819 -146.704009) (xy 118.883502 -146.715621) (xy 118.829074 -146.719519)
			(xy 118.774646 -146.715621) (xy 118.721329 -146.704009) (xy 118.670211 -146.684918) (xy 118.622334 -146.658738)
			(xy 118.578676 -146.626004) (xy 118.559072 -146.607022) (xy 118.551673 -146.60018) (xy 118.533073 -146.592461)
			(xy 118.523004 -146.592036) (xy 118.500144 -146.592036) (xy 118.490076 -146.592475) (xy 118.471478 -146.600185)
			(xy 118.464076 -146.607022) (xy 118.444472 -146.626004) (xy 118.400814 -146.658738) (xy 118.352937 -146.684918)
			(xy 118.301819 -146.704009) (xy 118.248502 -146.715621) (xy 118.194074 -146.719519) (xy 118.139646 -146.715621)
			(xy 118.086329 -146.704009) (xy 118.035211 -146.684918) (xy 117.987334 -146.658738) (xy 117.943676 -146.626004)
			(xy 117.924072 -146.607022) (xy 117.916673 -146.60018) (xy 117.898073 -146.592461) (xy 117.888004 -146.592036)
			(xy 117.865144 -146.592036) (xy 117.855076 -146.592475) (xy 117.836478 -146.600185) (xy 117.829076 -146.607022)
			(xy 117.809472 -146.626004) (xy 117.765814 -146.658738) (xy 117.717937 -146.684918) (xy 117.666819 -146.704009)
			(xy 117.613502 -146.715621) (xy 117.559074 -146.719519) (xy 117.504646 -146.715621) (xy 117.451329 -146.704009)
			(xy 117.400211 -146.684918) (xy 117.352334 -146.658738) (xy 117.308676 -146.626004) (xy 117.289072 -146.607022)
			(xy 117.281673 -146.60018) (xy 117.263073 -146.592461) (xy 117.253004 -146.592036) (xy 117.201188 -146.592036)
			(xy 117.176042 -146.608292) (xy 117.169946 -146.622008) (xy 117.158242 -146.6467) (xy 117.128821 -146.692745)
			(xy 117.093131 -146.734122) (xy 117.051901 -146.769981) (xy 117.005977 -146.799591) (xy 116.956297 -146.822344)
			(xy 116.903879 -146.837776) (xy 116.849795 -146.845569) (xy 116.822474 -146.846036) (xy 116.795102 -146.845601)
			(xy 116.740921 -146.837778) (xy 116.688417 -146.822282) (xy 116.638671 -146.799433) (xy 116.592706 -146.769701)
			(xy 116.571776 -146.752056) (xy 116.571522 -146.751802) (xy 116.564433 -146.746219) (xy 116.547518 -146.73997)
			(xy 116.538502 -146.73961) (xy 116.471446 -146.73961) (xy 116.462431 -146.739987) (xy 116.445514 -146.746221)
			(xy 116.438426 -146.751802) (xy 116.438426 -146.752056) (xy 116.438172 -146.752056) (xy 116.417218 -146.769668)
			(xy 116.371252 -146.799385) (xy 116.32151 -146.822227) (xy 116.269014 -146.837725) (xy 116.214842 -146.845559)
			(xy 116.187474 -146.846036) (xy 116.160223 -146.845546) (xy 116.106277 -146.837787) (xy 116.053984 -146.82243)
			(xy 116.004409 -146.799788) (xy 115.95856 -146.770322) (xy 115.917371 -146.734631) (xy 115.88168 -146.693442)
			(xy 115.852213 -146.647593) (xy 115.829571 -146.598018) (xy 115.814213 -146.545725) (xy 115.806454 -146.491779)
			(xy 115.805966 -146.464528) (xy 103.841002 -146.464528) (xy 103.851167 -146.480346) (xy 103.873805 -146.529922)
			(xy 103.889158 -146.582215) (xy 103.896912 -146.63616) (xy 103.89743 -146.66341) (xy 103.896999 -146.689255)
			(xy 103.890017 -146.740471) (xy 103.876183 -146.790275) (xy 103.855749 -146.837754) (xy 103.829091 -146.882039)
			(xy 103.796696 -146.922318) (xy 103.759159 -146.957853) (xy 103.738426 -146.97329) (xy 103.730747 -146.980154)
			(xy 103.721195 -146.998378) (xy 103.719884 -147.008596) (xy 103.71963 -147.01266) (xy 103.71963 -147.09521)
			(xy 103.719884 -147.099274) (xy 103.721178 -147.109495) (xy 103.730737 -147.127724) (xy 103.738426 -147.13458)
			(xy 103.75917 -147.150003) (xy 103.796703 -147.185543) (xy 103.829094 -147.225826) (xy 103.85575 -147.270113)
			(xy 103.876183 -147.317594) (xy 103.890018 -147.367398) (xy 103.897002 -147.418615) (xy 103.89743 -147.44446)
			(xy 103.89697 -147.471715) (xy 103.889218 -147.525672) (xy 103.873865 -147.577976) (xy 103.851225 -147.627562)
			(xy 103.821759 -147.673422) (xy 103.786065 -147.714621) (xy 103.744872 -147.750322) (xy 103.699017 -147.779796)
			(xy 103.649434 -147.802444) (xy 103.597132 -147.817804) (xy 103.543177 -147.825565) (xy 103.515922 -147.825968)
			(xy 103.488554 -147.825491) (xy 103.434382 -147.817656) (xy 103.381885 -147.80216) (xy 103.332143 -147.779319)
			(xy 103.286175 -147.749603) (xy 103.265224 -147.731988) (xy 103.26497 -147.731734) (xy 103.257526 -147.725863)
			(xy 103.239651 -147.719582) (xy 103.230172 -147.719542) (xy 103.220774 -147.719796) (xy 103.203502 -147.727162)
			(xy 103.144574 -147.785836) (xy 103.141172 -147.789407) (xy 103.135672 -147.797593) (xy 103.133652 -147.802092)
			(xy 103.131828 -147.806712) (xy 103.129786 -147.816432) (xy 103.129588 -147.821396) (xy 103.129588 -148.94052)
			(xy 103.129588 -148.941028) (xy 103.129932 -148.949246) (xy 103.135235 -148.964806) (xy 103.140002 -148.971508)
			(xy 103.144574 -148.976588) (xy 105.15212 -150.984134) (xy 109.251492 -150.984134) (xy 109.251492 -150.899438)
			(xy 109.259543 -150.815124) (xy 109.275572 -150.731958) (xy 109.299433 -150.650691) (xy 109.330912 -150.572061)
			(xy 109.369723 -150.49678) (xy 109.415513 -150.425528) (xy 109.467869 -150.358952) (xy 109.526317 -150.297654)
			(xy 109.590327 -150.242189) (xy 109.659319 -150.19306) (xy 109.732669 -150.150711) (xy 109.809712 -150.115527)
			(xy 109.889751 -150.087825) (xy 109.97206 -150.067857) (xy 110.055895 -150.055804) (xy 110.140496 -150.051774)
			(xy 110.225097 -150.055804) (xy 110.308932 -150.067857) (xy 110.391241 -150.087825) (xy 110.47128 -150.115527)
			(xy 110.548323 -150.150711) (xy 110.621673 -150.19306) (xy 110.690665 -150.242189) (xy 110.754675 -150.297654)
			(xy 110.813123 -150.358952) (xy 110.865479 -150.425528) (xy 110.911269 -150.49678) (xy 110.95008 -150.572061)
			(xy 110.981559 -150.650691) (xy 111.00542 -150.731958) (xy 111.021449 -150.815124) (xy 111.0295 -150.899438)
			(xy 111.030004 -150.941786) (xy 111.0295 -150.984134) (xy 111.751614 -150.984134) (xy 111.751614 -150.899438)
			(xy 111.759665 -150.815124) (xy 111.775694 -150.731958) (xy 111.799555 -150.650691) (xy 111.831034 -150.572061)
			(xy 111.869845 -150.49678) (xy 111.915635 -150.425528) (xy 111.967991 -150.358952) (xy 112.026439 -150.297654)
			(xy 112.090449 -150.242189) (xy 112.159441 -150.19306) (xy 112.232791 -150.150711) (xy 112.309834 -150.115527)
			(xy 112.389873 -150.087825) (xy 112.472182 -150.067857) (xy 112.556017 -150.055804) (xy 112.640618 -150.051774)
			(xy 112.725219 -150.055804) (xy 112.809054 -150.067857) (xy 112.891363 -150.087825) (xy 112.971402 -150.115527)
			(xy 113.048445 -150.150711) (xy 113.121795 -150.19306) (xy 113.190787 -150.242189) (xy 113.254797 -150.297654)
			(xy 113.313245 -150.358952) (xy 113.365601 -150.425528) (xy 113.411391 -150.49678) (xy 113.450202 -150.572061)
			(xy 113.481681 -150.650691) (xy 113.505542 -150.731958) (xy 113.521571 -150.815124) (xy 113.529622 -150.899438)
			(xy 113.530126 -150.941786) (xy 113.529622 -150.984134) (xy 113.521571 -151.068448) (xy 113.505542 -151.151614)
			(xy 113.481681 -151.232881) (xy 113.450202 -151.311511) (xy 113.411391 -151.386792) (xy 113.365601 -151.458044)
			(xy 113.313245 -151.52462) (xy 113.254797 -151.585918) (xy 113.190787 -151.641383) (xy 113.121795 -151.690512)
			(xy 113.048445 -151.732861) (xy 112.971402 -151.768045) (xy 112.891363 -151.795747) (xy 112.809054 -151.815715)
			(xy 112.725219 -151.827768) (xy 112.640618 -151.831799) (xy 112.556017 -151.827768) (xy 112.472182 -151.815715)
			(xy 112.389873 -151.795747) (xy 112.309834 -151.768045) (xy 112.232791 -151.732861) (xy 112.159441 -151.690512)
			(xy 112.090449 -151.641383) (xy 112.026439 -151.585918) (xy 111.967991 -151.52462) (xy 111.915635 -151.458044)
			(xy 111.869845 -151.386792) (xy 111.831034 -151.311511) (xy 111.799555 -151.232881) (xy 111.775694 -151.151614)
			(xy 111.759665 -151.068448) (xy 111.751614 -150.984134) (xy 111.0295 -150.984134) (xy 111.021449 -151.068448)
			(xy 111.00542 -151.151614) (xy 110.981559 -151.232881) (xy 110.95008 -151.311511) (xy 110.911269 -151.386792)
			(xy 110.865479 -151.458044) (xy 110.813123 -151.52462) (xy 110.754675 -151.585918) (xy 110.690665 -151.641383)
			(xy 110.621673 -151.690512) (xy 110.548323 -151.732861) (xy 110.47128 -151.768045) (xy 110.391241 -151.795747)
			(xy 110.308932 -151.815715) (xy 110.225097 -151.827768) (xy 110.140496 -151.831799) (xy 110.055895 -151.827768)
			(xy 109.97206 -151.815715) (xy 109.889751 -151.795747) (xy 109.809712 -151.768045) (xy 109.732669 -151.732861)
			(xy 109.659319 -151.690512) (xy 109.590327 -151.641383) (xy 109.526317 -151.585918) (xy 109.467869 -151.52462)
			(xy 109.415513 -151.458044) (xy 109.369723 -151.386792) (xy 109.330912 -151.311511) (xy 109.299433 -151.232881)
			(xy 109.275572 -151.151614) (xy 109.259543 -151.068448) (xy 109.251492 -150.984134) (xy 105.15212 -150.984134)
			(xy 106.825542 -152.657556) (xy 115.877086 -152.657556) (xy 115.877588 -152.630187) (xy 115.885398 -152.57601)
			(xy 115.900879 -152.523507) (xy 115.923712 -152.47376) (xy 115.953429 -152.427791) (xy 115.971066 -152.406858)
			(xy 115.97132 -152.406604) (xy 115.976913 -152.399522) (xy 115.983155 -152.382602) (xy 115.983512 -152.373584)
			(xy 115.983512 -152.306528) (xy 115.983139 -152.297513) (xy 115.976902 -152.280596) (xy 115.97132 -152.273508)
			(xy 115.971066 -152.273508) (xy 115.971066 -152.273254) (xy 115.953433 -152.252317) (xy 115.923722 -152.206345)
			(xy 115.900885 -152.156599) (xy 115.885392 -152.104099) (xy 115.877562 -152.049925) (xy 115.877086 -152.022556)
			(xy 115.877537 -151.995304) (xy 115.885299 -151.941355) (xy 115.90066 -151.88906) (xy 115.923305 -151.839483)
			(xy 115.952776 -151.793633) (xy 115.988471 -151.752444) (xy 116.029664 -151.716753) (xy 116.075517 -151.687287)
			(xy 116.125096 -151.664646) (xy 116.177392 -151.649291) (xy 116.231342 -151.641534) (xy 116.258594 -151.641048)
			(xy 116.285965 -151.641506) (xy 116.340145 -151.649324) (xy 116.392648 -151.664814) (xy 116.442395 -151.687658)
			(xy 116.488361 -151.717385) (xy 116.509292 -151.735028) (xy 116.509546 -151.735282) (xy 116.516646 -151.74085)
			(xy 116.533552 -151.747108) (xy 116.542566 -151.747474) (xy 116.609622 -151.747474) (xy 116.618641 -151.747133)
			(xy 116.635558 -151.740875) (xy 116.642642 -151.735282) (xy 116.642642 -151.735028) (xy 116.642896 -151.735028)
			(xy 116.663822 -151.717382) (xy 116.709796 -151.68767) (xy 116.759545 -151.664835) (xy 116.812047 -151.649346)
			(xy 116.866224 -151.64152) (xy 116.893594 -151.641048) (xy 116.922607 -151.64157) (xy 116.979966 -151.65034)
			(xy 117.035335 -151.667693) (xy 117.087439 -151.69323) (xy 117.135076 -151.726361) (xy 117.156484 -151.74595)
			(xy 117.163342 -151.752808) (xy 117.181376 -151.75992) (xy 117.271292 -151.75992) (xy 117.289326 -151.752808)
			(xy 117.296184 -151.74595) (xy 117.317594 -151.726366) (xy 117.365238 -151.693251) (xy 117.417343 -151.667723)
			(xy 117.472709 -151.650369) (xy 117.530063 -151.64159) (xy 117.559074 -151.641048) (xy 117.586444 -151.641518)
			(xy 117.640624 -151.649333) (xy 117.693127 -151.66482) (xy 117.742874 -151.687662) (xy 117.788841 -151.717386)
			(xy 117.809772 -151.735028) (xy 117.810026 -151.735282) (xy 117.817131 -151.740841) (xy 117.834034 -151.747105)
			(xy 117.843046 -151.747474) (xy 117.910102 -151.747474) (xy 117.91912 -151.747124) (xy 117.936037 -151.740872)
			(xy 117.943122 -151.735282) (xy 117.943122 -151.735028) (xy 117.943376 -151.735028) (xy 117.964309 -151.717387)
			(xy 118.010277 -151.687663) (xy 118.060023 -151.664817) (xy 118.112525 -151.649321) (xy 118.166703 -151.641492)
			(xy 118.221445 -151.641492) (xy 118.275623 -151.649321) (xy 118.328125 -151.664817) (xy 118.377871 -151.687663)
			(xy 118.423839 -151.717387) (xy 118.444772 -151.735028) (xy 118.445026 -151.735282) (xy 118.452131 -151.740841)
			(xy 118.469034 -151.747105) (xy 118.478046 -151.747474) (xy 118.545102 -151.747474) (xy 118.55412 -151.747124)
			(xy 118.571037 -151.740872) (xy 118.578122 -151.735282) (xy 118.578122 -151.735028) (xy 118.578376 -151.735028)
			(xy 118.599309 -151.717387) (xy 118.645277 -151.687663) (xy 118.695023 -151.664817) (xy 118.747525 -151.649321)
			(xy 118.801703 -151.641492) (xy 118.856445 -151.641492) (xy 118.910623 -151.649321) (xy 118.963125 -151.664817)
			(xy 119.012871 -151.687663) (xy 119.058839 -151.717387) (xy 119.079772 -151.735028) (xy 119.080026 -151.735282)
			(xy 119.087131 -151.740841) (xy 119.104034 -151.747105) (xy 119.113046 -151.747474) (xy 119.180102 -151.747474)
			(xy 119.18912 -151.747124) (xy 119.206037 -151.740872) (xy 119.213122 -151.735282) (xy 119.213122 -151.735028)
			(xy 119.213376 -151.735028) (xy 119.23431 -151.717391) (xy 119.280282 -151.687678) (xy 119.330029 -151.664841)
			(xy 119.382529 -151.64935) (xy 119.436705 -151.641522) (xy 119.464074 -151.641048) (xy 119.491323 -151.641602)
			(xy 119.545266 -151.649354) (xy 119.597556 -151.664704) (xy 119.64713 -151.687339) (xy 119.692979 -151.716798)
			(xy 119.734168 -151.752482) (xy 119.76986 -151.793665) (xy 119.799328 -151.839508) (xy 119.821972 -151.889078)
			(xy 119.837331 -151.941366) (xy 119.845093 -151.995308) (xy 119.845582 -152.022556) (xy 119.845095 -152.049926)
			(xy 119.837283 -152.104104) (xy 119.821799 -152.156607) (xy 119.798962 -152.206354) (xy 119.769241 -152.252322)
			(xy 119.751602 -152.273254) (xy 119.751348 -152.273508) (xy 119.745746 -152.280584) (xy 119.73951 -152.297509)
			(xy 119.739156 -152.306528) (xy 119.739156 -152.373584) (xy 119.739509 -152.382602) (xy 119.745758 -152.399519)
			(xy 119.751348 -152.406604) (xy 119.751602 -152.406604) (xy 119.751602 -152.406858) (xy 119.769235 -152.427795)
			(xy 119.798948 -152.473766) (xy 119.821785 -152.523513) (xy 119.837277 -152.576012) (xy 119.845107 -152.630187)
			(xy 119.845582 -152.657556) (xy 119.845104 -152.684809) (xy 119.837352 -152.738761) (xy 119.822 -152.79106)
			(xy 119.799361 -152.840642) (xy 119.769895 -152.886496) (xy 119.734203 -152.92769) (xy 119.693011 -152.963384)
			(xy 119.647157 -152.992852) (xy 119.597577 -153.015494) (xy 119.545278 -153.030848) (xy 119.491327 -153.038602)
			(xy 119.464074 -153.039064) (xy 119.436703 -153.038622) (xy 119.382522 -153.0308) (xy 119.330019 -153.015305)
			(xy 119.280272 -152.992458) (xy 119.234307 -152.962728) (xy 119.213376 -152.945084) (xy 119.213122 -152.94483)
			(xy 119.206039 -152.939238) (xy 119.189119 -152.932997) (xy 119.180102 -152.932638) (xy 119.113046 -152.932638)
			(xy 119.10403 -152.933009) (xy 119.087113 -152.939246) (xy 119.080026 -152.94483) (xy 119.079772 -152.945084)
			(xy 119.058839 -152.962725) (xy 119.012871 -152.992449) (xy 118.963125 -153.015295) (xy 118.910623 -153.030791)
			(xy 118.856445 -153.03862) (xy 118.801703 -153.03862) (xy 118.747525 -153.030791) (xy 118.695023 -153.015295)
			(xy 118.645277 -152.992449) (xy 118.599309 -152.962725) (xy 118.578376 -152.945084) (xy 118.578122 -152.94483)
			(xy 118.571039 -152.939238) (xy 118.554119 -152.932997) (xy 118.545102 -152.932638) (xy 118.478046 -152.932638)
			(xy 118.46903 -152.933009) (xy 118.452113 -152.939246) (xy 118.445026 -152.94483) (xy 118.445026 -152.945084)
			(xy 118.444772 -152.945084) (xy 118.423839 -152.962725) (xy 118.377871 -152.992449) (xy 118.328125 -153.015295)
			(xy 118.275623 -153.030791) (xy 118.221445 -153.03862) (xy 118.166703 -153.03862) (xy 118.112525 -153.030791)
			(xy 118.060023 -153.015295) (xy 118.010277 -152.992449) (xy 117.964309 -152.962725) (xy 117.943376 -152.945084)
			(xy 117.943122 -152.94483) (xy 117.936039 -152.939238) (xy 117.919119 -152.932997) (xy 117.910102 -152.932638)
			(xy 117.843046 -152.932638) (xy 117.83403 -152.933009) (xy 117.817113 -152.939246) (xy 117.810026 -152.94483)
			(xy 117.810026 -152.945084) (xy 117.809772 -152.945084) (xy 117.788822 -152.9627) (xy 117.742854 -152.992416)
			(xy 117.693111 -153.015257) (xy 117.640615 -153.030753) (xy 117.586442 -153.038587) (xy 117.559074 -153.039064)
			(xy 117.530061 -153.038558) (xy 117.472701 -153.029784) (xy 117.417332 -153.012427) (xy 117.365228 -152.986886)
			(xy 117.317592 -152.953752) (xy 117.296184 -152.934162) (xy 117.289326 -152.927304) (xy 117.271292 -152.920192)
			(xy 117.181376 -152.920192) (xy 117.163342 -152.927304) (xy 117.156484 -152.934162) (xy 117.135089 -152.953763)
			(xy 117.087441 -152.986876) (xy 117.035332 -153.0124) (xy 116.979963 -153.029749) (xy 116.922606 -153.038525)
			(xy 116.893594 -153.039064) (xy 116.866223 -153.03861) (xy 116.812043 -153.030791) (xy 116.75954 -153.015299)
			(xy 116.709793 -152.992455) (xy 116.663827 -152.962727) (xy 116.642896 -152.945084) (xy 116.642642 -152.94483)
			(xy 116.635554 -152.939247) (xy 116.618638 -152.933) (xy 116.609622 -152.932638) (xy 116.542566 -152.932638)
			(xy 116.533546 -152.93297) (xy 116.516629 -152.939234) (xy 116.509546 -152.94483) (xy 116.509546 -152.945084)
			(xy 116.509292 -152.945084) (xy 116.488372 -152.962738) (xy 116.442396 -152.992448) (xy 116.392645 -153.015281)
			(xy 116.340142 -153.030769) (xy 116.285964 -153.038593) (xy 116.258594 -153.039064) (xy 116.231339 -153.03865)
			(xy 116.177384 -153.030891) (xy 116.125083 -153.015532) (xy 116.075499 -152.992886) (xy 116.029644 -152.963413)
			(xy 115.988451 -152.927714) (xy 115.952757 -152.886516) (xy 115.92329 -152.840657) (xy 115.90065 -152.791071)
			(xy 115.885298 -152.738767) (xy 115.877546 -152.684811) (xy 115.877086 -152.657556) (xy 106.825542 -152.657556)
			(xy 108.701078 -154.533092) (xy 108.708433 -154.539745) (xy 108.726733 -154.547334) (xy 108.736638 -154.547824)
			(xy 121.275856 -154.547824) (xy 121.285759 -154.547313) (xy 121.304067 -154.539747) (xy 121.311416 -154.533092)
			(xy 123.470924 -152.373584) (xy 123.477776 -152.366188) (xy 123.485517 -152.347589) (xy 123.48591 -152.337516)
			(xy 123.48591 -152.316688) (xy 123.484894 -152.315672) (xy 126.579376 -149.22119) (xy 126.584367 -149.215693)
			(xy 126.591218 -149.202528) (xy 126.592838 -149.195282) (xy 126.593854 -149.18563) (xy 126.593854 -145.51025)
			(xy 126.594288 -145.500185) (xy 126.602021 -145.481599) (xy 126.60884 -145.474182) (xy 126.61646 -145.466562)
			(xy 126.623201 -145.459191) (xy 126.630785 -145.440729) (xy 126.631192 -145.430748) (xy 126.631192 -144.911318)
			(xy 126.631446 -144.903952) (xy 126.631446 -144.82699) (xy 126.631987 -144.817004) (xy 126.639708 -144.798579)
			(xy 126.646432 -144.791176) (xy 126.698248 -144.73936) (xy 126.698756 -144.738598) (xy 126.702058 -144.735042)
			(xy 126.705106 -144.732248) (xy 126.705868 -144.731486) (xy 130.518916 -140.918438) (xy 130.519678 -140.917676)
			(xy 130.522472 -140.914628) (xy 130.526028 -140.911326) (xy 130.52679 -140.910818) (xy 130.578606 -140.859002)
			(xy 130.585951 -140.852192) (xy 130.604414 -140.844461) (xy 130.61442 -140.844016) (xy 135.01116 -140.844016)
			(xy 135.021225 -140.844451) (xy 135.039812 -140.852182) (xy 135.047228 -140.859002) (xy 135.06196 -140.873734)
			(xy 135.06196 -140.886434) (xy 135.080502 -140.901674) (xy 135.09879 -140.918438) (xy 135.948166 -141.767814)
			(xy 137.379964 -143.199358) (xy 137.397182 -143.21747) (xy 137.424913 -143.259032) (xy 137.444014 -143.305201)
			(xy 137.453752 -143.354208) (xy 137.454386 -143.37919) (xy 137.454132 -145.02384) (xy 137.454132 -147.083018)
			(xy 137.454132 -147.083526) (xy 137.454475 -147.091745) (xy 137.459773 -147.107308) (xy 137.464546 -147.114006)
			(xy 137.469118 -147.119086) (xy 139.37107 -149.021038) (xy 139.37488 -149.024848) (xy 139.395708 -149.045676)
			(xy 139.395708 -149.04593) (xy 139.430506 -149.080728) (xy 139.437311 -149.088075) (xy 139.445033 -149.106537)
			(xy 139.445492 -149.116542) (xy 139.445492 -155.424378) (xy 139.444958 -155.434367) (xy 139.43725 -155.452804)
			(xy 139.430506 -155.460192) (xy 139.395708 -155.49499) (xy 139.395708 -155.495244) (xy 139.37488 -155.516072)
			(xy 139.37107 -155.519882) (xy 137.338562 -157.552644) (xy 137.334429 -157.558012) (xy 137.328881 -157.570368)
			(xy 137.32764 -157.577028) (xy 137.32764 -165.21303) (xy 137.328735 -165.219335) (xy 137.33362 -165.231157)
			(xy 137.337292 -165.236398) (xy 137.342118 -165.241986) (xy 139.226544 -167.126158) (xy 139.23389 -167.132966)
			(xy 139.252353 -167.140689) (xy 139.262358 -167.141144) (xy 139.288774 -167.141144) (xy 139.29642 -167.140889)
			(xy 139.311027 -167.136369) (xy 139.317476 -167.132254) (xy 139.323318 -167.12819) (xy 139.33297 -167.116506)
			(xy 139.335764 -167.109394) (xy 139.346897 -167.083437) (xy 139.375697 -167.034852) (xy 139.411346 -166.991045)
			(xy 139.453064 -166.952974) (xy 139.49994 -166.921469) (xy 139.550949 -166.897221) (xy 139.604975 -166.880759)
			(xy 139.660838 -166.872442) (xy 139.689078 -166.871904) (xy 139.716332 -166.872366) (xy 139.770284 -166.88012)
			(xy 139.822584 -166.895475) (xy 139.872166 -166.918116) (xy 139.918021 -166.947584) (xy 139.959215 -166.983277)
			(xy 139.99491 -167.024471) (xy 140.024379 -167.070325) (xy 140.047022 -167.119907) (xy 140.062378 -167.172206)
			(xy 140.070133 -167.226158) (xy 140.070586 -167.253412) (xy 140.070051 -167.282328) (xy 140.061322 -167.339498)
			(xy 140.044066 -167.394696) (xy 140.018679 -167.446658) (xy 139.985741 -167.494194) (xy 139.946007 -167.536215)
			(xy 139.92352 -167.554402) (xy 139.914732 -167.561942) (xy 139.904557 -167.582715) (xy 139.903962 -167.59428)
			(xy 139.903962 -167.674544) (xy 139.904652 -167.685989) (xy 139.914677 -167.706573) (xy 139.923266 -167.714168)
			(xy 139.925806 -167.7162) (xy 139.926822 -167.716962) (xy 139.927076 -167.717216) (xy 139.947635 -167.734182)
			(xy 139.984268 -167.772901) (xy 140.015145 -167.81635) (xy 140.039662 -167.86368) (xy 140.057341 -167.913966)
			(xy 140.067835 -167.966225) (xy 140.069824 -167.992806) (xy 140.069824 -167.993568) (xy 140.070554 -168.000674)
			(xy 140.075444 -168.014088) (xy 140.079476 -168.019984) (xy 140.084033 -168.025782) (xy 140.095777 -168.03469)
			(xy 140.10259 -168.03751) (xy 140.174726 -168.065196) (xy 140.175234 -168.065196) (xy 140.189204 -168.07053)
			(xy 140.198275 -168.073535) (xy 140.217369 -168.0733) (xy 140.23506 -168.066113) (xy 140.24229 -168.059862)
			(xy 140.242544 -168.059608) (xy 140.243052 -168.0591) (xy 141.996922 -166.30523) (xy 142.00251 -166.298372)
			(xy 143.118332 -164.620956) (xy 143.360648 -164.256212) (xy 143.36522 -164.245798) (xy 143.99641 -162.38601)
			(xy 143.997671 -162.382063) (xy 143.999069 -162.373896) (xy 143.999204 -162.369754) (xy 143.999204 -157.970728)
			(xy 143.999204 -157.96768) (xy 143.488156 -149.822662) (xy 143.38173 -148.126196) (xy 143.380714 -148.114766)
			(xy 143.375634 -148.105368) (xy 143.283178 -147.913852) (xy 143.283178 -147.913598) (xy 143.244062 -147.832572)
			(xy 143.150844 -147.640294) (xy 143.14297 -147.629626) (xy 132.600446 -137.087102) (xy 132.596715 -137.083582)
			(xy 132.588139 -137.077957) (xy 132.583428 -137.075926) (xy 132.574792 -137.07237) (xy 113.421668 -137.07237)
			(xy 113.411662 -137.072863) (xy 113.393176 -137.080527) (xy 113.379026 -137.094678) (xy 113.371363 -137.113164)
			(xy 113.370868 -137.12317) (xy 113.370868 -143.649446) (xy 113.370351 -143.68106) (xy 113.362098 -143.743747)
			(xy 113.345734 -143.804821) (xy 113.321537 -143.863236) (xy 113.289923 -143.917993) (xy 113.251432 -143.968155)
			(xy 113.206723 -144.012864) (xy 113.156561 -144.051355) (xy 113.101804 -144.082969) (xy 113.043389 -144.107166)
			(xy 112.982315 -144.12353) (xy 112.919628 -144.131783) (xy 112.8564 -144.131783) (xy 112.793713 -144.12353)
			(xy 112.732639 -144.107166) (xy 112.674224 -144.082969) (xy 112.619467 -144.051355) (xy 112.569305 -144.012864)
			(xy 112.524596 -143.968155) (xy 112.486105 -143.917993) (xy 112.454491 -143.863236) (xy 112.430294 -143.804821)
			(xy 112.41393 -143.743747) (xy 112.405677 -143.68106) (xy 112.40516 -143.649446) (xy 112.40516 -137.12317)
			(xy 112.404735 -137.113156) (xy 112.397058 -137.094656) (xy 112.382885 -137.080503) (xy 112.364375 -137.072852)
			(xy 112.35436 -137.07237) (xy 91.166696 -137.07237) (xy 91.156687 -137.072858) (xy 91.138191 -137.080517)
			(xy 91.124032 -137.094669) (xy 91.116363 -137.113161) (xy 91.115896 -137.12317) (xy 91.115896 -137.716514)
			(xy 94.936816 -137.716514) (xy 94.940887 -137.660892) (xy 94.953013 -137.606455) (xy 94.972936 -137.554364)
			(xy 95.000232 -137.505729) (xy 95.034318 -137.461586) (xy 95.074467 -137.422877) (xy 95.119825 -137.390426)
			(xy 95.169425 -137.364925) (xy 95.222209 -137.346918) (xy 95.277052 -137.336788) (xy 95.332786 -137.334751)
			(xy 95.388223 -137.340851) (xy 95.44218 -137.354957) (xy 95.493509 -137.376769) (xy 95.541115 -137.405823)
			(xy 95.583983 -137.441498) (xy 95.6212 -137.483035) (xy 95.651973 -137.529548) (xy 95.675645 -137.580045)
			(xy 95.691713 -137.633452) (xy 95.699833 -137.688628) (xy 95.700342 -137.716514) (xy 95.699833 -137.7444)
			(xy 95.691713 -137.799576) (xy 95.675645 -137.852983) (xy 95.651973 -137.90348) (xy 95.6212 -137.949993)
			(xy 95.583983 -137.99153) (xy 95.541115 -138.027205) (xy 95.493509 -138.056259) (xy 95.44218 -138.078071)
			(xy 95.388223 -138.092177) (xy 95.332786 -138.098277) (xy 95.277052 -138.09624) (xy 95.222209 -138.08611)
			(xy 95.169425 -138.068103) (xy 95.119825 -138.042602) (xy 95.074467 -138.010151) (xy 95.034318 -137.971442)
			(xy 95.000232 -137.927299) (xy 94.972936 -137.878664) (xy 94.953013 -137.826573) (xy 94.940887 -137.772136)
			(xy 94.936816 -137.716514) (xy 91.115896 -137.716514) (xy 91.115896 -137.775696) (xy 91.115359 -137.785684)
			(xy 91.107646 -137.804116) (xy 91.10091 -137.81151) (xy 91.033092 -137.879328) (xy 91.031822 -137.880598)
			(xy 91.030298 -137.882376) (xy 91.024456 -137.888472) (xy 90.582242 -138.330432) (xy 90.579634 -138.333179)
			(xy 90.57517 -138.3393) (xy 90.573352 -138.342624) (xy 90.57005 -138.34872) (xy 90.568526 -138.355832)
			(xy 90.56192 -138.38388) (xy 90.557317 -138.395964) (xy 95.912938 -138.395964) (xy 95.917009 -138.340342)
			(xy 95.929135 -138.285905) (xy 95.949058 -138.233814) (xy 95.976354 -138.185179) (xy 96.01044 -138.141036)
			(xy 96.050589 -138.102327) (xy 96.095947 -138.069876) (xy 96.145547 -138.044375) (xy 96.198331 -138.026368)
			(xy 96.253174 -138.016238) (xy 96.308908 -138.014201) (xy 96.364345 -138.020301) (xy 96.418302 -138.034407)
			(xy 96.469631 -138.056219) (xy 96.517237 -138.085273) (xy 96.560105 -138.120948) (xy 96.597322 -138.162485)
			(xy 96.628095 -138.208998) (xy 96.651767 -138.259495) (xy 96.667835 -138.312902) (xy 96.67348 -138.35126)
			(xy 104.87609 -138.35126) (xy 104.880161 -138.295638) (xy 104.892287 -138.241201) (xy 104.91221 -138.18911)
			(xy 104.939506 -138.140475) (xy 104.973592 -138.096332) (xy 105.013741 -138.057623) (xy 105.059099 -138.025172)
			(xy 105.108699 -137.999671) (xy 105.161483 -137.981664) (xy 105.216326 -137.971534) (xy 105.27206 -137.969497)
			(xy 105.327497 -137.975597) (xy 105.381454 -137.989703) (xy 105.432783 -138.011515) (xy 105.480389 -138.040569)
			(xy 105.523257 -138.076244) (xy 105.560474 -138.117781) (xy 105.591247 -138.164294) (xy 105.614919 -138.214791)
			(xy 105.630987 -138.268198) (xy 105.639107 -138.323374) (xy 105.639616 -138.35126) (xy 105.639107 -138.379146)
			(xy 105.630987 -138.434322) (xy 105.614919 -138.487729) (xy 105.591247 -138.538226) (xy 105.560474 -138.584739)
			(xy 105.523257 -138.626276) (xy 105.480389 -138.661951) (xy 105.432783 -138.691005) (xy 105.381454 -138.712817)
			(xy 105.327497 -138.726923) (xy 105.27206 -138.733023) (xy 105.216326 -138.730986) (xy 105.161483 -138.720856)
			(xy 105.108699 -138.702849) (xy 105.059099 -138.677348) (xy 105.013741 -138.644897) (xy 104.973592 -138.606188)
			(xy 104.939506 -138.562045) (xy 104.91221 -138.51341) (xy 104.892287 -138.461319) (xy 104.880161 -138.406882)
			(xy 104.87609 -138.35126) (xy 96.67348 -138.35126) (xy 96.675955 -138.368078) (xy 96.676464 -138.395964)
			(xy 96.675955 -138.42385) (xy 96.667835 -138.479026) (xy 96.651767 -138.532433) (xy 96.628095 -138.58293)
			(xy 96.597322 -138.629443) (xy 96.560105 -138.67098) (xy 96.517237 -138.706655) (xy 96.469631 -138.735709)
			(xy 96.418302 -138.757521) (xy 96.364345 -138.771627) (xy 96.308908 -138.777727) (xy 96.253174 -138.77569)
			(xy 96.198331 -138.76556) (xy 96.145547 -138.747553) (xy 96.095947 -138.722052) (xy 96.050589 -138.689601)
			(xy 96.01044 -138.650892) (xy 95.976354 -138.606749) (xy 95.949058 -138.558114) (xy 95.929135 -138.506023)
			(xy 95.917009 -138.451586) (xy 95.912938 -138.395964) (xy 90.557317 -138.395964) (xy 90.541409 -138.437727)
			(xy 90.513039 -138.48788) (xy 90.477453 -138.5332) (xy 90.435461 -138.572657) (xy 90.388016 -138.605356)
			(xy 90.336196 -138.630552) (xy 90.281177 -138.647675) (xy 90.224211 -138.656334) (xy 90.1954 -138.656822)
			(xy 90.16813 -138.656358) (xy 90.114145 -138.648596) (xy 90.061815 -138.633229) (xy 90.012204 -138.610571)
			(xy 89.966323 -138.581083) (xy 89.925107 -138.545365) (xy 89.889393 -138.504144) (xy 89.859909 -138.458261)
			(xy 89.837257 -138.408648) (xy 89.821895 -138.356316) (xy 89.814139 -138.30233) (xy 89.813638 -138.27506)
			(xy 89.814166 -138.246253) (xy 89.82283 -138.189295) (xy 89.839953 -138.134284) (xy 89.865149 -138.082472)
			(xy 89.897844 -138.035034) (xy 89.937296 -137.993047) (xy 89.98261 -137.957466) (xy 90.032755 -137.929097)
			(xy 90.086594 -137.908586) (xy 90.114628 -137.901934) (xy 90.12174 -137.90041) (xy 90.127836 -137.897108)
			(xy 90.131166 -137.895301) (xy 90.137286 -137.890833) (xy 90.140028 -137.888218) (xy 90.341958 -137.686034)
			(xy 90.477848 -137.550144) (xy 90.483121 -137.543719) (xy 90.489618 -137.52843) (xy 90.490548 -137.520172)
			(xy 90.490548 -137.12317) (xy 90.490055 -137.113163) (xy 90.482392 -137.094673) (xy 90.468242 -137.080518)
			(xy 90.449755 -137.072848) (xy 90.439748 -137.07237) (xy 78.391512 -137.07237) (xy 78.38144 -137.07279)
			(xy 78.36283 -137.080498) (xy 78.355444 -137.087356) (xy 77.517752 -137.925048) (xy 82.375246 -137.925048)
			(xy 82.379317 -137.869426) (xy 82.391443 -137.814989) (xy 82.411366 -137.762898) (xy 82.438662 -137.714263)
			(xy 82.472748 -137.67012) (xy 82.512897 -137.631411) (xy 82.558255 -137.59896) (xy 82.607855 -137.573459)
			(xy 82.660639 -137.555452) (xy 82.715482 -137.545322) (xy 82.771216 -137.543285) (xy 82.826653 -137.549385)
			(xy 82.88061 -137.563491) (xy 82.931939 -137.585303) (xy 82.979545 -137.614357) (xy 83.007989 -137.638028)
			(xy 88.661746 -137.638028) (xy 88.665817 -137.582406) (xy 88.677943 -137.527969) (xy 88.697866 -137.475878)
			(xy 88.725162 -137.427243) (xy 88.759248 -137.3831) (xy 88.799397 -137.344391) (xy 88.844755 -137.31194)
			(xy 88.894355 -137.286439) (xy 88.947139 -137.268432) (xy 89.001982 -137.258302) (xy 89.057716 -137.256265)
			(xy 89.113153 -137.262365) (xy 89.16711 -137.276471) (xy 89.218439 -137.298283) (xy 89.266045 -137.327337)
			(xy 89.308913 -137.363012) (xy 89.34613 -137.404549) (xy 89.376903 -137.451062) (xy 89.400575 -137.501559)
			(xy 89.416643 -137.554966) (xy 89.424763 -137.610142) (xy 89.425272 -137.638028) (xy 89.424763 -137.665914)
			(xy 89.416643 -137.72109) (xy 89.400575 -137.774497) (xy 89.376903 -137.824994) (xy 89.34613 -137.871507)
			(xy 89.308913 -137.913044) (xy 89.266045 -137.948719) (xy 89.218439 -137.977773) (xy 89.16711 -137.999585)
			(xy 89.113153 -138.013691) (xy 89.057716 -138.019791) (xy 89.001982 -138.017754) (xy 88.947139 -138.007624)
			(xy 88.894355 -137.989617) (xy 88.844755 -137.964116) (xy 88.799397 -137.931665) (xy 88.759248 -137.892956)
			(xy 88.725162 -137.848813) (xy 88.697866 -137.800178) (xy 88.677943 -137.748087) (xy 88.665817 -137.69365)
			(xy 88.661746 -137.638028) (xy 83.007989 -137.638028) (xy 83.022413 -137.650032) (xy 83.05963 -137.691569)
			(xy 83.090403 -137.738082) (xy 83.114075 -137.788579) (xy 83.130143 -137.841986) (xy 83.138263 -137.897162)
			(xy 83.138772 -137.925048) (xy 83.138263 -137.952934) (xy 83.130143 -138.00811) (xy 83.114075 -138.061517)
			(xy 83.090403 -138.112014) (xy 83.05963 -138.158527) (xy 83.022413 -138.200064) (xy 82.979545 -138.235739)
			(xy 82.931939 -138.264793) (xy 82.88061 -138.286605) (xy 82.826653 -138.300711) (xy 82.771216 -138.306811)
			(xy 82.715482 -138.304774) (xy 82.660639 -138.294644) (xy 82.607855 -138.276637) (xy 82.558255 -138.251136)
			(xy 82.512897 -138.218685) (xy 82.472748 -138.179976) (xy 82.438662 -138.135833) (xy 82.411366 -138.087198)
			(xy 82.391443 -138.035107) (xy 82.379317 -137.98067) (xy 82.375246 -137.925048) (xy 77.517752 -137.925048)
			(xy 76.830936 -138.611864) (xy 79.572102 -138.611864) (xy 79.576173 -138.556242) (xy 79.588299 -138.501805)
			(xy 79.608222 -138.449714) (xy 79.635518 -138.401079) (xy 79.669604 -138.356936) (xy 79.709753 -138.318227)
			(xy 79.755111 -138.285776) (xy 79.804711 -138.260275) (xy 79.857495 -138.242268) (xy 79.912338 -138.232138)
			(xy 79.968072 -138.230101) (xy 80.023509 -138.236201) (xy 80.077466 -138.250307) (xy 80.128795 -138.272119)
			(xy 80.176401 -138.301173) (xy 80.219269 -138.336848) (xy 80.256486 -138.378385) (xy 80.287259 -138.424898)
			(xy 80.310931 -138.475395) (xy 80.326999 -138.528802) (xy 80.335119 -138.583978) (xy 80.335628 -138.611864)
			(xy 80.335119 -138.63975) (xy 80.326999 -138.694926) (xy 80.310931 -138.748333) (xy 80.289532 -138.793982)
			(xy 96.825052 -138.793982) (xy 96.829123 -138.73836) (xy 96.841249 -138.683923) (xy 96.861172 -138.631832)
			(xy 96.888468 -138.583197) (xy 96.922554 -138.539054) (xy 96.962703 -138.500345) (xy 97.008061 -138.467894)
			(xy 97.057661 -138.442393) (xy 97.110445 -138.424386) (xy 97.165288 -138.414256) (xy 97.221022 -138.412219)
			(xy 97.276459 -138.418319) (xy 97.330416 -138.432425) (xy 97.381745 -138.454237) (xy 97.429351 -138.483291)
			(xy 97.472219 -138.518966) (xy 97.509436 -138.560503) (xy 97.540209 -138.607016) (xy 97.563881 -138.657513)
			(xy 97.579949 -138.71092) (xy 97.588069 -138.766096) (xy 97.588578 -138.793982) (xy 97.588069 -138.821868)
			(xy 97.579949 -138.877044) (xy 97.568105 -138.91641) (xy 102.14686 -138.91641) (xy 102.150931 -138.860788)
			(xy 102.163057 -138.806351) (xy 102.18298 -138.75426) (xy 102.210276 -138.705625) (xy 102.244362 -138.661482)
			(xy 102.284511 -138.622773) (xy 102.329869 -138.590322) (xy 102.379469 -138.564821) (xy 102.432253 -138.546814)
			(xy 102.487096 -138.536684) (xy 102.54283 -138.534647) (xy 102.598267 -138.540747) (xy 102.652224 -138.554853)
			(xy 102.703553 -138.576665) (xy 102.751159 -138.605719) (xy 102.794027 -138.641394) (xy 102.831244 -138.682931)
			(xy 102.862017 -138.729444) (xy 102.885689 -138.779941) (xy 102.901757 -138.833348) (xy 102.909877 -138.888524)
			(xy 102.910386 -138.91641) (xy 102.909877 -138.944296) (xy 102.901757 -138.999472) (xy 102.885689 -139.052879)
			(xy 102.862017 -139.103376) (xy 102.831244 -139.149889) (xy 102.794027 -139.191426) (xy 102.751159 -139.227101)
			(xy 102.703553 -139.256155) (xy 102.652224 -139.277967) (xy 102.598267 -139.292073) (xy 102.54283 -139.298173)
			(xy 102.487096 -139.296136) (xy 102.432253 -139.286006) (xy 102.379469 -139.267999) (xy 102.329869 -139.242498)
			(xy 102.284511 -139.210047) (xy 102.244362 -139.171338) (xy 102.210276 -139.127195) (xy 102.18298 -139.07856)
			(xy 102.163057 -139.026469) (xy 102.150931 -138.972032) (xy 102.14686 -138.91641) (xy 97.568105 -138.91641)
			(xy 97.563881 -138.930451) (xy 97.540209 -138.980948) (xy 97.509436 -139.027461) (xy 97.472219 -139.068998)
			(xy 97.429351 -139.104673) (xy 97.381745 -139.133727) (xy 97.330416 -139.155539) (xy 97.276459 -139.169645)
			(xy 97.221022 -139.175745) (xy 97.165288 -139.173708) (xy 97.110445 -139.163578) (xy 97.057661 -139.145571)
			(xy 97.008061 -139.12007) (xy 96.962703 -139.087619) (xy 96.922554 -139.04891) (xy 96.888468 -139.004767)
			(xy 96.861172 -138.956132) (xy 96.841249 -138.904041) (xy 96.829123 -138.849604) (xy 96.825052 -138.793982)
			(xy 80.289532 -138.793982) (xy 80.287259 -138.79883) (xy 80.256486 -138.845343) (xy 80.219269 -138.88688)
			(xy 80.176401 -138.922555) (xy 80.128795 -138.951609) (xy 80.077466 -138.973421) (xy 80.023509 -138.987527)
			(xy 79.968072 -138.993627) (xy 79.912338 -138.99159) (xy 79.857495 -138.98146) (xy 79.804711 -138.963453)
			(xy 79.755111 -138.937952) (xy 79.709753 -138.905501) (xy 79.669604 -138.866792) (xy 79.635518 -138.822649)
			(xy 79.608222 -138.774014) (xy 79.588299 -138.721923) (xy 79.576173 -138.667486) (xy 79.572102 -138.611864)
			(xy 76.830936 -138.611864) (xy 75.63739 -139.80541) (xy 88.81186 -139.80541) (xy 88.815931 -139.749788)
			(xy 88.828057 -139.695351) (xy 88.84798 -139.64326) (xy 88.875276 -139.594625) (xy 88.909362 -139.550482)
			(xy 88.949511 -139.511773) (xy 88.994869 -139.479322) (xy 89.044469 -139.453821) (xy 89.097253 -139.435814)
			(xy 89.152096 -139.425684) (xy 89.20783 -139.423647) (xy 89.263267 -139.429747) (xy 89.317224 -139.443853)
			(xy 89.368553 -139.465665) (xy 89.416159 -139.494719) (xy 89.459027 -139.530394) (xy 89.496244 -139.571931)
			(xy 89.527017 -139.618444) (xy 89.550689 -139.668941) (xy 89.566757 -139.722348) (xy 89.574877 -139.777524)
			(xy 89.575386 -139.80541) (xy 89.574877 -139.833296) (xy 89.566757 -139.888472) (xy 89.550689 -139.941879)
			(xy 89.540482 -139.963652) (xy 92.346016 -139.963652) (xy 92.350087 -139.90803) (xy 92.362213 -139.853593)
			(xy 92.382136 -139.801502) (xy 92.409432 -139.752867) (xy 92.443518 -139.708724) (xy 92.483667 -139.670015)
			(xy 92.529025 -139.637564) (xy 92.578625 -139.612063) (xy 92.631409 -139.594056) (xy 92.686252 -139.583926)
			(xy 92.741986 -139.581889) (xy 92.797423 -139.587989) (xy 92.85138 -139.602095) (xy 92.902709 -139.623907)
			(xy 92.950315 -139.652961) (xy 92.993183 -139.688636) (xy 93.0304 -139.730173) (xy 93.061173 -139.776686)
			(xy 93.084845 -139.827183) (xy 93.100913 -139.88059) (xy 93.109033 -139.935766) (xy 93.109542 -139.963652)
			(xy 93.109033 -139.991538) (xy 93.100913 -140.046714) (xy 93.084845 -140.100121) (xy 93.061173 -140.150618)
			(xy 93.0304 -140.197131) (xy 92.993183 -140.238668) (xy 92.950315 -140.274343) (xy 92.902709 -140.303397)
			(xy 92.85138 -140.325209) (xy 92.797423 -140.339315) (xy 92.741986 -140.345415) (xy 92.686252 -140.343378)
			(xy 92.631409 -140.333248) (xy 92.578625 -140.315241) (xy 92.529025 -140.28974) (xy 92.483667 -140.257289)
			(xy 92.443518 -140.21858) (xy 92.409432 -140.174437) (xy 92.382136 -140.125802) (xy 92.362213 -140.073711)
			(xy 92.350087 -140.019274) (xy 92.346016 -139.963652) (xy 89.540482 -139.963652) (xy 89.527017 -139.992376)
			(xy 89.496244 -140.038889) (xy 89.459027 -140.080426) (xy 89.416159 -140.116101) (xy 89.368553 -140.145155)
			(xy 89.317224 -140.166967) (xy 89.263267 -140.181073) (xy 89.20783 -140.187173) (xy 89.152096 -140.185136)
			(xy 89.097253 -140.175006) (xy 89.044469 -140.156999) (xy 88.994869 -140.131498) (xy 88.949511 -140.099047)
			(xy 88.909362 -140.060338) (xy 88.875276 -140.016195) (xy 88.84798 -139.96756) (xy 88.828057 -139.915469)
			(xy 88.815931 -139.861032) (xy 88.81186 -139.80541) (xy 75.63739 -139.80541) (xy 74.971148 -140.471652)
			(xy 93.184726 -140.471652) (xy 93.185197 -140.444014) (xy 93.193157 -140.389315) (xy 93.208932 -140.336339)
			(xy 93.232191 -140.286196) (xy 93.262446 -140.239937) (xy 93.299065 -140.198531) (xy 93.319854 -140.180314)
			(xy 93.326953 -140.173735) (xy 93.335955 -140.156615) (xy 93.33738 -140.14704) (xy 93.345 -140.076936)
			(xy 93.345591 -140.067316) (xy 93.340348 -140.04878) (xy 93.33484 -140.040868) (xy 93.334586 -140.040614)
			(xy 93.31952 -140.020498) (xy 93.294254 -139.977053) (xy 93.274912 -139.930666) (xy 93.261828 -139.88214)
			(xy 93.25523 -139.832317) (xy 93.25483 -139.807188) (xy 93.255316 -139.779937) (xy 93.263072 -139.725989)
			(xy 93.278427 -139.673694) (xy 93.301069 -139.624117) (xy 93.330535 -139.578267) (xy 93.366226 -139.537076)
			(xy 93.407417 -139.501385) (xy 93.453267 -139.471919) (xy 93.502844 -139.449277) (xy 93.555139 -139.433922)
			(xy 93.609087 -139.426166) (xy 93.663589 -139.426166) (xy 93.717537 -139.433922) (xy 93.769832 -139.449277)
			(xy 93.819409 -139.471919) (xy 93.865259 -139.501385) (xy 93.90645 -139.537076) (xy 93.942141 -139.578267)
			(xy 93.971607 -139.624117) (xy 93.994249 -139.673694) (xy 94.009604 -139.725989) (xy 94.01736 -139.779937)
			(xy 94.017846 -139.807188) (xy 94.017377 -139.834825) (xy 94.009413 -139.889523) (xy 93.993637 -139.942498)
			(xy 93.970377 -139.992641) (xy 93.940122 -140.0389) (xy 93.903506 -140.080307) (xy 93.882718 -140.098526)
			(xy 93.875637 -140.105122) (xy 93.866625 -140.12223) (xy 93.865192 -140.1318) (xy 93.857572 -140.201904)
			(xy 93.857017 -140.211524) (xy 93.862236 -140.230057) (xy 93.867732 -140.237972) (xy 93.867986 -140.238226)
			(xy 93.883066 -140.258332) (xy 93.908331 -140.30178) (xy 93.927671 -140.348169) (xy 93.940751 -140.396697)
			(xy 93.947345 -140.446522) (xy 93.947742 -140.471652) (xy 93.947234 -140.49121) (xy 93.947234 -140.491464)
			(xy 93.94724 -140.50176) (xy 93.954454 -140.521027) (xy 93.961204 -140.528802) (xy 94.02699 -140.598144)
			(xy 94.02826 -140.598144) (xy 94.038984 -140.597721) (xy 94.058588 -140.589039) (xy 94.066106 -140.58138)
			(xy 94.086934 -140.558012) (xy 94.093396 -140.550199) (xy 94.100064 -140.531067) (xy 94.099888 -140.520928)
			(xy 94.099126 -140.497052) (xy 94.099612 -140.469801) (xy 94.107368 -140.415853) (xy 94.122723 -140.363558)
			(xy 94.145365 -140.313981) (xy 94.174831 -140.268131) (xy 94.210522 -140.22694) (xy 94.251713 -140.191249)
			(xy 94.297563 -140.161783) (xy 94.34714 -140.139141) (xy 94.399435 -140.123786) (xy 94.453383 -140.11603)
			(xy 94.507885 -140.11603) (xy 94.561833 -140.123786) (xy 94.614128 -140.139141) (xy 94.663705 -140.161783)
			(xy 94.709555 -140.191249) (xy 94.750746 -140.22694) (xy 94.786437 -140.268131) (xy 94.815903 -140.313981)
			(xy 94.838545 -140.363558) (xy 94.8539 -140.415853) (xy 94.861656 -140.469801) (xy 94.862142 -140.497052)
			(xy 94.861593 -140.525011) (xy 94.853464 -140.580336) (xy 94.837342 -140.63388) (xy 94.813575 -140.684495)
			(xy 94.78267 -140.731098) (xy 94.745292 -140.772688) (xy 94.702242 -140.808374) (xy 94.654441 -140.83739)
			(xy 94.602916 -140.859116) (xy 94.548771 -140.873084) (xy 94.52102 -140.876528) (xy 94.511622 -140.877544)
			(xy 94.495112 -140.885926) (xy 94.443296 -140.943838) (xy 94.437382 -140.951003) (xy 94.430741 -140.968338)
			(xy 94.430342 -140.97762) (xy 94.430342 -140.979652) (xy 94.429856 -141.006903) (xy 94.4221 -141.060851)
			(xy 94.406745 -141.113146) (xy 94.384103 -141.162723) (xy 94.354637 -141.208573) (xy 94.318946 -141.249764)
			(xy 94.277755 -141.285455) (xy 94.231905 -141.314921) (xy 94.182328 -141.337563) (xy 94.130033 -141.352918)
			(xy 94.076085 -141.360674) (xy 94.021583 -141.360674) (xy 93.967635 -141.352918) (xy 93.91534 -141.337563)
			(xy 93.865763 -141.314921) (xy 93.819913 -141.285455) (xy 93.778722 -141.249764) (xy 93.743031 -141.208573)
			(xy 93.713565 -141.162723) (xy 93.690923 -141.113146) (xy 93.675568 -141.060851) (xy 93.667812 -141.006903)
			(xy 93.667326 -140.979652) (xy 93.667834 -140.960094) (xy 93.667834 -140.95984) (xy 93.667834 -140.949543)
			(xy 93.660617 -140.930276) (xy 93.653864 -140.922502) (xy 93.603064 -140.868908) (xy 93.595577 -140.861767)
			(xy 93.576569 -140.853642) (xy 93.566234 -140.85316) (xy 93.53898 -140.852713) (xy 93.485026 -140.844959)
			(xy 93.432725 -140.829605) (xy 93.383142 -140.806963) (xy 93.337286 -140.777494) (xy 93.296092 -140.741799)
			(xy 93.260397 -140.700603) (xy 93.23093 -140.654746) (xy 93.20829 -140.605162) (xy 93.192938 -140.552861)
			(xy 93.185186 -140.498906) (xy 93.184726 -140.471652) (xy 74.971148 -140.471652) (xy 74.181208 -141.261592)
			(xy 81.648552 -141.261592) (xy 81.652623 -141.20597) (xy 81.664749 -141.151533) (xy 81.684672 -141.099442)
			(xy 81.711968 -141.050807) (xy 81.746054 -141.006664) (xy 81.786203 -140.967955) (xy 81.831561 -140.935504)
			(xy 81.881161 -140.910003) (xy 81.933945 -140.891996) (xy 81.988788 -140.881866) (xy 82.044522 -140.879829)
			(xy 82.099959 -140.885929) (xy 82.153916 -140.900035) (xy 82.205245 -140.921847) (xy 82.240862 -140.943584)
			(xy 88.776554 -140.943584) (xy 88.780625 -140.887962) (xy 88.792751 -140.833525) (xy 88.812674 -140.781434)
			(xy 88.83997 -140.732799) (xy 88.874056 -140.688656) (xy 88.914205 -140.649947) (xy 88.959563 -140.617496)
			(xy 89.009163 -140.591995) (xy 89.061947 -140.573988) (xy 89.11679 -140.563858) (xy 89.172524 -140.561821)
			(xy 89.227961 -140.567921) (xy 89.281918 -140.582027) (xy 89.333247 -140.603839) (xy 89.380853 -140.632893)
			(xy 89.423721 -140.668568) (xy 89.460938 -140.710105) (xy 89.491711 -140.756618) (xy 89.515383 -140.807115)
			(xy 89.531451 -140.860522) (xy 89.539571 -140.915698) (xy 89.54008 -140.943584) (xy 89.539571 -140.97147)
			(xy 89.531451 -141.026646) (xy 89.515383 -141.080053) (xy 89.491711 -141.13055) (xy 89.460938 -141.177063)
			(xy 89.423721 -141.2186) (xy 89.380853 -141.254275) (xy 89.333247 -141.283329) (xy 89.281918 -141.305141)
			(xy 89.227961 -141.319247) (xy 89.172524 -141.325347) (xy 89.11679 -141.32331) (xy 89.061947 -141.31318)
			(xy 89.009163 -141.295173) (xy 88.959563 -141.269672) (xy 88.914205 -141.237221) (xy 88.874056 -141.198512)
			(xy 88.83997 -141.154369) (xy 88.812674 -141.105734) (xy 88.792751 -141.053643) (xy 88.780625 -140.999206)
			(xy 88.776554 -140.943584) (xy 82.240862 -140.943584) (xy 82.252851 -140.950901) (xy 82.295719 -140.986576)
			(xy 82.332936 -141.028113) (xy 82.363709 -141.074626) (xy 82.387381 -141.125123) (xy 82.403449 -141.17853)
			(xy 82.411569 -141.233706) (xy 82.412078 -141.261592) (xy 82.411569 -141.289478) (xy 82.403449 -141.344654)
			(xy 82.387381 -141.398061) (xy 82.376936 -141.420342) (xy 92.08592 -141.420342) (xy 92.089991 -141.36472)
			(xy 92.102117 -141.310283) (xy 92.12204 -141.258192) (xy 92.149336 -141.209557) (xy 92.183422 -141.165414)
			(xy 92.223571 -141.126705) (xy 92.268929 -141.094254) (xy 92.318529 -141.068753) (xy 92.371313 -141.050746)
			(xy 92.426156 -141.040616) (xy 92.48189 -141.038579) (xy 92.537327 -141.044679) (xy 92.591284 -141.058785)
			(xy 92.642613 -141.080597) (xy 92.690219 -141.109651) (xy 92.733087 -141.145326) (xy 92.770304 -141.186863)
			(xy 92.801077 -141.233376) (xy 92.824749 -141.283873) (xy 92.840817 -141.33728) (xy 92.848937 -141.392456)
			(xy 92.849446 -141.420342) (xy 92.848937 -141.448228) (xy 92.840817 -141.503404) (xy 92.824749 -141.556811)
			(xy 92.801077 -141.607308) (xy 92.770304 -141.653821) (xy 92.733087 -141.695358) (xy 92.690219 -141.731033)
			(xy 92.642613 -141.760087) (xy 92.591284 -141.781899) (xy 92.537327 -141.796005) (xy 92.48189 -141.802105)
			(xy 92.426156 -141.800068) (xy 92.371313 -141.789938) (xy 92.318529 -141.771931) (xy 92.268929 -141.74643)
			(xy 92.223571 -141.713979) (xy 92.183422 -141.67527) (xy 92.149336 -141.631127) (xy 92.12204 -141.582492)
			(xy 92.102117 -141.530401) (xy 92.089991 -141.475964) (xy 92.08592 -141.420342) (xy 82.376936 -141.420342)
			(xy 82.363709 -141.448558) (xy 82.332936 -141.495071) (xy 82.295719 -141.536608) (xy 82.252851 -141.572283)
			(xy 82.205245 -141.601337) (xy 82.153916 -141.623149) (xy 82.099959 -141.637255) (xy 82.044522 -141.643355)
			(xy 81.988788 -141.641318) (xy 81.933945 -141.631188) (xy 81.881161 -141.613181) (xy 81.831561 -141.58768)
			(xy 81.786203 -141.555229) (xy 81.746054 -141.51652) (xy 81.711968 -141.472377) (xy 81.684672 -141.423742)
			(xy 81.664749 -141.371651) (xy 81.652623 -141.317214) (xy 81.648552 -141.261592) (xy 74.181208 -141.261592)
			(xy 72.937624 -142.505176) (xy 91.124276 -142.505176) (xy 91.128347 -142.449554) (xy 91.140473 -142.395117)
			(xy 91.160396 -142.343026) (xy 91.187692 -142.294391) (xy 91.221778 -142.250248) (xy 91.261927 -142.211539)
			(xy 91.307285 -142.179088) (xy 91.356885 -142.153587) (xy 91.409669 -142.13558) (xy 91.464512 -142.12545)
			(xy 91.520246 -142.123413) (xy 91.575683 -142.129513) (xy 91.62964 -142.143619) (xy 91.680969 -142.165431)
			(xy 91.728575 -142.194485) (xy 91.771443 -142.23016) (xy 91.80866 -142.271697) (xy 91.839433 -142.31821)
			(xy 91.863105 -142.368707) (xy 91.879173 -142.422114) (xy 91.887293 -142.47729) (xy 91.887802 -142.505176)
			(xy 91.887293 -142.533062) (xy 91.879173 -142.588238) (xy 91.863105 -142.641645) (xy 91.839433 -142.692142)
			(xy 91.80866 -142.738655) (xy 91.771443 -142.780192) (xy 91.728575 -142.815867) (xy 91.680969 -142.844921)
			(xy 91.62964 -142.866733) (xy 91.575683 -142.880839) (xy 91.520246 -142.886939) (xy 91.464512 -142.884902)
			(xy 91.409669 -142.874772) (xy 91.356885 -142.856765) (xy 91.307285 -142.831264) (xy 91.261927 -142.798813)
			(xy 91.221778 -142.760104) (xy 91.187692 -142.715961) (xy 91.160396 -142.667326) (xy 91.140473 -142.615235)
			(xy 91.128347 -142.560798) (xy 91.124276 -142.505176) (xy 72.937624 -142.505176) (xy 72.088248 -143.354552)
			(xy 87.380316 -143.354552) (xy 87.384387 -143.29893) (xy 87.396513 -143.244493) (xy 87.416436 -143.192402)
			(xy 87.443732 -143.143767) (xy 87.477818 -143.099624) (xy 87.517967 -143.060915) (xy 87.563325 -143.028464)
			(xy 87.612925 -143.002963) (xy 87.665709 -142.984956) (xy 87.720552 -142.974826) (xy 87.776286 -142.972789)
			(xy 87.831723 -142.978889) (xy 87.88568 -142.992995) (xy 87.937009 -143.014807) (xy 87.984615 -143.043861)
			(xy 88.027483 -143.079536) (xy 88.0647 -143.121073) (xy 88.095473 -143.167586) (xy 88.119145 -143.218083)
			(xy 88.135213 -143.27149) (xy 88.143333 -143.326666) (xy 88.143842 -143.354552) (xy 88.143513 -143.372586)
			(xy 88.36533 -143.372586) (xy 88.365816 -143.345335) (xy 88.373572 -143.291387) (xy 88.388927 -143.239092)
			(xy 88.411569 -143.189515) (xy 88.441035 -143.143665) (xy 88.476726 -143.102474) (xy 88.517917 -143.066783)
			(xy 88.563767 -143.037317) (xy 88.613344 -143.014675) (xy 88.665639 -142.99932) (xy 88.719587 -142.991564)
			(xy 88.774089 -142.991564) (xy 88.828037 -142.99932) (xy 88.880332 -143.014675) (xy 88.929909 -143.037317)
			(xy 88.975759 -143.066783) (xy 89.01695 -143.102474) (xy 89.052641 -143.143665) (xy 89.082107 -143.189515)
			(xy 89.104749 -143.239092) (xy 89.120104 -143.291387) (xy 89.12786 -143.345335) (xy 89.128346 -143.372586)
			(xy 89.127829 -143.40195) (xy 89.118904 -143.459996) (xy 89.110566 -143.488156) (xy 89.106877 -143.501104)
			(xy 89.105692 -143.527992) (xy 89.111581 -143.554253) (xy 89.124133 -143.578061) (xy 89.142474 -143.597757)
			(xy 89.165329 -143.61197) (xy 89.191105 -143.619711) (xy 89.204546 -143.62049) (xy 89.231285 -143.621742)
			(xy 89.28406 -143.630677) (xy 89.335067 -143.646906) (xy 89.383303 -143.670109) (xy 89.42782 -143.69983)
			(xy 89.467742 -143.735484) (xy 89.502285 -143.776372) (xy 89.53077 -143.82169) (xy 89.552638 -143.870546)
			(xy 89.567457 -143.92198) (xy 89.574937 -143.974981) (xy 89.575386 -144.001744) (xy 89.5749 -144.028995)
			(xy 89.572922 -144.042754) (xy 90.855738 -144.042754) (xy 90.855738 -143.988246) (xy 90.863495 -143.934293)
			(xy 90.878852 -143.881992) (xy 90.901495 -143.83241) (xy 90.930965 -143.786555) (xy 90.96666 -143.74536)
			(xy 91.007855 -143.709665) (xy 91.05371 -143.680195) (xy 91.103292 -143.657552) (xy 91.155593 -143.642195)
			(xy 91.209546 -143.634438) (xy 91.2368 -143.633952) (xy 91.26329 -143.634388) (xy 91.315759 -143.641738)
			(xy 91.366705 -143.65628) (xy 91.415147 -143.677737) (xy 91.460151 -143.705694) (xy 91.500851 -143.739612)
			(xy 91.518994 -143.75892) (xy 91.52822 -143.768469) (xy 91.550551 -143.782819) (xy 91.575827 -143.790926)
			(xy 91.602338 -143.792242) (xy 91.628293 -143.786678) (xy 91.651935 -143.77461) (xy 91.671666 -143.756854)
			(xy 91.679268 -143.745966) (xy 91.694495 -143.723592) (xy 91.730189 -143.682913) (xy 91.771271 -143.647684)
			(xy 91.816917 -143.618611) (xy 91.866212 -143.596277) (xy 91.918167 -143.581129) (xy 91.971741 -143.573471)
			(xy 91.9988 -143.572992) (xy 92.026051 -143.573478) (xy 92.079999 -143.581234) (xy 92.132294 -143.596589)
			(xy 92.181871 -143.619231) (xy 92.227721 -143.648697) (xy 92.268912 -143.684388) (xy 92.304603 -143.725579)
			(xy 92.334069 -143.771429) (xy 92.356711 -143.821006) (xy 92.372066 -143.873301) (xy 92.379822 -143.927249)
			(xy 92.379822 -143.981751) (xy 92.372066 -144.035699) (xy 92.356711 -144.087994) (xy 92.334069 -144.137571)
			(xy 92.304603 -144.183421) (xy 92.268912 -144.224612) (xy 92.227721 -144.260303) (xy 92.181871 -144.289769)
			(xy 92.132294 -144.312411) (xy 92.079999 -144.327766) (xy 92.026051 -144.335522) (xy 91.9988 -144.336008)
			(xy 91.972309 -144.335585) (xy 91.919839 -144.328235) (xy 91.868893 -144.31369) (xy 91.820451 -144.292231)
			(xy 91.775447 -144.264272) (xy 91.734748 -144.23035) (xy 91.716606 -144.21104) (xy 91.705788 -144.199934)
			(xy 91.679009 -144.184333) (xy 91.648787 -144.177468) (xy 91.617896 -144.179968) (xy 91.589172 -144.191605)
			(xy 91.565251 -144.21131) (xy 91.556332 -144.223994) (xy 91.541125 -144.246382) (xy 91.505425 -144.287057)
			(xy 91.464339 -144.322283) (xy 91.418689 -144.351353) (xy 91.369392 -144.373686) (xy 91.317435 -144.388832)
			(xy 91.26386 -144.396489) (xy 91.2368 -144.396968) (xy 91.209546 -144.396562) (xy 91.155593 -144.388805)
			(xy 91.103292 -144.373448) (xy 91.05371 -144.350805) (xy 91.007855 -144.321335) (xy 90.96666 -144.28564)
			(xy 90.930965 -144.244445) (xy 90.901495 -144.19859) (xy 90.878852 -144.149008) (xy 90.863495 -144.096707)
			(xy 90.855738 -144.042754) (xy 89.572922 -144.042754) (xy 89.567144 -144.082943) (xy 89.551789 -144.135238)
			(xy 89.529147 -144.184815) (xy 89.499681 -144.230665) (xy 89.46399 -144.271856) (xy 89.422799 -144.307547)
			(xy 89.376949 -144.337013) (xy 89.327372 -144.359655) (xy 89.275077 -144.37501) (xy 89.221129 -144.382766)
			(xy 89.166627 -144.382766) (xy 89.112679 -144.37501) (xy 89.060384 -144.359655) (xy 89.010807 -144.337013)
			(xy 88.964957 -144.307547) (xy 88.923766 -144.271856) (xy 88.888075 -144.230665) (xy 88.858609 -144.184815)
			(xy 88.835967 -144.135238) (xy 88.820612 -144.082943) (xy 88.812856 -144.028995) (xy 88.81237 -144.001744)
			(xy 88.812875 -143.972379) (xy 88.821808 -143.914334) (xy 88.83015 -143.886174) (xy 88.833789 -143.873214)
			(xy 88.83498 -143.846333) (xy 88.829098 -143.820077) (xy 88.816555 -143.796273) (xy 88.798221 -143.776579)
			(xy 88.775375 -143.762365) (xy 88.749607 -143.754621) (xy 88.73617 -143.75384) (xy 88.709422 -143.752733)
			(xy 88.656639 -143.743785) (xy 88.605625 -143.727542) (xy 88.557385 -143.704324) (xy 88.512866 -143.674588)
			(xy 88.472943 -143.638918) (xy 88.438402 -143.598015) (xy 88.40992 -143.552684) (xy 88.388058 -143.503814)
			(xy 88.373246 -143.452367) (xy 88.365774 -143.399354) (xy 88.36533 -143.372586) (xy 88.143513 -143.372586)
			(xy 88.143333 -143.382438) (xy 88.135213 -143.437614) (xy 88.119145 -143.491021) (xy 88.095473 -143.541518)
			(xy 88.0647 -143.588031) (xy 88.027483 -143.629568) (xy 87.984615 -143.665243) (xy 87.937009 -143.694297)
			(xy 87.88568 -143.716109) (xy 87.831723 -143.730215) (xy 87.776286 -143.736315) (xy 87.720552 -143.734278)
			(xy 87.665709 -143.724148) (xy 87.612925 -143.706141) (xy 87.563325 -143.68064) (xy 87.517967 -143.648189)
			(xy 87.477818 -143.60948) (xy 87.443732 -143.565337) (xy 87.416436 -143.516702) (xy 87.396513 -143.464611)
			(xy 87.384387 -143.410174) (xy 87.380316 -143.354552) (xy 72.088248 -143.354552) (xy 71.656956 -143.785844)
			(xy 82.07832 -143.785844) (xy 82.082391 -143.730222) (xy 82.094517 -143.675785) (xy 82.11444 -143.623694)
			(xy 82.141736 -143.575059) (xy 82.175822 -143.530916) (xy 82.215971 -143.492207) (xy 82.261329 -143.459756)
			(xy 82.310929 -143.434255) (xy 82.363713 -143.416248) (xy 82.418556 -143.406118) (xy 82.47429 -143.404081)
			(xy 82.529727 -143.410181) (xy 82.583684 -143.424287) (xy 82.635013 -143.446099) (xy 82.682619 -143.475153)
			(xy 82.725487 -143.510828) (xy 82.762704 -143.552365) (xy 82.793477 -143.598878) (xy 82.817149 -143.649375)
			(xy 82.833217 -143.702782) (xy 82.841337 -143.757958) (xy 82.841846 -143.785844) (xy 82.841337 -143.81373)
			(xy 82.833217 -143.868906) (xy 82.817149 -143.922313) (xy 82.793477 -143.97281) (xy 82.762704 -144.019323)
			(xy 82.725487 -144.06086) (xy 82.682619 -144.096535) (xy 82.635013 -144.125589) (xy 82.583684 -144.147401)
			(xy 82.529727 -144.161507) (xy 82.47429 -144.167607) (xy 82.418556 -144.16557) (xy 82.363713 -144.15544)
			(xy 82.310929 -144.137433) (xy 82.261329 -144.111932) (xy 82.215971 -144.079481) (xy 82.175822 -144.040772)
			(xy 82.141736 -143.996629) (xy 82.11444 -143.947994) (xy 82.094517 -143.895903) (xy 82.082391 -143.841466)
			(xy 82.07832 -143.785844) (xy 71.656956 -143.785844) (xy 70.874382 -144.568418) (xy 70.866986 -144.57527)
			(xy 70.848387 -144.583011) (xy 70.838314 -144.583404) (xy 57.89803 -144.583404) (xy 57.888031 -144.583895)
			(xy 57.869545 -144.591525) (xy 57.855349 -144.605611) (xy 57.85104 -144.614646) (xy 57.814972 -144.70126)
			(xy 57.811485 -144.71073) (xy 57.81149 -144.730894) (xy 57.819278 -144.749494) (xy 57.826148 -144.756886)
			(xy 57.846886 -144.778492) (xy 57.882049 -144.826965) (xy 57.909211 -144.880335) (xy 57.910859 -144.88541)
			(xy 88.81186 -144.88541) (xy 88.815931 -144.829788) (xy 88.828057 -144.775351) (xy 88.84798 -144.72326)
			(xy 88.875276 -144.674625) (xy 88.909362 -144.630482) (xy 88.949511 -144.591773) (xy 88.994869 -144.559322)
			(xy 89.044469 -144.533821) (xy 89.097253 -144.515814) (xy 89.152096 -144.505684) (xy 89.20783 -144.503647)
			(xy 89.263267 -144.509747) (xy 89.317224 -144.523853) (xy 89.368553 -144.545665) (xy 89.416159 -144.574719)
			(xy 89.459027 -144.610394) (xy 89.496244 -144.651931) (xy 89.527017 -144.698444) (xy 89.550689 -144.748941)
			(xy 89.566757 -144.802348) (xy 89.574877 -144.857524) (xy 89.575386 -144.88541) (xy 89.574877 -144.913296)
			(xy 89.568253 -144.958308) (xy 90.97086 -144.958308) (xy 90.974931 -144.902686) (xy 90.987057 -144.848249)
			(xy 91.00698 -144.796158) (xy 91.034276 -144.747523) (xy 91.068362 -144.70338) (xy 91.108511 -144.664671)
			(xy 91.153869 -144.63222) (xy 91.203469 -144.606719) (xy 91.256253 -144.588712) (xy 91.311096 -144.578582)
			(xy 91.36683 -144.576545) (xy 91.422267 -144.582645) (xy 91.476224 -144.596751) (xy 91.527553 -144.618563)
			(xy 91.575159 -144.647617) (xy 91.618027 -144.683292) (xy 91.655244 -144.724829) (xy 91.686017 -144.771342)
			(xy 91.709689 -144.821839) (xy 91.725757 -144.875246) (xy 91.733877 -144.930422) (xy 91.734386 -144.958308)
			(xy 91.733877 -144.986194) (xy 91.725757 -145.04137) (xy 91.709689 -145.094777) (xy 91.686017 -145.145274)
			(xy 91.655244 -145.191787) (xy 91.618027 -145.233324) (xy 91.575159 -145.268999) (xy 91.527553 -145.298053)
			(xy 91.476224 -145.319865) (xy 91.422267 -145.333971) (xy 91.36683 -145.340071) (xy 91.311096 -145.338034)
			(xy 91.256253 -145.327904) (xy 91.203469 -145.309897) (xy 91.153869 -145.284396) (xy 91.108511 -145.251945)
			(xy 91.068362 -145.213236) (xy 91.034276 -145.169093) (xy 91.00698 -145.120458) (xy 90.987057 -145.068367)
			(xy 90.974931 -145.01393) (xy 90.97086 -144.958308) (xy 89.568253 -144.958308) (xy 89.566757 -144.968472)
			(xy 89.550689 -145.021879) (xy 89.527017 -145.072376) (xy 89.496244 -145.118889) (xy 89.459027 -145.160426)
			(xy 89.416159 -145.196101) (xy 89.368553 -145.225155) (xy 89.317224 -145.246967) (xy 89.263267 -145.261073)
			(xy 89.20783 -145.267173) (xy 89.152096 -145.265136) (xy 89.097253 -145.255006) (xy 89.044469 -145.236999)
			(xy 88.994869 -145.211498) (xy 88.949511 -145.179047) (xy 88.909362 -145.140338) (xy 88.875276 -145.096195)
			(xy 88.84798 -145.04756) (xy 88.828057 -144.995469) (xy 88.815931 -144.941032) (xy 88.81186 -144.88541)
			(xy 57.910859 -144.88541) (xy 57.927705 -144.937292) (xy 57.937076 -144.996438) (xy 57.937654 -145.02638)
			(xy 57.937168 -145.053631) (xy 57.929412 -145.107579) (xy 57.914057 -145.159874) (xy 57.891415 -145.209451)
			(xy 57.861949 -145.255301) (xy 57.826258 -145.296492) (xy 57.785067 -145.332183) (xy 57.739217 -145.361649)
			(xy 57.68964 -145.384291) (xy 57.637345 -145.399646) (xy 57.583397 -145.407402) (xy 57.528895 -145.407402)
			(xy 57.474947 -145.399646) (xy 57.422652 -145.384291) (xy 57.373075 -145.361649) (xy 57.327225 -145.332183)
			(xy 57.286034 -145.296492) (xy 57.250343 -145.255301) (xy 57.220877 -145.209451) (xy 57.198235 -145.159874)
			(xy 57.18288 -145.107579) (xy 57.175124 -145.053631) (xy 57.174638 -145.02638) (xy 57.175218 -144.996436)
			(xy 57.184567 -144.937281) (xy 57.203048 -144.880315) (xy 57.230206 -144.826938) (xy 57.265374 -144.778463)
			(xy 57.286144 -144.756886) (xy 57.292926 -144.749439) (xy 57.300663 -144.730866) (xy 57.300705 -144.710746)
			(xy 57.29732 -144.70126) (xy 57.261252 -144.614646) (xy 57.257024 -144.605548) (xy 57.24283 -144.591394)
			(xy 57.224287 -144.58378) (xy 57.214262 -144.583404) (xy 52.667154 -144.583404) (xy 52.657088 -144.583836)
			(xy 52.638496 -144.591562) (xy 52.631086 -144.59839) (xy 51.256184 -145.973292) (xy 69.238366 -145.973292)
			(xy 69.242437 -145.91767) (xy 69.254563 -145.863233) (xy 69.274486 -145.811142) (xy 69.301782 -145.762507)
			(xy 69.335868 -145.718364) (xy 69.376017 -145.679655) (xy 69.421375 -145.647204) (xy 69.470975 -145.621703)
			(xy 69.523759 -145.603696) (xy 69.578602 -145.593566) (xy 69.634336 -145.591529) (xy 69.689773 -145.597629)
			(xy 69.74373 -145.611735) (xy 69.795059 -145.633547) (xy 69.842665 -145.662601) (xy 69.885533 -145.698276)
			(xy 69.92275 -145.739813) (xy 69.953523 -145.786326) (xy 69.977195 -145.836823) (xy 69.993263 -145.89023)
			(xy 70.001383 -145.945406) (xy 70.001892 -145.973292) (xy 70.001383 -146.001178) (xy 69.993263 -146.056354)
			(xy 69.987686 -146.074892) (xy 73.130916 -146.074892) (xy 73.134987 -146.01927) (xy 73.147113 -145.964833)
			(xy 73.167036 -145.912742) (xy 73.194332 -145.864107) (xy 73.228418 -145.819964) (xy 73.268567 -145.781255)
			(xy 73.313925 -145.748804) (xy 73.363525 -145.723303) (xy 73.416309 -145.705296) (xy 73.471152 -145.695166)
			(xy 73.526886 -145.693129) (xy 73.582323 -145.699229) (xy 73.63628 -145.713335) (xy 73.687609 -145.735147)
			(xy 73.735215 -145.764201) (xy 73.778083 -145.799876) (xy 73.8153 -145.841413) (xy 73.846073 -145.887926)
			(xy 73.869745 -145.938423) (xy 73.873303 -145.95025) (xy 85.577678 -145.95025) (xy 85.577678 -145.89575)
			(xy 85.585434 -145.841804) (xy 85.600788 -145.789511) (xy 85.623428 -145.739935) (xy 85.652892 -145.694085)
			(xy 85.688581 -145.652895) (xy 85.729769 -145.617204) (xy 85.775617 -145.587737) (xy 85.825192 -145.565095)
			(xy 85.877484 -145.549738) (xy 85.93143 -145.541979) (xy 85.95868 -145.541492) (xy 85.984408 -145.541906)
			(xy 86.035397 -145.548825) (xy 86.084992 -145.56254) (xy 86.132291 -145.582801) (xy 86.176435 -145.609241)
			(xy 86.216621 -145.641379) (xy 86.252119 -145.67863) (xy 86.267544 -145.699226) (xy 86.275964 -145.710071)
			(xy 86.297411 -145.727195) (xy 86.322644 -145.737991) (xy 86.34984 -145.741678) (xy 86.377036 -145.737991)
			(xy 86.402269 -145.727195) (xy 86.423716 -145.710071) (xy 86.432136 -145.699226) (xy 86.44755 -145.678622)
			(xy 86.483053 -145.641377) (xy 86.523243 -145.609244) (xy 86.567389 -145.582808) (xy 86.614689 -145.562548)
			(xy 86.664283 -145.548834) (xy 86.715272 -145.541914) (xy 86.741 -145.541492) (xy 86.768251 -145.541978)
			(xy 86.822199 -145.549734) (xy 86.874494 -145.565089) (xy 86.924071 -145.587731) (xy 86.969921 -145.617197)
			(xy 87.011112 -145.652888) (xy 87.046803 -145.694079) (xy 87.076269 -145.739929) (xy 87.098911 -145.789506)
			(xy 87.114266 -145.841801) (xy 87.122022 -145.895749) (xy 87.122022 -145.90141) (xy 90.84386 -145.90141)
			(xy 90.847931 -145.845788) (xy 90.860057 -145.791351) (xy 90.87998 -145.73926) (xy 90.907276 -145.690625)
			(xy 90.941362 -145.646482) (xy 90.981511 -145.607773) (xy 91.026869 -145.575322) (xy 91.076469 -145.549821)
			(xy 91.129253 -145.531814) (xy 91.184096 -145.521684) (xy 91.23983 -145.519647) (xy 91.295267 -145.525747)
			(xy 91.349224 -145.539853) (xy 91.400553 -145.561665) (xy 91.448159 -145.590719) (xy 91.491027 -145.626394)
			(xy 91.528244 -145.667931) (xy 91.559017 -145.714444) (xy 91.582689 -145.764941) (xy 91.598757 -145.818348)
			(xy 91.606877 -145.873524) (xy 91.607386 -145.90141) (xy 91.606877 -145.929296) (xy 91.598757 -145.984472)
			(xy 91.582689 -146.037879) (xy 91.559017 -146.088376) (xy 91.528244 -146.134889) (xy 91.491027 -146.176426)
			(xy 91.448159 -146.212101) (xy 91.400553 -146.241155) (xy 91.349224 -146.262967) (xy 91.295267 -146.277073)
			(xy 91.23983 -146.283173) (xy 91.184096 -146.281136) (xy 91.129253 -146.271006) (xy 91.076469 -146.252999)
			(xy 91.026869 -146.227498) (xy 90.981511 -146.195047) (xy 90.941362 -146.156338) (xy 90.907276 -146.112195)
			(xy 90.87998 -146.06356) (xy 90.860057 -146.011469) (xy 90.847931 -145.957032) (xy 90.84386 -145.90141)
			(xy 87.122022 -145.90141) (xy 87.122022 -145.950251) (xy 87.114266 -146.004199) (xy 87.098911 -146.056494)
			(xy 87.076269 -146.106071) (xy 87.046803 -146.151921) (xy 87.011112 -146.193112) (xy 86.969921 -146.228803)
			(xy 86.924071 -146.258269) (xy 86.874494 -146.280911) (xy 86.822199 -146.296266) (xy 86.768251 -146.304022)
			(xy 86.741 -146.304508) (xy 86.715271 -146.304109) (xy 86.664282 -146.297187) (xy 86.614686 -146.28347)
			(xy 86.567387 -146.263206) (xy 86.523243 -146.236764) (xy 86.483058 -146.204624) (xy 86.44756 -146.167371)
			(xy 86.432136 -146.146774) (xy 86.423716 -146.135929) (xy 86.402269 -146.118805) (xy 86.377036 -146.108009)
			(xy 86.34984 -146.104322) (xy 86.322644 -146.108009) (xy 86.297411 -146.118805) (xy 86.275964 -146.135929)
			(xy 86.267544 -146.146774) (xy 86.252142 -146.167387) (xy 86.216637 -146.204632) (xy 86.176445 -146.236765)
			(xy 86.132297 -146.2632) (xy 86.084995 -146.283457) (xy 86.035399 -146.297169) (xy 85.984409 -146.304087)
			(xy 85.95868 -146.304508) (xy 85.93143 -146.304021) (xy 85.877484 -146.296262) (xy 85.825192 -146.280905)
			(xy 85.775617 -146.258263) (xy 85.729769 -146.228796) (xy 85.688581 -146.193105) (xy 85.652892 -146.151915)
			(xy 85.623428 -146.106065) (xy 85.600788 -146.056489) (xy 85.585434 -146.004196) (xy 85.577678 -145.95025)
			(xy 73.873303 -145.95025) (xy 73.885813 -145.99183) (xy 73.893933 -146.047006) (xy 73.894442 -146.074892)
			(xy 73.893933 -146.102778) (xy 73.885813 -146.157954) (xy 73.869745 -146.211361) (xy 73.846073 -146.261858)
			(xy 73.8153 -146.308371) (xy 73.778083 -146.349908) (xy 73.735215 -146.385583) (xy 73.687609 -146.414637)
			(xy 73.63628 -146.436449) (xy 73.582323 -146.450555) (xy 73.526886 -146.456655) (xy 73.471152 -146.454618)
			(xy 73.416309 -146.444488) (xy 73.363525 -146.426481) (xy 73.313925 -146.40098) (xy 73.268567 -146.368529)
			(xy 73.228418 -146.32982) (xy 73.194332 -146.285677) (xy 73.167036 -146.237042) (xy 73.147113 -146.184951)
			(xy 73.134987 -146.130514) (xy 73.130916 -146.074892) (xy 69.987686 -146.074892) (xy 69.977195 -146.109761)
			(xy 69.953523 -146.160258) (xy 69.92275 -146.206771) (xy 69.885533 -146.248308) (xy 69.842665 -146.283983)
			(xy 69.795059 -146.313037) (xy 69.74373 -146.334849) (xy 69.689773 -146.348955) (xy 69.634336 -146.355055)
			(xy 69.578602 -146.353018) (xy 69.523759 -146.342888) (xy 69.470975 -146.324881) (xy 69.421375 -146.29938)
			(xy 69.376017 -146.266929) (xy 69.335868 -146.22822) (xy 69.301782 -146.184077) (xy 69.274486 -146.135442)
			(xy 69.254563 -146.083351) (xy 69.242437 -146.028914) (xy 69.238366 -145.973292) (xy 51.256184 -145.973292)
			(xy 50.623724 -146.605752) (xy 74.369928 -146.605752) (xy 74.373999 -146.55013) (xy 74.386125 -146.495693)
			(xy 74.406048 -146.443602) (xy 74.433344 -146.394967) (xy 74.46743 -146.350824) (xy 74.507579 -146.312115)
			(xy 74.552937 -146.279664) (xy 74.602537 -146.254163) (xy 74.655321 -146.236156) (xy 74.710164 -146.226026)
			(xy 74.765898 -146.223989) (xy 74.821335 -146.230089) (xy 74.875292 -146.244195) (xy 74.926621 -146.266007)
			(xy 74.974227 -146.295061) (xy 75.017095 -146.330736) (xy 75.054312 -146.372273) (xy 75.085085 -146.418786)
			(xy 75.108757 -146.469283) (xy 75.124825 -146.52269) (xy 75.132945 -146.577866) (xy 75.133454 -146.605752)
			(xy 75.132945 -146.633638) (xy 75.124825 -146.688814) (xy 75.108757 -146.742221) (xy 75.085085 -146.792718)
			(xy 75.054312 -146.839231) (xy 75.017095 -146.880768) (xy 74.974227 -146.916443) (xy 74.937267 -146.939)
			(xy 86.612982 -146.939) (xy 86.617053 -146.883378) (xy 86.629179 -146.828941) (xy 86.649102 -146.77685)
			(xy 86.676398 -146.728215) (xy 86.710484 -146.684072) (xy 86.750633 -146.645363) (xy 86.795991 -146.612912)
			(xy 86.845591 -146.587411) (xy 86.898375 -146.569404) (xy 86.953218 -146.559274) (xy 87.008952 -146.557237)
			(xy 87.064389 -146.563337) (xy 87.118346 -146.577443) (xy 87.169675 -146.599255) (xy 87.217281 -146.628309)
			(xy 87.260149 -146.663984) (xy 87.297366 -146.705521) (xy 87.328139 -146.752034) (xy 87.351811 -146.802531)
			(xy 87.367879 -146.855938) (xy 87.375999 -146.911114) (xy 87.376508 -146.939) (xy 87.375999 -146.966886)
			(xy 87.367879 -147.022062) (xy 87.351811 -147.075469) (xy 87.328139 -147.125966) (xy 87.297366 -147.172479)
			(xy 87.260149 -147.214016) (xy 87.217281 -147.249691) (xy 87.169675 -147.278745) (xy 87.118346 -147.300557)
			(xy 87.064389 -147.314663) (xy 87.008952 -147.320763) (xy 86.953218 -147.318726) (xy 86.898375 -147.308596)
			(xy 86.845591 -147.290589) (xy 86.795991 -147.265088) (xy 86.750633 -147.232637) (xy 86.710484 -147.193928)
			(xy 86.676398 -147.149785) (xy 86.649102 -147.10115) (xy 86.629179 -147.049059) (xy 86.617053 -146.994622)
			(xy 86.612982 -146.939) (xy 74.937267 -146.939) (xy 74.926621 -146.945497) (xy 74.875292 -146.967309)
			(xy 74.821335 -146.981415) (xy 74.765898 -146.987515) (xy 74.710164 -146.985478) (xy 74.655321 -146.975348)
			(xy 74.602537 -146.957341) (xy 74.552937 -146.93184) (xy 74.507579 -146.899389) (xy 74.46743 -146.86068)
			(xy 74.433344 -146.816537) (xy 74.406048 -146.767902) (xy 74.386125 -146.715811) (xy 74.373999 -146.661374)
			(xy 74.369928 -146.605752) (xy 50.623724 -146.605752) (xy 50.583846 -146.64563) (xy 50.576999 -146.653028)
			(xy 50.569269 -146.671627) (xy 50.56886 -146.681698) (xy 50.56886 -147.417536) (xy 75.262992 -147.417536)
			(xy 75.267063 -147.361914) (xy 75.279189 -147.307477) (xy 75.299112 -147.255386) (xy 75.326408 -147.206751)
			(xy 75.360494 -147.162608) (xy 75.400643 -147.123899) (xy 75.446001 -147.091448) (xy 75.495601 -147.065947)
			(xy 75.548385 -147.04794) (xy 75.603228 -147.03781) (xy 75.658962 -147.035773) (xy 75.714399 -147.041873)
			(xy 75.768356 -147.055979) (xy 75.819685 -147.077791) (xy 75.867291 -147.106845) (xy 75.910159 -147.14252)
			(xy 75.947376 -147.184057) (xy 75.978149 -147.23057) (xy 76.001821 -147.281067) (xy 76.017889 -147.334474)
			(xy 76.026009 -147.38965) (xy 76.026518 -147.417536) (xy 76.026009 -147.445422) (xy 76.017889 -147.500598)
			(xy 76.001821 -147.554005) (xy 75.978149 -147.604502) (xy 75.947376 -147.651015) (xy 75.910159 -147.692552)
			(xy 75.867291 -147.728227) (xy 75.819685 -147.757281) (xy 75.768356 -147.779093) (xy 75.714399 -147.793199)
			(xy 75.658962 -147.799299) (xy 75.603228 -147.797262) (xy 75.548385 -147.787132) (xy 75.495601 -147.769125)
			(xy 75.446001 -147.743624) (xy 75.400643 -147.711173) (xy 75.360494 -147.672464) (xy 75.326408 -147.628321)
			(xy 75.299112 -147.579686) (xy 75.279189 -147.527595) (xy 75.267063 -147.473158) (xy 75.262992 -147.417536)
			(xy 50.56886 -147.417536) (xy 50.56886 -147.955) (xy 86.612982 -147.955) (xy 86.617053 -147.899378)
			(xy 86.629179 -147.844941) (xy 86.649102 -147.79285) (xy 86.676398 -147.744215) (xy 86.710484 -147.700072)
			(xy 86.750633 -147.661363) (xy 86.795991 -147.628912) (xy 86.845591 -147.603411) (xy 86.898375 -147.585404)
			(xy 86.953218 -147.575274) (xy 87.008952 -147.573237) (xy 87.064389 -147.579337) (xy 87.118346 -147.593443)
			(xy 87.169675 -147.615255) (xy 87.217281 -147.644309) (xy 87.260149 -147.679984) (xy 87.297366 -147.721521)
			(xy 87.328139 -147.768034) (xy 87.351811 -147.818531) (xy 87.367879 -147.871938) (xy 87.375999 -147.927114)
			(xy 87.376508 -147.955) (xy 87.375999 -147.982886) (xy 87.367879 -148.038062) (xy 87.351811 -148.091469)
			(xy 87.328139 -148.141966) (xy 87.297366 -148.188479) (xy 87.260149 -148.230016) (xy 87.217281 -148.265691)
			(xy 87.169675 -148.294745) (xy 87.118346 -148.316557) (xy 87.064389 -148.330663) (xy 87.008952 -148.336763)
			(xy 86.953218 -148.334726) (xy 86.898375 -148.324596) (xy 86.845591 -148.306589) (xy 86.795991 -148.281088)
			(xy 86.750633 -148.248637) (xy 86.710484 -148.209928) (xy 86.676398 -148.165785) (xy 86.649102 -148.11715)
			(xy 86.629179 -148.065059) (xy 86.617053 -148.010622) (xy 86.612982 -147.955) (xy 50.56886 -147.955)
			(xy 50.56886 -148.37664) (xy 76.359002 -148.37664) (xy 76.363073 -148.321018) (xy 76.375199 -148.266581)
			(xy 76.395122 -148.21449) (xy 76.422418 -148.165855) (xy 76.456504 -148.121712) (xy 76.496653 -148.083003)
			(xy 76.542011 -148.050552) (xy 76.591611 -148.025051) (xy 76.644395 -148.007044) (xy 76.699238 -147.996914)
			(xy 76.754972 -147.994877) (xy 76.810409 -148.000977) (xy 76.864366 -148.015083) (xy 76.915695 -148.036895)
			(xy 76.963301 -148.065949) (xy 77.006169 -148.101624) (xy 77.043386 -148.143161) (xy 77.074159 -148.189674)
			(xy 77.097831 -148.240171) (xy 77.113899 -148.293578) (xy 77.122019 -148.348754) (xy 77.122528 -148.37664)
			(xy 77.122019 -148.404526) (xy 77.113899 -148.459702) (xy 77.097831 -148.513109) (xy 77.074159 -148.563606)
			(xy 77.043386 -148.610119) (xy 77.006169 -148.651656) (xy 76.963301 -148.687331) (xy 76.915695 -148.716385)
			(xy 76.864366 -148.738197) (xy 76.810409 -148.752303) (xy 76.754972 -148.758403) (xy 76.699238 -148.756366)
			(xy 76.644395 -148.746236) (xy 76.591611 -148.728229) (xy 76.542011 -148.702728) (xy 76.496653 -148.670277)
			(xy 76.456504 -148.631568) (xy 76.422418 -148.587425) (xy 76.395122 -148.53879) (xy 76.375199 -148.486699)
			(xy 76.363073 -148.432262) (xy 76.359002 -148.37664) (xy 50.56886 -148.37664) (xy 50.56886 -148.786957)
			(xy 54.228627 -148.786957) (xy 54.228627 -148.732443) (xy 54.236386 -148.678484) (xy 54.251745 -148.626179)
			(xy 54.274393 -148.576592) (xy 54.303867 -148.530733) (xy 54.339569 -148.489536) (xy 54.38077 -148.45384)
			(xy 54.426632 -148.424371) (xy 54.476222 -148.401729) (xy 54.528529 -148.386376) (xy 54.582489 -148.378624)
			(xy 54.609746 -148.378164) (xy 54.638663 -148.378697) (xy 54.695834 -148.38742) (xy 54.751034 -148.404673)
			(xy 54.802996 -148.430062) (xy 54.85053 -148.463004) (xy 54.892546 -148.502745) (xy 54.910736 -148.52523)
			(xy 54.918332 -148.534049) (xy 54.939241 -148.544225) (xy 54.950868 -148.544788) (xy 55.030624 -148.544788)
			(xy 55.042256 -148.544253) (xy 55.063166 -148.534062) (xy 55.070756 -148.52523) (xy 55.087509 -148.504447)
			(xy 55.125863 -148.467317) (xy 55.169017 -148.435895) (xy 55.216131 -148.410796) (xy 55.266283 -148.39251)
			(xy 55.318494 -148.381393) (xy 55.371746 -148.377663) (xy 55.424998 -148.381393) (xy 55.477209 -148.39251)
			(xy 55.527361 -148.410796) (xy 55.574475 -148.435895) (xy 55.617629 -148.467317) (xy 55.655983 -148.504447)
			(xy 55.672736 -148.52523) (xy 55.680332 -148.534049) (xy 55.701241 -148.544225) (xy 55.712868 -148.544788)
			(xy 55.792624 -148.544788) (xy 55.804256 -148.544253) (xy 55.825166 -148.534062) (xy 55.832756 -148.52523)
			(xy 55.849509 -148.504447) (xy 55.887863 -148.467317) (xy 55.931017 -148.435895) (xy 55.978131 -148.410796)
			(xy 56.028283 -148.39251) (xy 56.080494 -148.381393) (xy 56.133746 -148.377663) (xy 56.186998 -148.381393)
			(xy 56.239209 -148.39251) (xy 56.289361 -148.410796) (xy 56.336475 -148.435895) (xy 56.379629 -148.467317)
			(xy 56.417983 -148.504447) (xy 56.434736 -148.52523) (xy 56.442332 -148.534049) (xy 56.463241 -148.544225)
			(xy 56.474868 -148.544788) (xy 56.554624 -148.544788) (xy 56.566256 -148.544253) (xy 56.587166 -148.534062)
			(xy 56.594756 -148.52523) (xy 56.612979 -148.502774) (xy 56.654992 -148.463036) (xy 56.702519 -148.430092)
			(xy 56.754475 -148.404699) (xy 56.809667 -148.387437) (xy 56.866832 -148.378702) (xy 56.895746 -148.378164)
			(xy 56.922993 -148.378709) (xy 56.976932 -148.386471) (xy 57.029217 -148.401829) (xy 57.078785 -148.424471)
			(xy 57.124626 -148.453936) (xy 57.165808 -148.489625) (xy 57.201492 -148.530811) (xy 57.230951 -148.576656)
			(xy 57.253588 -148.626226) (xy 57.268939 -148.678513) (xy 57.276694 -148.732453) (xy 57.276694 -148.786947)
			(xy 57.268939 -148.840887) (xy 57.253588 -148.893174) (xy 57.230951 -148.942744) (xy 57.226668 -148.94941)
			(xy 88.81186 -148.94941) (xy 88.815931 -148.893788) (xy 88.828057 -148.839351) (xy 88.84798 -148.78726)
			(xy 88.875276 -148.738625) (xy 88.909362 -148.694482) (xy 88.949511 -148.655773) (xy 88.994869 -148.623322)
			(xy 89.044469 -148.597821) (xy 89.097253 -148.579814) (xy 89.152096 -148.569684) (xy 89.20783 -148.567647)
			(xy 89.263267 -148.573747) (xy 89.317224 -148.587853) (xy 89.368553 -148.609665) (xy 89.416159 -148.638719)
			(xy 89.459027 -148.674394) (xy 89.496244 -148.715931) (xy 89.527017 -148.762444) (xy 89.550689 -148.812941)
			(xy 89.566757 -148.866348) (xy 89.574877 -148.921524) (xy 89.575386 -148.94941) (xy 89.574877 -148.977296)
			(xy 89.566757 -149.032472) (xy 89.550689 -149.085879) (xy 89.527017 -149.136376) (xy 89.496244 -149.182889)
			(xy 89.459027 -149.224426) (xy 89.416159 -149.260101) (xy 89.368553 -149.289155) (xy 89.317224 -149.310967)
			(xy 89.263267 -149.325073) (xy 89.20783 -149.331173) (xy 89.152096 -149.329136) (xy 89.097253 -149.319006)
			(xy 89.044469 -149.300999) (xy 88.994869 -149.275498) (xy 88.949511 -149.243047) (xy 88.909362 -149.204338)
			(xy 88.875276 -149.160195) (xy 88.84798 -149.11156) (xy 88.828057 -149.059469) (xy 88.815931 -149.005032)
			(xy 88.81186 -148.94941) (xy 57.226668 -148.94941) (xy 57.201492 -148.988589) (xy 57.165808 -149.029775)
			(xy 57.124626 -149.065464) (xy 57.078785 -149.094929) (xy 57.029217 -149.117571) (xy 56.976932 -149.132929)
			(xy 56.922993 -149.140691) (xy 56.895746 -149.14118) (xy 56.86683 -149.140636) (xy 56.80966 -149.131914)
			(xy 56.754461 -149.114661) (xy 56.702499 -149.089274) (xy 56.654964 -149.056335) (xy 56.612947 -149.016598)
			(xy 56.594756 -148.994114) (xy 56.587173 -148.985282) (xy 56.566253 -148.975115) (xy 56.554624 -148.974556)
			(xy 56.474868 -148.974556) (xy 56.463233 -148.975072) (xy 56.442322 -148.985275) (xy 56.434736 -148.994114)
			(xy 56.417983 -149.014897) (xy 56.379629 -149.052027) (xy 56.336475 -149.083449) (xy 56.289361 -149.108548)
			(xy 56.239209 -149.126834) (xy 56.186998 -149.137951) (xy 56.133746 -149.141681) (xy 56.080494 -149.137951)
			(xy 56.028283 -149.126834) (xy 55.978131 -149.108548) (xy 55.931017 -149.083449) (xy 55.887863 -149.052027)
			(xy 55.849509 -149.014897) (xy 55.832756 -148.994114) (xy 55.825173 -148.985282) (xy 55.804253 -148.975115)
			(xy 55.792624 -148.974556) (xy 55.712868 -148.974556) (xy 55.701233 -148.975072) (xy 55.680322 -148.985275)
			(xy 55.672736 -148.994114) (xy 55.655983 -149.014897) (xy 55.617629 -149.052027) (xy 55.574475 -149.083449)
			(xy 55.527361 -149.108548) (xy 55.477209 -149.126834) (xy 55.424998 -149.137951) (xy 55.371746 -149.141681)
			(xy 55.318494 -149.137951) (xy 55.266283 -149.126834) (xy 55.216131 -149.108548) (xy 55.169017 -149.083449)
			(xy 55.125863 -149.052027) (xy 55.087509 -149.014897) (xy 55.070756 -148.994114) (xy 55.063173 -148.985282)
			(xy 55.042253 -148.975115) (xy 55.030624 -148.974556) (xy 54.950868 -148.974556) (xy 54.939233 -148.975072)
			(xy 54.918322 -148.985275) (xy 54.910736 -148.994114) (xy 54.892528 -149.016583) (xy 54.850512 -149.056319)
			(xy 54.80298 -149.089259) (xy 54.751022 -149.11465) (xy 54.695828 -149.131909) (xy 54.638661 -149.140643)
			(xy 54.609746 -149.14118) (xy 54.582489 -149.140776) (xy 54.528529 -149.133024) (xy 54.476222 -149.117671)
			(xy 54.426632 -149.095029) (xy 54.38077 -149.06556) (xy 54.339569 -149.029864) (xy 54.303867 -148.988667)
			(xy 54.274393 -148.942808) (xy 54.251745 -148.893221) (xy 54.236386 -148.840916) (xy 54.228627 -148.786957)
			(xy 50.56886 -148.786957) (xy 50.56886 -149.412198) (xy 69.012814 -149.412198) (xy 69.016885 -149.356576)
			(xy 69.029011 -149.302139) (xy 69.048934 -149.250048) (xy 69.07623 -149.201413) (xy 69.110316 -149.15727)
			(xy 69.150465 -149.118561) (xy 69.195823 -149.08611) (xy 69.245423 -149.060609) (xy 69.298207 -149.042602)
			(xy 69.35305 -149.032472) (xy 69.408784 -149.030435) (xy 69.464221 -149.036535) (xy 69.518178 -149.050641)
			(xy 69.569507 -149.072453) (xy 69.617113 -149.101507) (xy 69.659981 -149.137182) (xy 69.697198 -149.178719)
			(xy 69.727971 -149.225232) (xy 69.751643 -149.275729) (xy 69.767711 -149.329136) (xy 69.775831 -149.384312)
			(xy 69.77634 -149.412198) (xy 69.775831 -149.440084) (xy 69.767711 -149.49526) (xy 69.751643 -149.548667)
			(xy 69.727971 -149.599164) (xy 69.697198 -149.645677) (xy 69.659981 -149.687214) (xy 69.617113 -149.722889)
			(xy 69.569507 -149.751943) (xy 69.518178 -149.773755) (xy 69.464221 -149.787861) (xy 69.408784 -149.793961)
			(xy 69.35305 -149.791924) (xy 69.298207 -149.781794) (xy 69.245423 -149.763787) (xy 69.195823 -149.738286)
			(xy 69.150465 -149.705835) (xy 69.110316 -149.667126) (xy 69.07623 -149.622983) (xy 69.048934 -149.574348)
			(xy 69.029011 -149.522257) (xy 69.016885 -149.46782) (xy 69.012814 -149.412198) (xy 50.56886 -149.412198)
			(xy 50.56886 -149.96541) (xy 88.81186 -149.96541) (xy 88.815931 -149.909788) (xy 88.828057 -149.855351)
			(xy 88.84798 -149.80326) (xy 88.875276 -149.754625) (xy 88.909362 -149.710482) (xy 88.949511 -149.671773)
			(xy 88.994869 -149.639322) (xy 89.044469 -149.613821) (xy 89.097253 -149.595814) (xy 89.152096 -149.585684)
			(xy 89.20783 -149.583647) (xy 89.263267 -149.589747) (xy 89.317224 -149.603853) (xy 89.368553 -149.625665)
			(xy 89.416159 -149.654719) (xy 89.459027 -149.690394) (xy 89.496244 -149.731931) (xy 89.527017 -149.778444)
			(xy 89.550689 -149.828941) (xy 89.566757 -149.882348) (xy 89.574877 -149.937524) (xy 89.575386 -149.96541)
			(xy 89.574877 -149.993296) (xy 89.566757 -150.048472) (xy 89.550689 -150.101879) (xy 89.527017 -150.152376)
			(xy 89.496244 -150.198889) (xy 89.459027 -150.240426) (xy 89.416159 -150.276101) (xy 89.368553 -150.305155)
			(xy 89.317224 -150.326967) (xy 89.263267 -150.341073) (xy 89.20783 -150.347173) (xy 89.152096 -150.345136)
			(xy 89.097253 -150.335006) (xy 89.044469 -150.316999) (xy 88.994869 -150.291498) (xy 88.949511 -150.259047)
			(xy 88.909362 -150.220338) (xy 88.875276 -150.176195) (xy 88.84798 -150.12756) (xy 88.828057 -150.075469)
			(xy 88.815931 -150.021032) (xy 88.81186 -149.96541) (xy 50.56886 -149.96541) (xy 50.56886 -150.984966)
			(xy 50.568722 -150.989856) (xy 50.5668 -150.999447) (xy 50.56505 -151.004016) (xy 50.56124 -151.013668)
			(xy 50.56124 -151.194051) (xy 52.515485 -151.194051) (xy 52.515485 -151.139549) (xy 52.523242 -151.0856)
			(xy 52.538598 -151.033305) (xy 52.56124 -150.983728) (xy 52.590707 -150.937878) (xy 52.626399 -150.896688)
			(xy 52.667591 -150.860997) (xy 52.713442 -150.831532) (xy 52.76302 -150.808892) (xy 52.815316 -150.793539)
			(xy 52.869265 -150.785784) (xy 52.896516 -150.785322) (xy 52.925431 -150.785893) (xy 52.9826 -150.79461)
			(xy 53.037798 -150.811857) (xy 53.08976 -150.837239) (xy 53.137296 -150.870173) (xy 53.179314 -150.909906)
			(xy 53.197506 -150.932388) (xy 53.205122 -150.941186) (xy 53.226016 -150.951375) (xy 53.237638 -150.951946)
			(xy 53.317394 -150.951946) (xy 53.329027 -150.951408) (xy 53.349937 -150.94122) (xy 53.357526 -150.932388)
			(xy 53.375699 -150.90989) (xy 53.417723 -150.870156) (xy 53.465262 -150.837219) (xy 53.517226 -150.811833)
			(xy 53.572427 -150.79458) (xy 53.629599 -150.785855) (xy 53.658516 -150.785322) (xy 53.685769 -150.785749)
			(xy 53.739719 -150.793508) (xy 53.792016 -150.808866) (xy 53.841595 -150.831509) (xy 53.887447 -150.860979)
			(xy 53.928638 -150.896673) (xy 53.964331 -150.937866) (xy 53.993798 -150.983719) (xy 54.01644 -151.033299)
			(xy 54.031795 -151.085597) (xy 54.039552 -151.139547) (xy 54.039552 -151.194053) (xy 54.031795 -151.248003)
			(xy 54.01644 -151.300301) (xy 53.993798 -151.349881) (xy 53.964331 -151.395734) (xy 53.928638 -151.436927)
			(xy 53.887447 -151.472621) (xy 53.841595 -151.502091) (xy 53.792016 -151.524734) (xy 53.739719 -151.540092)
			(xy 53.685769 -151.547851) (xy 53.658516 -151.548338) (xy 53.629598 -151.547832) (xy 53.572426 -151.539104)
			(xy 53.517225 -151.521845) (xy 53.465263 -151.496451) (xy 53.41773 -151.463504) (xy 53.375715 -151.423759)
			(xy 53.357526 -151.401272) (xy 53.349903 -151.392482) (xy 53.329014 -151.38229) (xy 53.317394 -151.381714)
			(xy 53.237638 -151.381714) (xy 53.226003 -151.382227) (xy 53.205093 -151.392434) (xy 53.197506 -151.401272)
			(xy 53.179305 -151.423747) (xy 53.137288 -151.463484) (xy 53.089755 -151.496425) (xy 53.037796 -151.521815)
			(xy 52.9826 -151.539073) (xy 52.925432 -151.547803) (xy 52.896516 -151.548338) (xy 52.869265 -151.547816)
			(xy 52.815316 -151.540061) (xy 52.76302 -151.524708) (xy 52.713442 -151.502068) (xy 52.667591 -151.472603)
			(xy 52.626399 -151.436912) (xy 52.590707 -151.395722) (xy 52.56124 -151.349872) (xy 52.538598 -151.300295)
			(xy 52.523242 -151.248) (xy 52.515485 -151.194051) (xy 50.56124 -151.194051) (xy 50.56124 -153.251451)
			(xy 52.515485 -153.251451) (xy 52.515485 -153.196949) (xy 52.523242 -153.143) (xy 52.538598 -153.090705)
			(xy 52.56124 -153.041128) (xy 52.590707 -152.995278) (xy 52.626399 -152.954088) (xy 52.667591 -152.918397)
			(xy 52.713442 -152.888932) (xy 52.76302 -152.866292) (xy 52.815316 -152.850939) (xy 52.869265 -152.843184)
			(xy 52.896516 -152.842722) (xy 52.925431 -152.843293) (xy 52.9826 -152.85201) (xy 53.037798 -152.869257)
			(xy 53.08976 -152.894639) (xy 53.137296 -152.927573) (xy 53.179314 -152.967306) (xy 53.197506 -152.989788)
			(xy 53.205122 -152.998586) (xy 53.226016 -153.008775) (xy 53.237638 -153.009346) (xy 53.317394 -153.009346)
			(xy 53.329027 -153.008808) (xy 53.349937 -152.99862) (xy 53.357526 -152.989788) (xy 53.375699 -152.96729)
			(xy 53.417723 -152.927556) (xy 53.465262 -152.894619) (xy 53.517226 -152.869233) (xy 53.572427 -152.85198)
			(xy 53.629599 -152.843255) (xy 53.658516 -152.842722) (xy 53.685769 -152.843149) (xy 53.739719 -152.850908)
			(xy 53.792016 -152.866266) (xy 53.841595 -152.888909) (xy 53.887447 -152.918379) (xy 53.928638 -152.954073)
			(xy 53.964331 -152.995266) (xy 53.993798 -153.041119) (xy 54.01644 -153.090699) (xy 54.031795 -153.142997)
			(xy 54.039552 -153.196947) (xy 54.039552 -153.251453) (xy 54.031795 -153.305403) (xy 54.01644 -153.357701)
			(xy 53.993798 -153.407281) (xy 53.964331 -153.453134) (xy 53.928638 -153.494327) (xy 53.887447 -153.530021)
			(xy 53.841595 -153.559491) (xy 53.792016 -153.582134) (xy 53.739719 -153.597492) (xy 53.685769 -153.605251)
			(xy 53.658516 -153.605738) (xy 53.629598 -153.605232) (xy 53.572426 -153.596504) (xy 53.517225 -153.579245)
			(xy 53.465263 -153.553851) (xy 53.41773 -153.520904) (xy 53.375715 -153.481159) (xy 53.357526 -153.458672)
			(xy 53.349903 -153.449882) (xy 53.329014 -153.43969) (xy 53.317394 -153.439114) (xy 53.237638 -153.439114)
			(xy 53.226003 -153.439627) (xy 53.205093 -153.449834) (xy 53.197506 -153.458672) (xy 53.179305 -153.481147)
			(xy 53.137288 -153.520884) (xy 53.089755 -153.553825) (xy 53.037796 -153.579215) (xy 52.9826 -153.596473)
			(xy 52.925432 -153.605203) (xy 52.896516 -153.605738) (xy 52.869265 -153.605216) (xy 52.815316 -153.597461)
			(xy 52.76302 -153.582108) (xy 52.713442 -153.559468) (xy 52.667591 -153.530003) (xy 52.626399 -153.494312)
			(xy 52.590707 -153.453122) (xy 52.56124 -153.407272) (xy 52.538598 -153.357695) (xy 52.523242 -153.3054)
			(xy 52.515485 -153.251451) (xy 50.56124 -153.251451) (xy 50.56124 -154.940254) (xy 52.452778 -154.940254)
			(xy 52.453308 -154.9115) (xy 52.461938 -154.854644) (xy 52.47901 -154.799729) (xy 52.504137 -154.748001)
			(xy 52.536749 -154.700635) (xy 52.576105 -154.658704) (xy 52.621313 -154.62316) (xy 52.646072 -154.60853)
			(xy 52.656314 -154.601905) (xy 52.669566 -154.581464) (xy 52.671472 -154.569414) (xy 52.681378 -154.474672)
			(xy 52.672488 -154.451812) (xy 52.66309 -154.443684) (xy 52.643127 -154.425459) (xy 52.607955 -154.384415)
			(xy 52.578923 -154.338822) (xy 52.556612 -154.289589) (xy 52.541467 -154.237702) (xy 52.533791 -154.184198)
			(xy 52.533296 -154.157172) (xy 52.533752 -154.12992) (xy 52.541512 -154.075971) (xy 52.556871 -154.023675)
			(xy 52.579516 -153.974098) (xy 52.608985 -153.928247) (xy 52.64468 -153.887057) (xy 52.685873 -153.851366)
			(xy 52.731726 -153.8219) (xy 52.781305 -153.79926) (xy 52.833602 -153.783905) (xy 52.887552 -153.776149)
			(xy 52.914804 -153.775664) (xy 52.943722 -153.776155) (xy 53.000896 -153.784886) (xy 53.056096 -153.802148)
			(xy 53.108058 -153.827545) (xy 53.155591 -153.860494) (xy 53.197606 -153.900241) (xy 53.215794 -153.92273)
			(xy 53.223408 -153.93153) (xy 53.244304 -153.941716) (xy 53.255926 -153.942288) (xy 53.335682 -153.942288)
			(xy 53.347311 -153.941728) (xy 53.368221 -153.931554) (xy 53.375814 -153.92273) (xy 53.394005 -153.900246)
			(xy 53.436024 -153.86051) (xy 53.483558 -153.82757) (xy 53.53552 -153.802181) (xy 53.590718 -153.784925)
			(xy 53.647888 -153.776198) (xy 53.676804 -153.775664) (xy 53.704349 -153.776165) (xy 53.758868 -153.78407)
			(xy 53.811679 -153.799745) (xy 53.861683 -153.822863) (xy 53.907836 -153.852941) (xy 53.949177 -153.889352)
			(xy 53.96738 -153.91003) (xy 53.974492 -153.918412) (xy 53.994558 -153.92781) (xy 54.093618 -153.928826)
			(xy 54.113684 -153.919682) (xy 54.12105 -153.9113) (xy 54.139233 -153.89135) (xy 54.180275 -153.856289)
			(xy 54.225848 -153.827363) (xy 54.275044 -153.805147) (xy 54.326879 -153.790086) (xy 54.380319 -153.78248)
			(xy 54.407308 -153.782014) (xy 54.436223 -153.782593) (xy 54.493391 -153.791309) (xy 54.548589 -153.808555)
			(xy 54.600551 -153.833935) (xy 54.648087 -153.866868) (xy 54.690106 -153.906599) (xy 54.708298 -153.92908)
			(xy 54.715902 -153.937889) (xy 54.736806 -153.948068) (xy 54.74843 -153.948638) (xy 54.828186 -153.948638)
			(xy 54.839818 -153.948098) (xy 54.860729 -153.937912) (xy 54.868318 -153.92908) (xy 54.885071 -153.908297)
			(xy 54.923425 -153.871167) (xy 54.966579 -153.839745) (xy 55.013693 -153.814646) (xy 55.063845 -153.79636)
			(xy 55.116056 -153.785243) (xy 55.169308 -153.781513) (xy 55.22256 -153.785243) (xy 55.274771 -153.79636)
			(xy 55.324923 -153.814646) (xy 55.372037 -153.839745) (xy 55.415191 -153.871167) (xy 55.453545 -153.908297)
			(xy 55.470298 -153.92908) (xy 55.477902 -153.937889) (xy 55.498806 -153.948068) (xy 55.51043 -153.948638)
			(xy 55.59044 -153.948638) (xy 55.602007 -153.948055) (xy 55.622779 -153.937871) (xy 55.630318 -153.92908)
			(xy 55.647801 -153.90749) (xy 55.687963 -153.869107) (xy 55.710328 -153.852626) (xy 55.720179 -153.844789)
			(xy 55.73138 -153.822283) (xy 55.731664 -153.8097) (xy 55.729124 -153.725372) (xy 55.728109 -153.712799)
			(xy 55.715588 -153.69094) (xy 55.705248 -153.683716) (xy 55.682195 -153.668651) (xy 55.640264 -153.632952)
			(xy 55.6039 -153.591597) (xy 55.573857 -153.545444) (xy 55.550761 -153.495452) (xy 55.53509 -153.442659)
			(xy 55.527171 -153.388163) (xy 55.526686 -153.360628) (xy 55.527181 -153.333376) (xy 55.534934 -153.279427)
			(xy 55.550287 -153.22713) (xy 55.572925 -153.17755) (xy 55.60239 -153.131697) (xy 55.63808 -153.090504)
			(xy 55.67927 -153.05481) (xy 55.72512 -153.025342) (xy 55.774698 -153.002698) (xy 55.826993 -152.987342)
			(xy 55.880942 -152.979584) (xy 55.908194 -152.97912) (xy 55.937111 -152.979635) (xy 55.994283 -152.988364)
			(xy 56.049482 -153.005622) (xy 56.101444 -153.031014) (xy 56.148978 -153.063958) (xy 56.190994 -153.1037)
			(xy 56.209184 -153.126186) (xy 56.216793 -153.13499) (xy 56.237693 -153.145172) (xy 56.249316 -153.145744)
			(xy 56.329072 -153.145744) (xy 56.340703 -153.145194) (xy 56.361614 -153.135015) (xy 56.369204 -153.126186)
			(xy 56.387389 -153.103698) (xy 56.429411 -153.063963) (xy 56.476947 -153.031025) (xy 56.528909 -153.005638)
			(xy 56.584108 -152.988383) (xy 56.641278 -152.979655) (xy 56.670194 -152.97912) (xy 56.697448 -152.979561)
			(xy 56.751401 -152.987318) (xy 56.803701 -153.002675) (xy 56.853283 -153.025318) (xy 56.899138 -153.054788)
			(xy 56.940331 -153.090485) (xy 56.976025 -153.13168) (xy 57.005492 -153.177536) (xy 57.028133 -153.22712)
			(xy 57.043487 -153.27942) (xy 57.051241 -153.333374) (xy 57.051702 -153.360628) (xy 57.051259 -153.386603)
			(xy 57.044214 -153.438073) (xy 57.030243 -153.48811) (xy 57.009607 -153.535785) (xy 56.982687 -153.580217)
			(xy 56.949983 -153.62058) (xy 56.9121 -153.656129) (xy 56.891174 -153.671524) (xy 56.8813 -153.679337)
			(xy 56.870111 -153.701861) (xy 56.869838 -153.71445) (xy 56.872378 -153.798778) (xy 56.873363 -153.811356)
			(xy 56.885906 -153.833214) (xy 56.896254 -153.840434) (xy 56.919285 -153.855531) (xy 56.961216 -153.891225)
			(xy 56.997581 -153.932575) (xy 57.027626 -153.978722) (xy 57.050726 -154.028709) (xy 57.066402 -154.081496)
			(xy 57.074328 -154.135989) (xy 57.074816 -154.163522) (xy 57.074448 -154.189074) (xy 57.067633 -154.239722)
			(xy 57.054115 -154.289006) (xy 57.034136 -154.336044) (xy 57.008055 -154.379992) (xy 56.976337 -154.420063)
			(xy 56.95823 -154.438096) (xy 56.951182 -154.445548) (xy 56.943198 -154.464424) (xy 56.942736 -154.474672)
			(xy 56.942736 -154.547824) (xy 56.943192 -154.558073) (xy 56.951179 -154.576949) (xy 56.95823 -154.5844)
			(xy 56.964326 -154.590496) (xy 56.96458 -154.59075) (xy 56.971935 -154.597397) (xy 56.990239 -154.604969)
			(xy 57.00014 -154.605482) (xy 57.072276 -154.60599) (xy 57.082344 -154.605555) (xy 57.100942 -154.597841)
			(xy 57.108344 -154.591004) (xy 57.129939 -154.570358) (xy 57.178341 -154.53534) (xy 57.231612 -154.508299)
			(xy 57.288448 -154.489897) (xy 57.347459 -154.480584) (xy 57.37733 -154.480006) (xy 57.406245 -154.480572)
			(xy 57.463414 -154.489291) (xy 57.518612 -154.506539) (xy 57.570574 -154.531922) (xy 57.618109 -154.564857)
			(xy 57.660128 -154.60459) (xy 57.67832 -154.627072) (xy 57.685916 -154.63589) (xy 57.706826 -154.646065)
			(xy 57.718452 -154.64663) (xy 57.798208 -154.64663) (xy 57.809842 -154.646106) (xy 57.830754 -154.635909)
			(xy 57.83834 -154.627072) (xy 57.856501 -154.604564) (xy 57.898528 -154.564831) (xy 57.946069 -154.531896)
			(xy 57.998036 -154.506512) (xy 58.053239 -154.489261) (xy 58.110412 -154.480538) (xy 58.13933 -154.480006)
			(xy 58.166581 -154.480466) (xy 58.220527 -154.488226) (xy 58.27282 -154.503584) (xy 58.322396 -154.526228)
			(xy 58.325172 -154.528012) (xy 67.588636 -154.528012) (xy 67.592707 -154.47239) (xy 67.604833 -154.417953)
			(xy 67.624756 -154.365862) (xy 67.652052 -154.317227) (xy 67.686138 -154.273084) (xy 67.726287 -154.234375)
			(xy 67.771645 -154.201924) (xy 67.821245 -154.176423) (xy 67.874029 -154.158416) (xy 67.928872 -154.148286)
			(xy 67.984606 -154.146249) (xy 68.040043 -154.152349) (xy 68.094 -154.166455) (xy 68.145329 -154.188267)
			(xy 68.192935 -154.217321) (xy 68.235803 -154.252996) (xy 68.27302 -154.294533) (xy 68.303793 -154.341046)
			(xy 68.327465 -154.391543) (xy 68.343533 -154.44495) (xy 68.351653 -154.500126) (xy 68.352162 -154.528012)
			(xy 68.351653 -154.555898) (xy 68.343533 -154.611074) (xy 68.327465 -154.664481) (xy 68.303793 -154.714978)
			(xy 68.27302 -154.761491) (xy 68.235803 -154.803028) (xy 68.192935 -154.838703) (xy 68.145329 -154.867757)
			(xy 68.094 -154.889569) (xy 68.040043 -154.903675) (xy 67.984606 -154.909775) (xy 67.928872 -154.907738)
			(xy 67.874029 -154.897608) (xy 67.821245 -154.879601) (xy 67.771645 -154.8541) (xy 67.726287 -154.821649)
			(xy 67.686138 -154.78294) (xy 67.652052 -154.738797) (xy 67.624756 -154.690162) (xy 67.604833 -154.638071)
			(xy 67.592707 -154.583634) (xy 67.588636 -154.528012) (xy 58.325172 -154.528012) (xy 58.368244 -154.555696)
			(xy 58.409432 -154.591389) (xy 58.445122 -154.63258) (xy 58.474586 -154.678431) (xy 58.497226 -154.728008)
			(xy 58.51258 -154.780302) (xy 58.520336 -154.834249) (xy 58.520336 -154.888751) (xy 58.51258 -154.942698)
			(xy 58.497226 -154.994992) (xy 58.474586 -155.044569) (xy 58.445122 -155.09042) (xy 58.409432 -155.131611)
			(xy 58.368244 -155.167304) (xy 58.322396 -155.196772) (xy 58.27282 -155.219416) (xy 58.220527 -155.234774)
			(xy 58.166581 -155.242534) (xy 58.13933 -155.243022) (xy 58.110412 -155.242512) (xy 58.053239 -155.233785)
			(xy 57.998039 -155.216528) (xy 57.946077 -155.191135) (xy 57.898543 -155.158188) (xy 57.856528 -155.118444)
			(xy 57.83834 -155.095956) (xy 57.830713 -155.08717) (xy 57.809827 -155.076977) (xy 57.798208 -155.076398)
			(xy 57.718452 -155.076398) (xy 57.706819 -155.076924) (xy 57.685909 -155.087122) (xy 57.67832 -155.095956)
			(xy 57.660107 -155.118421) (xy 57.618093 -155.158159) (xy 57.570563 -155.191102) (xy 57.518606 -155.216494)
			(xy 57.463412 -155.233753) (xy 57.406245 -155.242486) (xy 57.37733 -155.243022) (xy 57.347171 -155.242439)
			(xy 57.287605 -155.232939) (xy 57.230276 -155.214187) (xy 57.17661 -155.18665) (xy 57.127945 -155.151014)
			(xy 57.106312 -155.129992) (xy 57.106058 -155.129738) (xy 57.098691 -155.123106) (xy 57.080397 -155.115525)
			(xy 57.070498 -155.115006) (xy 56.998362 -155.114498) (xy 56.988287 -155.114878) (xy 56.969688 -155.122628)
			(xy 56.962294 -155.129484) (xy 56.940697 -155.150127) (xy 56.892294 -155.185142) (xy 56.839023 -155.212182)
			(xy 56.782188 -155.230585) (xy 56.723178 -155.239901) (xy 56.693308 -155.240482) (xy 56.664391 -155.239965)
			(xy 56.607219 -155.231236) (xy 56.55202 -155.213979) (xy 56.500059 -155.188587) (xy 56.452525 -155.155643)
			(xy 56.410508 -155.115902) (xy 56.392318 -155.093416) (xy 56.384708 -155.084613) (xy 56.363809 -155.07443)
			(xy 56.352186 -155.073858) (xy 56.27243 -155.073858) (xy 56.260799 -155.074408) (xy 56.239888 -155.084587)
			(xy 56.232298 -155.093416) (xy 56.215545 -155.114199) (xy 56.177191 -155.151329) (xy 56.134037 -155.182751)
			(xy 56.086923 -155.20785) (xy 56.036771 -155.226136) (xy 55.98456 -155.237253) (xy 55.931308 -155.240983)
			(xy 55.878056 -155.237253) (xy 55.825845 -155.226136) (xy 55.775693 -155.20785) (xy 55.728579 -155.182751)
			(xy 55.685425 -155.151329) (xy 55.647071 -155.114199) (xy 55.630318 -155.093416) (xy 55.622708 -155.084613)
			(xy 55.601809 -155.07443) (xy 55.590186 -155.073858) (xy 55.51043 -155.073858) (xy 55.498799 -155.074408)
			(xy 55.477888 -155.084587) (xy 55.470298 -155.093416) (xy 55.453545 -155.114199) (xy 55.415191 -155.151329)
			(xy 55.372037 -155.182751) (xy 55.324923 -155.20785) (xy 55.274771 -155.226136) (xy 55.22256 -155.237253)
			(xy 55.169308 -155.240983) (xy 55.116056 -155.237253) (xy 55.063845 -155.226136) (xy 55.013693 -155.20785)
			(xy 54.966579 -155.182751) (xy 54.923425 -155.151329) (xy 54.885071 -155.114199) (xy 54.868318 -155.093416)
			(xy 54.860708 -155.084613) (xy 54.839809 -155.07443) (xy 54.828186 -155.073858) (xy 54.74843 -155.073858)
			(xy 54.736799 -155.074408) (xy 54.715888 -155.084587) (xy 54.708298 -155.093416) (xy 54.690112 -155.115904)
			(xy 54.648091 -155.155638) (xy 54.600555 -155.188576) (xy 54.548593 -155.213963) (xy 54.493394 -155.231219)
			(xy 54.436224 -155.239947) (xy 54.407308 -155.240482) (xy 54.378559 -155.239983) (xy 54.321716 -155.231331)
			(xy 54.266813 -155.214251) (xy 54.215093 -155.18913) (xy 54.167725 -155.156535) (xy 54.125782 -155.117206)
			(xy 54.107588 -155.09494) (xy 54.102055 -155.088462) (xy 54.087697 -155.079306) (xy 54.071133 -155.075359)
			(xy 54.06263 -155.07589) (xy 53.977286 -155.084272) (xy 53.96884 -155.085398) (xy 53.953358 -155.092489)
			(xy 53.941061 -155.104269) (xy 53.9369 -155.111704) (xy 53.9369 -155.111958) (xy 53.924612 -155.135249)
			(xy 53.894686 -155.178579) (xy 53.859083 -155.217378) (xy 53.818478 -155.250907) (xy 53.773646 -155.27853)
			(xy 53.725438 -155.29972) (xy 53.674774 -155.314074) (xy 53.622615 -155.321319) (xy 53.596286 -155.321762)
			(xy 53.567371 -155.321196) (xy 53.510201 -155.312479) (xy 53.455003 -155.295231) (xy 53.40304 -155.269849)
			(xy 53.355505 -155.236913) (xy 53.313487 -155.197178) (xy 53.295296 -155.174696) (xy 53.287681 -155.165896)
			(xy 53.266786 -155.155709) (xy 53.255164 -155.155138) (xy 53.175408 -155.155138) (xy 53.163776 -155.155683)
			(xy 53.142866 -155.165866) (xy 53.135276 -155.174696) (xy 53.117098 -155.19719) (xy 53.075075 -155.236925)
			(xy 53.027538 -155.269863) (xy 52.975574 -155.295249) (xy 52.920374 -155.312503) (xy 52.863203 -155.321229)
			(xy 52.834286 -155.321762) (xy 52.807031 -155.321358) (xy 52.753075 -155.313598) (xy 52.700773 -155.298238)
			(xy 52.65119 -155.27559) (xy 52.605335 -155.246117) (xy 52.564141 -155.210417) (xy 52.528447 -155.169217)
			(xy 52.498981 -155.123357) (xy 52.476341 -155.07377) (xy 52.460989 -155.021466) (xy 52.453238 -154.967509)
			(xy 52.452778 -154.940254) (xy 50.56124 -154.940254) (xy 50.56124 -158.113052) (xy 54.997068 -158.113052)
			(xy 54.997068 -158.058548) (xy 55.004824 -158.004599) (xy 55.02018 -157.952304) (xy 55.042821 -157.902725)
			(xy 55.072288 -157.856874) (xy 55.10798 -157.815683) (xy 55.149171 -157.77999) (xy 55.195022 -157.750523)
			(xy 55.2446 -157.727881) (xy 55.296896 -157.712525) (xy 55.350844 -157.704768) (xy 55.378096 -157.704282)
			(xy 55.407014 -157.704772) (xy 55.464188 -157.713503) (xy 55.519389 -157.730764) (xy 55.571351 -157.756161)
			(xy 55.618884 -157.789111) (xy 55.660898 -157.828859) (xy 55.679086 -157.851348) (xy 55.686701 -157.860147)
			(xy 55.707596 -157.870333) (xy 55.719218 -157.870906) (xy 55.798974 -157.870906) (xy 55.810602 -157.870335)
			(xy 55.831512 -157.860169) (xy 55.839106 -157.851348) (xy 55.855859 -157.830565) (xy 55.894213 -157.793435)
			(xy 55.937367 -157.762013) (xy 55.984481 -157.736914) (xy 56.034633 -157.718628) (xy 56.086844 -157.707511)
			(xy 56.140096 -157.703781) (xy 56.193348 -157.707511) (xy 56.245559 -157.718628) (xy 56.295711 -157.736914)
			(xy 56.342825 -157.762013) (xy 56.385979 -157.793435) (xy 56.424333 -157.830565) (xy 56.441086 -157.851348)
			(xy 56.448701 -157.860147) (xy 56.469596 -157.870333) (xy 56.481218 -157.870906) (xy 56.560974 -157.870906)
			(xy 56.572602 -157.870335) (xy 56.593512 -157.860169) (xy 56.601106 -157.851348) (xy 56.617859 -157.830565)
			(xy 56.656213 -157.793435) (xy 56.699367 -157.762013) (xy 56.746481 -157.736914) (xy 56.796633 -157.718628)
			(xy 56.848844 -157.707511) (xy 56.902096 -157.703781) (xy 56.955348 -157.707511) (xy 57.007559 -157.718628)
			(xy 57.057711 -157.736914) (xy 57.104825 -157.762013) (xy 57.147979 -157.793435) (xy 57.186333 -157.830565)
			(xy 57.203086 -157.851348) (xy 57.210701 -157.860147) (xy 57.231596 -157.870333) (xy 57.243218 -157.870906)
			(xy 57.322974 -157.870906) (xy 57.334602 -157.870335) (xy 57.355512 -157.860169) (xy 57.363106 -157.851348)
			(xy 57.38128 -157.828851) (xy 57.423305 -157.789119) (xy 57.470844 -157.756183) (xy 57.522808 -157.730797)
			(xy 57.578008 -157.713544) (xy 57.635179 -157.704816) (xy 57.664096 -157.704282) (xy 57.691348 -157.704765)
			(xy 57.745298 -157.712521) (xy 57.797595 -157.727877) (xy 57.847175 -157.750518) (xy 57.893027 -157.779985)
			(xy 57.934219 -157.815678) (xy 57.969912 -157.85687) (xy 57.99938 -157.902722) (xy 58.022022 -157.952301)
			(xy 58.037378 -158.004598) (xy 58.045135 -158.058548) (xy 58.045135 -158.113052) (xy 58.037378 -158.167002)
			(xy 58.022022 -158.219299) (xy 57.99938 -158.268878) (xy 57.969912 -158.31473) (xy 57.934219 -158.355922)
			(xy 57.893027 -158.391615) (xy 57.847175 -158.421082) (xy 57.797595 -158.443723) (xy 57.745298 -158.459079)
			(xy 57.691348 -158.466835) (xy 57.664096 -158.467298) (xy 57.635179 -158.466783) (xy 57.578008 -158.458053)
			(xy 57.522809 -158.440795) (xy 57.470847 -158.415403) (xy 57.423313 -158.382458) (xy 57.381296 -158.342717)
			(xy 57.363106 -158.320232) (xy 57.355498 -158.311426) (xy 57.334598 -158.301245) (xy 57.322974 -158.300674)
			(xy 57.243218 -158.300674) (xy 57.231585 -158.301212) (xy 57.210674 -158.311399) (xy 57.203086 -158.320232)
			(xy 57.186333 -158.341015) (xy 57.147979 -158.378145) (xy 57.104825 -158.409567) (xy 57.057711 -158.434666)
			(xy 57.007559 -158.452952) (xy 56.955348 -158.464069) (xy 56.902096 -158.467799) (xy 56.848844 -158.464069)
			(xy 56.796633 -158.452952) (xy 56.746481 -158.434666) (xy 56.699367 -158.409567) (xy 56.656213 -158.378145)
			(xy 56.617859 -158.341015) (xy 56.601106 -158.320232) (xy 56.593498 -158.311426) (xy 56.572598 -158.301245)
			(xy 56.560974 -158.300674) (xy 56.481218 -158.300674) (xy 56.469585 -158.301212) (xy 56.448674 -158.311399)
			(xy 56.441086 -158.320232) (xy 56.424333 -158.341015) (xy 56.385979 -158.378145) (xy 56.342825 -158.409567)
			(xy 56.295711 -158.434666) (xy 56.245559 -158.452952) (xy 56.193348 -158.464069) (xy 56.140096 -158.467799)
			(xy 56.086844 -158.464069) (xy 56.034633 -158.452952) (xy 55.984481 -158.434666) (xy 55.937367 -158.409567)
			(xy 55.894213 -158.378145) (xy 55.855859 -158.341015) (xy 55.839106 -158.320232) (xy 55.831498 -158.311426)
			(xy 55.810598 -158.301245) (xy 55.798974 -158.300674) (xy 55.719218 -158.300674) (xy 55.707585 -158.301212)
			(xy 55.686674 -158.311399) (xy 55.679086 -158.320232) (xy 55.660911 -158.342729) (xy 55.618887 -158.382462)
			(xy 55.571348 -158.415398) (xy 55.519384 -158.440784) (xy 55.464184 -158.458038) (xy 55.407013 -158.466764)
			(xy 55.378096 -158.467298) (xy 55.350844 -158.466832) (xy 55.296896 -158.459075) (xy 55.2446 -158.443719)
			(xy 55.195022 -158.421077) (xy 55.149171 -158.39161) (xy 55.10798 -158.355917) (xy 55.072288 -158.314726)
			(xy 55.042821 -158.268875) (xy 55.02018 -158.219296) (xy 55.004824 -158.167001) (xy 54.997068 -158.113052)
			(xy 50.56124 -158.113052) (xy 50.56124 -160.653052) (xy 54.997068 -160.653052) (xy 54.997068 -160.598548)
			(xy 55.004824 -160.544599) (xy 55.02018 -160.492304) (xy 55.042821 -160.442725) (xy 55.072288 -160.396874)
			(xy 55.10798 -160.355683) (xy 55.149171 -160.31999) (xy 55.195022 -160.290523) (xy 55.2446 -160.267881)
			(xy 55.296896 -160.252525) (xy 55.350844 -160.244768) (xy 55.378096 -160.244282) (xy 55.407014 -160.244772)
			(xy 55.464188 -160.253503) (xy 55.519389 -160.270764) (xy 55.571351 -160.296161) (xy 55.618884 -160.329111)
			(xy 55.660898 -160.368859) (xy 55.679086 -160.391348) (xy 55.686701 -160.400147) (xy 55.707596 -160.410333)
			(xy 55.719218 -160.410906) (xy 55.798974 -160.410906) (xy 55.810602 -160.410335) (xy 55.831512 -160.400169)
			(xy 55.839106 -160.391348) (xy 55.855859 -160.370565) (xy 55.894213 -160.333435) (xy 55.937367 -160.302013)
			(xy 55.984481 -160.276914) (xy 56.034633 -160.258628) (xy 56.086844 -160.247511) (xy 56.140096 -160.243781)
			(xy 56.193348 -160.247511) (xy 56.245559 -160.258628) (xy 56.295711 -160.276914) (xy 56.342825 -160.302013)
			(xy 56.385979 -160.333435) (xy 56.424333 -160.370565) (xy 56.441086 -160.391348) (xy 56.448701 -160.400147)
			(xy 56.469596 -160.410333) (xy 56.481218 -160.410906) (xy 56.560974 -160.410906) (xy 56.572602 -160.410335)
			(xy 56.593512 -160.400169) (xy 56.601106 -160.391348) (xy 56.617859 -160.370565) (xy 56.656213 -160.333435)
			(xy 56.699367 -160.302013) (xy 56.746481 -160.276914) (xy 56.796633 -160.258628) (xy 56.848844 -160.247511)
			(xy 56.902096 -160.243781) (xy 56.955348 -160.247511) (xy 57.007559 -160.258628) (xy 57.057711 -160.276914)
			(xy 57.104825 -160.302013) (xy 57.147979 -160.333435) (xy 57.186333 -160.370565) (xy 57.203086 -160.391348)
			(xy 57.210701 -160.400147) (xy 57.231596 -160.410333) (xy 57.243218 -160.410906) (xy 57.322974 -160.410906)
			(xy 57.334602 -160.410335) (xy 57.355512 -160.400169) (xy 57.363106 -160.391348) (xy 57.38128 -160.368851)
			(xy 57.423305 -160.329119) (xy 57.470844 -160.296183) (xy 57.522808 -160.270797) (xy 57.578008 -160.253544)
			(xy 57.635179 -160.244816) (xy 57.664096 -160.244282) (xy 57.691348 -160.244765) (xy 57.745298 -160.252521)
			(xy 57.797595 -160.267877) (xy 57.847175 -160.290518) (xy 57.893027 -160.319985) (xy 57.934219 -160.355678)
			(xy 57.969912 -160.39687) (xy 57.99938 -160.442722) (xy 58.022022 -160.492301) (xy 58.037378 -160.544598)
			(xy 58.045135 -160.598548) (xy 58.045135 -160.653052) (xy 58.037378 -160.707002) (xy 58.022022 -160.759299)
			(xy 57.99938 -160.808878) (xy 57.969912 -160.85473) (xy 57.934219 -160.895922) (xy 57.893027 -160.931615)
			(xy 57.847175 -160.961082) (xy 57.797595 -160.983723) (xy 57.745298 -160.999079) (xy 57.691348 -161.006835)
			(xy 57.664096 -161.007298) (xy 57.635179 -161.006783) (xy 57.578008 -160.998053) (xy 57.522809 -160.980795)
			(xy 57.470847 -160.955403) (xy 57.423313 -160.922458) (xy 57.381296 -160.882717) (xy 57.363106 -160.860232)
			(xy 57.355498 -160.851426) (xy 57.334598 -160.841245) (xy 57.322974 -160.840674) (xy 57.243218 -160.840674)
			(xy 57.231585 -160.841212) (xy 57.210674 -160.851399) (xy 57.203086 -160.860232) (xy 57.186333 -160.881015)
			(xy 57.147979 -160.918145) (xy 57.104825 -160.949567) (xy 57.057711 -160.974666) (xy 57.007559 -160.992952)
			(xy 56.955348 -161.004069) (xy 56.902096 -161.007799) (xy 56.848844 -161.004069) (xy 56.796633 -160.992952)
			(xy 56.746481 -160.974666) (xy 56.699367 -160.949567) (xy 56.656213 -160.918145) (xy 56.617859 -160.881015)
			(xy 56.601106 -160.860232) (xy 56.593498 -160.851426) (xy 56.572598 -160.841245) (xy 56.560974 -160.840674)
			(xy 56.481218 -160.840674) (xy 56.469585 -160.841212) (xy 56.448674 -160.851399) (xy 56.441086 -160.860232)
			(xy 56.424333 -160.881015) (xy 56.385979 -160.918145) (xy 56.342825 -160.949567) (xy 56.295711 -160.974666)
			(xy 56.245559 -160.992952) (xy 56.193348 -161.004069) (xy 56.140096 -161.007799) (xy 56.086844 -161.004069)
			(xy 56.034633 -160.992952) (xy 55.984481 -160.974666) (xy 55.937367 -160.949567) (xy 55.894213 -160.918145)
			(xy 55.855859 -160.881015) (xy 55.839106 -160.860232) (xy 55.831498 -160.851426) (xy 55.810598 -160.841245)
			(xy 55.798974 -160.840674) (xy 55.719218 -160.840674) (xy 55.707585 -160.841212) (xy 55.686674 -160.851399)
			(xy 55.679086 -160.860232) (xy 55.660911 -160.882729) (xy 55.618887 -160.922462) (xy 55.571348 -160.955398)
			(xy 55.519384 -160.980784) (xy 55.464184 -160.998038) (xy 55.407013 -161.006764) (xy 55.378096 -161.007298)
			(xy 55.350844 -161.006832) (xy 55.296896 -160.999075) (xy 55.2446 -160.983719) (xy 55.195022 -160.961077)
			(xy 55.149171 -160.93161) (xy 55.10798 -160.895917) (xy 55.072288 -160.854726) (xy 55.042821 -160.808875)
			(xy 55.02018 -160.759296) (xy 55.004824 -160.707001) (xy 54.997068 -160.653052) (xy 50.56124 -160.653052)
			(xy 50.56124 -164.588698) (xy 65.341246 -164.588698) (xy 65.341732 -164.561447) (xy 65.349488 -164.507499)
			(xy 65.364843 -164.455204) (xy 65.387485 -164.405627) (xy 65.416951 -164.359777) (xy 65.452642 -164.318586)
			(xy 65.493833 -164.282895) (xy 65.539683 -164.253429) (xy 65.58926 -164.230787) (xy 65.641555 -164.215432)
			(xy 65.695503 -164.207676) (xy 65.750005 -164.207676) (xy 65.803953 -164.215432) (xy 65.856248 -164.230787)
			(xy 65.905825 -164.253429) (xy 65.951675 -164.282895) (xy 65.992866 -164.318586) (xy 66.028557 -164.359777)
			(xy 66.058023 -164.405627) (xy 66.080665 -164.455204) (xy 66.09602 -164.507499) (xy 66.103776 -164.561447)
			(xy 66.104262 -164.588698) (xy 66.10363 -164.620262) (xy 66.093232 -164.682528) (xy 66.072735 -164.742237)
			(xy 66.058288 -164.770308) (xy 66.053462 -164.779198) (xy 66.05143 -164.798756) (xy 66.07429 -164.877242)
			(xy 66.077525 -164.886667) (xy 66.089946 -164.902225) (xy 66.09842 -164.907468) (xy 66.105786 -164.911532)
			(xy 66.115692 -164.917374) (xy 66.137536 -164.919406) (xy 66.232278 -164.885878) (xy 66.248026 -164.870384)
			(xy 66.25209 -164.85997) (xy 66.262762 -164.833183) (xy 66.291054 -164.782942) (xy 66.326587 -164.737533)
			(xy 66.368553 -164.697991) (xy 66.415994 -164.665219) (xy 66.467828 -164.639963) (xy 66.522874 -164.622799)
			(xy 66.579876 -164.614118) (xy 66.608706 -164.61359) (xy 66.635957 -164.61408) (xy 66.689904 -164.621837)
			(xy 66.742197 -164.637193) (xy 66.791774 -164.659834) (xy 66.837623 -164.689301) (xy 66.878812 -164.724992)
			(xy 66.914503 -164.766182) (xy 66.943969 -164.812032) (xy 66.966609 -164.861608) (xy 66.981964 -164.913902)
			(xy 66.98972 -164.967849) (xy 66.98972 -165.022351) (xy 66.981964 -165.076298) (xy 66.972618 -165.108128)
			(xy 67.231514 -165.108128) (xy 67.232013 -165.080654) (xy 67.239902 -165.026275) (xy 67.255519 -164.973592)
			(xy 67.27854 -164.923699) (xy 67.30849 -164.87763) (xy 67.326256 -164.856668) (xy 67.32651 -164.856414)
			(xy 67.332098 -164.849328) (xy 67.338344 -164.832411) (xy 67.338702 -164.823394) (xy 67.338702 -164.75583)
			(xy 67.33833 -164.746815) (xy 67.332093 -164.729898) (xy 67.32651 -164.72281) (xy 67.326002 -164.722302)
			(xy 67.308274 -164.701352) (xy 67.27839 -164.65532) (xy 67.255423 -164.605476) (xy 67.239847 -164.552852)
			(xy 67.231985 -164.498537) (xy 67.231514 -164.471096) (xy 67.232 -164.443845) (xy 67.239756 -164.389897)
			(xy 67.255111 -164.337602) (xy 67.277753 -164.288025) (xy 67.307219 -164.242175) (xy 67.34291 -164.200984)
			(xy 67.384101 -164.165293) (xy 67.429951 -164.135827) (xy 67.479528 -164.113185) (xy 67.531823 -164.09783)
			(xy 67.585771 -164.090074) (xy 67.640273 -164.090074) (xy 67.694221 -164.09783) (xy 67.746516 -164.113185)
			(xy 67.796093 -164.135827) (xy 67.841943 -164.165293) (xy 67.883134 -164.200984) (xy 67.918825 -164.242175)
			(xy 67.948291 -164.288025) (xy 67.970933 -164.337602) (xy 67.986288 -164.389897) (xy 67.994044 -164.443845)
			(xy 67.99453 -164.471096) (xy 67.994034 -164.49857) (xy 67.986143 -164.552949) (xy 67.970525 -164.605631)
			(xy 67.947503 -164.655524) (xy 67.917554 -164.701593) (xy 67.899788 -164.722556) (xy 67.899534 -164.72281)
			(xy 67.893929 -164.729884) (xy 67.887695 -164.746811) (xy 67.887342 -164.75583) (xy 67.887342 -164.823394)
			(xy 67.887693 -164.832412) (xy 67.893944 -164.849329) (xy 67.899534 -164.856414) (xy 67.900042 -164.856922)
			(xy 67.917773 -164.877871) (xy 67.947658 -164.923902) (xy 67.970625 -164.973746) (xy 67.9862 -165.026371)
			(xy 67.99406 -165.080687) (xy 67.99453 -165.108128) (xy 67.994044 -165.135379) (xy 67.992411 -165.146736)
			(xy 68.56933 -165.146736) (xy 68.573401 -165.091114) (xy 68.585527 -165.036677) (xy 68.60545 -164.984586)
			(xy 68.632746 -164.935951) (xy 68.666832 -164.891808) (xy 68.706981 -164.853099) (xy 68.752339 -164.820648)
			(xy 68.801939 -164.795147) (xy 68.854723 -164.77714) (xy 68.909566 -164.76701) (xy 68.9653 -164.764973)
			(xy 69.020737 -164.771073) (xy 69.074694 -164.785179) (xy 69.126023 -164.806991) (xy 69.173629 -164.836045)
			(xy 69.216497 -164.87172) (xy 69.253714 -164.913257) (xy 69.284487 -164.95977) (xy 69.308159 -165.010267)
			(xy 69.324227 -165.063674) (xy 69.332347 -165.11885) (xy 69.332856 -165.146736) (xy 69.332347 -165.174622)
			(xy 69.324227 -165.229798) (xy 69.308159 -165.283205) (xy 69.284487 -165.333702) (xy 69.253714 -165.380215)
			(xy 69.216497 -165.421752) (xy 69.173629 -165.457427) (xy 69.126023 -165.486481) (xy 69.074694 -165.508293)
			(xy 69.020737 -165.522399) (xy 68.9653 -165.528499) (xy 68.909566 -165.526462) (xy 68.854723 -165.516332)
			(xy 68.801939 -165.498325) (xy 68.752339 -165.472824) (xy 68.706981 -165.440373) (xy 68.666832 -165.401664)
			(xy 68.632746 -165.357521) (xy 68.60545 -165.308886) (xy 68.585527 -165.256795) (xy 68.573401 -165.202358)
			(xy 68.56933 -165.146736) (xy 67.992411 -165.146736) (xy 67.986288 -165.189327) (xy 67.970933 -165.241622)
			(xy 67.948291 -165.291199) (xy 67.918825 -165.337049) (xy 67.883134 -165.37824) (xy 67.841943 -165.413931)
			(xy 67.796093 -165.443397) (xy 67.746516 -165.466039) (xy 67.694221 -165.481394) (xy 67.640273 -165.48915)
			(xy 67.585771 -165.48915) (xy 67.531823 -165.481394) (xy 67.479528 -165.466039) (xy 67.429951 -165.443397)
			(xy 67.384101 -165.413931) (xy 67.34291 -165.37824) (xy 67.307219 -165.337049) (xy 67.277753 -165.291199)
			(xy 67.255111 -165.241622) (xy 67.239756 -165.189327) (xy 67.232 -165.135379) (xy 67.231514 -165.108128)
			(xy 66.972618 -165.108128) (xy 66.966609 -165.128592) (xy 66.943969 -165.178168) (xy 66.914503 -165.224018)
			(xy 66.878812 -165.265208) (xy 66.837623 -165.300899) (xy 66.791774 -165.330366) (xy 66.742197 -165.353007)
			(xy 66.689904 -165.368363) (xy 66.635957 -165.37612) (xy 66.608706 -165.376606) (xy 66.608452 -165.376606)
			(xy 66.583249 -165.376191) (xy 66.533281 -165.369557) (xy 66.484626 -165.356385) (xy 66.438136 -165.336906)
			(xy 66.416174 -165.324536) (xy 66.406268 -165.318694) (xy 66.384424 -165.316662) (xy 66.289682 -165.35019)
			(xy 66.273934 -165.365684) (xy 66.26987 -165.376098) (xy 66.259131 -165.402856) (xy 66.230849 -165.453096)
			(xy 66.195325 -165.498506) (xy 66.15337 -165.538049) (xy 66.105939 -165.570825) (xy 66.054114 -165.596086)
			(xy 65.999076 -165.613257) (xy 65.942081 -165.621945) (xy 65.913254 -165.622478) (xy 65.886 -165.622065)
			(xy 65.832048 -165.614301) (xy 65.77975 -165.598939) (xy 65.730171 -165.57629) (xy 65.684319 -165.546816)
			(xy 65.643129 -165.511117) (xy 65.607438 -165.46992) (xy 65.577973 -165.424062) (xy 65.555335 -165.374478)
			(xy 65.539982 -165.322177) (xy 65.53223 -165.268224) (xy 65.531746 -165.24097) (xy 65.532404 -165.209407)
			(xy 65.542791 -165.147142) (xy 65.563278 -165.087432) (xy 65.57772 -165.05936) (xy 65.582546 -165.05047)
			(xy 65.584578 -165.030912) (xy 65.561718 -164.952426) (xy 65.558453 -164.943013) (xy 65.546054 -164.927448)
			(xy 65.537588 -164.9222) (xy 65.5125 -164.907631) (xy 65.466618 -164.87213) (xy 65.426643 -164.830089)
			(xy 65.393497 -164.782479) (xy 65.367944 -164.730398) (xy 65.350574 -164.675047) (xy 65.341788 -164.617704)
			(xy 65.341246 -164.588698) (xy 50.56124 -164.588698) (xy 50.56124 -166.86276) (xy 61.555122 -166.86276)
			(xy 61.555621 -166.835187) (xy 61.563566 -166.780615) (xy 61.579284 -166.727755) (xy 61.602447 -166.677709)
			(xy 61.632574 -166.631519) (xy 61.669037 -166.590146) (xy 61.689742 -166.57193) (xy 61.697811 -166.564369)
			(xy 61.707167 -166.544362) (xy 61.707776 -166.533322) (xy 61.707776 -166.455598) (xy 61.707161 -166.444554)
			(xy 61.697829 -166.424532) (xy 61.689742 -166.41699) (xy 61.669031 -166.398778) (xy 61.632559 -166.357411)
			(xy 61.602426 -166.311221) (xy 61.57926 -166.261173) (xy 61.563544 -166.20831) (xy 61.555606 -166.153735)
			(xy 61.555122 -166.12616) (xy 61.555621 -166.098587) (xy 61.563566 -166.044015) (xy 61.579284 -165.991155)
			(xy 61.602447 -165.941109) (xy 61.632574 -165.894919) (xy 61.669037 -165.853546) (xy 61.689742 -165.83533)
			(xy 61.697811 -165.827769) (xy 61.707167 -165.807762) (xy 61.707776 -165.796722) (xy 61.707776 -165.718998)
			(xy 61.707161 -165.707954) (xy 61.697829 -165.687932) (xy 61.689742 -165.68039) (xy 61.669031 -165.662178)
			(xy 61.632559 -165.620811) (xy 61.602426 -165.574621) (xy 61.57926 -165.524573) (xy 61.563544 -165.47171)
			(xy 61.555606 -165.417135) (xy 61.555122 -165.38956) (xy 61.555541 -165.362306) (xy 61.563303 -165.308355)
			(xy 61.578665 -165.256057) (xy 61.601313 -165.206478) (xy 61.630786 -165.160626) (xy 61.666485 -165.119435)
			(xy 61.707682 -165.083744) (xy 61.753539 -165.05428) (xy 61.803123 -165.031641) (xy 61.855423 -165.016289)
			(xy 61.909376 -165.008536) (xy 61.93663 -165.008052) (xy 61.964488 -165.008509) (xy 62.019608 -165.016639)
			(xy 62.072962 -165.032691) (xy 62.123417 -165.056325) (xy 62.169903 -165.08704) (xy 62.211432 -165.124184)
			(xy 62.247123 -165.166968) (xy 62.276219 -165.214484) (xy 62.298101 -165.265723) (xy 62.305692 -165.292532)
			(xy 62.307978 -165.301422) (xy 62.318646 -165.316662) (xy 62.390528 -165.364414) (xy 62.408562 -165.368478)
			(xy 62.417706 -165.367208) (xy 62.430723 -165.36554) (xy 62.456907 -165.363759) (xy 62.47003 -165.363652)
			(xy 62.484179 -165.363743) (xy 62.512402 -165.365779) (xy 62.526418 -165.367716) (xy 62.536324 -165.36924)
			(xy 62.556136 -165.364414) (xy 62.630558 -165.308534) (xy 62.640718 -165.291008) (xy 62.641988 -165.280848)
			(xy 62.646066 -165.253693) (xy 62.66104 -165.200862) (xy 62.683433 -165.150723) (xy 62.712781 -165.104313)
			(xy 62.74848 -165.062588) (xy 62.789791 -165.026412) (xy 62.835861 -164.996531) (xy 62.885739 -164.973563)
			(xy 62.938393 -164.957982) (xy 62.992738 -164.95011) (xy 63.020194 -164.949632) (xy 63.047449 -164.950061)
			(xy 63.101403 -164.957818) (xy 63.153704 -164.973176) (xy 63.203286 -164.99582) (xy 63.249142 -165.025291)
			(xy 63.290335 -165.060989) (xy 63.326029 -165.102186) (xy 63.355496 -165.148043) (xy 63.378136 -165.197628)
			(xy 63.393489 -165.249931) (xy 63.401241 -165.303885) (xy 63.401702 -165.33114) (xy 63.401194 -165.358713)
			(xy 63.39325 -165.413284) (xy 63.377533 -165.466143) (xy 63.354371 -165.516189) (xy 63.324246 -165.56238)
			(xy 63.287786 -165.603753) (xy 63.267082 -165.62197) (xy 63.259017 -165.629535) (xy 63.249658 -165.649539)
			(xy 63.249048 -165.660578) (xy 63.249048 -165.738302) (xy 63.249655 -165.749347) (xy 63.258991 -165.769369)
			(xy 63.267082 -165.77691) (xy 63.287798 -165.795116) (xy 63.324268 -165.836486) (xy 63.3544 -165.882676)
			(xy 63.377566 -165.932725) (xy 63.393281 -165.985589) (xy 63.401218 -166.040165) (xy 63.401252 -166.042086)
			(xy 67.99021 -166.042086) (xy 67.994281 -165.986464) (xy 68.006407 -165.932027) (xy 68.02633 -165.879936)
			(xy 68.053626 -165.831301) (xy 68.087712 -165.787158) (xy 68.127861 -165.748449) (xy 68.173219 -165.715998)
			(xy 68.222819 -165.690497) (xy 68.275603 -165.67249) (xy 68.330446 -165.66236) (xy 68.38618 -165.660323)
			(xy 68.441617 -165.666423) (xy 68.495574 -165.680529) (xy 68.546903 -165.702341) (xy 68.594509 -165.731395)
			(xy 68.637377 -165.76707) (xy 68.674594 -165.808607) (xy 68.705367 -165.85512) (xy 68.729039 -165.905617)
			(xy 68.745107 -165.959024) (xy 68.753227 -166.0142) (xy 68.753736 -166.042086) (xy 68.753227 -166.069972)
			(xy 68.745107 -166.125148) (xy 68.729039 -166.178555) (xy 68.705367 -166.229052) (xy 68.674594 -166.275565)
			(xy 68.637377 -166.317102) (xy 68.594509 -166.352777) (xy 68.546903 -166.381831) (xy 68.495574 -166.403643)
			(xy 68.441617 -166.417749) (xy 68.38618 -166.423849) (xy 68.330446 -166.421812) (xy 68.275603 -166.411682)
			(xy 68.222819 -166.393675) (xy 68.173219 -166.368174) (xy 68.127861 -166.335723) (xy 68.087712 -166.297014)
			(xy 68.053626 -166.252871) (xy 68.02633 -166.204236) (xy 68.006407 -166.152145) (xy 67.994281 -166.097708)
			(xy 67.99021 -166.042086) (xy 63.401252 -166.042086) (xy 63.401702 -166.06774) (xy 63.401259 -166.094993)
			(xy 63.393497 -166.148942) (xy 63.378137 -166.201238) (xy 63.355491 -166.250816) (xy 63.32602 -166.296666)
			(xy 63.290324 -166.337856) (xy 63.249129 -166.373547) (xy 63.203275 -166.403013) (xy 63.153695 -166.425653)
			(xy 63.101397 -166.441007) (xy 63.047447 -166.448763) (xy 63.020194 -166.449248) (xy 63.019686 -166.449248)
			(xy 62.985904 -166.447724) (xy 62.975744 -166.446708) (xy 62.95644 -166.452804) (xy 62.893448 -166.505636)
			(xy 62.886156 -166.512357) (xy 62.876877 -166.529864) (xy 62.875414 -166.539672) (xy 62.875414 -166.540434)
			(xy 62.872452 -166.568594) (xy 62.859246 -166.623654) (xy 62.838045 -166.676157) (xy 62.809314 -166.724948)
			(xy 62.773684 -166.768954) (xy 62.73194 -166.807209) (xy 62.684998 -166.838872) (xy 62.633891 -166.863246)
			(xy 62.579742 -166.879795) (xy 62.523741 -166.888157) (xy 62.49543 -166.888668) (xy 62.477411 -166.888452)
			(xy 62.441536 -166.885014) (xy 62.423802 -166.88181) (xy 62.41415 -166.880032) (xy 62.3951 -166.883588)
			(xy 62.32017 -166.931594) (xy 62.30874 -166.947342) (xy 62.306454 -166.95674) (xy 62.29908 -166.983791)
			(xy 62.277449 -167.03552) (xy 62.248482 -167.083526) (xy 62.212804 -167.126779) (xy 62.171182 -167.164346)
			(xy 62.124511 -167.195419) (xy 62.073796 -167.21933) (xy 62.020129 -167.235564) (xy 61.964664 -167.243771)
			(xy 61.93663 -167.244268) (xy 61.909376 -167.243817) (xy 61.855423 -167.236063) (xy 61.803122 -167.220708)
			(xy 61.753539 -167.198067) (xy 61.707684 -167.168598) (xy 61.66649 -167.132903) (xy 61.630796 -167.091708)
			(xy 61.601329 -167.045852) (xy 61.578688 -166.996269) (xy 61.563335 -166.943968) (xy 61.555583 -166.890014)
			(xy 61.555122 -166.86276) (xy 50.56124 -166.86276) (xy 50.56124 -168.42232) (xy 63.19774 -168.42232)
			(xy 63.198205 -168.394745) (xy 63.206156 -168.340172) (xy 63.22188 -168.287311) (xy 63.24505 -168.237265)
			(xy 63.275183 -168.191076) (xy 63.311652 -168.149705) (xy 63.33236 -168.13149) (xy 63.340449 -168.123948)
			(xy 63.349793 -168.103926) (xy 63.350394 -168.092882) (xy 63.350394 -168.015158) (xy 63.349795 -168.004112)
			(xy 63.340452 -167.984091) (xy 63.33236 -167.97655) (xy 63.311662 -167.958325) (xy 63.275192 -167.916958)
			(xy 63.245059 -167.870771) (xy 63.221892 -167.820726) (xy 63.206172 -167.767866) (xy 63.198228 -167.713294)
			(xy 63.19774 -167.68572) (xy 63.198161 -167.659185) (xy 63.205502 -167.606625) (xy 63.22006 -167.555591)
			(xy 63.241552 -167.507068) (xy 63.269564 -167.461993) (xy 63.303555 -167.421238) (xy 63.342869 -167.385588)
			(xy 63.386745 -167.355734) (xy 63.410338 -167.343582) (xy 63.420752 -167.338502) (xy 63.43523 -167.319706)
			(xy 63.455804 -167.217344) (xy 63.449708 -167.194484) (xy 63.441834 -167.185594) (xy 63.424552 -167.165109)
			(xy 63.395397 -167.12014) (xy 63.372986 -167.071458) (xy 63.357783 -167.020066) (xy 63.350099 -166.967027)
			(xy 63.349632 -166.94023) (xy 63.350062 -166.913611) (xy 63.357636 -166.860913) (xy 63.372633 -166.809831)
			(xy 63.394748 -166.761403) (xy 63.423531 -166.716615) (xy 63.458395 -166.676381) (xy 63.498631 -166.641519)
			(xy 63.54342 -166.612738) (xy 63.591849 -166.590626) (xy 63.642933 -166.575631) (xy 63.695631 -166.568061)
			(xy 63.72225 -166.567612) (xy 63.748673 -166.568038) (xy 63.80099 -166.575495) (xy 63.851729 -166.590267)
			(xy 63.899873 -166.612058) (xy 63.944456 -166.640431) (xy 63.96482 -166.657274) (xy 63.971678 -166.663116)
			(xy 63.988696 -166.669466) (xy 64.073024 -166.669466) (xy 64.090042 -166.663116) (xy 64.0969 -166.657274)
			(xy 64.117266 -166.640435) (xy 64.161852 -166.61207) (xy 64.209996 -166.590283) (xy 64.260733 -166.575512)
			(xy 64.313048 -166.568052) (xy 64.365892 -166.568052) (xy 64.418207 -166.575512) (xy 64.468944 -166.590283)
			(xy 64.517088 -166.61207) (xy 64.561674 -166.640435) (xy 64.58204 -166.657274) (xy 64.588898 -166.663116)
			(xy 64.605916 -166.669466) (xy 64.690244 -166.669466) (xy 64.707262 -166.663116) (xy 64.71412 -166.657274)
			(xy 64.734487 -166.640438) (xy 64.779076 -166.61208) (xy 64.82722 -166.590299) (xy 64.877956 -166.575531)
			(xy 64.930269 -166.568072) (xy 64.95669 -166.567612) (xy 64.984579 -166.568046) (xy 65.039736 -166.576358)
			(xy 65.093037 -166.592798) (xy 65.143292 -166.616999) (xy 65.18938 -166.64842) (xy 65.230269 -166.686358)
			(xy 65.265047 -166.729968) (xy 65.292937 -166.778274) (xy 65.313316 -166.830197) (xy 65.325728 -166.884577)
			(xy 65.329897 -166.9402) (xy 65.325728 -166.995823) (xy 65.313316 -167.050203) (xy 65.292937 -167.102126)
			(xy 65.265047 -167.150432) (xy 65.230269 -167.194042) (xy 65.18938 -167.23198) (xy 65.143292 -167.263401)
			(xy 65.093037 -167.287602) (xy 65.039736 -167.304042) (xy 64.984579 -167.312354) (xy 64.95669 -167.312848)
			(xy 64.930269 -167.312385) (xy 64.877954 -167.304934) (xy 64.827216 -167.29017) (xy 64.779071 -167.268388)
			(xy 64.734486 -167.240024) (xy 64.71412 -167.223186) (xy 64.707262 -167.217344) (xy 64.690244 -167.210994)
			(xy 64.605916 -167.210994) (xy 64.588898 -167.217344) (xy 64.58204 -167.223186) (xy 64.561674 -167.240025)
			(xy 64.517088 -167.26839) (xy 64.468944 -167.290177) (xy 64.418207 -167.304948) (xy 64.365892 -167.312408)
			(xy 64.313048 -167.312408) (xy 64.260733 -167.304948) (xy 64.209996 -167.290177) (xy 64.161852 -167.26839)
			(xy 64.117266 -167.240025) (xy 64.0969 -167.223186) (xy 64.090042 -167.217344) (xy 64.073024 -167.210994)
			(xy 63.988696 -167.210994) (xy 63.971678 -167.217344) (xy 63.96482 -167.223186) (xy 63.947904 -167.23723)
			(xy 63.911358 -167.261676) (xy 63.891922 -167.271954) (xy 63.881729 -167.277794) (xy 63.867686 -167.296588)
			(xy 63.864998 -167.308022) (xy 63.848234 -167.398954) (xy 63.854838 -167.421814) (xy 63.862712 -167.43045)
			(xy 63.881107 -167.451542) (xy 63.912082 -167.498155) (xy 63.935914 -167.548794) (xy 63.952091 -167.602371)
			(xy 63.960266 -167.657737) (xy 63.960756 -167.68572) (xy 63.960251 -167.713293) (xy 63.952308 -167.767865)
			(xy 63.936592 -167.820725) (xy 63.91343 -167.870771) (xy 63.883303 -167.916962) (xy 63.881378 -167.919146)
			(xy 68.949062 -167.919146) (xy 68.949529 -167.891234) (xy 68.957671 -167.836008) (xy 68.973773 -167.782557)
			(xy 68.997491 -167.732023) (xy 69.028319 -167.685484) (xy 69.046598 -167.664384) (xy 69.052501 -167.657211)
			(xy 69.059148 -167.639883) (xy 69.059552 -167.630602) (xy 69.059552 -167.552878) (xy 69.052948 -167.535606)
			(xy 69.046598 -167.528494) (xy 69.028343 -167.507376) (xy 68.997512 -167.460842) (xy 68.973792 -167.410313)
			(xy 68.957691 -167.356865) (xy 68.94955 -167.301642) (xy 68.949062 -167.273732) (xy 68.949548 -167.246481)
			(xy 68.957304 -167.192533) (xy 68.972659 -167.140238) (xy 68.995301 -167.090661) (xy 69.024767 -167.044811)
			(xy 69.060458 -167.00362) (xy 69.101649 -166.967929) (xy 69.147499 -166.938463) (xy 69.197076 -166.915821)
			(xy 69.249371 -166.900466) (xy 69.303319 -166.89271) (xy 69.357821 -166.89271) (xy 69.411769 -166.900466)
			(xy 69.464064 -166.915821) (xy 69.513641 -166.938463) (xy 69.559491 -166.967929) (xy 69.600682 -167.00362)
			(xy 69.636373 -167.044811) (xy 69.665839 -167.090661) (xy 69.688481 -167.140238) (xy 69.703836 -167.192533)
			(xy 69.711592 -167.246481) (xy 69.712078 -167.273732) (xy 69.711587 -167.301643) (xy 69.70345 -167.356868)
			(xy 69.687353 -167.410318) (xy 69.66364 -167.460853) (xy 69.632818 -167.507393) (xy 69.614542 -167.528494)
			(xy 69.608641 -167.535668) (xy 69.601994 -167.552996) (xy 69.601588 -167.562276) (xy 69.601588 -167.64)
			(xy 69.608192 -167.657272) (xy 69.614542 -167.664384) (xy 69.63284 -167.685466) (xy 69.663664 -167.73201)
			(xy 69.687374 -167.782549) (xy 69.703466 -167.836004) (xy 69.711595 -167.891234) (xy 69.712078 -167.919146)
			(xy 69.711592 -167.946397) (xy 69.703836 -168.000345) (xy 69.688481 -168.05264) (xy 69.665839 -168.102217)
			(xy 69.636373 -168.148067) (xy 69.600682 -168.189258) (xy 69.559491 -168.224949) (xy 69.513641 -168.254415)
			(xy 69.464064 -168.277057) (xy 69.411769 -168.292412) (xy 69.357821 -168.300168) (xy 69.303319 -168.300168)
			(xy 69.249371 -168.292412) (xy 69.197076 -168.277057) (xy 69.147499 -168.254415) (xy 69.101649 -168.224949)
			(xy 69.060458 -168.189258) (xy 69.024767 -168.148067) (xy 68.995301 -168.102217) (xy 68.972659 -168.05264)
			(xy 68.957304 -168.000345) (xy 68.949548 -167.946397) (xy 68.949062 -167.919146) (xy 63.881378 -167.919146)
			(xy 63.846841 -167.958334) (xy 63.826136 -167.97655) (xy 63.818028 -167.984075) (xy 63.808694 -168.00411)
			(xy 63.808102 -168.015158) (xy 63.808102 -168.092882) (xy 63.80868 -168.10393) (xy 63.818038 -168.123951)
			(xy 63.826136 -168.13149) (xy 63.846853 -168.149695) (xy 63.883321 -168.191066) (xy 63.913452 -168.237257)
			(xy 63.936616 -168.287306) (xy 63.952332 -168.34017) (xy 63.960271 -168.394745) (xy 63.960756 -168.42232)
			(xy 63.96027 -168.449571) (xy 63.952514 -168.503519) (xy 63.937159 -168.555814) (xy 63.914517 -168.605391)
			(xy 63.885051 -168.651241) (xy 63.84936 -168.692432) (xy 63.808169 -168.728123) (xy 63.762319 -168.757589)
			(xy 63.712742 -168.780231) (xy 63.660447 -168.795586) (xy 63.606499 -168.803342) (xy 63.551997 -168.803342)
			(xy 63.498049 -168.795586) (xy 63.445754 -168.780231) (xy 63.396177 -168.757589) (xy 63.350327 -168.728123)
			(xy 63.309136 -168.692432) (xy 63.273445 -168.651241) (xy 63.243979 -168.605391) (xy 63.221337 -168.555814)
			(xy 63.205982 -168.503519) (xy 63.198226 -168.449571) (xy 63.19774 -168.42232) (xy 50.56124 -168.42232)
			(xy 50.56124 -173.285912) (xy 73.654666 -173.285912) (xy 73.655152 -173.258661) (xy 73.662908 -173.204713)
			(xy 73.678263 -173.152418) (xy 73.700905 -173.102841) (xy 73.730371 -173.056991) (xy 73.766062 -173.0158)
			(xy 73.807253 -172.980109) (xy 73.853103 -172.950643) (xy 73.90268 -172.928001) (xy 73.954975 -172.912646)
			(xy 74.008923 -172.90489) (xy 74.063425 -172.90489) (xy 74.117373 -172.912646) (xy 74.169668 -172.928001)
			(xy 74.219245 -172.950643) (xy 74.265095 -172.980109) (xy 74.306286 -173.0158) (xy 74.341977 -173.056991)
			(xy 74.371443 -173.102841) (xy 74.394085 -173.152418) (xy 74.40944 -173.204713) (xy 74.417196 -173.258661)
			(xy 74.417682 -173.285912) (xy 74.417014 -173.317474) (xy 74.40663 -173.379739) (xy 74.386148 -173.439449)
			(xy 74.371708 -173.467522) (xy 74.366882 -173.476412) (xy 74.36485 -173.49597) (xy 74.38771 -173.574456)
			(xy 74.390933 -173.583887) (xy 74.403362 -173.599442) (xy 74.41184 -173.604682) (xy 74.419206 -173.608746)
			(xy 74.429112 -173.614588) (xy 74.450956 -173.61662) (xy 74.545698 -173.583092) (xy 74.561446 -173.567598)
			(xy 74.56551 -173.557184) (xy 74.576173 -173.530393) (xy 74.604465 -173.480151) (xy 74.639999 -173.43474)
			(xy 74.681966 -173.395199) (xy 74.729408 -173.362426) (xy 74.781244 -173.337171) (xy 74.836291 -173.320009)
			(xy 74.893296 -173.311331) (xy 74.922126 -173.310804) (xy 74.949377 -173.311268) (xy 75.003324 -173.319027)
			(xy 75.055617 -173.334385) (xy 75.105192 -173.357029) (xy 75.151041 -173.386496) (xy 75.192229 -173.422189)
			(xy 75.227919 -173.46338) (xy 75.257384 -173.509231) (xy 75.280024 -173.558808) (xy 75.295378 -173.611102)
			(xy 75.303134 -173.665049) (xy 75.303134 -173.719551) (xy 75.295378 -173.773498) (xy 75.286028 -173.805342)
			(xy 75.544934 -173.805342) (xy 75.545437 -173.777868) (xy 75.553323 -173.723489) (xy 75.568939 -173.670806)
			(xy 75.59196 -173.620913) (xy 75.621909 -173.574844) (xy 75.639676 -173.553882) (xy 75.63993 -173.553628)
			(xy 75.645514 -173.54654) (xy 75.651761 -173.529624) (xy 75.652122 -173.520608) (xy 75.652122 -173.453044)
			(xy 75.651739 -173.44403) (xy 75.645509 -173.427113) (xy 75.63993 -173.420024) (xy 75.639422 -173.419516)
			(xy 75.621703 -173.398558) (xy 75.591818 -173.352528) (xy 75.568848 -173.302687) (xy 75.55327 -173.250064)
			(xy 75.545406 -173.19575) (xy 75.544934 -173.16831) (xy 75.54542 -173.141059) (xy 75.553176 -173.087111)
			(xy 75.568531 -173.034816) (xy 75.591173 -172.985239) (xy 75.620639 -172.939389) (xy 75.65633 -172.898198)
			(xy 75.697521 -172.862507) (xy 75.743371 -172.833041) (xy 75.792948 -172.810399) (xy 75.845243 -172.795044)
			(xy 75.899191 -172.787288) (xy 75.953693 -172.787288) (xy 76.007641 -172.795044) (xy 76.059936 -172.810399)
			(xy 76.109513 -172.833041) (xy 76.155363 -172.862507) (xy 76.196554 -172.898198) (xy 76.232245 -172.939389)
			(xy 76.261711 -172.985239) (xy 76.284353 -173.034816) (xy 76.299708 -173.087111) (xy 76.307464 -173.141059)
			(xy 76.30795 -173.16831) (xy 76.307482 -173.195785) (xy 76.299587 -173.250166) (xy 76.283964 -173.302849)
			(xy 76.260935 -173.352742) (xy 76.230978 -173.398809) (xy 76.213208 -173.41977) (xy 76.212954 -173.420024)
			(xy 76.207346 -173.427096) (xy 76.201113 -173.444024) (xy 76.200762 -173.453044) (xy 76.200762 -173.520608)
			(xy 76.201123 -173.529624) (xy 76.207369 -173.546541) (xy 76.212954 -173.553628) (xy 76.213462 -173.554136)
			(xy 76.231203 -173.575077) (xy 76.261085 -173.62111) (xy 76.284051 -173.670957) (xy 76.299624 -173.723584)
			(xy 76.307481 -173.777901) (xy 76.30795 -173.805342) (xy 76.307464 -173.832593) (xy 76.305831 -173.84395)
			(xy 76.88275 -173.84395) (xy 76.886821 -173.788328) (xy 76.898947 -173.733891) (xy 76.91887 -173.6818)
			(xy 76.946166 -173.633165) (xy 76.980252 -173.589022) (xy 77.020401 -173.550313) (xy 77.065759 -173.517862)
			(xy 77.115359 -173.492361) (xy 77.168143 -173.474354) (xy 77.222986 -173.464224) (xy 77.27872 -173.462187)
			(xy 77.334157 -173.468287) (xy 77.388114 -173.482393) (xy 77.439443 -173.504205) (xy 77.487049 -173.533259)
			(xy 77.529917 -173.568934) (xy 77.567134 -173.610471) (xy 77.589183 -173.643798) (xy 80.334612 -173.643798)
			(xy 80.334612 -155.015946) (xy 80.33522 -154.990962) (xy 80.344966 -154.941955) (xy 80.364075 -154.895786)
			(xy 80.391813 -154.854225) (xy 80.409034 -154.836114) (xy 84.231988 -151.01316) (xy 84.250104 -150.995927)
			(xy 84.291641 -150.96811) (xy 84.337806 -150.94893) (xy 84.386825 -150.939124) (xy 84.41182 -150.938484)
			(xy 89.119202 -150.938484) (xy 89.129272 -150.938064) (xy 89.14787 -150.93034) (xy 89.15527 -150.923498)
			(xy 90.821002 -149.25802) (xy 90.839106 -149.240773) (xy 90.880648 -149.212961) (xy 90.926816 -149.193785)
			(xy 90.975838 -149.183982) (xy 91.000834 -149.183344) (xy 91.2495 -149.183344) (xy 91.259502 -149.182813)
			(xy 91.277986 -149.175162) (xy 91.292137 -149.161022) (xy 91.299804 -149.142546) (xy 91.3003 -149.132544)
			(xy 91.3003 -148.019262) (xy 91.300789 -147.995341) (xy 91.308316 -147.948093) (xy 91.323147 -147.902607)
			(xy 91.344915 -147.860003) (xy 91.373085 -147.821332) (xy 91.389708 -147.804124) (xy 91.669108 -147.524724)
			(xy 91.686324 -147.508114) (xy 91.725009 -147.479973) (xy 91.767613 -147.458217) (xy 91.813091 -147.44338)
			(xy 91.860328 -147.435826) (xy 91.884246 -147.435316) (xy 97.590864 -147.435316) (xy 97.600934 -147.434894)
			(xy 97.619533 -147.427173) (xy 97.626932 -147.42033) (xy 97.873058 -147.174204) (xy 97.879883 -147.166792)
			(xy 97.887613 -147.148202) (xy 97.888044 -147.138136) (xy 97.888044 -141.480032) (xy 97.890584 -141.444218)
			(xy 97.863152 -141.412468) (xy 97.842324 -141.410944) (xy 97.814791 -141.408419) (xy 97.760835 -141.396341)
			(xy 97.709186 -141.376607) (xy 97.660924 -141.349628) (xy 97.617059 -141.31597) (xy 97.578507 -141.276337)
			(xy 97.546076 -141.231556) (xy 97.520444 -141.182566) (xy 97.502147 -141.130391) (xy 97.496376 -141.10335)
			(xy 97.494007 -141.093564) (xy 97.4829 -141.076795) (xy 97.474786 -141.070838) (xy 97.414842 -141.030706)
			(xy 97.406155 -141.025472) (xy 97.386242 -141.02169) (xy 97.376234 -141.02334) (xy 97.357575 -141.02688)
			(xy 97.319786 -141.030698) (xy 97.300796 -141.03096) (xy 97.300034 -141.03096) (xy 97.273288 -141.030536)
			(xy 97.220321 -141.023048) (xy 97.168918 -141.008242) (xy 97.120084 -140.986407) (xy 97.074775 -140.957971)
			(xy 97.033877 -140.92349) (xy 96.998192 -140.88364) (xy 96.968417 -140.839199) (xy 96.956372 -140.815314)
			(xy 96.951292 -140.804646) (xy 96.933258 -140.790422) (xy 96.832674 -140.767816) (xy 96.810068 -140.77315)
			(xy 96.800924 -140.78077) (xy 96.780402 -140.796895) (xy 96.735811 -140.824015) (xy 96.68794 -140.844804)
			(xy 96.637681 -140.858872) (xy 96.585974 -140.865957) (xy 96.559878 -140.866368) (xy 96.530415 -140.865851)
			(xy 96.472187 -140.856813) (xy 96.416046 -140.838912) (xy 96.389444 -140.826236) (xy 96.379434 -140.821819)
			(xy 96.357587 -140.82104) (xy 96.34728 -140.824712) (xy 96.266 -140.858494) (xy 96.251014 -140.87475)
			(xy 96.247712 -140.885164) (xy 96.238928 -140.910191) (xy 96.215411 -140.957731) (xy 96.185537 -141.001556)
			(xy 96.14988 -141.040821) (xy 96.109128 -141.074768) (xy 96.064066 -141.102744) (xy 96.015565 -141.124208)
			(xy 95.964557 -141.138747) (xy 95.912028 -141.146081) (xy 95.885508 -141.14653) (xy 95.858258 -141.146015)
			(xy 95.804312 -141.13826) (xy 95.75202 -141.122907) (xy 95.702444 -141.100268) (xy 95.656594 -141.070805)
			(xy 95.615405 -141.035117) (xy 95.579713 -140.99393) (xy 95.550246 -140.948083) (xy 95.527604 -140.898509)
			(xy 95.512246 -140.846217) (xy 95.504487 -140.792272) (xy 95.504 -140.765022) (xy 95.504 -140.755624)
			(xy 95.504254 -140.744702) (xy 95.496126 -140.724636) (xy 95.423736 -140.657834) (xy 95.403162 -140.650976)
			(xy 95.392494 -140.651992) (xy 95.35414 -140.654024) (xy 95.326883 -140.653588) (xy 95.272924 -140.645835)
			(xy 95.220618 -140.630482) (xy 95.171029 -140.607841) (xy 95.125167 -140.578373) (xy 95.083966 -140.542678)
			(xy 95.048264 -140.501482) (xy 95.018788 -140.455625) (xy 94.996139 -140.40604) (xy 94.980778 -140.353736)
			(xy 94.973017 -140.299778) (xy 94.973013 -140.245265) (xy 94.980769 -140.191306) (xy 94.996124 -140.139)
			(xy 95.018768 -140.089412) (xy 95.048238 -140.043552) (xy 95.083935 -140.002352) (xy 95.125133 -139.966653)
			(xy 95.170991 -139.937179) (xy 95.220578 -139.914533) (xy 95.272883 -139.899174) (xy 95.326841 -139.891415)
			(xy 95.381354 -139.891415) (xy 95.435312 -139.899173) (xy 95.487617 -139.914531) (xy 95.537204 -139.937177)
			(xy 95.583063 -139.966649) (xy 95.624261 -140.002349) (xy 95.659959 -140.043548) (xy 95.68943 -140.089408)
			(xy 95.712074 -140.138995) (xy 95.72743 -140.191301) (xy 95.735186 -140.245259) (xy 95.735648 -140.272516)
			(xy 95.735648 -140.281914) (xy 95.735394 -140.292836) (xy 95.743522 -140.312902) (xy 95.815912 -140.379704)
			(xy 95.836486 -140.386562) (xy 95.847154 -140.385546) (xy 95.885508 -140.383514) (xy 95.885762 -140.383514)
			(xy 95.915182 -140.384055) (xy 95.973323 -140.393102) (xy 96.029379 -140.410988) (xy 96.055942 -140.423646)
			(xy 96.065955 -140.428055) (xy 96.087799 -140.42884) (xy 96.098106 -140.42517) (xy 96.179386 -140.391388)
			(xy 96.194372 -140.375132) (xy 96.197674 -140.364718) (xy 96.20646 -140.339692) (xy 96.229977 -140.292153)
			(xy 96.259852 -140.248328) (xy 96.29551 -140.209064) (xy 96.336261 -140.175118) (xy 96.381322 -140.147142)
			(xy 96.429823 -140.125678) (xy 96.48083 -140.111138) (xy 96.533359 -140.103802) (xy 96.559878 -140.103352)
			(xy 96.586625 -140.103759) (xy 96.639593 -140.111249) (xy 96.690996 -140.126058) (xy 96.739831 -140.147895)
			(xy 96.78514 -140.176333) (xy 96.826037 -140.210816) (xy 96.861722 -140.250669) (xy 96.891496 -140.295112)
			(xy 96.90354 -140.318998) (xy 96.90862 -140.329666) (xy 96.926654 -140.34389) (xy 97.027238 -140.366496)
			(xy 97.049844 -140.361162) (xy 97.058988 -140.353542) (xy 97.079478 -140.33746) (xy 97.123973 -140.310382)
			(xy 97.171738 -140.28961) (xy 97.221886 -140.275531) (xy 97.273483 -140.268406) (xy 97.299526 -140.267944)
			(xy 97.300034 -140.267944) (xy 97.326337 -140.268382) (xy 97.378441 -140.275627) (xy 97.429057 -140.289961)
			(xy 97.477223 -140.311112) (xy 97.522027 -140.33868) (xy 97.56262 -140.372141) (xy 97.598231 -140.410861)
			(xy 97.628185 -140.454106) (xy 97.651914 -140.501056) (xy 97.668969 -140.55082) (xy 97.67443 -140.576554)
			(xy 97.676796 -140.586341) (xy 97.687905 -140.60311) (xy 97.69602 -140.609066) (xy 97.755964 -140.649198)
			(xy 97.764675 -140.654383) (xy 97.784568 -140.658195) (xy 97.794572 -140.656564) (xy 97.813231 -140.653023)
			(xy 97.85102 -140.649205) (xy 97.87001 -140.648944) (xy 97.870772 -140.648944) (xy 97.897414 -140.649413)
			(xy 97.950184 -140.6568) (xy 97.975928 -140.663676) (xy 97.985082 -140.665901) (xy 98.003841 -140.664331)
			(xy 98.012504 -140.660628) (xy 98.040444 -140.646912) (xy 98.048551 -140.642519) (xy 98.06118 -140.629104)
			(xy 98.065082 -140.62075) (xy 98.077214 -140.593383) (xy 98.110478 -140.543623) (xy 98.131122 -140.521944)
			(xy 98.29546 -140.357606) (xy 98.312652 -140.340978) (xy 98.35134 -140.312857) (xy 98.393954 -140.29114)
			(xy 98.439443 -140.276363) (xy 98.486684 -140.26889) (xy 98.510598 -140.268452) (xy 100.991416 -140.268452)
			(xy 101.015323 -140.268962) (xy 101.062548 -140.276454) (xy 101.108021 -140.291234) (xy 101.150625 -140.312939)
			(xy 101.189313 -140.341037) (xy 101.206554 -140.357606) (xy 101.61143 -140.762482) (xy 101.628009 -140.779719)
			(xy 101.656139 -140.818394) (xy 101.677866 -140.860996) (xy 101.692655 -140.906475) (xy 101.70014 -140.953709)
			(xy 101.700584 -140.97762) (xy 101.700584 -141.6939) (xy 103.389682 -141.6939) (xy 103.393753 -141.638278)
			(xy 103.405879 -141.583841) (xy 103.425802 -141.53175) (xy 103.453098 -141.483115) (xy 103.487184 -141.438972)
			(xy 103.527333 -141.400263) (xy 103.572691 -141.367812) (xy 103.622291 -141.342311) (xy 103.675075 -141.324304)
			(xy 103.729918 -141.314174) (xy 103.785652 -141.312137) (xy 103.841089 -141.318237) (xy 103.895046 -141.332343)
			(xy 103.946375 -141.354155) (xy 103.993981 -141.383209) (xy 104.036849 -141.418884) (xy 104.074066 -141.460421)
			(xy 104.104839 -141.506934) (xy 104.128511 -141.557431) (xy 104.144579 -141.610838) (xy 104.152699 -141.666014)
			(xy 104.153208 -141.6939) (xy 104.152699 -141.721786) (xy 104.144579 -141.776962) (xy 104.128511 -141.830369)
			(xy 104.104839 -141.880866) (xy 104.074066 -141.927379) (xy 104.036849 -141.968916) (xy 103.993981 -142.004591)
			(xy 103.946375 -142.033645) (xy 103.895046 -142.055457) (xy 103.841089 -142.069563) (xy 103.785652 -142.075663)
			(xy 103.729918 -142.073626) (xy 103.675075 -142.063496) (xy 103.622291 -142.045489) (xy 103.572691 -142.019988)
			(xy 103.527333 -141.987537) (xy 103.487184 -141.948828) (xy 103.453098 -141.904685) (xy 103.425802 -141.85605)
			(xy 103.405879 -141.803959) (xy 103.393753 -141.749522) (xy 103.389682 -141.6939) (xy 101.700584 -141.6939)
			(xy 101.700584 -144.103852) (xy 102.455216 -144.103852) (xy 102.459287 -144.04823) (xy 102.471413 -143.993793)
			(xy 102.491336 -143.941702) (xy 102.518632 -143.893067) (xy 102.552718 -143.848924) (xy 102.592867 -143.810215)
			(xy 102.638225 -143.777764) (xy 102.687825 -143.752263) (xy 102.740609 -143.734256) (xy 102.795452 -143.724126)
			(xy 102.851186 -143.722089) (xy 102.906623 -143.728189) (xy 102.96058 -143.742295) (xy 103.011909 -143.764107)
			(xy 103.059515 -143.793161) (xy 103.102383 -143.828836) (xy 103.1396 -143.870373) (xy 103.170373 -143.916886)
			(xy 103.194045 -143.967383) (xy 103.210113 -144.02079) (xy 103.218233 -144.075966) (xy 103.218742 -144.103852)
			(xy 103.218233 -144.131738) (xy 103.210113 -144.186914) (xy 103.194045 -144.240321) (xy 103.170373 -144.290818)
			(xy 103.1396 -144.337331) (xy 103.102383 -144.378868) (xy 103.059515 -144.414543) (xy 103.011909 -144.443597)
			(xy 102.96058 -144.465409) (xy 102.906623 -144.479515) (xy 102.851186 -144.485615) (xy 102.795452 -144.483578)
			(xy 102.740609 -144.473448) (xy 102.687825 -144.455441) (xy 102.638225 -144.42994) (xy 102.592867 -144.397489)
			(xy 102.552718 -144.35878) (xy 102.518632 -144.314637) (xy 102.491336 -144.266002) (xy 102.471413 -144.213911)
			(xy 102.459287 -144.159474) (xy 102.455216 -144.103852) (xy 101.700584 -144.103852) (xy 101.700584 -145.673064)
			(xy 102.076756 -145.673064) (xy 102.080827 -145.617442) (xy 102.092953 -145.563005) (xy 102.112876 -145.510914)
			(xy 102.140172 -145.462279) (xy 102.174258 -145.418136) (xy 102.214407 -145.379427) (xy 102.259765 -145.346976)
			(xy 102.309365 -145.321475) (xy 102.362149 -145.303468) (xy 102.416992 -145.293338) (xy 102.472726 -145.291301)
			(xy 102.528163 -145.297401) (xy 102.58212 -145.311507) (xy 102.633449 -145.333319) (xy 102.681055 -145.362373)
			(xy 102.723923 -145.398048) (xy 102.76114 -145.439585) (xy 102.763024 -145.442432) (xy 103.786176 -145.442432)
			(xy 103.790247 -145.38681) (xy 103.802373 -145.332373) (xy 103.822296 -145.280282) (xy 103.849592 -145.231647)
			(xy 103.883678 -145.187504) (xy 103.923827 -145.148795) (xy 103.969185 -145.116344) (xy 104.018785 -145.090843)
			(xy 104.071569 -145.072836) (xy 104.126412 -145.062706) (xy 104.182146 -145.060669) (xy 104.237583 -145.066769)
			(xy 104.29154 -145.080875) (xy 104.342869 -145.102687) (xy 104.390475 -145.131741) (xy 104.433343 -145.167416)
			(xy 104.47056 -145.208953) (xy 104.501333 -145.255466) (xy 104.525005 -145.305963) (xy 104.541073 -145.35937)
			(xy 104.549193 -145.414546) (xy 104.549702 -145.442432) (xy 104.549193 -145.470318) (xy 104.541073 -145.525494)
			(xy 104.525005 -145.578901) (xy 104.501333 -145.629398) (xy 104.47056 -145.675911) (xy 104.433343 -145.717448)
			(xy 104.390475 -145.753123) (xy 104.342869 -145.782177) (xy 104.29154 -145.803989) (xy 104.237583 -145.818095)
			(xy 104.182146 -145.824195) (xy 104.126412 -145.822158) (xy 104.071569 -145.812028) (xy 104.018785 -145.794021)
			(xy 103.969185 -145.76852) (xy 103.923827 -145.736069) (xy 103.883678 -145.69736) (xy 103.849592 -145.653217)
			(xy 103.822296 -145.604582) (xy 103.802373 -145.552491) (xy 103.790247 -145.498054) (xy 103.786176 -145.442432)
			(xy 102.763024 -145.442432) (xy 102.791913 -145.486098) (xy 102.815585 -145.536595) (xy 102.831653 -145.590002)
			(xy 102.839773 -145.645178) (xy 102.840282 -145.673064) (xy 102.839773 -145.70095) (xy 102.831653 -145.756126)
			(xy 102.815585 -145.809533) (xy 102.791913 -145.86003) (xy 102.76114 -145.906543) (xy 102.723923 -145.94808)
			(xy 102.681055 -145.983755) (xy 102.633449 -146.012809) (xy 102.58212 -146.034621) (xy 102.528163 -146.048727)
			(xy 102.472726 -146.054827) (xy 102.416992 -146.05279) (xy 102.362149 -146.04266) (xy 102.309365 -146.024653)
			(xy 102.259765 -145.999152) (xy 102.214407 -145.966701) (xy 102.174258 -145.927992) (xy 102.140172 -145.883849)
			(xy 102.112876 -145.835214) (xy 102.092953 -145.783123) (xy 102.080827 -145.728686) (xy 102.076756 -145.673064)
			(xy 101.700584 -145.673064) (xy 101.700584 -149.21738) (xy 101.700364 -149.224945) (xy 101.695975 -149.239421)
			(xy 101.691948 -149.245828) (xy 101.60635 -149.372574) (xy 101.602046 -149.378574) (xy 101.590693 -149.388004)
			(xy 101.583998 -149.391116) (xy 101.510592 -149.42185) (xy 101.49459 -149.441408) (xy 101.492304 -149.453854)
			(xy 101.490437 -149.466254) (xy 101.497643 -149.490241) (xy 101.50602 -149.499574) (xy 107.897676 -155.89123)
			(xy 107.905087 -155.898056) (xy 107.923678 -155.905783) (xy 107.933744 -155.906216) (xy 122.211338 -155.906216)
			(xy 122.221412 -155.905833) (xy 122.240011 -155.898085) (xy 122.247406 -155.89123) (xy 127.972058 -150.166578)
			(xy 127.990177 -150.149366) (xy 128.031733 -150.121622) (xy 128.0779 -150.102511) (xy 128.126907 -150.092768)
			(xy 128.15189 -150.092156) (xy 134.182866 -150.092156) (xy 134.207851 -150.092744) (xy 134.25686 -150.102494)
			(xy 134.303029 -150.121609) (xy 134.344589 -150.149354) (xy 134.362698 -150.166578) (xy 134.729728 -150.533608)
			(xy 136.287 -150.533608) (xy 136.291071 -150.477986) (xy 136.303197 -150.423549) (xy 136.32312 -150.371458)
			(xy 136.350416 -150.322823) (xy 136.384502 -150.27868) (xy 136.424651 -150.239971) (xy 136.470009 -150.20752)
			(xy 136.519609 -150.182019) (xy 136.572393 -150.164012) (xy 136.627236 -150.153882) (xy 136.68297 -150.151845)
			(xy 136.738407 -150.157945) (xy 136.792364 -150.172051) (xy 136.843693 -150.193863) (xy 136.891299 -150.222917)
			(xy 136.934167 -150.258592) (xy 136.971384 -150.300129) (xy 137.002157 -150.346642) (xy 137.025829 -150.397139)
			(xy 137.041897 -150.450546) (xy 137.050017 -150.505722) (xy 137.050526 -150.533608) (xy 137.050017 -150.561494)
			(xy 137.041897 -150.61667) (xy 137.033492 -150.644606) (xy 137.304016 -150.644606) (xy 137.308087 -150.588984)
			(xy 137.320213 -150.534547) (xy 137.340136 -150.482456) (xy 137.367432 -150.433821) (xy 137.401518 -150.389678)
			(xy 137.441667 -150.350969) (xy 137.487025 -150.318518) (xy 137.536625 -150.293017) (xy 137.589409 -150.27501)
			(xy 137.644252 -150.26488) (xy 137.699986 -150.262843) (xy 137.755423 -150.268943) (xy 137.80938 -150.283049)
			(xy 137.860709 -150.304861) (xy 137.908315 -150.333915) (xy 137.951183 -150.36959) (xy 137.9884 -150.411127)
			(xy 138.019173 -150.45764) (xy 138.042845 -150.508137) (xy 138.058913 -150.561544) (xy 138.067033 -150.61672)
			(xy 138.067542 -150.644606) (xy 138.067033 -150.672492) (xy 138.058913 -150.727668) (xy 138.042845 -150.781075)
			(xy 138.019173 -150.831572) (xy 137.9884 -150.878085) (xy 137.951183 -150.919622) (xy 137.908315 -150.955297)
			(xy 137.860709 -150.984351) (xy 137.80938 -151.006163) (xy 137.755423 -151.020269) (xy 137.699986 -151.026369)
			(xy 137.644252 -151.024332) (xy 137.589409 -151.014202) (xy 137.536625 -150.996195) (xy 137.487025 -150.970694)
			(xy 137.441667 -150.938243) (xy 137.401518 -150.899534) (xy 137.367432 -150.855391) (xy 137.340136 -150.806756)
			(xy 137.320213 -150.754665) (xy 137.308087 -150.700228) (xy 137.304016 -150.644606) (xy 137.033492 -150.644606)
			(xy 137.025829 -150.670077) (xy 137.002157 -150.720574) (xy 136.971384 -150.767087) (xy 136.934167 -150.808624)
			(xy 136.891299 -150.844299) (xy 136.843693 -150.873353) (xy 136.792364 -150.895165) (xy 136.738407 -150.909271)
			(xy 136.68297 -150.915371) (xy 136.627236 -150.913334) (xy 136.572393 -150.903204) (xy 136.519609 -150.885197)
			(xy 136.470009 -150.859696) (xy 136.424651 -150.827245) (xy 136.384502 -150.788536) (xy 136.350416 -150.744393)
			(xy 136.32312 -150.695758) (xy 136.303197 -150.643667) (xy 136.291071 -150.58923) (xy 136.287 -150.533608)
			(xy 134.729728 -150.533608) (xy 135.16991 -150.97379) (xy 135.187135 -150.991898) (xy 135.214877 -151.033457)
			(xy 135.233985 -151.079628) (xy 135.243723 -151.128638) (xy 135.244332 -151.153622) (xy 135.244332 -152.27427)
			(xy 135.24375 -152.299255) (xy 135.233998 -152.348265) (xy 135.214882 -152.394434) (xy 135.187135 -152.435993)
			(xy 135.16991 -152.454102) (xy 134.874762 -152.74925) (xy 135.34593 -152.74925) (xy 135.350001 -152.693628)
			(xy 135.362127 -152.639191) (xy 135.38205 -152.5871) (xy 135.409346 -152.538465) (xy 135.443432 -152.494322)
			(xy 135.483581 -152.455613) (xy 135.528939 -152.423162) (xy 135.578539 -152.397661) (xy 135.631323 -152.379654)
			(xy 135.686166 -152.369524) (xy 135.7419 -152.367487) (xy 135.797337 -152.373587) (xy 135.851294 -152.387693)
			(xy 135.902623 -152.409505) (xy 135.950229 -152.438559) (xy 135.993097 -152.474234) (xy 136.030314 -152.515771)
			(xy 136.061087 -152.562284) (xy 136.084759 -152.612781) (xy 136.100827 -152.666188) (xy 136.108947 -152.721364)
			(xy 136.109456 -152.74925) (xy 136.108947 -152.777136) (xy 136.100827 -152.832312) (xy 136.084759 -152.885719)
			(xy 136.061087 -152.936216) (xy 136.030314 -152.982729) (xy 135.993097 -153.024266) (xy 135.950229 -153.059941)
			(xy 135.902623 -153.088995) (xy 135.851294 -153.110807) (xy 135.797337 -153.124913) (xy 135.7419 -153.131013)
			(xy 135.686166 -153.128976) (xy 135.631323 -153.118846) (xy 135.578539 -153.100839) (xy 135.528939 -153.075338)
			(xy 135.483581 -153.042887) (xy 135.443432 -153.004178) (xy 135.409346 -152.960035) (xy 135.38205 -152.9114)
			(xy 135.362127 -152.859309) (xy 135.350001 -152.804872) (xy 135.34593 -152.74925) (xy 134.874762 -152.74925)
			(xy 134.81304 -152.810972) (xy 134.805674 -152.826212) (xy 134.804658 -152.834848) (xy 134.80099 -152.862429)
			(xy 134.786775 -152.91622) (xy 134.764896 -152.967375) (xy 134.735817 -153.014809) (xy 134.700155 -153.057514)
			(xy 134.658667 -153.094586) (xy 134.612233 -153.125236) (xy 134.561839 -153.148815) (xy 134.508554 -153.164823)
			(xy 134.453509 -153.172919) (xy 134.42569 -153.17343) (xy 134.39844 -153.172932) (xy 134.344493 -153.165174)
			(xy 134.2922 -153.149819) (xy 134.242624 -153.127178) (xy 134.196775 -153.097713) (xy 134.155586 -153.062023)
			(xy 134.119894 -153.020835) (xy 134.090427 -152.974986) (xy 134.067785 -152.925411) (xy 134.052428 -152.873118)
			(xy 134.044669 -152.819172) (xy 134.044182 -152.791922) (xy 134.044637 -152.766434) (xy 134.051411 -152.71591)
			(xy 134.064856 -152.666739) (xy 134.084731 -152.619797) (xy 134.110683 -152.575922) (xy 134.142248 -152.535894)
			(xy 134.16026 -152.517856) (xy 134.160514 -152.517602) (xy 134.167688 -152.509864) (xy 134.175551 -152.490307)
			(xy 134.175754 -152.479756) (xy 134.173722 -152.404826) (xy 134.172846 -152.394318) (xy 134.163803 -152.375297)
			(xy 134.156196 -152.367996) (xy 134.155942 -152.367742) (xy 134.135549 -152.349514) (xy 134.099616 -152.30828)
			(xy 134.06994 -152.262337) (xy 134.047131 -152.212627) (xy 134.031655 -152.160168) (xy 134.023831 -152.106037)
			(xy 134.023354 -152.07869) (xy 134.023865 -152.050384) (xy 134.032212 -151.99439) (xy 134.048748 -151.940247)
			(xy 134.073112 -151.889146) (xy 134.104766 -151.84221) (xy 134.143015 -151.800473) (xy 134.187017 -151.764853)
			(xy 134.235803 -151.736134) (xy 134.288301 -151.714947) (xy 134.315708 -151.70785) (xy 134.315962 -151.70785)
			(xy 134.32689 -151.704619) (xy 134.344566 -151.690284) (xy 134.354278 -151.669703) (xy 134.354824 -151.65832)
			(xy 134.354824 -151.438102) (xy 134.354418 -151.42803) (xy 134.346686 -151.409431) (xy 134.339838 -151.402034)
			(xy 133.934454 -150.99665) (xy 133.927024 -150.989848) (xy 133.908448 -150.982105) (xy 133.898386 -150.981664)
			(xy 128.43637 -150.981664) (xy 128.426297 -150.982057) (xy 128.407698 -150.989798) (xy 128.400302 -150.99665)
			(xy 127.20574 -152.191212) (xy 132.117846 -152.191212) (xy 132.118332 -152.163961) (xy 132.126088 -152.110013)
			(xy 132.141443 -152.057718) (xy 132.164085 -152.008141) (xy 132.193551 -151.962291) (xy 132.229242 -151.9211)
			(xy 132.270433 -151.885409) (xy 132.316283 -151.855943) (xy 132.36586 -151.833301) (xy 132.418155 -151.817946)
			(xy 132.472103 -151.81019) (xy 132.526605 -151.81019) (xy 132.580553 -151.817946) (xy 132.632848 -151.833301)
			(xy 132.682425 -151.855943) (xy 132.728275 -151.885409) (xy 132.769466 -151.9211) (xy 132.805157 -151.962291)
			(xy 132.834623 -152.008141) (xy 132.857265 -152.057718) (xy 132.87262 -152.110013) (xy 132.880376 -152.163961)
			(xy 132.880862 -152.191212) (xy 132.880196 -152.222775) (xy 132.869812 -152.28504) (xy 132.849329 -152.344749)
			(xy 132.834888 -152.372822) (xy 132.830062 -152.381712) (xy 132.82803 -152.40127) (xy 132.85089 -152.479756)
			(xy 132.85412 -152.489184) (xy 132.866544 -152.50474) (xy 132.87502 -152.509982) (xy 132.882386 -152.514046)
			(xy 132.892292 -152.519888) (xy 132.914136 -152.52192) (xy 133.008878 -152.488392) (xy 133.024626 -152.472898)
			(xy 133.02869 -152.462484) (xy 133.039369 -152.4357) (xy 133.067659 -152.385458) (xy 133.103192 -152.340049)
			(xy 133.145156 -152.300507) (xy 133.192596 -152.267734) (xy 133.244429 -152.242477) (xy 133.299474 -152.225313)
			(xy 133.356476 -152.216632) (xy 133.385306 -152.216104) (xy 133.412558 -152.216566) (xy 133.466507 -152.224324)
			(xy 133.518802 -152.23968) (xy 133.56838 -152.262322) (xy 133.614231 -152.291789) (xy 133.655422 -152.327482)
			(xy 133.691114 -152.368673) (xy 133.720581 -152.414525) (xy 133.743222 -152.464103) (xy 133.758578 -152.516399)
			(xy 133.766334 -152.570348) (xy 133.766334 -152.624852) (xy 133.758578 -152.678801) (xy 133.743222 -152.731097)
			(xy 133.720581 -152.780675) (xy 133.691114 -152.826527) (xy 133.655422 -152.867718) (xy 133.614231 -152.903411)
			(xy 133.56838 -152.932878) (xy 133.518802 -152.95552) (xy 133.466507 -152.970876) (xy 133.412558 -152.978634)
			(xy 133.385306 -152.97912) (xy 133.385052 -152.97912) (xy 133.359849 -152.978703) (xy 133.309881 -152.972069)
			(xy 133.261227 -152.958898) (xy 133.214736 -152.93942) (xy 133.192774 -152.92705) (xy 133.182868 -152.921208)
			(xy 133.161024 -152.919176) (xy 133.066282 -152.952704) (xy 133.050534 -152.968198) (xy 133.04647 -152.978612)
			(xy 133.035739 -153.005373) (xy 133.007455 -153.055613) (xy 132.97193 -153.101022) (xy 132.929973 -153.140565)
			(xy 132.882541 -153.17334) (xy 132.830715 -153.198601) (xy 132.775677 -153.215771) (xy 132.718681 -153.224459)
			(xy 132.689854 -153.224992) (xy 132.662601 -153.224565) (xy 132.60865 -153.216802) (xy 132.556353 -153.20144)
			(xy 132.506775 -153.178792) (xy 132.460924 -153.14932) (xy 132.419734 -153.113622) (xy 132.384043 -153.072426)
			(xy 132.354578 -153.026571) (xy 132.331938 -152.976988) (xy 132.316585 -152.924689) (xy 132.308831 -152.870737)
			(xy 132.308346 -152.843484) (xy 132.309009 -152.811921) (xy 132.319394 -152.749656) (xy 132.339879 -152.689947)
			(xy 132.35432 -152.661874) (xy 132.359146 -152.652984) (xy 132.361178 -152.633426) (xy 132.338318 -152.55494)
			(xy 132.335087 -152.545513) (xy 132.322663 -152.529957) (xy 132.314188 -152.524714) (xy 132.289062 -152.510206)
			(xy 132.24318 -152.474696) (xy 132.203207 -152.432645) (xy 132.170065 -152.385024) (xy 132.144518 -152.332933)
			(xy 132.127157 -152.277572) (xy 132.118382 -152.220221) (xy 132.117846 -152.191212) (xy 127.20574 -152.191212)
			(xy 124.931678 -154.465274) (xy 128.331722 -154.465274) (xy 128.332231 -154.437701) (xy 128.340174 -154.38313)
			(xy 128.35589 -154.33027) (xy 128.379051 -154.280224) (xy 128.409177 -154.234033) (xy 128.445638 -154.192661)
			(xy 128.466342 -154.174444) (xy 128.474405 -154.166878) (xy 128.483764 -154.146874) (xy 128.484376 -154.135836)
			(xy 128.484376 -154.058112) (xy 128.483809 -154.047062) (xy 128.474444 -154.027041) (xy 128.466342 -154.019504)
			(xy 128.445638 -154.001285) (xy 128.409165 -153.959919) (xy 128.379031 -153.913731) (xy 128.355864 -153.863684)
			(xy 128.340147 -153.810823) (xy 128.332207 -153.756248) (xy 128.331722 -153.728674) (xy 128.332231 -153.701101)
			(xy 128.340174 -153.64653) (xy 128.35589 -153.59367) (xy 128.379051 -153.543624) (xy 128.409177 -153.497433)
			(xy 128.445638 -153.456061) (xy 128.466342 -153.437844) (xy 128.474405 -153.430278) (xy 128.483764 -153.410274)
			(xy 128.484376 -153.399236) (xy 128.484376 -153.321512) (xy 128.483809 -153.310462) (xy 128.474444 -153.290441)
			(xy 128.466342 -153.282904) (xy 128.445638 -153.264685) (xy 128.409165 -153.223319) (xy 128.379031 -153.177131)
			(xy 128.355864 -153.127084) (xy 128.340147 -153.074223) (xy 128.332207 -153.019648) (xy 128.331722 -152.992074)
			(xy 128.332131 -152.964819) (xy 128.339892 -152.910865) (xy 128.355253 -152.858564) (xy 128.377901 -152.808982)
			(xy 128.407374 -152.763127) (xy 128.443074 -152.721934) (xy 128.484272 -152.686241) (xy 128.530131 -152.656774)
			(xy 128.579716 -152.634133) (xy 128.632019 -152.61878) (xy 128.685975 -152.611027) (xy 128.71323 -152.610566)
			(xy 128.741085 -152.611087) (xy 128.796199 -152.619214) (xy 128.849548 -152.635262) (xy 128.9 -152.65889)
			(xy 128.946483 -152.689597) (xy 128.988012 -152.726732) (xy 129.023706 -152.769506) (xy 129.052806 -152.817012)
			(xy 129.074696 -152.868242) (xy 129.082292 -152.895046) (xy 129.084578 -152.903936) (xy 129.095246 -152.919176)
			(xy 129.167128 -152.966928) (xy 129.185162 -152.970992) (xy 129.194306 -152.969722) (xy 129.207323 -152.968054)
			(xy 129.233507 -152.966273) (xy 129.24663 -152.966166) (xy 129.260779 -152.966257) (xy 129.289002 -152.968293)
			(xy 129.303018 -152.97023) (xy 129.312924 -152.971754) (xy 129.332736 -152.966928) (xy 129.407158 -152.911048)
			(xy 129.417318 -152.893522) (xy 129.418588 -152.883362) (xy 129.422677 -152.856208) (xy 129.437649 -152.803378)
			(xy 129.46004 -152.753239) (xy 129.489387 -152.706828) (xy 129.525085 -152.665104) (xy 129.566394 -152.628927)
			(xy 129.612463 -152.599046) (xy 129.66234 -152.576077) (xy 129.714994 -152.560496) (xy 129.769338 -152.552624)
			(xy 129.796794 -152.552146) (xy 129.824043 -152.552683) (xy 129.877987 -152.560438) (xy 129.930277 -152.57579)
			(xy 129.979852 -152.598427) (xy 130.0257 -152.627888) (xy 130.066889 -152.663574) (xy 130.102581 -152.704758)
			(xy 130.132048 -152.750603) (xy 130.154692 -152.800174) (xy 130.170051 -152.852463) (xy 130.177813 -152.906405)
			(xy 130.178302 -152.933654) (xy 130.177804 -152.961227) (xy 130.169858 -153.015799) (xy 130.154139 -153.068658)
			(xy 130.130975 -153.118704) (xy 130.100849 -153.164894) (xy 130.064387 -153.206267) (xy 130.043682 -153.224484)
			(xy 130.035611 -153.232043) (xy 130.026255 -153.252052) (xy 130.025648 -153.263092) (xy 130.025648 -153.340816)
			(xy 130.026248 -153.351862) (xy 130.035589 -153.371884) (xy 130.043682 -153.379424) (xy 130.064404 -153.397623)
			(xy 130.100875 -153.438994) (xy 130.131006 -153.485186) (xy 130.15417 -153.535237) (xy 130.169883 -153.588102)
			(xy 130.177819 -153.642678) (xy 130.177853 -153.6446) (xy 134.76681 -153.6446) (xy 134.770881 -153.588978)
			(xy 134.783007 -153.534541) (xy 134.80293 -153.48245) (xy 134.830226 -153.433815) (xy 134.864312 -153.389672)
			(xy 134.904461 -153.350963) (xy 134.949819 -153.318512) (xy 134.999419 -153.293011) (xy 135.052203 -153.275004)
			(xy 135.107046 -153.264874) (xy 135.16278 -153.262837) (xy 135.218217 -153.268937) (xy 135.272174 -153.283043)
			(xy 135.323503 -153.304855) (xy 135.371109 -153.333909) (xy 135.413977 -153.369584) (xy 135.451194 -153.411121)
			(xy 135.481967 -153.457634) (xy 135.505639 -153.508131) (xy 135.521707 -153.561538) (xy 135.529827 -153.616714)
			(xy 135.530336 -153.6446) (xy 135.529827 -153.672486) (xy 135.521707 -153.727662) (xy 135.505639 -153.781069)
			(xy 135.481967 -153.831566) (xy 135.451194 -153.878079) (xy 135.413977 -153.919616) (xy 135.371109 -153.955291)
			(xy 135.323503 -153.984345) (xy 135.272174 -154.006157) (xy 135.218217 -154.020263) (xy 135.16278 -154.026363)
			(xy 135.107046 -154.024326) (xy 135.052203 -154.014196) (xy 134.999419 -153.996189) (xy 134.949819 -153.970688)
			(xy 134.904461 -153.938237) (xy 134.864312 -153.899528) (xy 134.830226 -153.855385) (xy 134.80293 -153.80675)
			(xy 134.783007 -153.754659) (xy 134.770881 -153.700222) (xy 134.76681 -153.6446) (xy 130.177853 -153.6446)
			(xy 130.178302 -153.670254) (xy 130.177802 -153.697506) (xy 130.170051 -153.751456) (xy 130.154701 -153.803753)
			(xy 130.132063 -153.853334) (xy 130.102599 -153.899187) (xy 130.066909 -153.940381) (xy 130.02572 -153.976075)
			(xy 129.979869 -154.005544) (xy 129.930291 -154.028187) (xy 129.877995 -154.043543) (xy 129.824046 -154.051299)
			(xy 129.796794 -154.051762) (xy 129.796286 -154.051762) (xy 129.762504 -154.050238) (xy 129.752344 -154.049222)
			(xy 129.73304 -154.055318) (xy 129.670048 -154.10815) (xy 129.66275 -154.114866) (xy 129.653475 -154.132376)
			(xy 129.652014 -154.142186) (xy 129.652014 -154.142948) (xy 129.649063 -154.171109) (xy 129.635856 -154.22617)
			(xy 129.614653 -154.278673) (xy 129.58592 -154.327463) (xy 129.550289 -154.37147) (xy 129.508544 -154.409724)
			(xy 129.461601 -154.441386) (xy 129.410493 -154.46576) (xy 129.356343 -154.48231) (xy 129.300341 -154.490671)
			(xy 129.27203 -154.491182) (xy 129.254011 -154.490966) (xy 129.218136 -154.487528) (xy 129.200402 -154.484324)
			(xy 129.19075 -154.482546) (xy 129.1717 -154.486102) (xy 129.09677 -154.534108) (xy 129.08534 -154.549856)
			(xy 129.083054 -154.559254) (xy 129.075689 -154.586308) (xy 129.054056 -154.638036) (xy 129.025088 -154.686042)
			(xy 128.989409 -154.729294) (xy 128.947785 -154.766861) (xy 128.901113 -154.797934) (xy 128.850398 -154.821844)
			(xy 128.79673 -154.838078) (xy 128.741265 -154.846285) (xy 128.71323 -154.846782) (xy 128.685977 -154.846317)
			(xy 128.632024 -154.838563) (xy 128.579725 -154.82321) (xy 128.530143 -154.800569) (xy 128.484289 -154.771101)
			(xy 128.443095 -154.735408) (xy 128.407401 -154.694214) (xy 128.377933 -154.64836) (xy 128.355292 -154.598779)
			(xy 128.339938 -154.546479) (xy 128.332184 -154.492527) (xy 128.331722 -154.465274) (xy 124.931678 -154.465274)
			(xy 123.456192 -155.94076) (xy 129.92354 -155.94076) (xy 129.924033 -155.913186) (xy 129.931978 -155.858614)
			(xy 129.947697 -155.805754) (xy 129.970862 -155.755708) (xy 130.00099 -155.709517) (xy 130.037454 -155.668146)
			(xy 130.05816 -155.64993) (xy 130.066231 -155.642372) (xy 130.075585 -155.622362) (xy 130.076194 -155.611322)
			(xy 130.076194 -155.533598) (xy 130.075573 -155.522555) (xy 130.066245 -155.502534) (xy 130.05816 -155.49499)
			(xy 130.037433 -155.476797) (xy 130.000965 -155.435423) (xy 129.970836 -155.389229) (xy 129.947674 -155.339178)
			(xy 129.93196 -155.286313) (xy 129.924024 -155.231736) (xy 129.92354 -155.20416) (xy 129.923989 -155.177973)
			(xy 129.93117 -155.126093) (xy 129.945377 -155.075683) (xy 129.966344 -155.027688) (xy 129.993677 -154.983012)
			(xy 130.026862 -154.942493) (xy 130.065276 -154.906892) (xy 130.108198 -154.876878) (xy 130.131312 -154.864562)
			(xy 130.140139 -154.859448) (xy 130.153105 -154.843718) (xy 130.156458 -154.834082) (xy 130.180842 -154.754072)
			(xy 130.178556 -154.733752) (xy 130.173476 -154.724608) (xy 130.158654 -154.6967) (xy 130.137613 -154.63712)
			(xy 130.126918 -154.574845) (xy 130.126232 -154.543252) (xy 130.126232 -154.542744) (xy 130.126675 -154.516125)
			(xy 130.134247 -154.463428) (xy 130.149242 -154.412346) (xy 130.171355 -154.363918) (xy 130.200137 -154.31913)
			(xy 130.235 -154.278896) (xy 130.275235 -154.244033) (xy 130.320023 -154.215252) (xy 130.368451 -154.19314)
			(xy 130.419534 -154.178145) (xy 130.472231 -154.170575) (xy 130.49885 -154.170126) (xy 130.525272 -154.170572)
			(xy 130.577587 -154.178028) (xy 130.628325 -154.192796) (xy 130.676469 -154.214582) (xy 130.721054 -154.242948)
			(xy 130.74142 -154.259788) (xy 130.748278 -154.26563) (xy 130.765296 -154.27198) (xy 130.849624 -154.27198)
			(xy 130.866642 -154.26563) (xy 130.8735 -154.259788) (xy 130.893866 -154.242949) (xy 130.938452 -154.214584)
			(xy 130.986596 -154.192797) (xy 131.037333 -154.178026) (xy 131.089648 -154.170566) (xy 131.142492 -154.170566)
			(xy 131.194807 -154.178026) (xy 131.245544 -154.192797) (xy 131.293688 -154.214584) (xy 131.338274 -154.242949)
			(xy 131.35864 -154.259788) (xy 131.365498 -154.26563) (xy 131.382516 -154.27198) (xy 131.466844 -154.27198)
			(xy 131.483862 -154.26563) (xy 131.49072 -154.259788) (xy 131.511077 -154.242939) (xy 131.555669 -154.214586)
			(xy 131.603816 -154.192809) (xy 131.654554 -154.178044) (xy 131.706869 -154.170586) (xy 131.73329 -154.170126)
			(xy 131.761181 -154.170532) (xy 131.816339 -154.178845) (xy 131.869642 -154.195285) (xy 131.919899 -154.219487)
			(xy 131.965988 -154.250909) (xy 132.006879 -154.288849) (xy 132.041659 -154.33246) (xy 132.048975 -154.345132)
			(xy 136.69086 -154.345132) (xy 136.694931 -154.28951) (xy 136.707057 -154.235073) (xy 136.72698 -154.182982)
			(xy 136.754276 -154.134347) (xy 136.788362 -154.090204) (xy 136.828511 -154.051495) (xy 136.873869 -154.019044)
			(xy 136.923469 -153.993543) (xy 136.976253 -153.975536) (xy 137.031096 -153.965406) (xy 137.08683 -153.963369)
			(xy 137.142267 -153.969469) (xy 137.196224 -153.983575) (xy 137.247553 -154.005387) (xy 137.295159 -154.034441)
			(xy 137.338027 -154.070116) (xy 137.375244 -154.111653) (xy 137.406017 -154.158166) (xy 137.429689 -154.208663)
			(xy 137.445757 -154.26207) (xy 137.453877 -154.317246) (xy 137.454386 -154.345132) (xy 137.453877 -154.373018)
			(xy 137.445757 -154.428194) (xy 137.429689 -154.481601) (xy 137.406017 -154.532098) (xy 137.375244 -154.578611)
			(xy 137.338027 -154.620148) (xy 137.295159 -154.655823) (xy 137.247553 -154.684877) (xy 137.196224 -154.706689)
			(xy 137.142267 -154.720795) (xy 137.08683 -154.726895) (xy 137.031096 -154.724858) (xy 136.976253 -154.714728)
			(xy 136.923469 -154.696721) (xy 136.873869 -154.67122) (xy 136.828511 -154.638769) (xy 136.788362 -154.60006)
			(xy 136.754276 -154.555917) (xy 136.72698 -154.507282) (xy 136.707057 -154.455191) (xy 136.694931 -154.400754)
			(xy 136.69086 -154.345132) (xy 132.048975 -154.345132) (xy 132.06955 -154.380767) (xy 132.089929 -154.432692)
			(xy 132.102342 -154.487075) (xy 132.106511 -154.5427) (xy 132.102342 -154.598325) (xy 132.089929 -154.652708)
			(xy 132.06955 -154.704633) (xy 132.041659 -154.75294) (xy 132.006879 -154.796551) (xy 131.965988 -154.834491)
			(xy 131.919899 -154.865913) (xy 131.869642 -154.890115) (xy 131.816339 -154.906555) (xy 131.761181 -154.914868)
			(xy 131.73329 -154.915362) (xy 131.706869 -154.914895) (xy 131.654554 -154.907445) (xy 131.603816 -154.892682)
			(xy 131.555672 -154.8709) (xy 131.511086 -154.842538) (xy 131.49072 -154.8257) (xy 131.483862 -154.819858)
			(xy 131.466844 -154.813508) (xy 131.382516 -154.813508) (xy 131.365498 -154.819858) (xy 131.35864 -154.8257)
			(xy 131.338274 -154.842539) (xy 131.293688 -154.870904) (xy 131.245544 -154.892691) (xy 131.194807 -154.907462)
			(xy 131.142492 -154.914922) (xy 131.089648 -154.914922) (xy 131.037333 -154.907462) (xy 130.986596 -154.892691)
			(xy 130.938452 -154.870904) (xy 130.893866 -154.842539) (xy 130.8735 -154.8257) (xy 130.866642 -154.819858)
			(xy 130.849624 -154.813508) (xy 130.765296 -154.813508) (xy 130.748278 -154.819858) (xy 130.74142 -154.8257)
			(xy 130.725853 -154.838706) (xy 130.692378 -154.861619) (xy 130.674618 -154.87142) (xy 130.665474 -154.876246)
			(xy 130.65252 -154.892248) (xy 130.62966 -154.972512) (xy 130.627365 -154.9825) (xy 130.629979 -155.002807)
			(xy 130.63474 -155.011882) (xy 130.63474 -155.012136) (xy 130.647068 -155.034075) (xy 130.666446 -155.08052)
			(xy 130.679551 -155.129108) (xy 130.686158 -155.178997) (xy 130.686556 -155.20416) (xy 130.686078 -155.231734)
			(xy 130.67813 -155.286307) (xy 130.662409 -155.339168) (xy 130.639241 -155.389214) (xy 130.60911 -155.435404)
			(xy 130.572643 -155.476775) (xy 130.551936 -155.49499) (xy 130.543855 -155.502539) (xy 130.534924 -155.52166)
			(xy 135.725662 -155.52166) (xy 135.726138 -155.493749) (xy 135.734277 -155.438522) (xy 135.750377 -155.385072)
			(xy 135.774094 -155.334537) (xy 135.80492 -155.287998) (xy 135.823198 -155.266898) (xy 135.829095 -155.259721)
			(xy 135.835746 -155.242396) (xy 135.836152 -155.233116) (xy 135.836152 -155.155392) (xy 135.829548 -155.13812)
			(xy 135.823198 -155.131008) (xy 135.804902 -155.109923) (xy 135.774077 -155.063381) (xy 135.750365 -155.012842)
			(xy 135.734273 -154.959388) (xy 135.726144 -154.904158) (xy 135.725662 -154.876246) (xy 135.726148 -154.848995)
			(xy 135.733904 -154.795047) (xy 135.749259 -154.742752) (xy 135.771901 -154.693175) (xy 135.801367 -154.647325)
			(xy 135.837058 -154.606134) (xy 135.878249 -154.570443) (xy 135.924099 -154.540977) (xy 135.973676 -154.518335)
			(xy 136.025971 -154.50298) (xy 136.079919 -154.495224) (xy 136.134421 -154.495224) (xy 136.188369 -154.50298)
			(xy 136.240664 -154.518335) (xy 136.290241 -154.540977) (xy 136.336091 -154.570443) (xy 136.377282 -154.606134)
			(xy 136.412973 -154.647325) (xy 136.442439 -154.693175) (xy 136.465081 -154.742752) (xy 136.480436 -154.795047)
			(xy 136.488192 -154.848995) (xy 136.488678 -154.876246) (xy 136.488196 -154.904157) (xy 136.480056 -154.959383)
			(xy 136.463957 -155.012833) (xy 136.440243 -155.063367) (xy 136.409418 -155.109907) (xy 136.391142 -155.131008)
			(xy 136.385235 -155.138178) (xy 136.378592 -155.155509) (xy 136.378188 -155.16479) (xy 136.378188 -155.242514)
			(xy 136.384792 -155.259786) (xy 136.391142 -155.266898) (xy 136.4094 -155.288014) (xy 136.440229 -155.334549)
			(xy 136.463947 -155.385079) (xy 136.480049 -155.438527) (xy 136.488189 -155.49375) (xy 136.488678 -155.52166)
			(xy 136.488192 -155.548911) (xy 136.480436 -155.602859) (xy 136.465081 -155.655154) (xy 136.442439 -155.704731)
			(xy 136.412973 -155.750581) (xy 136.377282 -155.791772) (xy 136.336091 -155.827463) (xy 136.290241 -155.856929)
			(xy 136.240664 -155.879571) (xy 136.188369 -155.894926) (xy 136.134421 -155.902682) (xy 136.079919 -155.902682)
			(xy 136.025971 -155.894926) (xy 135.973676 -155.879571) (xy 135.924099 -155.856929) (xy 135.878249 -155.827463)
			(xy 135.837058 -155.791772) (xy 135.801367 -155.750581) (xy 135.771901 -155.704731) (xy 135.749259 -155.655154)
			(xy 135.733904 -155.602859) (xy 135.726148 -155.548911) (xy 135.725662 -155.52166) (xy 130.534924 -155.52166)
			(xy 130.534506 -155.522556) (xy 130.533902 -155.533598) (xy 130.533902 -155.611322) (xy 130.534513 -155.622366)
			(xy 130.543848 -155.642388) (xy 130.551936 -155.64993) (xy 130.572672 -155.668114) (xy 130.609139 -155.709489)
			(xy 130.639267 -155.755685) (xy 130.662428 -155.805738) (xy 130.67814 -155.858605) (xy 130.686074 -155.913184)
			(xy 130.686556 -155.94076) (xy 130.68607 -155.968011) (xy 130.678314 -156.021959) (xy 130.662959 -156.074254)
			(xy 130.640317 -156.123831) (xy 130.610851 -156.169681) (xy 130.57516 -156.210872) (xy 130.533969 -156.246563)
			(xy 130.488119 -156.276029) (xy 130.438542 -156.298671) (xy 130.386247 -156.314026) (xy 130.332299 -156.321782)
			(xy 130.277797 -156.321782) (xy 130.223849 -156.314026) (xy 130.171554 -156.298671) (xy 130.121977 -156.276029)
			(xy 130.076127 -156.246563) (xy 130.034936 -156.210872) (xy 129.999245 -156.169681) (xy 129.969779 -156.123831)
			(xy 129.947137 -156.074254) (xy 129.931782 -156.021959) (xy 129.924026 -155.968011) (xy 129.92354 -155.94076)
			(xy 123.456192 -155.94076) (xy 122.67565 -156.721302) (xy 122.657524 -156.738507) (xy 122.615971 -156.766253)
			(xy 122.569806 -156.785366) (xy 122.520801 -156.795111) (xy 122.495818 -156.795724) (xy 107.604052 -156.795724)
			(xy 107.579067 -156.795131) (xy 107.530058 -156.785383) (xy 107.483888 -156.76627) (xy 107.442329 -156.738526)
			(xy 107.42422 -156.721302) (xy 101.787198 -151.084534) (xy 101.779796 -151.07786) (xy 101.761382 -151.070283)
			(xy 101.741471 -151.070272) (xy 101.73208 -151.073612) (xy 101.700584 -151.086566) (xy 101.700584 -151.09698)
			(xy 101.700364 -151.104545) (xy 101.695975 -151.119021) (xy 101.691948 -151.125428) (xy 101.60635 -151.252174)
			(xy 101.602046 -151.258174) (xy 101.590693 -151.267604) (xy 101.583998 -151.270716) (xy 101.510592 -151.30145)
			(xy 101.49459 -151.321008) (xy 101.492304 -151.333454) (xy 101.490437 -151.345854) (xy 101.497643 -151.369841)
			(xy 101.50602 -151.379174) (xy 107.824016 -157.69717) (xy 107.83142 -157.704005) (xy 107.850016 -157.711729)
			(xy 107.860084 -157.712156) (xy 124.683266 -157.712156) (xy 124.708251 -157.712744) (xy 124.75726 -157.722494)
			(xy 124.803429 -157.741609) (xy 124.844989 -157.769354) (xy 124.863098 -157.786578) (xy 126.71171 -159.63519)
			(xy 126.728935 -159.653298) (xy 126.756677 -159.694857) (xy 126.775785 -159.741028) (xy 126.785523 -159.790038)
			(xy 126.786132 -159.815022) (xy 126.786132 -160.888934) (xy 126.785528 -160.913918) (xy 126.775783 -160.962927)
			(xy 126.756674 -161.009096) (xy 126.728933 -161.050657) (xy 126.71171 -161.068766) (xy 126.370046 -161.41065)
			(xy 126.88773 -161.41065) (xy 126.891801 -161.355028) (xy 126.903927 -161.300591) (xy 126.92385 -161.2485)
			(xy 126.951146 -161.199865) (xy 126.985232 -161.155722) (xy 127.025381 -161.117013) (xy 127.070739 -161.084562)
			(xy 127.120339 -161.059061) (xy 127.173123 -161.041054) (xy 127.227966 -161.030924) (xy 127.2837 -161.028887)
			(xy 127.339137 -161.034987) (xy 127.393094 -161.049093) (xy 127.444423 -161.070905) (xy 127.492029 -161.099959)
			(xy 127.534897 -161.135634) (xy 127.572114 -161.177171) (xy 127.602887 -161.223684) (xy 127.626559 -161.274181)
			(xy 127.642627 -161.327588) (xy 127.650747 -161.382764) (xy 127.651256 -161.41065) (xy 127.650747 -161.438536)
			(xy 127.642627 -161.493712) (xy 127.626559 -161.547119) (xy 127.602887 -161.597616) (xy 127.572114 -161.644129)
			(xy 127.534897 -161.685666) (xy 127.492029 -161.721341) (xy 127.444423 -161.750395) (xy 127.393094 -161.772207)
			(xy 127.339137 -161.786313) (xy 127.2837 -161.792413) (xy 127.227966 -161.790376) (xy 127.173123 -161.780246)
			(xy 127.120339 -161.762239) (xy 127.070739 -161.736738) (xy 127.025381 -161.704287) (xy 126.985232 -161.665578)
			(xy 126.951146 -161.621435) (xy 126.92385 -161.5728) (xy 126.903927 -161.520709) (xy 126.891801 -161.466272)
			(xy 126.88773 -161.41065) (xy 126.370046 -161.41065) (xy 126.316994 -161.463736) (xy 126.310898 -161.473896)
			(xy 126.308866 -161.479992) (xy 126.308866 -161.4805) (xy 126.300637 -161.506424) (xy 126.277934 -161.555845)
			(xy 126.24844 -161.601541) (xy 126.212756 -161.642584) (xy 126.171603 -161.678143) (xy 126.125818 -161.707495)
			(xy 126.076327 -161.730048) (xy 126.024135 -161.745342) (xy 125.970299 -161.753067) (xy 125.943106 -161.75355)
			(xy 125.915857 -161.753017) (xy 125.861913 -161.745262) (xy 125.809622 -161.72991) (xy 125.760047 -161.707273)
			(xy 125.714199 -161.677811) (xy 125.67301 -161.642124) (xy 125.637318 -161.60094) (xy 125.60785 -161.555095)
			(xy 125.585207 -161.505523) (xy 125.569848 -161.453234) (xy 125.562087 -161.399291) (xy 125.561598 -161.372042)
			(xy 125.562067 -161.345249) (xy 125.569567 -161.292189) (xy 125.58441 -161.240699) (xy 125.606306 -161.19179)
			(xy 125.634823 -161.146422) (xy 125.651768 -161.125662) (xy 125.657864 -161.11855) (xy 125.663706 -161.101532)
			(xy 125.662436 -161.025078) (xy 125.661904 -161.015906) (xy 125.655131 -160.998844) (xy 125.649228 -160.991804)
			(xy 125.630608 -160.970642) (xy 125.59923 -160.923815) (xy 125.575084 -160.872882) (xy 125.558692 -160.81895)
			(xy 125.550413 -160.763194) (xy 125.549914 -160.73501) (xy 125.550476 -160.705939) (xy 125.55931 -160.648473)
			(xy 125.57676 -160.593011) (xy 125.602422 -160.540839) (xy 125.635702 -160.493164) (xy 125.675829 -160.45109)
			(xy 125.721875 -160.41559) (xy 125.772774 -160.387486) (xy 125.827346 -160.36743) (xy 125.85573 -160.361122)
			(xy 125.855984 -160.361122) (xy 125.86729 -160.358195) (xy 125.885749 -160.343934) (xy 125.89604 -160.323001)
			(xy 125.896624 -160.311338) (xy 125.896624 -160.099502) (xy 125.896218 -160.08943) (xy 125.888486 -160.070831)
			(xy 125.881638 -160.063434) (xy 124.434854 -158.61665) (xy 124.427424 -158.609848) (xy 124.408848 -158.602105)
			(xy 124.398786 -158.601664) (xy 107.540298 -158.601664) (xy 107.515316 -158.601031) (xy 107.466309 -158.591294)
			(xy 107.420139 -158.572193) (xy 107.378577 -158.54446) (xy 107.360466 -158.527242) (xy 101.793294 -152.96007)
			(xy 101.785183 -152.952681) (xy 101.764638 -152.945044) (xy 101.75367 -152.945338) (xy 101.665786 -152.951688)
			(xy 101.646736 -152.962102) (xy 101.639878 -152.970992) (xy 101.633287 -152.979682) (xy 101.619049 -152.996208)
			(xy 101.61143 -153.004012) (xy 101.293422 -153.32202) (xy 101.276184 -153.338606) (xy 101.237506 -153.366752)
			(xy 101.194908 -153.388513) (xy 101.149434 -153.403356) (xy 101.1022 -153.410916) (xy 101.078284 -153.411428)
			(xy 100.470208 -153.411428) (xy 100.444808 -153.428446) (xy 100.438966 -153.44267) (xy 100.435525 -153.452102)
			(xy 100.435579 -153.472166) (xy 100.443318 -153.490677) (xy 100.450142 -153.498042) (xy 107.804471 -160.852612)
			(xy 123.659646 -160.852612) (xy 123.660132 -160.825361) (xy 123.667888 -160.771413) (xy 123.683243 -160.719118)
			(xy 123.705885 -160.669541) (xy 123.735351 -160.623691) (xy 123.771042 -160.5825) (xy 123.812233 -160.546809)
			(xy 123.858083 -160.517343) (xy 123.90766 -160.494701) (xy 123.959955 -160.479346) (xy 124.013903 -160.47159)
			(xy 124.068405 -160.47159) (xy 124.122353 -160.479346) (xy 124.174648 -160.494701) (xy 124.224225 -160.517343)
			(xy 124.270075 -160.546809) (xy 124.311266 -160.5825) (xy 124.346957 -160.623691) (xy 124.376423 -160.669541)
			(xy 124.399065 -160.719118) (xy 124.41442 -160.771413) (xy 124.422176 -160.825361) (xy 124.422662 -160.852612)
			(xy 124.421996 -160.884175) (xy 124.411612 -160.94644) (xy 124.391129 -161.006149) (xy 124.376688 -161.034222)
			(xy 124.371862 -161.043112) (xy 124.36983 -161.06267) (xy 124.39269 -161.141156) (xy 124.39592 -161.150584)
			(xy 124.408344 -161.16614) (xy 124.41682 -161.171382) (xy 124.424186 -161.175446) (xy 124.434092 -161.181288)
			(xy 124.455936 -161.18332) (xy 124.550678 -161.149792) (xy 124.566426 -161.134298) (xy 124.57049 -161.123884)
			(xy 124.581169 -161.0971) (xy 124.609459 -161.046858) (xy 124.644992 -161.001449) (xy 124.686956 -160.961907)
			(xy 124.734396 -160.929134) (xy 124.786229 -160.903877) (xy 124.841274 -160.886713) (xy 124.898276 -160.878032)
			(xy 124.927106 -160.877504) (xy 124.954358 -160.877966) (xy 125.008307 -160.885724) (xy 125.060602 -160.90108)
			(xy 125.11018 -160.923722) (xy 125.156031 -160.953189) (xy 125.197222 -160.988882) (xy 125.232914 -161.030073)
			(xy 125.262381 -161.075925) (xy 125.285022 -161.125503) (xy 125.300378 -161.177799) (xy 125.308134 -161.231748)
			(xy 125.308134 -161.286252) (xy 125.300378 -161.340201) (xy 125.285022 -161.392497) (xy 125.262381 -161.442075)
			(xy 125.232914 -161.487927) (xy 125.197222 -161.529118) (xy 125.156031 -161.564811) (xy 125.11018 -161.594278)
			(xy 125.060602 -161.61692) (xy 125.008307 -161.632276) (xy 124.954358 -161.640034) (xy 124.927106 -161.64052)
			(xy 124.926852 -161.64052) (xy 124.901649 -161.640103) (xy 124.851681 -161.633469) (xy 124.803027 -161.620298)
			(xy 124.756536 -161.60082) (xy 124.734574 -161.58845) (xy 124.724668 -161.582608) (xy 124.702824 -161.580576)
			(xy 124.608082 -161.614104) (xy 124.592334 -161.629598) (xy 124.58827 -161.640012) (xy 124.577539 -161.666773)
			(xy 124.549255 -161.717013) (xy 124.51373 -161.762422) (xy 124.471773 -161.801965) (xy 124.424341 -161.83474)
			(xy 124.372515 -161.860001) (xy 124.317477 -161.877171) (xy 124.260481 -161.885859) (xy 124.231654 -161.886392)
			(xy 124.204401 -161.885965) (xy 124.15045 -161.878202) (xy 124.098153 -161.86284) (xy 124.048575 -161.840192)
			(xy 124.002724 -161.81072) (xy 123.961534 -161.775022) (xy 123.925843 -161.733826) (xy 123.896378 -161.687971)
			(xy 123.873738 -161.638388) (xy 123.858385 -161.586089) (xy 123.850631 -161.532137) (xy 123.850146 -161.504884)
			(xy 123.850809 -161.473321) (xy 123.861194 -161.411056) (xy 123.881679 -161.351347) (xy 123.89612 -161.323274)
			(xy 123.900946 -161.314384) (xy 123.902978 -161.294826) (xy 123.880118 -161.21634) (xy 123.876887 -161.206913)
			(xy 123.864463 -161.191357) (xy 123.855988 -161.186114) (xy 123.830862 -161.171606) (xy 123.78498 -161.136096)
			(xy 123.745007 -161.094045) (xy 123.711865 -161.046424) (xy 123.686318 -160.994333) (xy 123.668957 -160.938972)
			(xy 123.660182 -160.881621) (xy 123.659646 -160.852612) (xy 107.804471 -160.852612) (xy 108.205016 -161.25317)
			(xy 108.21242 -161.260005) (xy 108.231016 -161.267729) (xy 108.241084 -161.268156) (xy 113.227866 -161.268156)
			(xy 113.252851 -161.268744) (xy 113.30186 -161.278494) (xy 113.348029 -161.297609) (xy 113.389589 -161.325354)
			(xy 113.407698 -161.342578) (xy 115.191794 -163.126674) (xy 119.873522 -163.126674) (xy 119.874031 -163.099101)
			(xy 119.881974 -163.04453) (xy 119.89769 -162.99167) (xy 119.920851 -162.941624) (xy 119.950977 -162.895433)
			(xy 119.987438 -162.854061) (xy 120.008142 -162.835844) (xy 120.016205 -162.828278) (xy 120.025564 -162.808274)
			(xy 120.026176 -162.797236) (xy 120.026176 -162.719512) (xy 120.025609 -162.708462) (xy 120.016244 -162.688441)
			(xy 120.008142 -162.680904) (xy 119.987438 -162.662685) (xy 119.950965 -162.621319) (xy 119.920831 -162.575131)
			(xy 119.897664 -162.525084) (xy 119.881947 -162.472223) (xy 119.874007 -162.417648) (xy 119.873522 -162.390074)
			(xy 119.874031 -162.362501) (xy 119.881974 -162.30793) (xy 119.89769 -162.25507) (xy 119.920851 -162.205024)
			(xy 119.950977 -162.158833) (xy 119.987438 -162.117461) (xy 120.008142 -162.099244) (xy 120.016205 -162.091678)
			(xy 120.025564 -162.071674) (xy 120.026176 -162.060636) (xy 120.026176 -161.982912) (xy 120.025609 -161.971862)
			(xy 120.016244 -161.951841) (xy 120.008142 -161.944304) (xy 119.987438 -161.926085) (xy 119.950965 -161.884719)
			(xy 119.920831 -161.838531) (xy 119.897664 -161.788484) (xy 119.881947 -161.735623) (xy 119.874007 -161.681048)
			(xy 119.873522 -161.653474) (xy 119.873931 -161.626219) (xy 119.881692 -161.572265) (xy 119.897053 -161.519964)
			(xy 119.919701 -161.470382) (xy 119.949174 -161.424527) (xy 119.984874 -161.383334) (xy 120.026072 -161.347641)
			(xy 120.071931 -161.318174) (xy 120.121516 -161.295533) (xy 120.173819 -161.28018) (xy 120.227775 -161.272427)
			(xy 120.25503 -161.271966) (xy 120.282885 -161.272487) (xy 120.337999 -161.280614) (xy 120.391348 -161.296662)
			(xy 120.4418 -161.32029) (xy 120.488283 -161.350997) (xy 120.529812 -161.388132) (xy 120.565506 -161.430906)
			(xy 120.594606 -161.478412) (xy 120.616496 -161.529642) (xy 120.624092 -161.556446) (xy 120.626378 -161.565336)
			(xy 120.637046 -161.580576) (xy 120.708928 -161.628328) (xy 120.726962 -161.632392) (xy 120.736106 -161.631122)
			(xy 120.749123 -161.629454) (xy 120.775307 -161.627673) (xy 120.78843 -161.627566) (xy 120.802579 -161.627657)
			(xy 120.830802 -161.629693) (xy 120.844818 -161.63163) (xy 120.854724 -161.633154) (xy 120.874536 -161.628328)
			(xy 120.948958 -161.572448) (xy 120.959118 -161.554922) (xy 120.960388 -161.544762) (xy 120.964477 -161.517608)
			(xy 120.979449 -161.464778) (xy 121.00184 -161.414639) (xy 121.031187 -161.368228) (xy 121.066885 -161.326504)
			(xy 121.108194 -161.290327) (xy 121.154263 -161.260446) (xy 121.20414 -161.237477) (xy 121.256794 -161.221896)
			(xy 121.311138 -161.214024) (xy 121.338594 -161.213546) (xy 121.365843 -161.214083) (xy 121.419787 -161.221838)
			(xy 121.472077 -161.23719) (xy 121.521652 -161.259827) (xy 121.5675 -161.289288) (xy 121.608689 -161.324974)
			(xy 121.644381 -161.366158) (xy 121.673848 -161.412003) (xy 121.696492 -161.461574) (xy 121.711851 -161.513863)
			(xy 121.719613 -161.567805) (xy 121.720102 -161.595054) (xy 121.719604 -161.622627) (xy 121.711658 -161.677199)
			(xy 121.695939 -161.730058) (xy 121.672775 -161.780104) (xy 121.642649 -161.826294) (xy 121.606187 -161.867667)
			(xy 121.585482 -161.885884) (xy 121.577411 -161.893443) (xy 121.568055 -161.913452) (xy 121.567448 -161.924492)
			(xy 121.567448 -162.002216) (xy 121.568048 -162.013262) (xy 121.577389 -162.033284) (xy 121.585482 -162.040824)
			(xy 121.606204 -162.059023) (xy 121.642675 -162.100394) (xy 121.672806 -162.146586) (xy 121.69597 -162.196637)
			(xy 121.711683 -162.249502) (xy 121.719619 -162.304078) (xy 121.719653 -162.306) (xy 126.30861 -162.306)
			(xy 126.312681 -162.250378) (xy 126.324807 -162.195941) (xy 126.34473 -162.14385) (xy 126.372026 -162.095215)
			(xy 126.406112 -162.051072) (xy 126.446261 -162.012363) (xy 126.491619 -161.979912) (xy 126.541219 -161.954411)
			(xy 126.594003 -161.936404) (xy 126.648846 -161.926274) (xy 126.70458 -161.924237) (xy 126.760017 -161.930337)
			(xy 126.813974 -161.944443) (xy 126.865303 -161.966255) (xy 126.912909 -161.995309) (xy 126.955777 -162.030984)
			(xy 126.992994 -162.072521) (xy 127.023767 -162.119034) (xy 127.047439 -162.169531) (xy 127.063507 -162.222938)
			(xy 127.071627 -162.278114) (xy 127.072136 -162.306) (xy 127.071627 -162.333886) (xy 127.063507 -162.389062)
			(xy 127.047439 -162.442469) (xy 127.023767 -162.492966) (xy 126.992994 -162.539479) (xy 126.955777 -162.581016)
			(xy 126.912909 -162.616691) (xy 126.865303 -162.645745) (xy 126.813974 -162.667557) (xy 126.760017 -162.681663)
			(xy 126.70458 -162.687763) (xy 126.648846 -162.685726) (xy 126.594003 -162.675596) (xy 126.541219 -162.657589)
			(xy 126.491619 -162.632088) (xy 126.446261 -162.599637) (xy 126.406112 -162.560928) (xy 126.372026 -162.516785)
			(xy 126.34473 -162.46815) (xy 126.324807 -162.416059) (xy 126.312681 -162.361622) (xy 126.30861 -162.306)
			(xy 121.719653 -162.306) (xy 121.720102 -162.331654) (xy 121.719602 -162.358906) (xy 121.711851 -162.412856)
			(xy 121.696501 -162.465153) (xy 121.673863 -162.514734) (xy 121.644399 -162.560587) (xy 121.608709 -162.601781)
			(xy 121.56752 -162.637475) (xy 121.521669 -162.666944) (xy 121.472091 -162.689587) (xy 121.419795 -162.704943)
			(xy 121.365846 -162.712699) (xy 121.338594 -162.713162) (xy 121.338086 -162.713162) (xy 121.304304 -162.711638)
			(xy 121.294144 -162.710622) (xy 121.27484 -162.716718) (xy 121.211848 -162.76955) (xy 121.20455 -162.776266)
			(xy 121.195275 -162.793776) (xy 121.193814 -162.803586) (xy 121.193814 -162.804348) (xy 121.190863 -162.832509)
			(xy 121.177656 -162.88757) (xy 121.156453 -162.940073) (xy 121.12772 -162.988863) (xy 121.092089 -163.03287)
			(xy 121.050344 -163.071124) (xy 121.003401 -163.102786) (xy 120.952293 -163.12716) (xy 120.898143 -163.14371)
			(xy 120.842141 -163.152071) (xy 120.81383 -163.152582) (xy 120.795811 -163.152366) (xy 120.759936 -163.148928)
			(xy 120.742202 -163.145724) (xy 120.73255 -163.143946) (xy 120.7135 -163.147502) (xy 120.63857 -163.195508)
			(xy 120.62714 -163.211256) (xy 120.624854 -163.220654) (xy 120.617489 -163.247708) (xy 120.595856 -163.299436)
			(xy 120.566888 -163.347442) (xy 120.531209 -163.390694) (xy 120.489585 -163.428261) (xy 120.442913 -163.459334)
			(xy 120.392198 -163.483244) (xy 120.33853 -163.499478) (xy 120.283065 -163.507685) (xy 120.25503 -163.508182)
			(xy 120.227777 -163.507717) (xy 120.173824 -163.499963) (xy 120.121525 -163.48461) (xy 120.071943 -163.461969)
			(xy 120.026089 -163.432501) (xy 119.984895 -163.396808) (xy 119.949201 -163.355614) (xy 119.919733 -163.30976)
			(xy 119.897092 -163.260179) (xy 119.881738 -163.207879) (xy 119.873984 -163.153927) (xy 119.873522 -163.126674)
			(xy 115.191794 -163.126674) (xy 116.69268 -164.62756) (xy 121.49074 -164.62756) (xy 121.491233 -164.599986)
			(xy 121.499178 -164.545414) (xy 121.514897 -164.492554) (xy 121.538062 -164.442508) (xy 121.56819 -164.396317)
			(xy 121.604654 -164.354946) (xy 121.62536 -164.33673) (xy 121.633431 -164.329172) (xy 121.642785 -164.309162)
			(xy 121.643394 -164.298122) (xy 121.643394 -164.220398) (xy 121.642773 -164.209355) (xy 121.633445 -164.189334)
			(xy 121.62536 -164.18179) (xy 121.604633 -164.163597) (xy 121.568165 -164.122223) (xy 121.538036 -164.076029)
			(xy 121.514874 -164.025978) (xy 121.49916 -163.973113) (xy 121.491224 -163.918536) (xy 121.49074 -163.89096)
			(xy 121.491336 -163.861514) (xy 121.500398 -163.803322) (xy 121.518285 -163.747211) (xy 121.544574 -163.694511)
			(xy 121.578641 -163.646472) (xy 121.619678 -163.604231) (xy 121.666714 -163.56879) (xy 121.692416 -163.55441)
			(xy 121.701814 -163.54933) (xy 121.715022 -163.532566) (xy 121.738898 -163.43884) (xy 121.735342 -163.418012)
			(xy 121.7295 -163.409122) (xy 121.714965 -163.386192) (xy 121.691987 -163.337005) (xy 121.676395 -163.285003)
			(xy 121.668519 -163.231289) (xy 121.668032 -163.204144) (xy 121.668475 -163.177525) (xy 121.676047 -163.124828)
			(xy 121.691042 -163.073746) (xy 121.713155 -163.025318) (xy 121.741937 -162.98053) (xy 121.7768 -162.940296)
			(xy 121.817035 -162.905433) (xy 121.861823 -162.876652) (xy 121.910251 -162.85454) (xy 121.961334 -162.839545)
			(xy 122.014031 -162.831975) (xy 122.04065 -162.831526) (xy 122.067072 -162.831972) (xy 122.119387 -162.839428)
			(xy 122.170125 -162.854196) (xy 122.218269 -162.875982) (xy 122.262854 -162.904348) (xy 122.28322 -162.921188)
			(xy 122.290078 -162.92703) (xy 122.307096 -162.93338) (xy 122.391424 -162.93338) (xy 122.408442 -162.92703)
			(xy 122.4153 -162.921188) (xy 122.435666 -162.904349) (xy 122.480252 -162.875984) (xy 122.528396 -162.854197)
			(xy 122.579133 -162.839426) (xy 122.631448 -162.831966) (xy 122.684292 -162.831966) (xy 122.736607 -162.839426)
			(xy 122.787344 -162.854197) (xy 122.835488 -162.875984) (xy 122.880074 -162.904349) (xy 122.90044 -162.921188)
			(xy 122.907298 -162.92703) (xy 122.924316 -162.93338) (xy 123.008644 -162.93338) (xy 123.025662 -162.92703)
			(xy 123.03252 -162.921188) (xy 123.052877 -162.904339) (xy 123.097469 -162.875986) (xy 123.145616 -162.854209)
			(xy 123.196354 -162.839444) (xy 123.248669 -162.831986) (xy 123.27509 -162.831526) (xy 123.302981 -162.831932)
			(xy 123.358139 -162.840245) (xy 123.411442 -162.856685) (xy 123.461699 -162.880887) (xy 123.507788 -162.912309)
			(xy 123.548679 -162.950249) (xy 123.583459 -162.99386) (xy 123.61135 -163.042167) (xy 123.631729 -163.094092)
			(xy 123.644142 -163.148475) (xy 123.648311 -163.2041) (xy 123.644142 -163.259725) (xy 123.631729 -163.314108)
			(xy 123.61135 -163.366033) (xy 123.583459 -163.41434) (xy 123.548679 -163.457951) (xy 123.507788 -163.495891)
			(xy 123.461699 -163.527313) (xy 123.411442 -163.551515) (xy 123.358139 -163.567955) (xy 123.302981 -163.576268)
			(xy 123.27509 -163.576762) (xy 123.248669 -163.576295) (xy 123.196354 -163.568845) (xy 123.145616 -163.554082)
			(xy 123.097472 -163.5323) (xy 123.052886 -163.503938) (xy 123.03252 -163.4871) (xy 123.025662 -163.481258)
			(xy 123.008644 -163.474908) (xy 122.924316 -163.474908) (xy 122.907298 -163.481258) (xy 122.90044 -163.4871)
			(xy 122.880074 -163.503939) (xy 122.835488 -163.532304) (xy 122.787344 -163.554091) (xy 122.736607 -163.568862)
			(xy 122.684292 -163.576322) (xy 122.631448 -163.576322) (xy 122.579133 -163.568862) (xy 122.528396 -163.554091)
			(xy 122.480252 -163.532304) (xy 122.435666 -163.503939) (xy 122.4153 -163.4871) (xy 122.408442 -163.481258)
			(xy 122.391424 -163.474908) (xy 122.307096 -163.474908) (xy 122.290078 -163.481258) (xy 122.28322 -163.4871)
			(xy 122.268829 -163.499111) (xy 122.238035 -163.520486) (xy 122.221752 -163.529772) (xy 122.212688 -163.535318)
			(xy 122.199934 -163.552292) (xy 122.197114 -163.562538) (xy 122.177302 -163.646104) (xy 122.181112 -163.666678)
			(xy 122.187208 -163.675568) (xy 122.187208 -163.676076) (xy 122.202908 -163.69994) (xy 122.227774 -163.751363)
			(xy 122.244676 -163.805925) (xy 122.253234 -163.8624) (xy 122.253756 -163.89096) (xy 122.253278 -163.918534)
			(xy 122.24533 -163.973107) (xy 122.229609 -164.025968) (xy 122.206441 -164.076014) (xy 122.17631 -164.122204)
			(xy 122.139843 -164.163575) (xy 122.119136 -164.18179) (xy 122.117776 -164.18306) (xy 127.267462 -164.18306)
			(xy 127.267938 -164.155149) (xy 127.276077 -164.099922) (xy 127.292177 -164.046472) (xy 127.315894 -163.995937)
			(xy 127.34672 -163.949398) (xy 127.364998 -163.928298) (xy 127.370895 -163.921121) (xy 127.377546 -163.903796)
			(xy 127.377952 -163.894516) (xy 127.377952 -163.816792) (xy 127.371348 -163.79952) (xy 127.364998 -163.792408)
			(xy 127.346702 -163.771323) (xy 127.315877 -163.724781) (xy 127.292165 -163.674242) (xy 127.276073 -163.620788)
			(xy 127.267944 -163.565558) (xy 127.267462 -163.537646) (xy 127.267948 -163.510395) (xy 127.275704 -163.456447)
			(xy 127.291059 -163.404152) (xy 127.313701 -163.354575) (xy 127.343167 -163.308725) (xy 127.378858 -163.267534)
			(xy 127.420049 -163.231843) (xy 127.465899 -163.202377) (xy 127.515476 -163.179735) (xy 127.567771 -163.16438)
			(xy 127.621719 -163.156624) (xy 127.676221 -163.156624) (xy 127.730169 -163.16438) (xy 127.782464 -163.179735)
			(xy 127.832041 -163.202377) (xy 127.877891 -163.231843) (xy 127.919082 -163.267534) (xy 127.954773 -163.308725)
			(xy 127.984239 -163.354575) (xy 128.006881 -163.404152) (xy 128.022236 -163.456447) (xy 128.029992 -163.510395)
			(xy 128.030478 -163.537646) (xy 128.029996 -163.565557) (xy 128.021856 -163.620783) (xy 128.005757 -163.674233)
			(xy 127.982043 -163.724767) (xy 127.951218 -163.771307) (xy 127.932942 -163.792408) (xy 127.927035 -163.799578)
			(xy 127.920392 -163.816909) (xy 127.919988 -163.82619) (xy 127.919988 -163.903914) (xy 127.926592 -163.921186)
			(xy 127.932942 -163.928298) (xy 127.9512 -163.949414) (xy 127.982029 -163.995949) (xy 128.005747 -164.046479)
			(xy 128.021849 -164.099927) (xy 128.029989 -164.15515) (xy 128.030478 -164.18306) (xy 128.029992 -164.210311)
			(xy 128.022236 -164.264259) (xy 128.006881 -164.316554) (xy 127.984239 -164.366131) (xy 127.954773 -164.411981)
			(xy 127.919082 -164.453172) (xy 127.877891 -164.488863) (xy 127.832041 -164.518329) (xy 127.782464 -164.540971)
			(xy 127.730169 -164.556326) (xy 127.676221 -164.564082) (xy 127.621719 -164.564082) (xy 127.567771 -164.556326)
			(xy 127.515476 -164.540971) (xy 127.465899 -164.518329) (xy 127.420049 -164.488863) (xy 127.378858 -164.453172)
			(xy 127.343167 -164.411981) (xy 127.313701 -164.366131) (xy 127.291059 -164.316554) (xy 127.275704 -164.264259)
			(xy 127.267948 -164.210311) (xy 127.267462 -164.18306) (xy 122.117776 -164.18306) (xy 122.111055 -164.189339)
			(xy 122.101706 -164.209356) (xy 122.101102 -164.220398) (xy 122.101102 -164.298122) (xy 122.101713 -164.309166)
			(xy 122.111048 -164.329188) (xy 122.119136 -164.33673) (xy 122.139872 -164.354914) (xy 122.176339 -164.396289)
			(xy 122.206467 -164.442485) (xy 122.229628 -164.492538) (xy 122.24534 -164.545405) (xy 122.253274 -164.599984)
			(xy 122.253756 -164.62756) (xy 122.25327 -164.654811) (xy 122.245514 -164.708759) (xy 122.230159 -164.761054)
			(xy 122.207517 -164.810631) (xy 122.178051 -164.856481) (xy 122.14236 -164.897672) (xy 122.101169 -164.933363)
			(xy 122.055319 -164.962829) (xy 122.005742 -164.985471) (xy 121.953447 -165.000826) (xy 121.899499 -165.008582)
			(xy 121.844997 -165.008582) (xy 121.791049 -165.000826) (xy 121.738754 -164.985471) (xy 121.689177 -164.962829)
			(xy 121.643327 -164.933363) (xy 121.602136 -164.897672) (xy 121.566445 -164.856481) (xy 121.536979 -164.810631)
			(xy 121.514337 -164.761054) (xy 121.498982 -164.708759) (xy 121.491226 -164.654811) (xy 121.49074 -164.62756)
			(xy 116.69268 -164.62756) (xy 118.43131 -166.36619) (xy 118.448535 -166.384298) (xy 118.476277 -166.425857)
			(xy 118.495385 -166.472028) (xy 118.505123 -166.521038) (xy 118.505732 -166.546022) (xy 118.505732 -167.619934)
			(xy 118.505128 -167.644918) (xy 118.495383 -167.693927) (xy 118.476274 -167.740096) (xy 118.448533 -167.781657)
			(xy 118.43131 -167.799766) (xy 118.089426 -168.14165) (xy 118.60733 -168.14165) (xy 118.611401 -168.086028)
			(xy 118.623527 -168.031591) (xy 118.64345 -167.9795) (xy 118.670746 -167.930865) (xy 118.704832 -167.886722)
			(xy 118.744981 -167.848013) (xy 118.790339 -167.815562) (xy 118.839939 -167.790061) (xy 118.892723 -167.772054)
			(xy 118.947566 -167.761924) (xy 119.0033 -167.759887) (xy 119.058737 -167.765987) (xy 119.112694 -167.780093)
			(xy 119.164023 -167.801905) (xy 119.211629 -167.830959) (xy 119.254497 -167.866634) (xy 119.291714 -167.908171)
			(xy 119.322487 -167.954684) (xy 119.346159 -168.005181) (xy 119.362227 -168.058588) (xy 119.370347 -168.113764)
			(xy 119.370856 -168.14165) (xy 119.370347 -168.169536) (xy 119.362227 -168.224712) (xy 119.346159 -168.278119)
			(xy 119.322487 -168.328616) (xy 119.291714 -168.375129) (xy 119.254497 -168.416666) (xy 119.211629 -168.452341)
			(xy 119.164023 -168.481395) (xy 119.112694 -168.503207) (xy 119.058737 -168.517313) (xy 119.0033 -168.523413)
			(xy 118.947566 -168.521376) (xy 118.892723 -168.511246) (xy 118.839939 -168.493239) (xy 118.790339 -168.467738)
			(xy 118.744981 -168.435287) (xy 118.704832 -168.396578) (xy 118.670746 -168.352435) (xy 118.64345 -168.3038)
			(xy 118.623527 -168.251709) (xy 118.611401 -168.197272) (xy 118.60733 -168.14165) (xy 118.089426 -168.14165)
			(xy 118.015766 -168.21531) (xy 118.011956 -168.226486) (xy 118.003042 -168.251254) (xy 117.979334 -168.298253)
			(xy 117.949387 -168.341544) (xy 117.913771 -168.380305) (xy 117.873162 -168.413799) (xy 117.828332 -168.441389)
			(xy 117.780134 -168.462551) (xy 117.729483 -168.476883) (xy 117.677342 -168.484113) (xy 117.651022 -168.48455)
			(xy 117.623773 -168.484001) (xy 117.56983 -168.476249) (xy 117.517539 -168.460899) (xy 117.467965 -168.438263)
			(xy 117.422116 -168.408803) (xy 117.380927 -168.373118) (xy 117.345235 -168.331935) (xy 117.315767 -168.286091)
			(xy 117.293124 -168.236521) (xy 117.277765 -168.184233) (xy 117.270003 -168.130291) (xy 117.269514 -168.103042)
			(xy 117.270022 -168.075568) (xy 117.277908 -168.021189) (xy 117.293523 -167.968507) (xy 117.316543 -167.918614)
			(xy 117.34649 -167.872544) (xy 117.364256 -167.851582) (xy 117.36451 -167.851328) (xy 117.370092 -167.844238)
			(xy 117.376341 -167.827324) (xy 117.376702 -167.818308) (xy 117.376702 -167.750744) (xy 117.376324 -167.741729)
			(xy 117.370091 -167.724812) (xy 117.36451 -167.717724) (xy 117.364002 -167.717216) (xy 117.34628 -167.69626)
			(xy 117.316396 -167.65023) (xy 117.293427 -167.600387) (xy 117.27785 -167.547764) (xy 117.269986 -167.49345)
			(xy 117.269514 -167.46601) (xy 117.270076 -167.436939) (xy 117.27891 -167.379473) (xy 117.29636 -167.324011)
			(xy 117.322022 -167.271839) (xy 117.355302 -167.224164) (xy 117.395429 -167.18209) (xy 117.441475 -167.14659)
			(xy 117.492374 -167.118486) (xy 117.546946 -167.09843) (xy 117.57533 -167.092122) (xy 117.575584 -167.092122)
			(xy 117.58689 -167.089195) (xy 117.605349 -167.074934) (xy 117.61564 -167.054001) (xy 117.616224 -167.042338)
			(xy 117.616224 -166.830502) (xy 117.615818 -166.82043) (xy 117.608086 -166.801831) (xy 117.601238 -166.794434)
			(xy 112.979454 -162.17265) (xy 112.972024 -162.165848) (xy 112.953448 -162.158105) (xy 112.943386 -162.157664)
			(xy 107.860592 -162.157664) (xy 107.835609 -162.157035) (xy 107.786602 -162.147296) (xy 107.740433 -162.128194)
			(xy 107.698871 -162.100461) (xy 107.68076 -162.083242) (xy 99.023678 -153.426414) (xy 99.016278 -153.419574)
			(xy 98.997679 -153.411854) (xy 98.98761 -153.411428) (xy 97.193862 -153.411428) (xy 97.168462 -153.428446)
			(xy 97.16262 -153.44267) (xy 97.159165 -153.452099) (xy 97.159218 -153.472167) (xy 97.166966 -153.490679)
			(xy 97.173796 -153.498042) (xy 102.07371 -158.39821) (xy 102.090944 -158.416309) (xy 102.118685 -158.457871)
			(xy 102.13779 -158.504045) (xy 102.147525 -158.553057) (xy 102.148132 -158.578042) (xy 102.148132 -167.583612)
			(xy 115.379246 -167.583612) (xy 115.379732 -167.556361) (xy 115.387488 -167.502413) (xy 115.402843 -167.450118)
			(xy 115.425485 -167.400541) (xy 115.454951 -167.354691) (xy 115.490642 -167.3135) (xy 115.531833 -167.277809)
			(xy 115.577683 -167.248343) (xy 115.62726 -167.225701) (xy 115.679555 -167.210346) (xy 115.733503 -167.20259)
			(xy 115.788005 -167.20259) (xy 115.841953 -167.210346) (xy 115.894248 -167.225701) (xy 115.943825 -167.248343)
			(xy 115.989675 -167.277809) (xy 116.030866 -167.3135) (xy 116.066557 -167.354691) (xy 116.096023 -167.400541)
			(xy 116.118665 -167.450118) (xy 116.13402 -167.502413) (xy 116.141776 -167.556361) (xy 116.142262 -167.583612)
			(xy 116.141596 -167.615175) (xy 116.131212 -167.67744) (xy 116.110729 -167.737149) (xy 116.096288 -167.765222)
			(xy 116.091462 -167.774112) (xy 116.08943 -167.79367) (xy 116.11229 -167.872156) (xy 116.11552 -167.881584)
			(xy 116.127944 -167.89714) (xy 116.13642 -167.902382) (xy 116.143786 -167.906446) (xy 116.153692 -167.912288)
			(xy 116.175536 -167.91432) (xy 116.270278 -167.880792) (xy 116.286026 -167.865298) (xy 116.29009 -167.854884)
			(xy 116.300769 -167.8281) (xy 116.329059 -167.777858) (xy 116.364592 -167.732449) (xy 116.406556 -167.692907)
			(xy 116.453996 -167.660134) (xy 116.505829 -167.634877) (xy 116.560874 -167.617713) (xy 116.617876 -167.609032)
			(xy 116.646706 -167.608504) (xy 116.673958 -167.608966) (xy 116.727907 -167.616724) (xy 116.780202 -167.63208)
			(xy 116.82978 -167.654722) (xy 116.875631 -167.684189) (xy 116.916822 -167.719882) (xy 116.952514 -167.761073)
			(xy 116.981981 -167.806925) (xy 117.004622 -167.856503) (xy 117.019978 -167.908799) (xy 117.027734 -167.962748)
			(xy 117.027734 -168.017252) (xy 117.019978 -168.071201) (xy 117.004622 -168.123497) (xy 116.981981 -168.173075)
			(xy 116.952514 -168.218927) (xy 116.916822 -168.260118) (xy 116.875631 -168.295811) (xy 116.82978 -168.325278)
			(xy 116.780202 -168.34792) (xy 116.727907 -168.363276) (xy 116.673958 -168.371034) (xy 116.646706 -168.37152)
			(xy 116.646452 -168.37152) (xy 116.621249 -168.371103) (xy 116.571281 -168.364469) (xy 116.522627 -168.351298)
			(xy 116.476136 -168.33182) (xy 116.454174 -168.31945) (xy 116.444268 -168.313608) (xy 116.422424 -168.311576)
			(xy 116.327682 -168.345104) (xy 116.311934 -168.360598) (xy 116.30787 -168.371012) (xy 116.297139 -168.397773)
			(xy 116.268855 -168.448013) (xy 116.23333 -168.493422) (xy 116.191373 -168.532965) (xy 116.143941 -168.56574)
			(xy 116.092115 -168.591001) (xy 116.037077 -168.608171) (xy 115.980081 -168.616859) (xy 115.951254 -168.617392)
			(xy 115.924001 -168.616965) (xy 115.87005 -168.609202) (xy 115.817753 -168.59384) (xy 115.768175 -168.571192)
			(xy 115.722324 -168.54172) (xy 115.681134 -168.506022) (xy 115.645443 -168.464826) (xy 115.615978 -168.418971)
			(xy 115.593338 -168.369388) (xy 115.577985 -168.317089) (xy 115.570231 -168.263137) (xy 115.569746 -168.235884)
			(xy 115.570409 -168.204321) (xy 115.580794 -168.142056) (xy 115.601279 -168.082347) (xy 115.61572 -168.054274)
			(xy 115.620546 -168.045384) (xy 115.622578 -168.025826) (xy 115.599718 -167.94734) (xy 115.596487 -167.937913)
			(xy 115.584063 -167.922357) (xy 115.575588 -167.917114) (xy 115.550462 -167.902606) (xy 115.50458 -167.867096)
			(xy 115.464607 -167.825045) (xy 115.431465 -167.777424) (xy 115.405918 -167.725333) (xy 115.388557 -167.669972)
			(xy 115.379782 -167.612621) (xy 115.379246 -167.583612) (xy 102.148132 -167.583612) (xy 102.148132 -169.015918)
			(xy 102.14854 -169.025989) (xy 102.156272 -169.044587) (xy 102.163118 -169.051986) (xy 102.968887 -169.857674)
			(xy 111.593122 -169.857674) (xy 111.593631 -169.830101) (xy 111.601574 -169.77553) (xy 111.61729 -169.72267)
			(xy 111.640451 -169.672624) (xy 111.670577 -169.626433) (xy 111.707038 -169.585061) (xy 111.727742 -169.566844)
			(xy 111.735805 -169.559278) (xy 111.745164 -169.539274) (xy 111.745776 -169.528236) (xy 111.745776 -169.450512)
			(xy 111.745209 -169.439462) (xy 111.735844 -169.419441) (xy 111.727742 -169.411904) (xy 111.707038 -169.393685)
			(xy 111.670565 -169.352319) (xy 111.640431 -169.306131) (xy 111.617264 -169.256084) (xy 111.601547 -169.203223)
			(xy 111.593607 -169.148648) (xy 111.593122 -169.121074) (xy 111.593631 -169.093501) (xy 111.601574 -169.03893)
			(xy 111.61729 -168.98607) (xy 111.640451 -168.936024) (xy 111.670577 -168.889833) (xy 111.707038 -168.848461)
			(xy 111.727742 -168.830244) (xy 111.735805 -168.822678) (xy 111.745164 -168.802674) (xy 111.745776 -168.791636)
			(xy 111.745776 -168.713912) (xy 111.745209 -168.702862) (xy 111.735844 -168.682841) (xy 111.727742 -168.675304)
			(xy 111.707038 -168.657085) (xy 111.670565 -168.615719) (xy 111.640431 -168.569531) (xy 111.617264 -168.519484)
			(xy 111.601547 -168.466623) (xy 111.593607 -168.412048) (xy 111.593122 -168.384474) (xy 111.593531 -168.357219)
			(xy 111.601292 -168.303265) (xy 111.616653 -168.250964) (xy 111.639301 -168.201382) (xy 111.668774 -168.155527)
			(xy 111.704474 -168.114334) (xy 111.745672 -168.078641) (xy 111.791531 -168.049174) (xy 111.841116 -168.026533)
			(xy 111.893419 -168.01118) (xy 111.947375 -168.003427) (xy 111.97463 -168.002966) (xy 112.002485 -168.003487)
			(xy 112.057599 -168.011614) (xy 112.110948 -168.027662) (xy 112.1614 -168.05129) (xy 112.207883 -168.081997)
			(xy 112.249412 -168.119132) (xy 112.285106 -168.161906) (xy 112.314206 -168.209412) (xy 112.336096 -168.260642)
			(xy 112.343692 -168.287446) (xy 112.345978 -168.296336) (xy 112.356646 -168.311576) (xy 112.428528 -168.359328)
			(xy 112.446562 -168.363392) (xy 112.455706 -168.362122) (xy 112.468723 -168.360454) (xy 112.494907 -168.358673)
			(xy 112.50803 -168.358566) (xy 112.522179 -168.358657) (xy 112.550402 -168.360693) (xy 112.564418 -168.36263)
			(xy 112.574324 -168.364154) (xy 112.594136 -168.359328) (xy 112.668558 -168.303448) (xy 112.678718 -168.285922)
			(xy 112.679988 -168.275762) (xy 112.684077 -168.248608) (xy 112.699049 -168.195778) (xy 112.72144 -168.145639)
			(xy 112.750787 -168.099228) (xy 112.786485 -168.057504) (xy 112.827794 -168.021327) (xy 112.873863 -167.991446)
			(xy 112.92374 -167.968477) (xy 112.976394 -167.952896) (xy 113.030738 -167.945024) (xy 113.058194 -167.944546)
			(xy 113.085443 -167.945083) (xy 113.139387 -167.952838) (xy 113.191677 -167.96819) (xy 113.241252 -167.990827)
			(xy 113.2871 -168.020288) (xy 113.328289 -168.055974) (xy 113.363981 -168.097158) (xy 113.393448 -168.143003)
			(xy 113.416092 -168.192574) (xy 113.431451 -168.244863) (xy 113.439213 -168.298805) (xy 113.439702 -168.326054)
			(xy 113.439204 -168.353627) (xy 113.431258 -168.408199) (xy 113.415539 -168.461058) (xy 113.392375 -168.511104)
			(xy 113.362249 -168.557294) (xy 113.325787 -168.598667) (xy 113.305082 -168.616884) (xy 113.297011 -168.624443)
			(xy 113.287655 -168.644452) (xy 113.287048 -168.655492) (xy 113.287048 -168.733216) (xy 113.287648 -168.744262)
			(xy 113.296989 -168.764284) (xy 113.305082 -168.771824) (xy 113.325804 -168.790023) (xy 113.362275 -168.831394)
			(xy 113.392406 -168.877586) (xy 113.41557 -168.927637) (xy 113.431283 -168.980502) (xy 113.439219 -169.035078)
			(xy 113.439253 -169.037) (xy 118.02821 -169.037) (xy 118.032281 -168.981378) (xy 118.044407 -168.926941)
			(xy 118.06433 -168.87485) (xy 118.091626 -168.826215) (xy 118.125712 -168.782072) (xy 118.165861 -168.743363)
			(xy 118.211219 -168.710912) (xy 118.260819 -168.685411) (xy 118.313603 -168.667404) (xy 118.368446 -168.657274)
			(xy 118.42418 -168.655237) (xy 118.479617 -168.661337) (xy 118.533574 -168.675443) (xy 118.584903 -168.697255)
			(xy 118.632509 -168.726309) (xy 118.675377 -168.761984) (xy 118.712594 -168.803521) (xy 118.743367 -168.850034)
			(xy 118.767039 -168.900531) (xy 118.783107 -168.953938) (xy 118.791227 -169.009114) (xy 118.791736 -169.037)
			(xy 118.791227 -169.064886) (xy 118.783107 -169.120062) (xy 118.767039 -169.173469) (xy 118.743367 -169.223966)
			(xy 118.712594 -169.270479) (xy 118.675377 -169.312016) (xy 118.632509 -169.347691) (xy 118.584903 -169.376745)
			(xy 118.533574 -169.398557) (xy 118.479617 -169.412663) (xy 118.42418 -169.418763) (xy 118.368446 -169.416726)
			(xy 118.313603 -169.406596) (xy 118.260819 -169.388589) (xy 118.211219 -169.363088) (xy 118.165861 -169.330637)
			(xy 118.125712 -169.291928) (xy 118.091626 -169.247785) (xy 118.06433 -169.19915) (xy 118.044407 -169.147059)
			(xy 118.032281 -169.092622) (xy 118.02821 -169.037) (xy 113.439253 -169.037) (xy 113.439702 -169.062654)
			(xy 113.439202 -169.089906) (xy 113.431451 -169.143856) (xy 113.416101 -169.196153) (xy 113.393463 -169.245734)
			(xy 113.363999 -169.291587) (xy 113.328309 -169.332781) (xy 113.28712 -169.368475) (xy 113.241269 -169.397944)
			(xy 113.191691 -169.420587) (xy 113.139395 -169.435943) (xy 113.085446 -169.443699) (xy 113.058194 -169.444162)
			(xy 113.057686 -169.444162) (xy 113.023904 -169.442638) (xy 113.013744 -169.441622) (xy 112.99444 -169.447718)
			(xy 112.931448 -169.50055) (xy 112.92415 -169.507266) (xy 112.914875 -169.524776) (xy 112.913414 -169.534586)
			(xy 112.913414 -169.535348) (xy 112.910463 -169.563509) (xy 112.897256 -169.61857) (xy 112.876053 -169.671073)
			(xy 112.84732 -169.719863) (xy 112.811689 -169.76387) (xy 112.769944 -169.802124) (xy 112.723001 -169.833786)
			(xy 112.671893 -169.85816) (xy 112.617743 -169.87471) (xy 112.561741 -169.883071) (xy 112.53343 -169.883582)
			(xy 112.515411 -169.883366) (xy 112.479536 -169.879928) (xy 112.461802 -169.876724) (xy 112.45215 -169.874946)
			(xy 112.4331 -169.878502) (xy 112.35817 -169.926508) (xy 112.34674 -169.942256) (xy 112.344454 -169.951654)
			(xy 112.337089 -169.978708) (xy 112.315456 -170.030436) (xy 112.286488 -170.078442) (xy 112.250809 -170.121694)
			(xy 112.209185 -170.159261) (xy 112.162513 -170.190334) (xy 112.111798 -170.214244) (xy 112.05813 -170.230478)
			(xy 112.002665 -170.238685) (xy 111.97463 -170.239182) (xy 111.947377 -170.238717) (xy 111.893424 -170.230963)
			(xy 111.841125 -170.21561) (xy 111.791543 -170.192969) (xy 111.745689 -170.163501) (xy 111.704495 -170.127808)
			(xy 111.668801 -170.086614) (xy 111.639333 -170.04076) (xy 111.616692 -169.991179) (xy 111.601338 -169.938879)
			(xy 111.593584 -169.884927) (xy 111.593122 -169.857674) (xy 102.968887 -169.857674) (xy 104.44452 -171.33316)
			(xy 113.21034 -171.33316) (xy 113.210833 -171.305586) (xy 113.218778 -171.251014) (xy 113.234497 -171.198154)
			(xy 113.257662 -171.148108) (xy 113.28779 -171.101917) (xy 113.324254 -171.060546) (xy 113.34496 -171.04233)
			(xy 113.353031 -171.034772) (xy 113.362385 -171.014762) (xy 113.362994 -171.003722) (xy 113.362994 -170.925998)
			(xy 113.362373 -170.914955) (xy 113.353045 -170.894934) (xy 113.34496 -170.88739) (xy 113.324233 -170.869197)
			(xy 113.287765 -170.827823) (xy 113.257636 -170.781629) (xy 113.234474 -170.731578) (xy 113.21876 -170.678713)
			(xy 113.210824 -170.624136) (xy 113.21034 -170.59656) (xy 113.210869 -170.567888) (xy 113.219469 -170.511192)
			(xy 113.236454 -170.456421) (xy 113.261442 -170.404807) (xy 113.293871 -170.357513) (xy 113.333011 -170.315602)
			(xy 113.37798 -170.280019) (xy 113.402618 -170.265344) (xy 113.402872 -170.265344) (xy 113.411379 -170.259887)
			(xy 113.423556 -170.243773) (xy 113.426494 -170.234102) (xy 113.44783 -170.154092) (xy 113.445036 -170.134026)
			(xy 113.439702 -170.125136) (xy 113.42735 -170.103476) (xy 113.407872 -170.057577) (xy 113.394688 -170.00949)
			(xy 113.388033 -169.960075) (xy 113.387632 -169.935144) (xy 113.388075 -169.908525) (xy 113.395647 -169.855828)
			(xy 113.410642 -169.804746) (xy 113.432755 -169.756318) (xy 113.461537 -169.71153) (xy 113.4964 -169.671296)
			(xy 113.536635 -169.636433) (xy 113.581423 -169.607652) (xy 113.629851 -169.58554) (xy 113.680934 -169.570545)
			(xy 113.733631 -169.562975) (xy 113.76025 -169.562526) (xy 113.786672 -169.562972) (xy 113.838987 -169.570428)
			(xy 113.889725 -169.585196) (xy 113.937869 -169.606982) (xy 113.982454 -169.635348) (xy 114.00282 -169.652188)
			(xy 114.009678 -169.65803) (xy 114.026696 -169.66438) (xy 114.111024 -169.66438) (xy 114.128042 -169.65803)
			(xy 114.1349 -169.652188) (xy 114.155266 -169.635349) (xy 114.199852 -169.606984) (xy 114.247996 -169.585197)
			(xy 114.298733 -169.570426) (xy 114.351048 -169.562966) (xy 114.403892 -169.562966) (xy 114.456207 -169.570426)
			(xy 114.506944 -169.585197) (xy 114.555088 -169.606984) (xy 114.599674 -169.635349) (xy 114.62004 -169.652188)
			(xy 114.626898 -169.65803) (xy 114.643916 -169.66438) (xy 114.728244 -169.66438) (xy 114.745262 -169.65803)
			(xy 114.75212 -169.652188) (xy 114.772477 -169.635339) (xy 114.817069 -169.606986) (xy 114.865216 -169.585209)
			(xy 114.915954 -169.570444) (xy 114.968269 -169.562986) (xy 114.99469 -169.562526) (xy 115.022581 -169.562932)
			(xy 115.077739 -169.571245) (xy 115.131042 -169.587685) (xy 115.181299 -169.611887) (xy 115.227388 -169.643309)
			(xy 115.268279 -169.681249) (xy 115.303059 -169.72486) (xy 115.33095 -169.773167) (xy 115.351329 -169.825092)
			(xy 115.363742 -169.879475) (xy 115.367911 -169.9351) (xy 115.363742 -169.990725) (xy 115.351329 -170.045108)
			(xy 115.33095 -170.097033) (xy 115.303059 -170.14534) (xy 115.268279 -170.188951) (xy 115.227388 -170.226891)
			(xy 115.181299 -170.258313) (xy 115.131042 -170.282515) (xy 115.077739 -170.298955) (xy 115.022581 -170.307268)
			(xy 114.99469 -170.307762) (xy 114.968269 -170.307295) (xy 114.915954 -170.299845) (xy 114.865216 -170.285082)
			(xy 114.817072 -170.2633) (xy 114.772486 -170.234938) (xy 114.75212 -170.2181) (xy 114.745262 -170.212258)
			(xy 114.728244 -170.205908) (xy 114.643916 -170.205908) (xy 114.626898 -170.212258) (xy 114.62004 -170.2181)
			(xy 114.599674 -170.234939) (xy 114.555088 -170.263304) (xy 114.506944 -170.285091) (xy 114.456207 -170.299862)
			(xy 114.403892 -170.307322) (xy 114.351048 -170.307322) (xy 114.298733 -170.299862) (xy 114.247996 -170.285091)
			(xy 114.199852 -170.263304) (xy 114.155266 -170.234939) (xy 114.1349 -170.2181) (xy 114.128042 -170.212258)
			(xy 114.111024 -170.205908) (xy 114.026696 -170.205908) (xy 114.009678 -170.212258) (xy 114.00282 -170.2181)
			(xy 113.990525 -170.228404) (xy 113.964455 -170.247101) (xy 113.95075 -170.255438) (xy 113.942114 -170.260518)
			(xy 113.929922 -170.277028) (xy 113.907824 -170.367198) (xy 113.911126 -170.387264) (xy 113.91646 -170.3959)
			(xy 113.929919 -170.418564) (xy 113.951182 -170.466795) (xy 113.965598 -170.517495) (xy 113.972893 -170.569697)
			(xy 113.973356 -170.596052) (xy 113.973356 -170.59656) (xy 113.972878 -170.624134) (xy 113.96493 -170.678707)
			(xy 113.949209 -170.731568) (xy 113.926041 -170.781614) (xy 113.89591 -170.827804) (xy 113.859443 -170.869175)
			(xy 113.838736 -170.88739) (xy 113.830655 -170.894939) (xy 113.821724 -170.91406) (xy 118.987062 -170.91406)
			(xy 118.987538 -170.886149) (xy 118.995677 -170.830922) (xy 119.011777 -170.777472) (xy 119.035494 -170.726937)
			(xy 119.06632 -170.680398) (xy 119.084598 -170.659298) (xy 119.090495 -170.652121) (xy 119.097146 -170.634796)
			(xy 119.097552 -170.625516) (xy 119.097552 -170.547792) (xy 119.090948 -170.53052) (xy 119.084598 -170.523408)
			(xy 119.066302 -170.502323) (xy 119.035477 -170.455781) (xy 119.011765 -170.405242) (xy 118.995673 -170.351788)
			(xy 118.987544 -170.296558) (xy 118.987062 -170.268646) (xy 118.987548 -170.241395) (xy 118.995304 -170.187447)
			(xy 119.010659 -170.135152) (xy 119.033301 -170.085575) (xy 119.062767 -170.039725) (xy 119.098458 -169.998534)
			(xy 119.139649 -169.962843) (xy 119.185499 -169.933377) (xy 119.235076 -169.910735) (xy 119.287371 -169.89538)
			(xy 119.341319 -169.887624) (xy 119.395821 -169.887624) (xy 119.449769 -169.89538) (xy 119.502064 -169.910735)
			(xy 119.551641 -169.933377) (xy 119.597491 -169.962843) (xy 119.638682 -169.998534) (xy 119.674373 -170.039725)
			(xy 119.703839 -170.085575) (xy 119.726481 -170.135152) (xy 119.741836 -170.187447) (xy 119.749592 -170.241395)
			(xy 119.750078 -170.268646) (xy 119.749596 -170.296557) (xy 119.741456 -170.351783) (xy 119.725357 -170.405233)
			(xy 119.701643 -170.455767) (xy 119.670818 -170.502307) (xy 119.652542 -170.523408) (xy 119.646635 -170.530578)
			(xy 119.639992 -170.547909) (xy 119.639588 -170.55719) (xy 119.639588 -170.634914) (xy 119.646192 -170.652186)
			(xy 119.652542 -170.659298) (xy 119.6708 -170.680414) (xy 119.701629 -170.726949) (xy 119.725347 -170.777479)
			(xy 119.741449 -170.830927) (xy 119.749589 -170.88615) (xy 119.750078 -170.91406) (xy 119.749592 -170.941311)
			(xy 119.741836 -170.995259) (xy 119.726481 -171.047554) (xy 119.703839 -171.097131) (xy 119.674373 -171.142981)
			(xy 119.638682 -171.184172) (xy 119.597491 -171.219863) (xy 119.551641 -171.249329) (xy 119.502064 -171.271971)
			(xy 119.449769 -171.287326) (xy 119.395821 -171.295082) (xy 119.341319 -171.295082) (xy 119.287371 -171.287326)
			(xy 119.235076 -171.271971) (xy 119.185499 -171.249329) (xy 119.139649 -171.219863) (xy 119.098458 -171.184172)
			(xy 119.062767 -171.142981) (xy 119.033301 -171.097131) (xy 119.010659 -171.047554) (xy 118.995304 -170.995259)
			(xy 118.987548 -170.941311) (xy 118.987062 -170.91406) (xy 113.821724 -170.91406) (xy 113.821306 -170.914956)
			(xy 113.820702 -170.925998) (xy 113.820702 -171.003722) (xy 113.821313 -171.014766) (xy 113.830648 -171.034788)
			(xy 113.838736 -171.04233) (xy 113.859472 -171.060514) (xy 113.895939 -171.101889) (xy 113.926067 -171.148085)
			(xy 113.949228 -171.198138) (xy 113.96494 -171.251005) (xy 113.972874 -171.305584) (xy 113.973356 -171.33316)
			(xy 113.97287 -171.360411) (xy 113.965114 -171.414359) (xy 113.949759 -171.466654) (xy 113.927117 -171.516231)
			(xy 113.897651 -171.562081) (xy 113.86196 -171.603272) (xy 113.820769 -171.638963) (xy 113.774919 -171.668429)
			(xy 113.725342 -171.691071) (xy 113.673047 -171.706426) (xy 113.619099 -171.714182) (xy 113.564597 -171.714182)
			(xy 113.510649 -171.706426) (xy 113.458354 -171.691071) (xy 113.408777 -171.668429) (xy 113.362927 -171.638963)
			(xy 113.321736 -171.603272) (xy 113.286045 -171.562081) (xy 113.256579 -171.516231) (xy 113.233937 -171.466654)
			(xy 113.218582 -171.414359) (xy 113.210826 -171.360411) (xy 113.21034 -171.33316) (xy 104.44452 -171.33316)
			(xy 104.704896 -171.59351) (xy 104.712302 -171.600342) (xy 104.730897 -171.608066) (xy 104.740964 -171.608496)
			(xy 109.09046 -171.608496) (xy 109.115456 -171.609136) (xy 109.16448 -171.618936) (xy 109.210651 -171.638108)
			(xy 109.252196 -171.665916) (xy 109.270292 -171.683172) (xy 110.20171 -172.61459) (xy 110.218935 -172.632698)
			(xy 110.246677 -172.674257) (xy 110.265785 -172.720428) (xy 110.275523 -172.769438) (xy 110.276132 -172.794422)
			(xy 110.276132 -173.59884) (xy 130.214624 -173.59884) (xy 130.215108 -173.57147) (xy 130.22292 -173.517292)
			(xy 130.238405 -173.464789) (xy 130.261243 -173.415041) (xy 130.290964 -173.369074) (xy 130.308604 -173.348142)
			(xy 130.308858 -173.347888) (xy 130.314463 -173.340814) (xy 130.320697 -173.323887) (xy 130.32105 -173.314868)
			(xy 130.32105 -173.247812) (xy 130.320698 -173.238794) (xy 130.314448 -173.221877) (xy 130.308858 -173.214792)
			(xy 130.308604 -173.214792) (xy 130.308604 -173.214538) (xy 130.291003 -173.193573) (xy 130.261279 -173.14761)
			(xy 130.238432 -173.097869) (xy 130.222934 -173.045372) (xy 130.215102 -172.991199) (xy 130.215098 -172.936462)
			(xy 130.222921 -172.882287) (xy 130.238411 -172.829787) (xy 130.26125 -172.780043) (xy 130.290967 -172.734075)
			(xy 130.308604 -172.713142) (xy 130.308858 -172.712888) (xy 130.314463 -172.705814) (xy 130.320697 -172.688887)
			(xy 130.32105 -172.679868) (xy 130.32105 -172.612812) (xy 130.320698 -172.603794) (xy 130.314448 -172.586877)
			(xy 130.308858 -172.579792) (xy 130.308604 -172.579792) (xy 130.308604 -172.579538) (xy 130.291003 -172.558573)
			(xy 130.261279 -172.51261) (xy 130.238432 -172.462869) (xy 130.222934 -172.410372) (xy 130.215102 -172.356199)
			(xy 130.215098 -172.301462) (xy 130.222921 -172.247287) (xy 130.238411 -172.194787) (xy 130.26125 -172.145043)
			(xy 130.290967 -172.099075) (xy 130.308604 -172.078142) (xy 130.308858 -172.077888) (xy 130.314463 -172.070814)
			(xy 130.320697 -172.053887) (xy 130.32105 -172.044868) (xy 130.32105 -171.977812) (xy 130.320698 -171.968794)
			(xy 130.314448 -171.951877) (xy 130.308858 -171.944792) (xy 130.308604 -171.944792) (xy 130.308604 -171.944538)
			(xy 130.29097 -171.923602) (xy 130.261257 -171.87763) (xy 130.23842 -171.827884) (xy 130.222928 -171.775384)
			(xy 130.215099 -171.721209) (xy 130.214624 -171.69384) (xy 130.215109 -171.665965) (xy 130.22322 -171.610807)
			(xy 130.239275 -171.557418) (xy 130.262932 -171.506936) (xy 130.293686 -171.460435) (xy 130.311906 -171.439332)
			(xy 130.318002 -171.432474) (xy 130.324606 -171.415202) (xy 130.32486 -171.328588) (xy 130.318256 -171.311316)
			(xy 130.31216 -171.304458) (xy 130.31216 -171.304204) (xy 130.294099 -171.283136) (xy 130.263576 -171.236796)
			(xy 130.240103 -171.186515) (xy 130.224177 -171.13336) (xy 130.216135 -171.078457) (xy 130.21564 -171.050712)
			(xy 130.216103 -171.023342) (xy 130.22392 -170.969162) (xy 130.23941 -170.916658) (xy 130.262252 -170.866912)
			(xy 130.291978 -170.820945) (xy 130.30962 -170.800014) (xy 130.309874 -170.79976) (xy 130.31545 -170.792667)
			(xy 130.321701 -170.775755) (xy 130.322066 -170.76674) (xy 130.322066 -170.699684) (xy 130.321724 -170.690665)
			(xy 130.315467 -170.673748) (xy 130.309874 -170.666664) (xy 130.30962 -170.666664) (xy 130.30962 -170.66641)
			(xy 130.291991 -170.645468) (xy 130.262267 -170.599501) (xy 130.239421 -170.549757) (xy 130.223924 -170.497256)
			(xy 130.216095 -170.443079) (xy 130.216093 -170.388339) (xy 130.22392 -170.334162) (xy 130.239415 -170.28166)
			(xy 130.262258 -170.231915) (xy 130.29198 -170.185947) (xy 130.30962 -170.165014) (xy 130.309874 -170.16476)
			(xy 130.31545 -170.157667) (xy 130.321701 -170.140755) (xy 130.322066 -170.13174) (xy 130.322066 -170.064684)
			(xy 130.321724 -170.055665) (xy 130.315467 -170.038748) (xy 130.309874 -170.031664) (xy 130.30962 -170.031664)
			(xy 130.30962 -170.03141) (xy 130.291991 -170.010468) (xy 130.262267 -169.964501) (xy 130.239421 -169.914757)
			(xy 130.223924 -169.862256) (xy 130.216095 -169.808079) (xy 130.216093 -169.753339) (xy 130.22392 -169.699162)
			(xy 130.239415 -169.64666) (xy 130.262258 -169.596915) (xy 130.29198 -169.550947) (xy 130.30962 -169.530014)
			(xy 130.309874 -169.52976) (xy 130.31545 -169.522667) (xy 130.321701 -169.505755) (xy 130.322066 -169.49674)
			(xy 130.322066 -169.429684) (xy 130.321724 -169.420665) (xy 130.315467 -169.403748) (xy 130.309874 -169.396664)
			(xy 130.30962 -169.396664) (xy 130.30962 -169.39641) (xy 130.291975 -169.375482) (xy 130.262264 -169.329509)
			(xy 130.239428 -169.27976) (xy 130.223939 -169.227258) (xy 130.216113 -169.173082) (xy 130.21564 -169.145712)
			(xy 130.216121 -169.118413) (xy 130.223892 -169.064371) (xy 130.23929 -169.01199) (xy 130.262002 -168.96234)
			(xy 130.291562 -168.916437) (xy 130.309112 -168.895522) (xy 130.31496 -168.888335) (xy 130.321465 -168.871)
			(xy 130.321812 -168.86174) (xy 130.321558 -168.785794) (xy 130.315208 -168.768776) (xy 130.309112 -168.761918)
			(xy 130.291409 -168.740948) (xy 130.261528 -168.694919) (xy 130.238559 -168.645079) (xy 130.222977 -168.592461)
			(xy 130.215103 -168.538151) (xy 130.214624 -168.510712) (xy 130.215067 -168.483458) (xy 130.222823 -168.429505)
			(xy 130.238179 -168.377204) (xy 130.260822 -168.327622) (xy 130.290292 -168.281768) (xy 130.325988 -168.240574)
			(xy 130.367184 -168.20488) (xy 130.41304 -168.175413) (xy 130.462623 -168.152772) (xy 130.514924 -168.137418)
			(xy 130.568878 -168.129665) (xy 130.596132 -168.129204) (xy 130.623503 -168.12965) (xy 130.677683 -168.137473)
			(xy 130.730186 -168.152966) (xy 130.779933 -168.175813) (xy 130.825899 -168.205541) (xy 130.84683 -168.223184)
			(xy 130.847084 -168.223438) (xy 130.854168 -168.229028) (xy 130.871087 -168.235272) (xy 130.880104 -168.23563)
			(xy 130.94716 -168.23563) (xy 130.956174 -168.235247) (xy 130.973091 -168.229017) (xy 130.98018 -168.223438)
			(xy 130.98018 -168.223184) (xy 130.980434 -168.223184) (xy 131.001378 -168.20556) (xy 131.047348 -168.175846)
			(xy 131.097092 -168.153008) (xy 131.14959 -168.137513) (xy 131.203764 -168.129681) (xy 131.231132 -168.129204)
			(xy 131.258385 -168.129648) (xy 131.312334 -168.137409) (xy 131.364631 -168.152769) (xy 131.414209 -168.175415)
			(xy 131.46006 -168.204886) (xy 131.50125 -168.240581) (xy 131.536941 -168.281776) (xy 131.566406 -168.32763)
			(xy 131.589046 -168.377211) (xy 131.6044 -168.429509) (xy 131.612155 -168.483459) (xy 131.61264 -168.510712)
			(xy 131.612153 -168.538011) (xy 131.604381 -168.592051) (xy 131.588983 -168.644432) (xy 131.566273 -168.694081)
			(xy 131.536716 -168.739986) (xy 131.519168 -168.760902) (xy 131.51335 -168.76811) (xy 131.506828 -168.785429)
			(xy 131.506468 -168.794684) (xy 131.506722 -168.87063) (xy 131.513072 -168.887648) (xy 131.519168 -168.894506)
			(xy 131.53688 -168.915469) (xy 131.56676 -168.9615) (xy 131.589727 -169.011341) (xy 131.605308 -169.063962)
			(xy 131.613178 -169.118273) (xy 131.613656 -169.145712) (xy 131.613208 -169.173083) (xy 131.605387 -169.227263)
			(xy 131.589895 -169.279767) (xy 131.567049 -169.329514) (xy 131.53732 -169.375479) (xy 131.519676 -169.39641)
			(xy 131.519422 -169.396664) (xy 131.513835 -169.40375) (xy 131.507591 -169.420668) (xy 131.50723 -169.429684)
			(xy 131.50723 -169.49674) (xy 131.507561 -169.50576) (xy 131.513826 -169.522677) (xy 131.519422 -169.52976)
			(xy 131.519676 -169.52976) (xy 131.519676 -169.530014) (xy 131.537328 -169.550937) (xy 131.567052 -169.596907)
			(xy 131.589897 -169.646655) (xy 131.605392 -169.699158) (xy 131.61322 -169.753338) (xy 131.613218 -169.80808)
			(xy 131.605388 -169.86226) (xy 131.589891 -169.914762) (xy 131.567044 -169.964509) (xy 131.537317 -170.010477)
			(xy 131.519676 -170.03141) (xy 131.519422 -170.031664) (xy 131.513835 -170.03875) (xy 131.507591 -170.055668)
			(xy 131.50723 -170.064684) (xy 131.50723 -170.13174) (xy 131.507561 -170.14076) (xy 131.513826 -170.157677)
			(xy 131.519422 -170.16476) (xy 131.519676 -170.16476) (xy 131.519676 -170.165014) (xy 131.537328 -170.185937)
			(xy 131.567052 -170.231907) (xy 131.589897 -170.281655) (xy 131.605392 -170.334158) (xy 131.61322 -170.388338)
			(xy 131.613218 -170.44308) (xy 131.605388 -170.49726) (xy 131.589891 -170.549762) (xy 131.567044 -170.599509)
			(xy 131.537317 -170.645477) (xy 131.519676 -170.66641) (xy 131.519422 -170.666664) (xy 131.513835 -170.67375)
			(xy 131.507591 -170.690668) (xy 131.50723 -170.699684) (xy 131.50723 -170.76674) (xy 131.507561 -170.77576)
			(xy 131.513826 -170.792677) (xy 131.519422 -170.79976) (xy 131.519676 -170.79976) (xy 131.519676 -170.800014)
			(xy 131.537285 -170.820971) (xy 131.567002 -170.866936) (xy 131.589844 -170.916678) (xy 131.605342 -170.969173)
			(xy 131.613178 -171.023344) (xy 131.613656 -171.050712) (xy 131.613122 -171.078585) (xy 131.60502 -171.13374)
			(xy 131.588975 -171.187128) (xy 131.56533 -171.237611) (xy 131.534587 -171.284114) (xy 131.516374 -171.30522)
			(xy 131.510278 -171.312078) (xy 131.503674 -171.32935) (xy 131.50342 -171.415964) (xy 131.510024 -171.433236)
			(xy 131.51612 -171.440094) (xy 131.51612 -171.440348) (xy 131.534202 -171.461398) (xy 131.564723 -171.507743)
			(xy 131.588192 -171.558028) (xy 131.604113 -171.611187) (xy 131.612148 -171.666094) (xy 131.61264 -171.69384)
			(xy 131.612153 -171.72121) (xy 131.604343 -171.775388) (xy 131.588859 -171.827892) (xy 131.566022 -171.877639)
			(xy 131.5363 -171.923606) (xy 131.51866 -171.944538) (xy 131.518406 -171.944792) (xy 131.512817 -171.951877)
			(xy 131.506572 -171.968795) (xy 131.506214 -171.977812) (xy 131.506214 -172.044868) (xy 131.506584 -172.053884)
			(xy 131.512822 -172.070801) (xy 131.518406 -172.077888) (xy 131.51866 -172.077888) (xy 131.51866 -172.078142)
			(xy 131.53634 -172.099043) (xy 131.566065 -172.145016) (xy 131.588908 -172.194767) (xy 131.604402 -172.247274)
			(xy 131.612227 -172.301457) (xy 131.612225 -172.32884) (xy 133.592824 -172.32884) (xy 133.593308 -172.30147)
			(xy 133.60112 -172.247292) (xy 133.616605 -172.194789) (xy 133.639443 -172.145041) (xy 133.669164 -172.099074)
			(xy 133.686804 -172.078142) (xy 133.687058 -172.077888) (xy 133.692663 -172.070814) (xy 133.698897 -172.053887)
			(xy 133.69925 -172.044868) (xy 133.69925 -171.977812) (xy 133.698898 -171.968794) (xy 133.692648 -171.951877)
			(xy 133.687058 -171.944792) (xy 133.686804 -171.944792) (xy 133.686804 -171.944538) (xy 133.66917 -171.923602)
			(xy 133.639457 -171.87763) (xy 133.61662 -171.827884) (xy 133.601128 -171.775384) (xy 133.593299 -171.721209)
			(xy 133.592824 -171.69384) (xy 133.593309 -171.665965) (xy 133.60142 -171.610807) (xy 133.617475 -171.557418)
			(xy 133.641132 -171.506936) (xy 133.671886 -171.460435) (xy 133.690106 -171.439332) (xy 133.696202 -171.432474)
			(xy 133.702806 -171.415202) (xy 133.70306 -171.328588) (xy 133.696456 -171.311316) (xy 133.69036 -171.304458)
			(xy 133.69036 -171.304204) (xy 133.672299 -171.283136) (xy 133.641776 -171.236796) (xy 133.618303 -171.186515)
			(xy 133.602377 -171.13336) (xy 133.594335 -171.078457) (xy 133.59384 -171.050712) (xy 133.594303 -171.023342)
			(xy 133.60212 -170.969162) (xy 133.61761 -170.916658) (xy 133.640452 -170.866912) (xy 133.670178 -170.820945)
			(xy 133.68782 -170.800014) (xy 133.688074 -170.79976) (xy 133.69365 -170.792667) (xy 133.699901 -170.775755)
			(xy 133.700266 -170.76674) (xy 133.700266 -170.699684) (xy 133.699924 -170.690665) (xy 133.693667 -170.673748)
			(xy 133.688074 -170.666664) (xy 133.68782 -170.666664) (xy 133.68782 -170.66641) (xy 133.670191 -170.645468)
			(xy 133.640467 -170.599501) (xy 133.617621 -170.549757) (xy 133.602124 -170.497256) (xy 133.594295 -170.443079)
			(xy 133.594293 -170.388339) (xy 133.60212 -170.334162) (xy 133.617615 -170.28166) (xy 133.640458 -170.231915)
			(xy 133.67018 -170.185947) (xy 133.68782 -170.165014) (xy 133.688074 -170.16476) (xy 133.69365 -170.157667)
			(xy 133.699901 -170.140755) (xy 133.700266 -170.13174) (xy 133.700266 -170.064684) (xy 133.699924 -170.055665)
			(xy 133.693667 -170.038748) (xy 133.688074 -170.031664) (xy 133.68782 -170.031664) (xy 133.68782 -170.03141)
			(xy 133.670191 -170.010468) (xy 133.640467 -169.964501) (xy 133.617621 -169.914757) (xy 133.602124 -169.862256)
			(xy 133.594295 -169.808079) (xy 133.594293 -169.753339) (xy 133.60212 -169.699162) (xy 133.617615 -169.64666)
			(xy 133.640458 -169.596915) (xy 133.67018 -169.550947) (xy 133.68782 -169.530014) (xy 133.688074 -169.52976)
			(xy 133.69365 -169.522667) (xy 133.699901 -169.505755) (xy 133.700266 -169.49674) (xy 133.700266 -169.429684)
			(xy 133.699924 -169.420665) (xy 133.693667 -169.403748) (xy 133.688074 -169.396664) (xy 133.68782 -169.396664)
			(xy 133.68782 -169.39641) (xy 133.670175 -169.375482) (xy 133.640464 -169.329509) (xy 133.617628 -169.27976)
			(xy 133.602139 -169.227258) (xy 133.594313 -169.173082) (xy 133.59384 -169.145712) (xy 133.594321 -169.118413)
			(xy 133.602092 -169.064371) (xy 133.61749 -169.01199) (xy 133.640202 -168.96234) (xy 133.669762 -168.916437)
			(xy 133.687312 -168.895522) (xy 133.69316 -168.888335) (xy 133.699665 -168.871) (xy 133.700012 -168.86174)
			(xy 133.699758 -168.785794) (xy 133.693408 -168.768776) (xy 133.687312 -168.761918) (xy 133.669609 -168.740948)
			(xy 133.639728 -168.694919) (xy 133.616759 -168.645079) (xy 133.601177 -168.592461) (xy 133.593303 -168.538151)
			(xy 133.592824 -168.510712) (xy 133.593267 -168.483458) (xy 133.601023 -168.429505) (xy 133.616379 -168.377204)
			(xy 133.639022 -168.327622) (xy 133.668492 -168.281768) (xy 133.704188 -168.240574) (xy 133.745384 -168.20488)
			(xy 133.79124 -168.175413) (xy 133.840823 -168.152772) (xy 133.893124 -168.137418) (xy 133.947078 -168.129665)
			(xy 133.974332 -168.129204) (xy 134.001703 -168.12965) (xy 134.055883 -168.137473) (xy 134.108386 -168.152966)
			(xy 134.158133 -168.175813) (xy 134.204099 -168.205541) (xy 134.22503 -168.223184) (xy 134.225284 -168.223438)
			(xy 134.232368 -168.229028) (xy 134.249287 -168.235272) (xy 134.258304 -168.23563) (xy 134.32536 -168.23563)
			(xy 134.334374 -168.235247) (xy 134.351291 -168.229017) (xy 134.35838 -168.223438) (xy 134.35838 -168.223184)
			(xy 134.358634 -168.223184) (xy 134.379578 -168.20556) (xy 134.425548 -168.175846) (xy 134.475292 -168.153008)
			(xy 134.52779 -168.137513) (xy 134.581964 -168.129681) (xy 134.609332 -168.129204) (xy 134.637242 -168.129699)
			(xy 134.692467 -168.137836) (xy 134.745917 -168.153933) (xy 134.796452 -168.177644) (xy 134.842993 -168.208465)
			(xy 134.864094 -168.22674) (xy 134.871169 -168.232561) (xy 134.88822 -168.239216) (xy 134.897368 -168.239694)
			(xy 134.973568 -168.24071) (xy 134.991094 -168.234614) (xy 134.997952 -168.228518) (xy 135.018731 -168.211373)
			(xy 135.064232 -168.182532) (xy 135.11334 -168.160384) (xy 135.165077 -168.145372) (xy 135.218412 -168.137793)
			(xy 135.245348 -168.137332) (xy 135.272718 -168.137821) (xy 135.326896 -168.145632) (xy 135.379399 -168.161115)
			(xy 135.429146 -168.183952) (xy 135.475114 -168.213673) (xy 135.496046 -168.231312) (xy 135.4963 -168.231566)
			(xy 135.503377 -168.237166) (xy 135.520301 -168.243403) (xy 135.52932 -168.243758) (xy 135.596376 -168.243758)
			(xy 135.605393 -168.243399) (xy 135.62231 -168.237154) (xy 135.629396 -168.231566) (xy 135.629396 -168.231312)
			(xy 135.62965 -168.231312) (xy 135.650592 -168.213685) (xy 135.696562 -168.183971) (xy 135.746307 -168.161132)
			(xy 135.798805 -168.145639) (xy 135.852979 -168.137807) (xy 135.880348 -168.137332) (xy 135.907602 -168.137733)
			(xy 135.961555 -168.145497) (xy 136.013854 -168.160861) (xy 136.063434 -168.18351) (xy 136.109286 -168.212985)
			(xy 136.150477 -168.248686) (xy 136.186168 -168.289885) (xy 136.215632 -168.335743) (xy 136.23827 -168.385329)
			(xy 136.253621 -168.437631) (xy 136.261373 -168.491586) (xy 136.261856 -168.51884) (xy 136.261365 -168.546209)
			(xy 136.253555 -168.600388) (xy 136.238072 -168.652891) (xy 136.215236 -168.702639) (xy 136.185515 -168.748606)
			(xy 136.167876 -168.769538) (xy 136.167622 -168.769792) (xy 136.162024 -168.77687) (xy 136.155786 -168.793794)
			(xy 136.15543 -168.802812) (xy 136.15543 -168.869868) (xy 136.155796 -168.878884) (xy 136.162037 -168.895801)
			(xy 136.167622 -168.902888) (xy 136.167876 -168.902888) (xy 136.167876 -168.903142) (xy 136.185556 -168.924043)
			(xy 136.215279 -168.970016) (xy 136.238122 -169.019768) (xy 136.253615 -169.072275) (xy 136.261439 -169.126458)
			(xy 136.261435 -169.181203) (xy 136.253602 -169.235384) (xy 136.2381 -169.287889) (xy 136.21525 -169.337636)
			(xy 136.185519 -169.383605) (xy 136.167876 -169.404538) (xy 136.167622 -169.404792) (xy 136.162024 -169.41187)
			(xy 136.155786 -169.428794) (xy 136.15543 -169.437812) (xy 136.15543 -169.504868) (xy 136.155796 -169.513884)
			(xy 136.162037 -169.530801) (xy 136.167622 -169.537888) (xy 136.167876 -169.537888) (xy 136.167876 -169.538142)
			(xy 136.185556 -169.559043) (xy 136.215279 -169.605016) (xy 136.238122 -169.654768) (xy 136.253615 -169.707275)
			(xy 136.261439 -169.761458) (xy 136.261435 -169.816203) (xy 136.253602 -169.870384) (xy 136.2381 -169.922889)
			(xy 136.21525 -169.972636) (xy 136.185519 -170.018605) (xy 136.167876 -170.039538) (xy 136.167622 -170.039792)
			(xy 136.162024 -170.04687) (xy 136.155786 -170.063794) (xy 136.15543 -170.072812) (xy 136.15543 -170.139868)
			(xy 136.155796 -170.148884) (xy 136.162037 -170.165801) (xy 136.167622 -170.172888) (xy 136.167876 -170.172888)
			(xy 136.167876 -170.173142) (xy 136.185556 -170.194043) (xy 136.215279 -170.240016) (xy 136.238122 -170.289768)
			(xy 136.253615 -170.342275) (xy 136.261439 -170.396458) (xy 136.261435 -170.451203) (xy 136.253602 -170.505384)
			(xy 136.2381 -170.557889) (xy 136.21525 -170.607636) (xy 136.185519 -170.653605) (xy 136.167876 -170.674538)
			(xy 136.167622 -170.674792) (xy 136.162024 -170.68187) (xy 136.155786 -170.698794) (xy 136.15543 -170.707812)
			(xy 136.15543 -170.774868) (xy 136.155796 -170.783884) (xy 136.162037 -170.800801) (xy 136.167622 -170.807888)
			(xy 136.167876 -170.807888) (xy 136.167876 -170.808142) (xy 136.185556 -170.829043) (xy 136.215279 -170.875016)
			(xy 136.238122 -170.924768) (xy 136.253615 -170.977275) (xy 136.261439 -171.031458) (xy 136.261435 -171.086203)
			(xy 136.253602 -171.140384) (xy 136.2381 -171.192889) (xy 136.21525 -171.242636) (xy 136.185519 -171.288605)
			(xy 136.167876 -171.309538) (xy 136.167622 -171.309792) (xy 136.162024 -171.31687) (xy 136.155786 -171.333794)
			(xy 136.15543 -171.342812) (xy 136.15543 -171.409868) (xy 136.155796 -171.418884) (xy 136.162037 -171.435801)
			(xy 136.167622 -171.442888) (xy 136.167876 -171.442888) (xy 136.167876 -171.443142) (xy 136.185498 -171.464088)
			(xy 136.215213 -171.510057) (xy 136.238053 -171.559801) (xy 136.253548 -171.612298) (xy 136.26138 -171.666472)
			(xy 136.261856 -171.69384) (xy 136.26136 -171.72109) (xy 136.253599 -171.775035) (xy 136.238241 -171.827326)
			(xy 136.215599 -171.876901) (xy 136.186133 -171.922749) (xy 136.150443 -171.963937) (xy 136.109255 -171.999628)
			(xy 136.063408 -172.029095) (xy 136.013834 -172.051738) (xy 135.961543 -172.067097) (xy 135.907598 -172.074859)
			(xy 135.880348 -172.075348) (xy 135.852978 -172.074866) (xy 135.798799 -172.067054) (xy 135.746296 -172.05157)
			(xy 135.696549 -172.028731) (xy 135.650582 -171.999009) (xy 135.62965 -171.981368) (xy 135.629396 -171.981114)
			(xy 135.622314 -171.975521) (xy 135.605394 -171.969278) (xy 135.596376 -171.968922) (xy 135.52932 -171.968922)
			(xy 135.520304 -171.969284) (xy 135.503386 -171.975528) (xy 135.4963 -171.981114) (xy 135.4963 -171.981368)
			(xy 135.496046 -171.981368) (xy 135.475103 -171.998994) (xy 135.429134 -172.028709) (xy 135.379389 -172.051548)
			(xy 135.326891 -172.067042) (xy 135.272717 -172.074873) (xy 135.245348 -172.075348) (xy 135.215799 -172.074812)
			(xy 135.157408 -172.065693) (xy 135.101122 -172.047679) (xy 135.048286 -172.021203) (xy 135.000164 -171.986897)
			(xy 134.978648 -171.966636) (xy 134.971245 -171.960086) (xy 134.95296 -171.952629) (xy 134.943088 -171.952158)
			(xy 134.890002 -171.952158) (xy 134.882636 -171.960032) (xy 134.876086 -171.967354) (xy 134.868652 -171.985524)
			(xy 134.868158 -171.995338) (xy 134.868158 -172.027342) (xy 134.868643 -172.037156) (xy 134.87609 -172.05532)
			(xy 134.882636 -172.062648) (xy 134.90283 -172.084129) (xy 134.936972 -172.132193) (xy 134.963315 -172.184937)
			(xy 134.981232 -172.241106) (xy 134.990294 -172.299362) (xy 134.99084 -172.32884) (xy 134.990359 -172.356091)
			(xy 134.982598 -172.410037) (xy 134.96724 -172.46233) (xy 134.944596 -172.511905) (xy 134.915129 -172.557754)
			(xy 134.879437 -172.598943) (xy 134.838247 -172.634634) (xy 134.792398 -172.6641) (xy 134.742822 -172.686743)
			(xy 134.690529 -172.7021) (xy 134.636583 -172.70986) (xy 134.609332 -172.710348) (xy 134.581962 -172.709876)
			(xy 134.527783 -172.702061) (xy 134.475279 -172.686574) (xy 134.425532 -172.663734) (xy 134.379565 -172.634009)
			(xy 134.358634 -172.616368) (xy 134.35838 -172.616114) (xy 134.351302 -172.610514) (xy 134.334379 -172.604275)
			(xy 134.32536 -172.603922) (xy 134.258304 -172.603922) (xy 134.249287 -172.604276) (xy 134.232369 -172.610525)
			(xy 134.225284 -172.616114) (xy 134.225284 -172.616368) (xy 134.22503 -172.616368) (xy 134.204093 -172.634002)
			(xy 134.158122 -172.663715) (xy 134.108376 -172.686553) (xy 134.055876 -172.702045) (xy 134.001701 -172.709874)
			(xy 133.974332 -172.710348) (xy 133.947083 -172.709792) (xy 133.89314 -172.702041) (xy 133.840849 -172.686692)
			(xy 133.791275 -172.664057) (xy 133.745426 -172.634598) (xy 133.704237 -172.598914) (xy 133.668545 -172.557731)
			(xy 133.639077 -172.511888) (xy 133.616433 -172.462318) (xy 133.601074 -172.41003) (xy 133.593313 -172.356089)
			(xy 133.592824 -172.32884) (xy 131.612225 -172.32884) (xy 131.612223 -172.356203) (xy 131.604389 -172.410385)
			(xy 131.588887 -172.462889) (xy 131.566036 -172.512637) (xy 131.536304 -172.558605) (xy 131.51866 -172.579538)
			(xy 131.518406 -172.579792) (xy 131.512817 -172.586877) (xy 131.506572 -172.603795) (xy 131.506214 -172.612812)
			(xy 131.506214 -172.679868) (xy 131.506584 -172.688884) (xy 131.512822 -172.705801) (xy 131.518406 -172.712888)
			(xy 131.51866 -172.712888) (xy 131.51866 -172.713142) (xy 131.53634 -172.734043) (xy 131.566065 -172.780016)
			(xy 131.588908 -172.829767) (xy 131.604402 -172.882274) (xy 131.612227 -172.936457) (xy 131.612223 -172.991203)
			(xy 131.604389 -173.045385) (xy 131.588887 -173.097889) (xy 131.566036 -173.147637) (xy 131.536304 -173.193605)
			(xy 131.51866 -173.214538) (xy 131.518406 -173.214792) (xy 131.512817 -173.221877) (xy 131.506572 -173.238795)
			(xy 131.506214 -173.247812) (xy 131.506214 -173.314868) (xy 131.506584 -173.323884) (xy 131.512822 -173.340801)
			(xy 131.518406 -173.347888) (xy 131.51866 -173.347888) (xy 131.51866 -173.348142) (xy 131.536279 -173.36909)
			(xy 131.565995 -173.415058) (xy 131.588836 -173.464801) (xy 131.604331 -173.517299) (xy 131.612164 -173.571472)
			(xy 131.61264 -173.59884) (xy 131.612159 -173.626091) (xy 131.604398 -173.680037) (xy 131.58904 -173.73233)
			(xy 131.566396 -173.781905) (xy 131.536929 -173.827754) (xy 131.501237 -173.868943) (xy 131.460047 -173.904634)
			(xy 131.414198 -173.9341) (xy 131.364622 -173.956743) (xy 131.312329 -173.9721) (xy 131.258383 -173.97986)
			(xy 131.231132 -173.980348) (xy 131.203762 -173.979876) (xy 131.149583 -173.972061) (xy 131.097079 -173.956574)
			(xy 131.047332 -173.933734) (xy 131.001365 -173.904009) (xy 130.980434 -173.886368) (xy 130.98018 -173.886114)
			(xy 130.973102 -173.880514) (xy 130.956179 -173.874275) (xy 130.94716 -173.873922) (xy 130.880104 -173.873922)
			(xy 130.871087 -173.874276) (xy 130.854169 -173.880525) (xy 130.847084 -173.886114) (xy 130.847084 -173.886368)
			(xy 130.84683 -173.886368) (xy 130.825893 -173.904002) (xy 130.779922 -173.933715) (xy 130.730176 -173.956553)
			(xy 130.677676 -173.972045) (xy 130.623501 -173.979874) (xy 130.596132 -173.980348) (xy 130.568883 -173.979792)
			(xy 130.51494 -173.972041) (xy 130.462649 -173.956692) (xy 130.413075 -173.934057) (xy 130.367226 -173.904598)
			(xy 130.326037 -173.868914) (xy 130.290345 -173.827731) (xy 130.260877 -173.781888) (xy 130.238233 -173.732318)
			(xy 130.222874 -173.68003) (xy 130.215113 -173.626089) (xy 130.214624 -173.59884) (xy 110.276132 -173.59884)
			(xy 110.276132 -173.868334) (xy 110.275528 -173.893318) (xy 110.265783 -173.942327) (xy 110.246674 -173.988496)
			(xy 110.218933 -174.030057) (xy 110.20171 -174.048166) (xy 109.859826 -174.39005) (xy 110.37773 -174.39005)
			(xy 110.381801 -174.334428) (xy 110.393927 -174.279991) (xy 110.41385 -174.2279) (xy 110.441146 -174.179265)
			(xy 110.475232 -174.135122) (xy 110.515381 -174.096413) (xy 110.560739 -174.063962) (xy 110.610339 -174.038461)
			(xy 110.663123 -174.020454) (xy 110.717966 -174.010324) (xy 110.7737 -174.008287) (xy 110.829137 -174.014387)
			(xy 110.883094 -174.028493) (xy 110.934423 -174.050305) (xy 110.982029 -174.079359) (xy 111.024897 -174.115034)
			(xy 111.062114 -174.156571) (xy 111.092887 -174.203084) (xy 111.116559 -174.253581) (xy 111.132627 -174.306988)
			(xy 111.140747 -174.362164) (xy 111.141256 -174.39005) (xy 111.140747 -174.417936) (xy 111.132627 -174.473112)
			(xy 111.116559 -174.526519) (xy 111.092887 -174.577016) (xy 111.062114 -174.623529) (xy 111.024897 -174.665066)
			(xy 110.982029 -174.700741) (xy 110.934423 -174.729795) (xy 110.883094 -174.751607) (xy 110.829137 -174.765713)
			(xy 110.7737 -174.771813) (xy 110.717966 -174.769776) (xy 110.663123 -174.759646) (xy 110.610339 -174.741639)
			(xy 110.560739 -174.716138) (xy 110.515381 -174.683687) (xy 110.475232 -174.644978) (xy 110.441146 -174.600835)
			(xy 110.41385 -174.5522) (xy 110.393927 -174.500109) (xy 110.381801 -174.445672) (xy 110.37773 -174.39005)
			(xy 109.859826 -174.39005) (xy 109.786166 -174.46371) (xy 109.782356 -174.474886) (xy 109.773442 -174.499654)
			(xy 109.749734 -174.546653) (xy 109.719787 -174.589944) (xy 109.684171 -174.628705) (xy 109.643562 -174.662199)
			(xy 109.598732 -174.689789) (xy 109.550534 -174.710951) (xy 109.499883 -174.725283) (xy 109.447742 -174.732513)
			(xy 109.421422 -174.73295) (xy 109.394173 -174.732401) (xy 109.34023 -174.724649) (xy 109.287939 -174.709299)
			(xy 109.238365 -174.686663) (xy 109.192516 -174.657203) (xy 109.151327 -174.621518) (xy 109.115635 -174.580335)
			(xy 109.086167 -174.534491) (xy 109.063524 -174.484921) (xy 109.048165 -174.432633) (xy 109.040403 -174.378691)
			(xy 109.039914 -174.351442) (xy 109.040422 -174.323968) (xy 109.048308 -174.269589) (xy 109.063923 -174.216907)
			(xy 109.086943 -174.167014) (xy 109.11689 -174.120944) (xy 109.134656 -174.099982) (xy 109.13491 -174.099728)
			(xy 109.140492 -174.092638) (xy 109.146741 -174.075724) (xy 109.147102 -174.066708) (xy 109.147102 -173.999144)
			(xy 109.146724 -173.990129) (xy 109.140491 -173.973212) (xy 109.13491 -173.966124) (xy 109.134402 -173.965616)
			(xy 109.11668 -173.94466) (xy 109.086796 -173.89863) (xy 109.063827 -173.848787) (xy 109.04825 -173.796164)
			(xy 109.040386 -173.74185) (xy 109.039914 -173.71441) (xy 109.040476 -173.685339) (xy 109.04931 -173.627873)
			(xy 109.06676 -173.572411) (xy 109.092422 -173.520239) (xy 109.125702 -173.472564) (xy 109.165829 -173.43049)
			(xy 109.211875 -173.39499) (xy 109.262774 -173.366886) (xy 109.317346 -173.34683) (xy 109.34573 -173.340522)
			(xy 109.345984 -173.340522) (xy 109.35729 -173.337595) (xy 109.375749 -173.323334) (xy 109.38604 -173.302401)
			(xy 109.386624 -173.290738) (xy 109.386624 -173.078902) (xy 109.386218 -173.06883) (xy 109.378486 -173.050231)
			(xy 109.371638 -173.042834) (xy 108.842048 -172.513498) (xy 108.834626 -172.506686) (xy 108.816043 -172.49895)
			(xy 108.80598 -172.498512) (xy 104.456484 -172.498512) (xy 104.431486 -172.497904) (xy 104.382461 -172.488094)
			(xy 104.33629 -172.468913) (xy 104.294746 -172.441096) (xy 104.276652 -172.423836) (xy 101.333046 -169.48023)
			(xy 101.315823 -169.462121) (xy 101.288082 -169.420561) (xy 101.268975 -169.374391) (xy 101.259235 -169.325382)
			(xy 101.258624 -169.300398) (xy 101.258624 -158.958788) (xy 101.258225 -158.948715) (xy 101.250488 -158.930117)
			(xy 101.243638 -158.92272) (xy 95.747078 -153.426414) (xy 95.739678 -153.419574) (xy 95.721079 -153.411854)
			(xy 95.71101 -153.411428) (xy 95.569786 -153.411428) (xy 95.55554 -153.411251) (xy 95.527173 -153.40858)
			(xy 95.513144 -153.406094) (xy 95.501714 -153.403808) (xy 95.47987 -153.409396) (xy 95.411036 -153.4668)
			(xy 95.40282 -153.47443) (xy 95.393334 -153.494719) (xy 95.392748 -153.505916) (xy 95.392748 -154.46756)
			(xy 95.393182 -154.477629) (xy 95.400895 -154.496227) (xy 95.407734 -154.503628) (xy 99.562666 -158.658814)
			(xy 99.579911 -158.676903) (xy 99.607648 -158.71847) (xy 99.626749 -158.764646) (xy 99.636481 -158.81366)
			(xy 99.637088 -158.838646) (xy 99.637088 -173.832012) (xy 107.149646 -173.832012) (xy 107.150132 -173.804761)
			(xy 107.157888 -173.750813) (xy 107.173243 -173.698518) (xy 107.195885 -173.648941) (xy 107.225351 -173.603091)
			(xy 107.261042 -173.5619) (xy 107.302233 -173.526209) (xy 107.348083 -173.496743) (xy 107.39766 -173.474101)
			(xy 107.449955 -173.458746) (xy 107.503903 -173.45099) (xy 107.558405 -173.45099) (xy 107.612353 -173.458746)
			(xy 107.664648 -173.474101) (xy 107.714225 -173.496743) (xy 107.760075 -173.526209) (xy 107.801266 -173.5619)
			(xy 107.836957 -173.603091) (xy 107.866423 -173.648941) (xy 107.889065 -173.698518) (xy 107.90442 -173.750813)
			(xy 107.912176 -173.804761) (xy 107.912662 -173.832012) (xy 107.911996 -173.863575) (xy 107.901612 -173.92584)
			(xy 107.881129 -173.985549) (xy 107.866688 -174.013622) (xy 107.861862 -174.022512) (xy 107.85983 -174.04207)
			(xy 107.88269 -174.120556) (xy 107.88592 -174.129984) (xy 107.898344 -174.14554) (xy 107.90682 -174.150782)
			(xy 107.914186 -174.154846) (xy 107.924092 -174.160688) (xy 107.945936 -174.16272) (xy 108.040678 -174.129192)
			(xy 108.056426 -174.113698) (xy 108.06049 -174.103284) (xy 108.071169 -174.0765) (xy 108.099459 -174.026258)
			(xy 108.134992 -173.980849) (xy 108.176956 -173.941307) (xy 108.224396 -173.908534) (xy 108.276229 -173.883277)
			(xy 108.331274 -173.866113) (xy 108.388276 -173.857432) (xy 108.417106 -173.856904) (xy 108.444358 -173.857366)
			(xy 108.498307 -173.865124) (xy 108.550602 -173.88048) (xy 108.60018 -173.903122) (xy 108.646031 -173.932589)
			(xy 108.687222 -173.968282) (xy 108.722914 -174.009473) (xy 108.752381 -174.055325) (xy 108.775022 -174.104903)
			(xy 108.790378 -174.157199) (xy 108.798134 -174.211148) (xy 108.798134 -174.265652) (xy 108.790378 -174.319601)
			(xy 108.775022 -174.371897) (xy 108.752381 -174.421475) (xy 108.722914 -174.467327) (xy 108.687222 -174.508518)
			(xy 108.646031 -174.544211) (xy 108.60018 -174.573678) (xy 108.550602 -174.59632) (xy 108.498307 -174.611676)
			(xy 108.444358 -174.619434) (xy 108.417106 -174.61992) (xy 108.416852 -174.61992) (xy 108.391649 -174.619503)
			(xy 108.341681 -174.612869) (xy 108.293027 -174.599698) (xy 108.246536 -174.58022) (xy 108.224574 -174.56785)
			(xy 108.214668 -174.562008) (xy 108.192824 -174.559976) (xy 108.098082 -174.593504) (xy 108.082334 -174.608998)
			(xy 108.07827 -174.619412) (xy 108.067539 -174.646173) (xy 108.039255 -174.696413) (xy 108.00373 -174.741822)
			(xy 107.961773 -174.781365) (xy 107.914341 -174.81414) (xy 107.862515 -174.839401) (xy 107.807477 -174.856571)
			(xy 107.750481 -174.865259) (xy 107.721654 -174.865792) (xy 107.694401 -174.865365) (xy 107.64045 -174.857602)
			(xy 107.588153 -174.84224) (xy 107.538575 -174.819592) (xy 107.492724 -174.79012) (xy 107.451534 -174.754422)
			(xy 107.415843 -174.713226) (xy 107.386378 -174.667371) (xy 107.363738 -174.617788) (xy 107.348385 -174.565489)
			(xy 107.340631 -174.511537) (xy 107.340146 -174.484284) (xy 107.340809 -174.452721) (xy 107.351194 -174.390456)
			(xy 107.371679 -174.330747) (xy 107.38612 -174.302674) (xy 107.390946 -174.293784) (xy 107.392978 -174.274226)
			(xy 107.370118 -174.19574) (xy 107.366887 -174.186313) (xy 107.354463 -174.170757) (xy 107.345988 -174.165514)
			(xy 107.320862 -174.151006) (xy 107.27498 -174.115496) (xy 107.235007 -174.073445) (xy 107.201865 -174.025824)
			(xy 107.176318 -173.973733) (xy 107.158957 -173.918372) (xy 107.150182 -173.861021) (xy 107.149646 -173.832012)
			(xy 99.637088 -173.832012) (xy 99.637088 -174.932086) (xy 99.637497 -174.942158) (xy 99.645227 -174.960757)
			(xy 99.652074 -174.968154) (xy 100.789994 -176.106074) (xy 103.363522 -176.106074) (xy 103.364031 -176.078501)
			(xy 103.371974 -176.02393) (xy 103.38769 -175.97107) (xy 103.410851 -175.921024) (xy 103.440977 -175.874833)
			(xy 103.477438 -175.833461) (xy 103.498142 -175.815244) (xy 103.506205 -175.807678) (xy 103.515564 -175.787674)
			(xy 103.516176 -175.776636) (xy 103.516176 -175.698912) (xy 103.515609 -175.687862) (xy 103.506244 -175.667841)
			(xy 103.498142 -175.660304) (xy 103.477438 -175.642085) (xy 103.440965 -175.600719) (xy 103.410831 -175.554531)
			(xy 103.387664 -175.504484) (xy 103.371947 -175.451623) (xy 103.364007 -175.397048) (xy 103.363522 -175.369474)
			(xy 103.364031 -175.341901) (xy 103.371974 -175.28733) (xy 103.38769 -175.23447) (xy 103.410851 -175.184424)
			(xy 103.440977 -175.138233) (xy 103.477438 -175.096861) (xy 103.498142 -175.078644) (xy 103.506205 -175.071078)
			(xy 103.515564 -175.051074) (xy 103.516176 -175.040036) (xy 103.516176 -174.962312) (xy 103.515609 -174.951262)
			(xy 103.506244 -174.931241) (xy 103.498142 -174.923704) (xy 103.477438 -174.905485) (xy 103.440965 -174.864119)
			(xy 103.410831 -174.817931) (xy 103.387664 -174.767884) (xy 103.371947 -174.715023) (xy 103.364007 -174.660448)
			(xy 103.363522 -174.632874) (xy 103.363931 -174.605619) (xy 103.371692 -174.551665) (xy 103.387053 -174.499364)
			(xy 103.409701 -174.449782) (xy 103.439174 -174.403927) (xy 103.474874 -174.362734) (xy 103.516072 -174.327041)
			(xy 103.561931 -174.297574) (xy 103.611516 -174.274933) (xy 103.663819 -174.25958) (xy 103.717775 -174.251827)
			(xy 103.74503 -174.251366) (xy 103.772885 -174.251887) (xy 103.827999 -174.260014) (xy 103.881348 -174.276062)
			(xy 103.9318 -174.29969) (xy 103.978283 -174.330397) (xy 104.019812 -174.367532) (xy 104.055506 -174.410306)
			(xy 104.084606 -174.457812) (xy 104.106496 -174.509042) (xy 104.114092 -174.535846) (xy 104.116378 -174.544736)
			(xy 104.127046 -174.559976) (xy 104.198928 -174.607728) (xy 104.216962 -174.611792) (xy 104.226106 -174.610522)
			(xy 104.239123 -174.608854) (xy 104.265307 -174.607073) (xy 104.27843 -174.606966) (xy 104.292579 -174.607057)
			(xy 104.320802 -174.609093) (xy 104.334818 -174.61103) (xy 104.344724 -174.612554) (xy 104.364536 -174.607728)
			(xy 104.438958 -174.551848) (xy 104.449118 -174.534322) (xy 104.450388 -174.524162) (xy 104.454477 -174.497008)
			(xy 104.469449 -174.444178) (xy 104.49184 -174.394039) (xy 104.521187 -174.347628) (xy 104.556885 -174.305904)
			(xy 104.598194 -174.269727) (xy 104.644263 -174.239846) (xy 104.69414 -174.216877) (xy 104.746794 -174.201296)
			(xy 104.801138 -174.193424) (xy 104.828594 -174.192946) (xy 104.855843 -174.193483) (xy 104.909787 -174.201238)
			(xy 104.962077 -174.21659) (xy 105.011652 -174.239227) (xy 105.0575 -174.268688) (xy 105.098689 -174.304374)
			(xy 105.134381 -174.345558) (xy 105.163848 -174.391403) (xy 105.186492 -174.440974) (xy 105.201851 -174.493263)
			(xy 105.209613 -174.547205) (xy 105.210102 -174.574454) (xy 105.209604 -174.602027) (xy 105.201658 -174.656599)
			(xy 105.185939 -174.709458) (xy 105.162775 -174.759504) (xy 105.132649 -174.805694) (xy 105.096187 -174.847067)
			(xy 105.075482 -174.865284) (xy 105.067411 -174.872843) (xy 105.058055 -174.892852) (xy 105.057448 -174.903892)
			(xy 105.057448 -174.981616) (xy 105.058048 -174.992662) (xy 105.067389 -175.012684) (xy 105.075482 -175.020224)
			(xy 105.096204 -175.038423) (xy 105.132675 -175.079794) (xy 105.162806 -175.125986) (xy 105.18597 -175.176037)
			(xy 105.201683 -175.228902) (xy 105.209619 -175.283478) (xy 105.209653 -175.2854) (xy 109.79861 -175.2854)
			(xy 109.802681 -175.229778) (xy 109.814807 -175.175341) (xy 109.83473 -175.12325) (xy 109.862026 -175.074615)
			(xy 109.896112 -175.030472) (xy 109.936261 -174.991763) (xy 109.981619 -174.959312) (xy 110.031219 -174.933811)
			(xy 110.084003 -174.915804) (xy 110.138846 -174.905674) (xy 110.19458 -174.903637) (xy 110.250017 -174.909737)
			(xy 110.303974 -174.923843) (xy 110.355303 -174.945655) (xy 110.402909 -174.974709) (xy 110.445777 -175.010384)
			(xy 110.482994 -175.051921) (xy 110.513767 -175.098434) (xy 110.537439 -175.148931) (xy 110.553507 -175.202338)
			(xy 110.561627 -175.257514) (xy 110.562136 -175.2854) (xy 110.561627 -175.313286) (xy 110.553507 -175.368462)
			(xy 110.537439 -175.421869) (xy 110.513767 -175.472366) (xy 110.482994 -175.518879) (xy 110.445777 -175.560416)
			(xy 110.402909 -175.596091) (xy 110.355303 -175.625145) (xy 110.303974 -175.646957) (xy 110.250017 -175.661063)
			(xy 110.19458 -175.667163) (xy 110.138846 -175.665126) (xy 110.084003 -175.654996) (xy 110.031219 -175.636989)
			(xy 109.981619 -175.611488) (xy 109.936261 -175.579037) (xy 109.896112 -175.540328) (xy 109.862026 -175.496185)
			(xy 109.83473 -175.44755) (xy 109.814807 -175.395459) (xy 109.802681 -175.341022) (xy 109.79861 -175.2854)
			(xy 105.209653 -175.2854) (xy 105.210102 -175.311054) (xy 105.209602 -175.338306) (xy 105.201851 -175.392256)
			(xy 105.186501 -175.444553) (xy 105.163863 -175.494134) (xy 105.134399 -175.539987) (xy 105.098709 -175.581181)
			(xy 105.05752 -175.616875) (xy 105.011669 -175.646344) (xy 104.962091 -175.668987) (xy 104.909795 -175.684343)
			(xy 104.855846 -175.692099) (xy 104.828594 -175.692562) (xy 104.828086 -175.692562) (xy 104.794304 -175.691038)
			(xy 104.784144 -175.690022) (xy 104.76484 -175.696118) (xy 104.701848 -175.74895) (xy 104.69455 -175.755666)
			(xy 104.685275 -175.773176) (xy 104.683814 -175.782986) (xy 104.683814 -175.783748) (xy 104.680863 -175.811909)
			(xy 104.667656 -175.86697) (xy 104.646453 -175.919473) (xy 104.61772 -175.968263) (xy 104.582089 -176.01227)
			(xy 104.540344 -176.050524) (xy 104.493401 -176.082186) (xy 104.442293 -176.10656) (xy 104.388143 -176.12311)
			(xy 104.332141 -176.131471) (xy 104.30383 -176.131982) (xy 104.285811 -176.131766) (xy 104.249936 -176.128328)
			(xy 104.232202 -176.125124) (xy 104.22255 -176.123346) (xy 104.2035 -176.126902) (xy 104.12857 -176.174908)
			(xy 104.11714 -176.190656) (xy 104.114854 -176.200054) (xy 104.107489 -176.227108) (xy 104.085856 -176.278836)
			(xy 104.056888 -176.326842) (xy 104.021209 -176.370094) (xy 103.979585 -176.407661) (xy 103.932913 -176.438734)
			(xy 103.882198 -176.462644) (xy 103.82853 -176.478878) (xy 103.773065 -176.487085) (xy 103.74503 -176.487582)
			(xy 103.717777 -176.487117) (xy 103.663824 -176.479363) (xy 103.611525 -176.46401) (xy 103.561943 -176.441369)
			(xy 103.516089 -176.411901) (xy 103.474895 -176.376208) (xy 103.439201 -176.335014) (xy 103.409733 -176.28916)
			(xy 103.387092 -176.239579) (xy 103.371738 -176.187279) (xy 103.363984 -176.133327) (xy 103.363522 -176.106074)
			(xy 100.789994 -176.106074) (xy 101.81971 -177.13579) (xy 101.836935 -177.153898) (xy 101.864677 -177.195457)
			(xy 101.883785 -177.241628) (xy 101.893523 -177.290638) (xy 101.894132 -177.315622) (xy 101.894132 -177.65776)
			(xy 104.95534 -177.65776) (xy 104.955833 -177.630186) (xy 104.963778 -177.575614) (xy 104.979497 -177.522754)
			(xy 105.002662 -177.472708) (xy 105.03279 -177.426517) (xy 105.069254 -177.385146) (xy 105.08996 -177.36693)
			(xy 105.098031 -177.359372) (xy 105.107385 -177.339362) (xy 105.107994 -177.328322) (xy 105.107994 -177.250598)
			(xy 105.107373 -177.239555) (xy 105.098045 -177.219534) (xy 105.08996 -177.21199) (xy 105.069233 -177.193797)
			(xy 105.032765 -177.152423) (xy 105.002636 -177.106229) (xy 104.979474 -177.056178) (xy 104.96376 -177.003313)
			(xy 104.955824 -176.948736) (xy 104.95534 -176.92116) (xy 104.955873 -176.892873) (xy 104.964232 -176.836919)
			(xy 104.980763 -176.782814) (xy 105.005102 -176.731742) (xy 105.036715 -176.684824) (xy 105.07491 -176.643089)
			(xy 105.118849 -176.607451) (xy 105.167569 -176.578693) (xy 105.193592 -176.567592) (xy 105.204768 -176.56302)
			(xy 105.220516 -176.545494) (xy 105.247694 -176.443894) (xy 105.243122 -176.42078) (xy 105.235756 -176.411382)
			(xy 105.217491 -176.38675) (xy 105.188467 -176.332735) (xy 105.168676 -176.274697) (xy 105.158649 -176.214204)
			(xy 105.158032 -176.183544) (xy 105.158475 -176.156925) (xy 105.166047 -176.104228) (xy 105.181042 -176.053146)
			(xy 105.203155 -176.004718) (xy 105.231937 -175.95993) (xy 105.2668 -175.919696) (xy 105.307035 -175.884833)
			(xy 105.351823 -175.856052) (xy 105.400251 -175.83394) (xy 105.451334 -175.818945) (xy 105.504031 -175.811375)
			(xy 105.53065 -175.810926) (xy 105.557072 -175.811372) (xy 105.609387 -175.818828) (xy 105.660125 -175.833596)
			(xy 105.708269 -175.855382) (xy 105.752854 -175.883748) (xy 105.77322 -175.900588) (xy 105.780078 -175.90643)
			(xy 105.797096 -175.91278) (xy 105.881424 -175.91278) (xy 105.898442 -175.90643) (xy 105.9053 -175.900588)
			(xy 105.925666 -175.883749) (xy 105.970252 -175.855384) (xy 106.018396 -175.833597) (xy 106.069133 -175.818826)
			(xy 106.121448 -175.811366) (xy 106.174292 -175.811366) (xy 106.226607 -175.818826) (xy 106.277344 -175.833597)
			(xy 106.325488 -175.855384) (xy 106.370074 -175.883749) (xy 106.39044 -175.900588) (xy 106.397298 -175.90643)
			(xy 106.414316 -175.91278) (xy 106.498644 -175.91278) (xy 106.515662 -175.90643) (xy 106.52252 -175.900588)
			(xy 106.542877 -175.883739) (xy 106.587469 -175.855386) (xy 106.635616 -175.833609) (xy 106.686354 -175.818844)
			(xy 106.738669 -175.811386) (xy 106.76509 -175.810926) (xy 106.792981 -175.811332) (xy 106.848139 -175.819645)
			(xy 106.901442 -175.836085) (xy 106.951699 -175.860287) (xy 106.997788 -175.891709) (xy 107.038679 -175.929649)
			(xy 107.073459 -175.97326) (xy 107.10135 -176.021567) (xy 107.121729 -176.073492) (xy 107.134142 -176.127875)
			(xy 107.138311 -176.1835) (xy 107.134142 -176.239125) (xy 107.121729 -176.293508) (xy 107.10135 -176.345433)
			(xy 107.073459 -176.39374) (xy 107.038679 -176.437351) (xy 106.997788 -176.475291) (xy 106.951699 -176.506713)
			(xy 106.901442 -176.530915) (xy 106.848139 -176.547355) (xy 106.792981 -176.555668) (xy 106.76509 -176.556162)
			(xy 106.738669 -176.555695) (xy 106.686354 -176.548245) (xy 106.635616 -176.533482) (xy 106.587472 -176.5117)
			(xy 106.542886 -176.483338) (xy 106.52252 -176.4665) (xy 106.515662 -176.460658) (xy 106.498644 -176.454308)
			(xy 106.414316 -176.454308) (xy 106.397298 -176.460658) (xy 106.39044 -176.4665) (xy 106.370074 -176.483339)
			(xy 106.325488 -176.511704) (xy 106.277344 -176.533491) (xy 106.226607 -176.548262) (xy 106.174292 -176.555722)
			(xy 106.121448 -176.555722) (xy 106.069133 -176.548262) (xy 106.018396 -176.533491) (xy 105.970252 -176.511704)
			(xy 105.925666 -176.483339) (xy 105.9053 -176.4665) (xy 105.898442 -176.460658) (xy 105.881424 -176.454308)
			(xy 105.797096 -176.454308) (xy 105.780078 -176.460658) (xy 105.77322 -176.4665) (xy 105.750945 -176.484878)
			(xy 105.701825 -176.515237) (xy 105.67543 -176.526952) (xy 105.664508 -176.531524) (xy 105.649014 -176.549304)
			(xy 105.626154 -176.639474) (xy 105.623809 -176.651027) (xy 105.628721 -176.67406) (xy 105.635552 -176.68367)
			(xy 105.651188 -176.703966) (xy 105.677413 -176.747981) (xy 105.697503 -176.795114) (xy 105.711096 -176.844513)
			(xy 105.717947 -176.895288) (xy 105.718356 -176.920906) (xy 105.718356 -176.92116) (xy 105.717878 -176.948734)
			(xy 105.70993 -177.003307) (xy 105.694209 -177.056168) (xy 105.671041 -177.106214) (xy 105.64091 -177.152404)
			(xy 105.632046 -177.16246) (xy 110.757462 -177.16246) (xy 110.757938 -177.134549) (xy 110.766077 -177.079322)
			(xy 110.782177 -177.025872) (xy 110.805894 -176.975337) (xy 110.83672 -176.928798) (xy 110.854998 -176.907698)
			(xy 110.860895 -176.900521) (xy 110.867546 -176.883196) (xy 110.867952 -176.873916) (xy 110.867952 -176.796192)
			(xy 110.861348 -176.77892) (xy 110.854998 -176.771808) (xy 110.836702 -176.750723) (xy 110.805877 -176.704181)
			(xy 110.782165 -176.653642) (xy 110.766073 -176.600188) (xy 110.757944 -176.544958) (xy 110.757462 -176.517046)
			(xy 110.757948 -176.489795) (xy 110.765704 -176.435847) (xy 110.781059 -176.383552) (xy 110.803701 -176.333975)
			(xy 110.833167 -176.288125) (xy 110.868858 -176.246934) (xy 110.910049 -176.211243) (xy 110.955899 -176.181777)
			(xy 111.005476 -176.159135) (xy 111.057771 -176.14378) (xy 111.111719 -176.136024) (xy 111.166221 -176.136024)
			(xy 111.220169 -176.14378) (xy 111.272464 -176.159135) (xy 111.322041 -176.181777) (xy 111.367891 -176.211243)
			(xy 111.409082 -176.246934) (xy 111.444773 -176.288125) (xy 111.474239 -176.333975) (xy 111.496881 -176.383552)
			(xy 111.512236 -176.435847) (xy 111.519992 -176.489795) (xy 111.520478 -176.517046) (xy 111.519996 -176.544957)
			(xy 111.511856 -176.600183) (xy 111.495757 -176.653633) (xy 111.472043 -176.704167) (xy 111.441218 -176.750707)
			(xy 111.422942 -176.771808) (xy 111.417035 -176.778978) (xy 111.410392 -176.796309) (xy 111.409988 -176.80559)
			(xy 111.409988 -176.883314) (xy 111.416592 -176.900586) (xy 111.422942 -176.907698) (xy 111.4412 -176.928814)
			(xy 111.472029 -176.975349) (xy 111.495747 -177.025879) (xy 111.511849 -177.079327) (xy 111.519989 -177.13455)
			(xy 111.520478 -177.16246) (xy 111.519992 -177.189711) (xy 111.512236 -177.243659) (xy 111.496881 -177.295954)
			(xy 111.474239 -177.345531) (xy 111.444773 -177.391381) (xy 111.409082 -177.432572) (xy 111.367891 -177.468263)
			(xy 111.322041 -177.497729) (xy 111.272464 -177.520371) (xy 111.220169 -177.535726) (xy 111.166221 -177.543482)
			(xy 111.111719 -177.543482) (xy 111.057771 -177.535726) (xy 111.005476 -177.520371) (xy 110.955899 -177.497729)
			(xy 110.910049 -177.468263) (xy 110.868858 -177.432572) (xy 110.833167 -177.391381) (xy 110.803701 -177.345531)
			(xy 110.781059 -177.295954) (xy 110.765704 -177.243659) (xy 110.757948 -177.189711) (xy 110.757462 -177.16246)
			(xy 105.632046 -177.16246) (xy 105.604443 -177.193775) (xy 105.583736 -177.21199) (xy 105.575655 -177.219539)
			(xy 105.566306 -177.239556) (xy 105.565702 -177.250598) (xy 105.565702 -177.328322) (xy 105.566313 -177.339366)
			(xy 105.575648 -177.359388) (xy 105.583736 -177.36693) (xy 105.604472 -177.385114) (xy 105.640939 -177.426489)
			(xy 105.671067 -177.472685) (xy 105.694228 -177.522738) (xy 105.70994 -177.575605) (xy 105.717874 -177.630184)
			(xy 105.718356 -177.65776) (xy 105.71787 -177.685011) (xy 105.710114 -177.738959) (xy 105.694759 -177.791254)
			(xy 105.672117 -177.840831) (xy 105.642651 -177.886681) (xy 105.60696 -177.927872) (xy 105.565769 -177.963563)
			(xy 105.519919 -177.993029) (xy 105.470342 -178.015671) (xy 105.418047 -178.031026) (xy 105.364099 -178.038782)
			(xy 105.309597 -178.038782) (xy 105.255649 -178.031026) (xy 105.203354 -178.015671) (xy 105.153777 -177.993029)
			(xy 105.107927 -177.963563) (xy 105.066736 -177.927872) (xy 105.031045 -177.886681) (xy 105.001579 -177.840831)
			(xy 104.978937 -177.791254) (xy 104.963582 -177.738959) (xy 104.955826 -177.685011) (xy 104.95534 -177.65776)
			(xy 101.894132 -177.65776) (xy 101.894132 -178.389534) (xy 101.893528 -178.414518) (xy 101.883783 -178.463527)
			(xy 101.864674 -178.509696) (xy 101.836933 -178.551257) (xy 101.81971 -178.569366) (xy 101.477826 -178.91125)
			(xy 101.99573 -178.91125) (xy 101.999801 -178.855628) (xy 102.011927 -178.801191) (xy 102.03185 -178.7491)
			(xy 102.059146 -178.700465) (xy 102.093232 -178.656322) (xy 102.133381 -178.617613) (xy 102.178739 -178.585162)
			(xy 102.228339 -178.559661) (xy 102.281123 -178.541654) (xy 102.335966 -178.531524) (xy 102.3917 -178.529487)
			(xy 102.447137 -178.535587) (xy 102.501094 -178.549693) (xy 102.552423 -178.571505) (xy 102.600029 -178.600559)
			(xy 102.642897 -178.636234) (xy 102.680114 -178.677771) (xy 102.710887 -178.724284) (xy 102.734559 -178.774781)
			(xy 102.750627 -178.828188) (xy 102.758747 -178.883364) (xy 102.759256 -178.91125) (xy 102.758747 -178.939136)
			(xy 102.750627 -178.994312) (xy 102.734559 -179.047719) (xy 102.710887 -179.098216) (xy 102.680114 -179.144729)
			(xy 102.642897 -179.186266) (xy 102.600029 -179.221941) (xy 102.552423 -179.250995) (xy 102.501094 -179.272807)
			(xy 102.447137 -179.286913) (xy 102.3917 -179.293013) (xy 102.335966 -179.290976) (xy 102.281123 -179.280846)
			(xy 102.228339 -179.262839) (xy 102.178739 -179.237338) (xy 102.133381 -179.204887) (xy 102.093232 -179.166178)
			(xy 102.059146 -179.122035) (xy 102.03185 -179.0734) (xy 102.011927 -179.021309) (xy 101.999801 -178.966872)
			(xy 101.99573 -178.91125) (xy 101.477826 -178.91125) (xy 101.404166 -178.98491) (xy 101.400356 -178.996086)
			(xy 101.391442 -179.020854) (xy 101.367734 -179.067853) (xy 101.337787 -179.111144) (xy 101.302171 -179.149905)
			(xy 101.261562 -179.183399) (xy 101.216732 -179.210989) (xy 101.168534 -179.232151) (xy 101.117883 -179.246483)
			(xy 101.065742 -179.253713) (xy 101.039422 -179.25415) (xy 101.012173 -179.253601) (xy 100.95823 -179.245849)
			(xy 100.905939 -179.230499) (xy 100.856365 -179.207863) (xy 100.810516 -179.178403) (xy 100.769327 -179.142718)
			(xy 100.733635 -179.101535) (xy 100.704167 -179.055691) (xy 100.681524 -179.006121) (xy 100.666165 -178.953833)
			(xy 100.658403 -178.899891) (xy 100.657914 -178.872642) (xy 100.658422 -178.845168) (xy 100.666308 -178.790789)
			(xy 100.681923 -178.738107) (xy 100.704943 -178.688214) (xy 100.73489 -178.642144) (xy 100.752656 -178.621182)
			(xy 100.75291 -178.620928) (xy 100.758492 -178.613838) (xy 100.764741 -178.596924) (xy 100.765102 -178.587908)
			(xy 100.765102 -178.520344) (xy 100.764724 -178.511329) (xy 100.758491 -178.494412) (xy 100.75291 -178.487324)
			(xy 100.752402 -178.486816) (xy 100.73468 -178.46586) (xy 100.704796 -178.41983) (xy 100.681827 -178.369987)
			(xy 100.66625 -178.317364) (xy 100.658386 -178.26305) (xy 100.657914 -178.23561) (xy 100.658476 -178.206539)
			(xy 100.66731 -178.149073) (xy 100.68476 -178.093611) (xy 100.710422 -178.041439) (xy 100.743702 -177.993764)
			(xy 100.783829 -177.95169) (xy 100.829875 -177.91619) (xy 100.880774 -177.888086) (xy 100.935346 -177.86803)
			(xy 100.96373 -177.861722) (xy 100.963984 -177.861722) (xy 100.97529 -177.858795) (xy 100.993749 -177.844534)
			(xy 101.00404 -177.823601) (xy 101.004624 -177.811938) (xy 101.004624 -177.600102) (xy 101.004218 -177.59003)
			(xy 100.996486 -177.571431) (xy 100.989638 -177.564034) (xy 98.822002 -175.396398) (xy 98.804774 -175.378294)
			(xy 98.777031 -175.336733) (xy 98.757925 -175.290562) (xy 98.748188 -175.241551) (xy 98.74758 -175.216566)
			(xy 98.74758 -159.165544) (xy 98.747137 -159.155477) (xy 98.739429 -159.136878) (xy 98.732594 -159.129476)
			(xy 94.557342 -154.954224) (xy 94.540116 -154.936118) (xy 94.512376 -154.894557) (xy 94.493269 -154.848386)
			(xy 94.48353 -154.799376) (xy 94.48292 -154.774392) (xy 94.48292 -153.462228) (xy 94.482458 -153.452211)
			(xy 94.474801 -153.433699) (xy 94.460642 -153.419526) (xy 94.442137 -153.411852) (xy 94.43212 -153.411428)
			(xy 94.225872 -153.411428) (xy 94.211753 -153.411228) (xy 94.183642 -153.408557) (xy 94.169738 -153.406094)
			(xy 94.158562 -153.403808) (xy 94.136718 -153.409396) (xy 94.067376 -153.4668) (xy 94.059166 -153.474436)
			(xy 94.049675 -153.49472) (xy 94.049088 -153.505916) (xy 94.049088 -157.103572) (xy 94.049504 -157.113643)
			(xy 94.057229 -157.132242) (xy 94.064074 -157.13964) (xy 96.895666 -159.971232) (xy 96.912873 -159.989356)
			(xy 96.940616 -160.03091) (xy 96.959728 -160.077076) (xy 96.969474 -160.126082) (xy 96.970088 -160.151064)
			(xy 96.970088 -172.853096) (xy 96.969445 -172.878078) (xy 96.95971 -172.927084) (xy 96.940611 -172.973253)
			(xy 96.912883 -173.014816) (xy 96.895666 -173.032928) (xy 93.527118 -176.401476) (xy 93.520298 -176.408892)
			(xy 93.512566 -176.427479) (xy 93.512132 -176.437544) (xy 93.512132 -178.353212) (xy 98.767646 -178.353212)
			(xy 98.768132 -178.325961) (xy 98.775888 -178.272013) (xy 98.791243 -178.219718) (xy 98.813885 -178.170141)
			(xy 98.843351 -178.124291) (xy 98.879042 -178.0831) (xy 98.920233 -178.047409) (xy 98.966083 -178.017943)
			(xy 99.01566 -177.995301) (xy 99.067955 -177.979946) (xy 99.121903 -177.97219) (xy 99.176405 -177.97219)
			(xy 99.230353 -177.979946) (xy 99.282648 -177.995301) (xy 99.332225 -178.017943) (xy 99.378075 -178.047409)
			(xy 99.419266 -178.0831) (xy 99.454957 -178.124291) (xy 99.484423 -178.170141) (xy 99.507065 -178.219718)
			(xy 99.52242 -178.272013) (xy 99.530176 -178.325961) (xy 99.530662 -178.353212) (xy 99.529996 -178.384775)
			(xy 99.519612 -178.44704) (xy 99.499129 -178.506749) (xy 99.484688 -178.534822) (xy 99.479862 -178.543712)
			(xy 99.47783 -178.56327) (xy 99.50069 -178.641756) (xy 99.50392 -178.651184) (xy 99.516344 -178.66674)
			(xy 99.52482 -178.671982) (xy 99.532186 -178.676046) (xy 99.542092 -178.681888) (xy 99.563936 -178.68392)
			(xy 99.658678 -178.650392) (xy 99.674426 -178.634898) (xy 99.67849 -178.624484) (xy 99.689169 -178.5977)
			(xy 99.717459 -178.547458) (xy 99.752992 -178.502049) (xy 99.794956 -178.462507) (xy 99.842396 -178.429734)
			(xy 99.894229 -178.404477) (xy 99.949274 -178.387313) (xy 100.006276 -178.378632) (xy 100.035106 -178.378104)
			(xy 100.062358 -178.378566) (xy 100.116307 -178.386324) (xy 100.168602 -178.40168) (xy 100.21818 -178.424322)
			(xy 100.264031 -178.453789) (xy 100.305222 -178.489482) (xy 100.340914 -178.530673) (xy 100.370381 -178.576525)
			(xy 100.393022 -178.626103) (xy 100.408378 -178.678399) (xy 100.416134 -178.732348) (xy 100.416134 -178.786852)
			(xy 100.408378 -178.840801) (xy 100.393022 -178.893097) (xy 100.370381 -178.942675) (xy 100.340914 -178.988527)
			(xy 100.305222 -179.029718) (xy 100.264031 -179.065411) (xy 100.21818 -179.094878) (xy 100.168602 -179.11752)
			(xy 100.116307 -179.132876) (xy 100.062358 -179.140634) (xy 100.035106 -179.14112) (xy 100.034852 -179.14112)
			(xy 100.009649 -179.140703) (xy 99.959681 -179.134069) (xy 99.911027 -179.120898) (xy 99.864536 -179.10142)
			(xy 99.842574 -179.08905) (xy 99.832668 -179.083208) (xy 99.810824 -179.081176) (xy 99.716082 -179.114704)
			(xy 99.700334 -179.130198) (xy 99.69627 -179.140612) (xy 99.685539 -179.167373) (xy 99.657255 -179.217613)
			(xy 99.62173 -179.263022) (xy 99.579773 -179.302565) (xy 99.532341 -179.33534) (xy 99.480515 -179.360601)
			(xy 99.425477 -179.377771) (xy 99.368481 -179.386459) (xy 99.339654 -179.386992) (xy 99.312401 -179.386565)
			(xy 99.25845 -179.378802) (xy 99.206153 -179.36344) (xy 99.156575 -179.340792) (xy 99.110724 -179.31132)
			(xy 99.069534 -179.275622) (xy 99.033843 -179.234426) (xy 99.004378 -179.188571) (xy 98.981738 -179.138988)
			(xy 98.966385 -179.086689) (xy 98.958631 -179.032737) (xy 98.958146 -179.005484) (xy 98.958809 -178.973921)
			(xy 98.969194 -178.911656) (xy 98.989679 -178.851947) (xy 99.00412 -178.823874) (xy 99.008946 -178.814984)
			(xy 99.010978 -178.795426) (xy 98.988118 -178.71694) (xy 98.984887 -178.707513) (xy 98.972463 -178.691957)
			(xy 98.963988 -178.686714) (xy 98.938862 -178.672206) (xy 98.89298 -178.636696) (xy 98.853007 -178.594645)
			(xy 98.819865 -178.547024) (xy 98.794318 -178.494933) (xy 98.776957 -178.439572) (xy 98.768182 -178.382221)
			(xy 98.767646 -178.353212) (xy 93.512132 -178.353212) (xy 93.512132 -178.362102) (xy 93.511509 -178.387085)
			(xy 93.50177 -178.436093) (xy 93.482666 -178.482263) (xy 93.45493 -178.523824) (xy 93.43771 -178.541934)
			(xy 93.085666 -178.893978) (xy 93.60357 -178.893978) (xy 93.607641 -178.838356) (xy 93.619767 -178.783919)
			(xy 93.63969 -178.731828) (xy 93.666986 -178.683193) (xy 93.701072 -178.63905) (xy 93.741221 -178.600341)
			(xy 93.786579 -178.56789) (xy 93.836179 -178.542389) (xy 93.888963 -178.524382) (xy 93.943806 -178.514252)
			(xy 93.99954 -178.512215) (xy 94.054977 -178.518315) (xy 94.108934 -178.532421) (xy 94.160263 -178.554233)
			(xy 94.207869 -178.583287) (xy 94.250737 -178.618962) (xy 94.287954 -178.660499) (xy 94.318727 -178.707012)
			(xy 94.342399 -178.757509) (xy 94.358467 -178.810916) (xy 94.366587 -178.866092) (xy 94.367096 -178.893978)
			(xy 94.366587 -178.921864) (xy 94.358467 -178.97704) (xy 94.342399 -179.030447) (xy 94.318727 -179.080944)
			(xy 94.287954 -179.127457) (xy 94.250737 -179.168994) (xy 94.207869 -179.204669) (xy 94.160263 -179.233723)
			(xy 94.108934 -179.255535) (xy 94.054977 -179.269641) (xy 93.99954 -179.275741) (xy 93.943806 -179.273704)
			(xy 93.888963 -179.263574) (xy 93.836179 -179.245567) (xy 93.786579 -179.220066) (xy 93.741221 -179.187615)
			(xy 93.701072 -179.148906) (xy 93.666986 -179.104763) (xy 93.63969 -179.056128) (xy 93.619767 -179.004037)
			(xy 93.607641 -178.9496) (xy 93.60357 -178.893978) (xy 93.085666 -178.893978) (xy 93.012006 -178.967638)
			(xy 93.008196 -178.978814) (xy 92.999264 -179.003575) (xy 92.975556 -179.050571) (xy 92.94561 -179.09386)
			(xy 92.909996 -179.13262) (xy 92.869389 -179.166114) (xy 92.824562 -179.193705) (xy 92.776367 -179.214869)
			(xy 92.725719 -179.229204) (xy 92.673581 -179.236438) (xy 92.647262 -179.236878) (xy 92.620008 -179.236457)
			(xy 92.566057 -179.228695) (xy 92.513759 -179.213334) (xy 92.46418 -179.190686) (xy 92.418328 -179.161213)
			(xy 92.377137 -179.125514) (xy 92.341446 -179.084317) (xy 92.311982 -179.038461) (xy 92.289343 -178.988877)
			(xy 92.273991 -178.936577) (xy 92.266238 -178.882624) (xy 92.265754 -178.85537) (xy 92.266209 -178.827894)
			(xy 92.274107 -178.773513) (xy 92.289733 -178.720829) (xy 92.312765 -178.670937) (xy 92.342725 -178.62487)
			(xy 92.360496 -178.60391) (xy 92.36075 -178.603656) (xy 92.366325 -178.596562) (xy 92.372578 -178.579651)
			(xy 92.372942 -178.570636) (xy 92.372942 -178.503072) (xy 92.372611 -178.494052) (xy 92.366347 -178.477135)
			(xy 92.36075 -178.470052) (xy 92.360242 -178.469544) (xy 92.342493 -178.44861) (xy 92.312611 -178.402575)
			(xy 92.289647 -178.352727) (xy 92.274076 -178.300098) (xy 92.266221 -178.24578) (xy 92.265754 -178.218338)
			(xy 92.266241 -178.191718) (xy 92.273626 -178.138994) (xy 92.288272 -178.087809) (xy 92.309895 -178.039158)
			(xy 92.338073 -177.993987) (xy 92.372259 -177.953175) (xy 92.41179 -177.917513) (xy 92.455895 -177.887695)
			(xy 92.503719 -177.864301) (xy 92.554332 -177.847786) (xy 92.58046 -177.842672) (xy 92.589201 -177.84085)
			(xy 92.604687 -177.831978) (xy 92.616183 -177.818327) (xy 92.622291 -177.801558) (xy 92.622624 -177.792634)
			(xy 92.622624 -176.085754) (xy 92.623233 -176.06077) (xy 92.632979 -176.011763) (xy 92.652087 -175.965593)
			(xy 92.679825 -175.924033) (xy 92.697046 -175.905922) (xy 96.065594 -172.537374) (xy 96.072437 -172.529976)
			(xy 96.080155 -172.511375) (xy 96.08058 -172.501306) (xy 96.08058 -160.435544) (xy 96.080137 -160.425477)
			(xy 96.072429 -160.406878) (xy 96.065594 -160.399476) (xy 93.234002 -157.567884) (xy 93.216767 -157.549786)
			(xy 93.189026 -157.508223) (xy 93.169921 -157.46205) (xy 93.160187 -157.413037) (xy 93.15958 -157.388052)
			(xy 93.15958 -153.462228) (xy 93.159157 -153.452206) (xy 93.151492 -153.433686) (xy 93.137321 -153.419512)
			(xy 93.118802 -153.411845) (xy 93.10878 -153.411428) (xy 92.304362 -153.411428) (xy 92.298433 -153.411283)
			(xy 92.286887 -153.408581) (xy 92.281502 -153.406094) (xy 92.155518 -153.342594) (xy 92.150354 -153.339794)
			(xy 92.141376 -153.332221) (xy 92.137738 -153.327608) (xy 92.109036 -153.289254) (xy 92.088386 -153.262565)
			(xy 92.041187 -153.214338) (xy 91.988022 -153.172779) (xy 91.929825 -153.138621) (xy 91.867621 -153.112463)
			(xy 91.802502 -153.094766) (xy 91.735614 -153.085841) (xy 91.701874 -153.085292) (xy 91.70162 -153.085292)
			(xy 91.676728 -153.0858) (xy 91.675204 -153.0858) (xy 91.624912 -153.08961) (xy 91.61948 -153.089872)
			(xy 91.608718 -153.088332) (xy 91.603576 -153.086562) (xy 91.5035 -153.049478) (xy 91.498677 -153.047612)
			(xy 91.489847 -153.042236) (xy 91.485974 -153.03881) (xy 91.39555 -152.952958) (xy 91.377921 -152.935612)
			(xy 91.34796 -152.896265) (xy 91.32475 -152.852596) (xy 91.308899 -152.80575) (xy 91.300825 -152.756959)
			(xy 91.3003 -152.732232) (xy 91.3003 -150.24989) (xy 91.300709 -150.228973) (xy 91.306576 -150.18755)
			(xy 91.311984 -150.16734) (xy 91.315794 -150.154132) (xy 91.308682 -150.127208) (xy 91.29903 -150.117556)
			(xy 91.291618 -150.110872) (xy 91.273185 -150.103275) (xy 91.253247 -150.103275) (xy 91.234814 -150.110872)
			(xy 91.227402 -150.117556) (xy 89.59088 -151.753824) (xy 89.57279 -151.771087) (xy 89.531243 -151.798894)
			(xy 89.48507 -151.818065) (xy 89.436045 -151.827864) (xy 89.411048 -151.8285) (xy 84.6963 -151.8285)
			(xy 84.686254 -151.828869) (xy 84.667657 -151.836456) (xy 84.660232 -151.843232) (xy 84.653374 -151.85009)
			(xy 84.646655 -151.857409) (xy 84.639002 -151.875727) (xy 84.638904 -151.895578) (xy 84.642198 -151.904954)
			(xy 84.682076 -152.005792) (xy 84.706714 -152.023064) (xy 84.721954 -152.023572) (xy 84.74861 -152.024895)
			(xy 84.80119 -152.034042) (xy 84.851981 -152.050431) (xy 84.899992 -152.07374) (xy 84.944284 -152.103514)
			(xy 84.983994 -152.139172) (xy 85.018344 -152.180018) (xy 85.046665 -152.225254) (xy 85.068404 -152.273996)
			(xy 85.083135 -152.325292) (xy 85.090571 -152.378141) (xy 85.091016 -152.404826) (xy 85.090476 -152.433743)
			(xy 85.081756 -152.490914) (xy 85.064505 -152.546114) (xy 85.039117 -152.598076) (xy 85.006176 -152.645611)
			(xy 84.966435 -152.687626) (xy 84.94395 -152.705816) (xy 84.935137 -152.713417) (xy 84.924958 -152.734323)
			(xy 84.924392 -152.745948) (xy 84.924392 -152.825704) (xy 84.924946 -152.837334) (xy 84.935125 -152.858243)
			(xy 84.94395 -152.865836) (xy 84.966461 -152.883994) (xy 85.006192 -152.926022) (xy 85.039127 -152.973564)
			(xy 85.06451 -153.025532) (xy 85.081761 -153.080735) (xy 85.090484 -153.137908) (xy 85.091016 -153.166826)
			(xy 85.090546 -153.194078) (xy 85.082787 -153.248025) (xy 85.067429 -153.30032) (xy 85.044785 -153.349897)
			(xy 85.015317 -153.395747) (xy 84.979624 -153.436936) (xy 84.938432 -153.472628) (xy 84.892581 -153.502094)
			(xy 84.843003 -153.524735) (xy 84.790708 -153.54009) (xy 84.73676 -153.547848) (xy 84.709508 -153.548334)
			(xy 84.682233 -153.547865) (xy 84.628235 -153.540121) (xy 84.575892 -153.524761) (xy 84.526271 -153.502099)
			(xy 84.480387 -153.472597) (xy 84.439175 -153.436857) (xy 84.403476 -153.39561) (xy 84.37402 -153.349696)
			(xy 84.36229 -153.325068) (xy 84.356194 -153.31186) (xy 84.332572 -153.295858) (xy 84.212938 -153.291286)
			(xy 84.188046 -153.305256) (xy 84.181188 -153.317702) (xy 84.168386 -153.339816) (xy 84.137788 -153.38074)
			(xy 84.102019 -153.417232) (xy 84.082128 -153.433272) (xy 84.073332 -153.440889) (xy 84.063145 -153.461783)
			(xy 84.06257 -153.473404) (xy 84.06257 -153.55316) (xy 84.063064 -153.564798) (xy 84.073282 -153.585709)
			(xy 84.082128 -153.593292) (xy 84.104613 -153.61148) (xy 84.144347 -153.653502) (xy 84.177285 -153.701037)
			(xy 84.202673 -153.752999) (xy 84.219929 -153.808197) (xy 84.228659 -153.865366) (xy 84.229194 -153.894282)
			(xy 84.228708 -153.921533) (xy 84.220952 -153.975481) (xy 84.205597 -154.027776) (xy 84.182955 -154.077353)
			(xy 84.153489 -154.123203) (xy 84.117798 -154.164394) (xy 84.076607 -154.200085) (xy 84.030757 -154.229551)
			(xy 83.98118 -154.252193) (xy 83.928885 -154.267548) (xy 83.874937 -154.275304) (xy 83.820435 -154.275304)
			(xy 83.766487 -154.267548) (xy 83.714192 -154.252193) (xy 83.664615 -154.229551) (xy 83.618765 -154.200085)
			(xy 83.577574 -154.164394) (xy 83.541883 -154.123203) (xy 83.512417 -154.077353) (xy 83.489775 -154.027776)
			(xy 83.47442 -153.975481) (xy 83.466664 -153.921533) (xy 83.466178 -153.894282) (xy 83.466726 -153.865366)
			(xy 83.475445 -153.808195) (xy 83.492695 -153.752995) (xy 83.518081 -153.701033) (xy 83.551021 -153.653498)
			(xy 83.590759 -153.611482) (xy 83.613244 -153.593292) (xy 83.622052 -153.585686) (xy 83.632233 -153.564784)
			(xy 83.632802 -153.55316) (xy 83.632802 -153.473404) (xy 83.632246 -153.461774) (xy 83.622069 -153.440865)
			(xy 83.613244 -153.433272) (xy 83.589776 -153.414278) (xy 83.548587 -153.37014) (xy 83.514863 -153.320066)
			(xy 83.489446 -153.265305) (xy 83.480656 -153.236422) (xy 83.4771 -153.223468) (xy 83.457796 -153.204672)
			(xy 83.360006 -153.179272) (xy 83.351366 -153.177378) (xy 83.333764 -153.179) (xy 83.317757 -153.186501)
			(xy 83.311238 -153.19248) (xy 81.239106 -155.264358) (xy 81.232293 -155.271779) (xy 81.224557 -155.290362)
			(xy 81.22412 -155.300426) (xy 81.22412 -155.828495) (xy 83.791294 -155.828495) (xy 83.795025 -155.775242)
			(xy 83.806143 -155.72303) (xy 83.824431 -155.672877) (xy 83.849532 -155.625763) (xy 83.880955 -155.582608)
			(xy 83.918088 -155.544255) (xy 83.938872 -155.527502) (xy 83.94768 -155.519896) (xy 83.95786 -155.498994)
			(xy 83.95843 -155.48737) (xy 83.95843 -155.407614) (xy 83.957893 -155.395981) (xy 83.947705 -155.37507)
			(xy 83.938872 -155.367482) (xy 83.916374 -155.349308) (xy 83.876641 -155.307284) (xy 83.843705 -155.259745)
			(xy 83.818319 -155.207781) (xy 83.801066 -155.152581) (xy 83.79234 -155.095409) (xy 83.791806 -155.066492)
			(xy 83.792248 -155.039238) (xy 83.800006 -154.985286) (xy 83.815364 -154.932987) (xy 83.838009 -154.883406)
			(xy 83.867479 -154.837552) (xy 83.903175 -154.796359) (xy 83.94437 -154.760666) (xy 83.990225 -154.731198)
			(xy 84.039807 -154.708556) (xy 84.092107 -154.693202) (xy 84.14606 -154.685446) (xy 84.173314 -154.684984)
			(xy 84.202588 -154.685536) (xy 84.260445 -154.694503) (xy 84.316252 -154.712208) (xy 84.368696 -154.738236)
			(xy 84.416546 -154.771974) (xy 84.437982 -154.791918) (xy 84.438236 -154.792172) (xy 84.445552 -154.798555)
			(xy 84.463586 -154.805721) (xy 84.473288 -154.806142) (xy 84.5439 -154.806142) (xy 84.553602 -154.805721)
			(xy 84.571629 -154.798549) (xy 84.578952 -154.792172) (xy 84.57946 -154.791664) (xy 84.600916 -154.771799)
			(xy 84.648736 -154.738156) (xy 84.701126 -154.712197) (xy 84.756862 -154.69453) (xy 84.81464 -154.685566)
			(xy 84.843874 -154.684984) (xy 84.872792 -154.685489) (xy 84.929965 -154.694216) (xy 84.985166 -154.711475)
			(xy 85.037128 -154.736869) (xy 85.084661 -154.769816) (xy 85.126676 -154.809562) (xy 85.144864 -154.83205)
			(xy 85.152488 -154.840839) (xy 85.173376 -154.851031) (xy 85.184996 -154.851608) (xy 85.264752 -154.851608)
			(xy 85.276385 -154.851082) (xy 85.297294 -154.840883) (xy 85.304884 -154.83205) (xy 85.319664 -154.813652)
			(xy 85.353034 -154.780281) (xy 85.371432 -154.765502) (xy 85.380234 -154.75789) (xy 85.390419 -154.736993)
			(xy 85.39099 -154.72537) (xy 85.39099 -154.645614) (xy 85.390432 -154.633984) (xy 85.380257 -154.613075)
			(xy 85.371432 -154.605482) (xy 85.348947 -154.587293) (xy 85.30921 -154.545274) (xy 85.27627 -154.497739)
			(xy 85.250882 -154.445777) (xy 85.233627 -154.390579) (xy 85.2249 -154.333408) (xy 85.224366 -154.304492)
			(xy 85.22487 -154.277242) (xy 85.232627 -154.223296) (xy 85.247982 -154.171003) (xy 85.270622 -154.121428)
			(xy 85.300087 -154.075579) (xy 85.335776 -154.034389) (xy 85.376964 -153.998698) (xy 85.422812 -153.969231)
			(xy 85.472386 -153.946588) (xy 85.524678 -153.931231) (xy 85.578624 -153.923472) (xy 85.605874 -153.922984)
			(xy 85.634792 -153.923489) (xy 85.691965 -153.932216) (xy 85.747166 -153.949475) (xy 85.799128 -153.974869)
			(xy 85.846661 -154.007816) (xy 85.888676 -154.047562) (xy 85.906864 -154.07005) (xy 85.914488 -154.078839)
			(xy 85.935376 -154.089031) (xy 85.946996 -154.089608) (xy 86.026752 -154.089608) (xy 86.038385 -154.089082)
			(xy 86.059294 -154.078883) (xy 86.066884 -154.07005) (xy 86.081664 -154.051652) (xy 86.115034 -154.018281)
			(xy 86.133432 -154.003502) (xy 86.142234 -153.99589) (xy 86.152419 -153.974993) (xy 86.15299 -153.96337)
			(xy 86.15299 -153.883614) (xy 86.152432 -153.871984) (xy 86.142257 -153.851075) (xy 86.133432 -153.843482)
			(xy 86.110947 -153.825293) (xy 86.07121 -153.783274) (xy 86.03827 -153.735739) (xy 86.012882 -153.683777)
			(xy 85.995627 -153.628579) (xy 85.9869 -153.571408) (xy 85.986366 -153.542492) (xy 85.98687 -153.515242)
			(xy 85.994627 -153.461296) (xy 86.009982 -153.409003) (xy 86.032622 -153.359428) (xy 86.062087 -153.313579)
			(xy 86.097776 -153.272389) (xy 86.138964 -153.236698) (xy 86.184812 -153.207231) (xy 86.234386 -153.184588)
			(xy 86.286678 -153.169231) (xy 86.340624 -153.161472) (xy 86.367874 -153.160984) (xy 86.396792 -153.161489)
			(xy 86.453965 -153.170216) (xy 86.509166 -153.187475) (xy 86.561128 -153.212869) (xy 86.608661 -153.245816)
			(xy 86.650676 -153.285562) (xy 86.668864 -153.30805) (xy 86.676488 -153.316839) (xy 86.697376 -153.327031)
			(xy 86.708996 -153.327608) (xy 86.788752 -153.327608) (xy 86.800385 -153.327082) (xy 86.821294 -153.316883)
			(xy 86.828884 -153.30805) (xy 86.845637 -153.287267) (xy 86.883991 -153.250137) (xy 86.927145 -153.218715)
			(xy 86.974259 -153.193616) (xy 87.024411 -153.17533) (xy 87.076622 -153.164213) (xy 87.129874 -153.160483)
			(xy 87.183126 -153.164213) (xy 87.235337 -153.17533) (xy 87.285489 -153.193616) (xy 87.332603 -153.218715)
			(xy 87.375757 -153.250137) (xy 87.414111 -153.287267) (xy 87.430864 -153.30805) (xy 87.438488 -153.316839)
			(xy 87.459376 -153.327031) (xy 87.470996 -153.327608) (xy 87.550752 -153.327608) (xy 87.562385 -153.327082)
			(xy 87.583294 -153.316883) (xy 87.590884 -153.30805) (xy 87.607637 -153.287267) (xy 87.645991 -153.250137)
			(xy 87.689145 -153.218715) (xy 87.736259 -153.193616) (xy 87.786411 -153.17533) (xy 87.838622 -153.164213)
			(xy 87.891874 -153.160483) (xy 87.945126 -153.164213) (xy 87.997337 -153.17533) (xy 88.047489 -153.193616)
			(xy 88.094603 -153.218715) (xy 88.137757 -153.250137) (xy 88.176111 -153.287267) (xy 88.192864 -153.30805)
			(xy 88.200488 -153.316839) (xy 88.221376 -153.327031) (xy 88.232996 -153.327608) (xy 88.312752 -153.327608)
			(xy 88.324385 -153.327082) (xy 88.345294 -153.316883) (xy 88.352884 -153.30805) (xy 88.369637 -153.287267)
			(xy 88.407991 -153.250137) (xy 88.451145 -153.218715) (xy 88.498259 -153.193616) (xy 88.548411 -153.17533)
			(xy 88.600622 -153.164213) (xy 88.653874 -153.160483) (xy 88.707126 -153.164213) (xy 88.759337 -153.17533)
			(xy 88.809489 -153.193616) (xy 88.856603 -153.218715) (xy 88.899757 -153.250137) (xy 88.938111 -153.287267)
			(xy 88.954864 -153.30805) (xy 88.962488 -153.316839) (xy 88.983376 -153.327031) (xy 88.994996 -153.327608)
			(xy 89.074752 -153.327608) (xy 89.086385 -153.327082) (xy 89.107294 -153.316883) (xy 89.114884 -153.30805)
			(xy 89.131637 -153.287267) (xy 89.169991 -153.250137) (xy 89.213145 -153.218715) (xy 89.260259 -153.193616)
			(xy 89.310411 -153.17533) (xy 89.362622 -153.164213) (xy 89.415874 -153.160483) (xy 89.469126 -153.164213)
			(xy 89.521337 -153.17533) (xy 89.571489 -153.193616) (xy 89.618603 -153.218715) (xy 89.661757 -153.250137)
			(xy 89.700111 -153.287267) (xy 89.716864 -153.30805) (xy 89.724488 -153.316839) (xy 89.745376 -153.327031)
			(xy 89.756996 -153.327608) (xy 89.836752 -153.327608) (xy 89.848385 -153.327082) (xy 89.869294 -153.316883)
			(xy 89.876884 -153.30805) (xy 89.893637 -153.287267) (xy 89.931991 -153.250137) (xy 89.975145 -153.218715)
			(xy 90.022259 -153.193616) (xy 90.072411 -153.17533) (xy 90.124622 -153.164213) (xy 90.177874 -153.160483)
			(xy 90.231126 -153.164213) (xy 90.283337 -153.17533) (xy 90.333489 -153.193616) (xy 90.380603 -153.218715)
			(xy 90.423757 -153.250137) (xy 90.462111 -153.287267) (xy 90.478864 -153.30805) (xy 90.486488 -153.316839)
			(xy 90.507376 -153.327031) (xy 90.518996 -153.327608) (xy 90.598752 -153.327608) (xy 90.610385 -153.327082)
			(xy 90.631294 -153.316883) (xy 90.638884 -153.30805) (xy 90.657071 -153.285564) (xy 90.699093 -153.245831)
			(xy 90.74663 -153.212894) (xy 90.798591 -153.187506) (xy 90.853789 -153.17025) (xy 90.910958 -153.16152)
			(xy 90.939874 -153.160984) (xy 90.967126 -153.161479) (xy 91.021075 -153.169233) (xy 91.073372 -153.184585)
			(xy 91.122951 -153.207224) (xy 91.168804 -153.236688) (xy 91.209997 -153.272379) (xy 91.245691 -153.313568)
			(xy 91.27516 -153.359419) (xy 91.297803 -153.408996) (xy 91.31316 -153.461292) (xy 91.320918 -153.51524)
			(xy 91.321382 -153.542492) (xy 91.320865 -153.571409) (xy 91.312136 -153.628581) (xy 91.294879 -153.68378)
			(xy 91.269487 -153.735741) (xy 91.236543 -153.783275) (xy 91.196802 -153.825292) (xy 91.174316 -153.843482)
			(xy 91.165513 -153.851092) (xy 91.15533 -153.871991) (xy 91.154758 -153.883614) (xy 91.154758 -153.96337)
			(xy 91.155308 -153.975001) (xy 91.165487 -153.995912) (xy 91.174316 -154.003502) (xy 91.192712 -154.018284)
			(xy 91.226085 -154.051652) (xy 91.240864 -154.07005) (xy 91.248488 -154.078839) (xy 91.269376 -154.089031)
			(xy 91.280996 -154.089608) (xy 91.360752 -154.089608) (xy 91.372385 -154.089082) (xy 91.393294 -154.078883)
			(xy 91.400884 -154.07005) (xy 91.419071 -154.047564) (xy 91.461093 -154.007831) (xy 91.50863 -153.974894)
			(xy 91.560591 -153.949506) (xy 91.615789 -153.93225) (xy 91.672958 -153.92352) (xy 91.701874 -153.922984)
			(xy 91.729126 -153.923479) (xy 91.783075 -153.931233) (xy 91.835372 -153.946585) (xy 91.884951 -153.969224)
			(xy 91.930804 -153.998688) (xy 91.971997 -154.034379) (xy 92.007691 -154.075568) (xy 92.03716 -154.121419)
			(xy 92.059803 -154.170996) (xy 92.07516 -154.223292) (xy 92.082918 -154.27724) (xy 92.083382 -154.304492)
			(xy 92.082865 -154.333409) (xy 92.074136 -154.390581) (xy 92.056879 -154.44578) (xy 92.031487 -154.497741)
			(xy 91.998543 -154.545275) (xy 91.958802 -154.587292) (xy 91.936316 -154.605482) (xy 91.927513 -154.613092)
			(xy 91.91733 -154.633991) (xy 91.916758 -154.645614) (xy 91.916758 -154.72537) (xy 91.917308 -154.737001)
			(xy 91.927487 -154.757912) (xy 91.936316 -154.765502) (xy 91.957092 -154.782264) (xy 91.994224 -154.820615)
			(xy 92.025648 -154.863768) (xy 92.050749 -154.910881) (xy 92.069037 -154.961032) (xy 92.080155 -155.013244)
			(xy 92.083885 -155.066495) (xy 92.080156 -155.119747) (xy 92.06904 -155.171958) (xy 92.050753 -155.22211)
			(xy 92.025653 -155.269223) (xy 91.994231 -155.312377) (xy 91.957099 -155.350729) (xy 91.936316 -155.367482)
			(xy 91.927513 -155.375092) (xy 91.91733 -155.395991) (xy 91.916758 -155.407614) (xy 91.916758 -155.48737)
			(xy 91.917308 -155.499001) (xy 91.927487 -155.519912) (xy 91.936316 -155.527502) (xy 91.957092 -155.544264)
			(xy 91.994224 -155.582615) (xy 92.025648 -155.625768) (xy 92.050749 -155.672881) (xy 92.069037 -155.723032)
			(xy 92.080155 -155.775244) (xy 92.083885 -155.828495) (xy 92.080156 -155.881747) (xy 92.06904 -155.933958)
			(xy 92.050753 -155.98411) (xy 92.025653 -156.031223) (xy 91.994231 -156.074377) (xy 91.957099 -156.112729)
			(xy 91.936316 -156.129482) (xy 91.927513 -156.137092) (xy 91.91733 -156.157991) (xy 91.916758 -156.169614)
			(xy 91.916758 -156.24937) (xy 91.917308 -156.261001) (xy 91.927487 -156.281912) (xy 91.936316 -156.289502)
			(xy 91.958804 -156.307688) (xy 91.998538 -156.349709) (xy 92.031476 -156.397245) (xy 92.056863 -156.449207)
			(xy 92.074119 -156.504406) (xy 92.082847 -156.561576) (xy 92.083382 -156.590492) (xy 92.082917 -156.618067)
			(xy 92.074965 -156.67264) (xy 92.059241 -156.7255) (xy 92.03607 -156.775546) (xy 92.005937 -156.821736)
			(xy 91.969469 -156.863106) (xy 91.948762 -156.881322) (xy 91.940671 -156.888862) (xy 91.931327 -156.908885)
			(xy 91.930728 -156.91993) (xy 91.930728 -156.997654) (xy 91.931313 -157.008701) (xy 91.940665 -157.028723)
			(xy 91.948762 -157.036262) (xy 91.96945 -157.054498) (xy 92.005924 -157.095861) (xy 92.03606 -157.142045)
			(xy 92.05923 -157.192088) (xy 92.074951 -157.244947) (xy 92.082895 -157.299519) (xy 92.083382 -157.327092)
			(xy 92.082937 -157.354346) (xy 92.075181 -157.408299) (xy 92.059824 -157.460599) (xy 92.037181 -157.51018)
			(xy 92.007711 -157.556035) (xy 91.972015 -157.597228) (xy 91.93082 -157.632922) (xy 91.884965 -157.662389)
			(xy 91.835382 -157.685031) (xy 91.783081 -157.700384) (xy 91.729128 -157.708138) (xy 91.701874 -157.7086)
			(xy 91.672959 -157.708029) (xy 91.61579 -157.699311) (xy 91.560593 -157.682063) (xy 91.508631 -157.656682)
			(xy 91.461095 -157.623747) (xy 91.419076 -157.584015) (xy 91.400884 -157.561534) (xy 91.393285 -157.552719)
			(xy 91.372378 -157.542542) (xy 91.360752 -157.541976) (xy 91.280996 -157.541976) (xy 91.269362 -157.542501)
			(xy 91.248451 -157.552697) (xy 91.240864 -157.561534) (xy 91.224111 -157.582317) (xy 91.185757 -157.619447)
			(xy 91.142603 -157.650869) (xy 91.095489 -157.675968) (xy 91.045337 -157.694254) (xy 90.993126 -157.705371)
			(xy 90.939874 -157.709101) (xy 90.886622 -157.705371) (xy 90.834411 -157.694254) (xy 90.784259 -157.675968)
			(xy 90.737145 -157.650869) (xy 90.693991 -157.619447) (xy 90.655637 -157.582317) (xy 90.638884 -157.561534)
			(xy 90.631285 -157.552719) (xy 90.610378 -157.542542) (xy 90.598752 -157.541976) (xy 90.518996 -157.541976)
			(xy 90.507362 -157.542501) (xy 90.486451 -157.552697) (xy 90.478864 -157.561534) (xy 90.460702 -157.584042)
			(xy 90.418675 -157.623774) (xy 90.371134 -157.656709) (xy 90.319167 -157.682093) (xy 90.263965 -157.699344)
			(xy 90.206792 -157.708068) (xy 90.177874 -157.7086) (xy 90.15153 -157.708154) (xy 90.099341 -157.700917)
			(xy 90.048644 -157.686571) (xy 90.000402 -157.665389) (xy 89.955532 -157.637772) (xy 89.914886 -157.604247)
			(xy 89.879239 -157.565449) (xy 89.849266 -157.522118) (xy 89.837006 -157.498796) (xy 89.830656 -157.485842)
			(xy 89.806272 -157.470856) (xy 86.739476 -157.470856) (xy 86.715092 -157.485842) (xy 86.708742 -157.498796)
			(xy 86.696496 -157.522125) (xy 86.666517 -157.565453) (xy 86.630865 -157.604247) (xy 86.590217 -157.63777)
			(xy 86.545346 -157.665386) (xy 86.497103 -157.686569) (xy 86.446407 -157.700918) (xy 86.394218 -157.708159)
			(xy 86.367874 -157.7086) (xy 86.338959 -157.708029) (xy 86.28179 -157.699311) (xy 86.226593 -157.682063)
			(xy 86.174631 -157.656682) (xy 86.127095 -157.623747) (xy 86.085076 -157.584015) (xy 86.066884 -157.561534)
			(xy 86.059285 -157.552719) (xy 86.038378 -157.542542) (xy 86.026752 -157.541976) (xy 85.946996 -157.541976)
			(xy 85.935362 -157.542501) (xy 85.914451 -157.552697) (xy 85.906864 -157.561534) (xy 85.890111 -157.582317)
			(xy 85.851757 -157.619447) (xy 85.808603 -157.650869) (xy 85.761489 -157.675968) (xy 85.711337 -157.694254)
			(xy 85.659126 -157.705371) (xy 85.605874 -157.709101) (xy 85.552622 -157.705371) (xy 85.500411 -157.694254)
			(xy 85.450259 -157.675968) (xy 85.403145 -157.650869) (xy 85.359991 -157.619447) (xy 85.321637 -157.582317)
			(xy 85.304884 -157.561534) (xy 85.297285 -157.552719) (xy 85.276378 -157.542542) (xy 85.264752 -157.541976)
			(xy 85.184996 -157.541976) (xy 85.173362 -157.542501) (xy 85.152451 -157.552697) (xy 85.144864 -157.561534)
			(xy 85.126702 -157.584042) (xy 85.084675 -157.623774) (xy 85.037134 -157.656709) (xy 84.985167 -157.682093)
			(xy 84.929965 -157.699344) (xy 84.872792 -157.708068) (xy 84.843874 -157.7086) (xy 84.8146 -157.70806)
			(xy 84.756742 -157.699091) (xy 84.700935 -157.681383) (xy 84.64849 -157.655352) (xy 84.600641 -157.621611)
			(xy 84.579206 -157.601666) (xy 84.578952 -157.601412) (xy 84.571598 -157.595078) (xy 84.553594 -157.587881)
			(xy 84.5439 -157.587442) (xy 84.473288 -157.587442) (xy 84.463586 -157.587861) (xy 84.445559 -157.595035)
			(xy 84.438236 -157.601412) (xy 84.437728 -157.60192) (xy 84.416275 -157.621788) (xy 84.368454 -157.655431)
			(xy 84.316063 -157.68139) (xy 84.260327 -157.699056) (xy 84.202548 -157.708019) (xy 84.173314 -157.7086)
			(xy 84.146061 -157.708132) (xy 84.09211 -157.700376) (xy 84.039812 -157.685022) (xy 83.990231 -157.66238)
			(xy 83.944378 -157.632913) (xy 83.903185 -157.59722) (xy 83.867491 -157.556027) (xy 83.838023 -157.510174)
			(xy 83.81538 -157.460594) (xy 83.800025 -157.408296) (xy 83.792269 -157.354345) (xy 83.791806 -157.327092)
			(xy 83.792333 -157.29952) (xy 83.800273 -157.244949) (xy 83.815985 -157.192091) (xy 83.839144 -157.142044)
			(xy 83.869266 -157.095853) (xy 83.905723 -157.054479) (xy 83.926426 -157.036262) (xy 83.934523 -157.028726)
			(xy 83.943864 -157.0087) (xy 83.94446 -156.997654) (xy 83.94446 -156.91993) (xy 83.943888 -156.908881)
			(xy 83.934527 -156.888859) (xy 83.926426 -156.881322) (xy 83.905727 -156.863097) (xy 83.869255 -156.821732)
			(xy 83.839121 -156.775545) (xy 83.815953 -156.7255) (xy 83.800234 -156.672639) (xy 83.792292 -156.618066)
			(xy 83.791806 -156.590492) (xy 83.792388 -156.561577) (xy 83.801103 -156.504409) (xy 83.818349 -156.449211)
			(xy 83.843728 -156.397249) (xy 83.876661 -156.349714) (xy 83.916391 -156.307694) (xy 83.938872 -156.289502)
			(xy 83.94768 -156.281896) (xy 83.95786 -156.260994) (xy 83.95843 -156.24937) (xy 83.95843 -156.169614)
			(xy 83.957893 -156.157981) (xy 83.947705 -156.13707) (xy 83.938872 -156.129482) (xy 83.91808 -156.112738)
			(xy 83.880949 -156.074385) (xy 83.849526 -156.031229) (xy 83.824427 -155.984115) (xy 83.80614 -155.933961)
			(xy 83.795023 -155.881748) (xy 83.791294 -155.828495) (xy 81.22412 -155.828495) (xy 81.22412 -164.097716)
			(xy 86.637622 -164.097716) (xy 86.638123 -164.068308) (xy 86.647149 -164.010189) (xy 86.66499 -163.954145)
			(xy 86.691223 -163.901503) (xy 86.725225 -163.853512) (xy 86.745318 -163.832032) (xy 86.751922 -163.825428)
			(xy 86.759288 -163.807902) (xy 86.761828 -163.730178) (xy 86.761678 -163.720682) (xy 86.755299 -163.702808)
			(xy 86.749382 -163.69538) (xy 86.732199 -163.674557) (xy 86.703277 -163.62897) (xy 86.681067 -163.579764)
			(xy 86.66601 -163.527919) (xy 86.658407 -163.47447) (xy 86.657942 -163.447476) (xy 86.658384 -163.420105)
			(xy 86.666206 -163.365924) (xy 86.6817 -163.31342) (xy 86.704547 -163.263674) (xy 86.734278 -163.217709)
			(xy 86.751922 -163.196778) (xy 86.752176 -163.196524) (xy 86.757768 -163.189441) (xy 86.764009 -163.172521)
			(xy 86.764368 -163.163504) (xy 86.764368 -163.096448) (xy 86.763995 -163.087433) (xy 86.757759 -163.070515)
			(xy 86.752176 -163.063428) (xy 86.751922 -163.063428) (xy 86.751922 -163.063174) (xy 86.734308 -163.042222)
			(xy 86.704591 -162.996255) (xy 86.68175 -162.946513) (xy 86.666253 -162.894016) (xy 86.658419 -162.839844)
			(xy 86.657942 -162.812476) (xy 86.658333 -162.78522) (xy 86.666094 -162.731264) (xy 86.681456 -162.678962)
			(xy 86.704105 -162.629378) (xy 86.73358 -162.583523) (xy 86.769281 -162.542329) (xy 86.810482 -162.506636)
			(xy 86.856343 -162.477169) (xy 86.905931 -162.45453) (xy 86.958236 -162.439178) (xy 87.012194 -162.431427)
			(xy 87.03945 -162.430968) (xy 87.06682 -162.431447) (xy 87.120999 -162.439259) (xy 87.173503 -162.454744)
			(xy 87.22325 -162.477584) (xy 87.269217 -162.507307) (xy 87.290148 -162.524948) (xy 87.290402 -162.525202)
			(xy 87.297484 -162.530796) (xy 87.314404 -162.537038) (xy 87.323422 -162.537394) (xy 87.390478 -162.537394)
			(xy 87.399494 -162.537028) (xy 87.416411 -162.530787) (xy 87.423498 -162.525202) (xy 87.423498 -162.524948)
			(xy 87.423752 -162.524948) (xy 87.444685 -162.507307) (xy 87.490653 -162.477583) (xy 87.540399 -162.454737)
			(xy 87.592901 -162.439241) (xy 87.647079 -162.431412) (xy 87.701821 -162.431412) (xy 87.755999 -162.439241)
			(xy 87.808501 -162.454737) (xy 87.858247 -162.477583) (xy 87.904215 -162.507307) (xy 87.925148 -162.524948)
			(xy 87.925402 -162.525202) (xy 87.932484 -162.530796) (xy 87.949404 -162.537038) (xy 87.958422 -162.537394)
			(xy 88.025478 -162.537394) (xy 88.034494 -162.537028) (xy 88.051411 -162.530787) (xy 88.058498 -162.525202)
			(xy 88.058498 -162.524948) (xy 88.058752 -162.524948) (xy 88.079685 -162.507307) (xy 88.125653 -162.477583)
			(xy 88.175399 -162.454737) (xy 88.227901 -162.439241) (xy 88.282079 -162.431412) (xy 88.336821 -162.431412)
			(xy 88.390999 -162.439241) (xy 88.443501 -162.454737) (xy 88.493247 -162.477583) (xy 88.539215 -162.507307)
			(xy 88.560148 -162.524948) (xy 88.560402 -162.525202) (xy 88.567484 -162.530796) (xy 88.584404 -162.537038)
			(xy 88.593422 -162.537394) (xy 88.660478 -162.537394) (xy 88.669494 -162.537028) (xy 88.686411 -162.530787)
			(xy 88.693498 -162.525202) (xy 88.693498 -162.524948) (xy 88.693752 -162.524948) (xy 88.714685 -162.507307)
			(xy 88.760653 -162.477583) (xy 88.810399 -162.454737) (xy 88.862901 -162.439241) (xy 88.917079 -162.431412)
			(xy 88.971821 -162.431412) (xy 89.025999 -162.439241) (xy 89.078501 -162.454737) (xy 89.128247 -162.477583)
			(xy 89.174215 -162.507307) (xy 89.195148 -162.524948) (xy 89.195402 -162.525202) (xy 89.202484 -162.530796)
			(xy 89.219404 -162.537038) (xy 89.228422 -162.537394) (xy 89.295478 -162.537394) (xy 89.304494 -162.537028)
			(xy 89.321411 -162.530787) (xy 89.328498 -162.525202) (xy 89.328498 -162.524948) (xy 89.328752 -162.524948)
			(xy 89.349698 -162.507325) (xy 89.395666 -162.477609) (xy 89.44541 -162.45477) (xy 89.497908 -162.439275)
			(xy 89.552082 -162.431443) (xy 89.57945 -162.430968) (xy 89.60876 -162.431511) (xy 89.666686 -162.440505)
			(xy 89.722554 -162.458257) (xy 89.775046 -162.48435) (xy 89.822928 -162.518168) (xy 89.844372 -162.538156)
			(xy 89.851569 -162.544521) (xy 89.869324 -162.551829) (xy 89.878916 -162.55238) (xy 89.958164 -162.553396)
			(xy 89.976198 -162.546538) (xy 89.98331 -162.540188) (xy 90.004476 -162.521627) (xy 90.051268 -162.490328)
			(xy 90.102149 -162.466241) (xy 90.156017 -162.449889) (xy 90.211702 -162.441627) (xy 90.23985 -162.441128)
			(xy 90.267103 -162.441602) (xy 90.321056 -162.449353) (xy 90.373356 -162.464705) (xy 90.422938 -162.487344)
			(xy 90.468793 -162.51681) (xy 90.509987 -162.552503) (xy 90.545682 -162.593696) (xy 90.575149 -162.63955)
			(xy 90.597791 -162.689131) (xy 90.613144 -162.741431) (xy 90.620897 -162.795383) (xy 90.621358 -162.822636)
			(xy 90.620923 -162.850007) (xy 90.613099 -162.904188) (xy 90.597604 -162.956692) (xy 90.574755 -163.006439)
			(xy 90.545023 -163.052404) (xy 90.527378 -163.073334) (xy 90.527124 -163.073588) (xy 90.521527 -163.080667)
			(xy 90.515289 -163.09759) (xy 90.514932 -163.106608) (xy 90.514932 -163.173664) (xy 90.515299 -163.18268)
			(xy 90.521539 -163.199597) (xy 90.527124 -163.206684) (xy 90.527378 -163.206684) (xy 90.527378 -163.206938)
			(xy 90.544998 -163.227885) (xy 90.574714 -163.273854) (xy 90.597553 -163.323597) (xy 90.613049 -163.376095)
			(xy 90.620882 -163.430268) (xy 90.621358 -163.457636) (xy 90.620806 -163.487042) (xy 90.611789 -163.545157)
			(xy 90.593959 -163.601201) (xy 90.567738 -163.653843) (xy 90.533749 -163.701837) (xy 90.513662 -163.72332)
			(xy 90.507058 -163.729924) (xy 90.499692 -163.74745) (xy 90.497152 -163.825174) (xy 90.497338 -163.834663)
			(xy 90.503725 -163.852516) (xy 90.509598 -163.859972) (xy 90.526755 -163.880815) (xy 90.555682 -163.926396)
			(xy 90.577898 -163.975598) (xy 90.592961 -164.027438) (xy 90.60057 -164.080884) (xy 90.601038 -164.107876)
			(xy 90.6005 -164.135125) (xy 90.592747 -164.189069) (xy 90.577396 -164.241361) (xy 90.55476 -164.290936)
			(xy 90.525299 -164.336785) (xy 90.489613 -164.377975) (xy 90.448429 -164.413667) (xy 90.402584 -164.443134)
			(xy 90.353012 -164.465778) (xy 90.300722 -164.481136) (xy 90.246779 -164.488896) (xy 90.21953 -164.489384)
			(xy 90.19022 -164.488839) (xy 90.132295 -164.479843) (xy 90.076428 -164.462091) (xy 90.023935 -164.435999)
			(xy 89.976053 -164.402183) (xy 89.954608 -164.382196) (xy 89.947422 -164.375816) (xy 89.929659 -164.368518)
			(xy 89.920064 -164.367972) (xy 89.840816 -164.366956) (xy 89.822782 -164.373814) (xy 89.81567 -164.380164)
			(xy 89.794479 -164.398695) (xy 89.747694 -164.429997) (xy 89.696818 -164.454089) (xy 89.642956 -164.470448)
			(xy 89.587276 -164.478719) (xy 89.55913 -164.479224) (xy 89.53176 -164.478759) (xy 89.47758 -164.470944)
			(xy 89.425076 -164.455455) (xy 89.375329 -164.432613) (xy 89.329363 -164.402887) (xy 89.308432 -164.385244)
			(xy 89.308178 -164.38499) (xy 89.301103 -164.379387) (xy 89.284177 -164.37315) (xy 89.275158 -164.372798)
			(xy 89.208102 -164.372798) (xy 89.199085 -164.373156) (xy 89.182168 -164.379403) (xy 89.175082 -164.38499)
			(xy 89.175082 -164.385244) (xy 89.174828 -164.385244) (xy 89.153895 -164.402885) (xy 89.107927 -164.432609)
			(xy 89.058181 -164.455455) (xy 89.005679 -164.470951) (xy 88.951501 -164.47878) (xy 88.896759 -164.47878)
			(xy 88.842581 -164.470951) (xy 88.790079 -164.455455) (xy 88.740333 -164.432609) (xy 88.694365 -164.402885)
			(xy 88.673432 -164.385244) (xy 88.673178 -164.38499) (xy 88.666103 -164.379387) (xy 88.649177 -164.37315)
			(xy 88.640158 -164.372798) (xy 88.573102 -164.372798) (xy 88.564085 -164.373156) (xy 88.547168 -164.379403)
			(xy 88.540082 -164.38499) (xy 88.540082 -164.385244) (xy 88.539828 -164.385244) (xy 88.518895 -164.402885)
			(xy 88.472927 -164.432609) (xy 88.423181 -164.455455) (xy 88.370679 -164.470951) (xy 88.316501 -164.47878)
			(xy 88.261759 -164.47878) (xy 88.207581 -164.470951) (xy 88.155079 -164.455455) (xy 88.105333 -164.432609)
			(xy 88.059365 -164.402885) (xy 88.038432 -164.385244) (xy 88.038178 -164.38499) (xy 88.031103 -164.379387)
			(xy 88.014177 -164.37315) (xy 88.005158 -164.372798) (xy 87.938102 -164.372798) (xy 87.929085 -164.373156)
			(xy 87.912168 -164.379403) (xy 87.905082 -164.38499) (xy 87.905082 -164.385244) (xy 87.904828 -164.385244)
			(xy 87.883895 -164.402885) (xy 87.837927 -164.432609) (xy 87.788181 -164.455455) (xy 87.735679 -164.470951)
			(xy 87.681501 -164.47878) (xy 87.626759 -164.47878) (xy 87.572581 -164.470951) (xy 87.520079 -164.455455)
			(xy 87.470333 -164.432609) (xy 87.424365 -164.402885) (xy 87.403432 -164.385244) (xy 87.403178 -164.38499)
			(xy 87.396103 -164.379387) (xy 87.379177 -164.37315) (xy 87.370158 -164.372798) (xy 87.303102 -164.372798)
			(xy 87.294085 -164.373156) (xy 87.277168 -164.379403) (xy 87.270082 -164.38499) (xy 87.270082 -164.385244)
			(xy 87.269828 -164.385244) (xy 87.248902 -164.402891) (xy 87.202927 -164.4326) (xy 87.153178 -164.455434)
			(xy 87.100676 -164.470923) (xy 87.046499 -164.478751) (xy 87.01913 -164.479224) (xy 86.991879 -164.478717)
			(xy 86.93793 -164.470964) (xy 86.885634 -164.455613) (xy 86.836055 -164.432975) (xy 86.790203 -164.403512)
			(xy 86.74901 -164.367823) (xy 86.713316 -164.326634) (xy 86.683847 -164.280785) (xy 86.661203 -164.231209)
			(xy 86.645845 -164.178915) (xy 86.638086 -164.124967) (xy 86.637622 -164.097716) (xy 81.22412 -164.097716)
			(xy 81.22412 -166.004424) (xy 82.10067 -166.004424) (xy 82.10067 -165.919728) (xy 82.108721 -165.835414)
			(xy 82.12475 -165.752248) (xy 82.148611 -165.670981) (xy 82.18009 -165.592351) (xy 82.218901 -165.51707)
			(xy 82.264691 -165.445818) (xy 82.317047 -165.379242) (xy 82.375495 -165.317944) (xy 82.439505 -165.262479)
			(xy 82.508497 -165.21335) (xy 82.581847 -165.171001) (xy 82.65889 -165.135817) (xy 82.738929 -165.108115)
			(xy 82.821238 -165.088147) (xy 82.905073 -165.076094) (xy 82.989674 -165.072064) (xy 83.074275 -165.076094)
			(xy 83.15811 -165.088147) (xy 83.240419 -165.108115) (xy 83.320458 -165.135817) (xy 83.397501 -165.171001)
			(xy 83.470851 -165.21335) (xy 83.539843 -165.262479) (xy 83.603853 -165.317944) (xy 83.662301 -165.379242)
			(xy 83.714657 -165.445818) (xy 83.760447 -165.51707) (xy 83.799258 -165.592351) (xy 83.830737 -165.670981)
			(xy 83.854598 -165.752248) (xy 83.870627 -165.835414) (xy 83.878678 -165.919728) (xy 83.879182 -165.962076)
			(xy 83.878678 -166.004424) (xy 91.49867 -166.004424) (xy 91.49867 -165.919728) (xy 91.506721 -165.835414)
			(xy 91.52275 -165.752248) (xy 91.546611 -165.670981) (xy 91.57809 -165.592351) (xy 91.616901 -165.51707)
			(xy 91.662691 -165.445818) (xy 91.715047 -165.379242) (xy 91.773495 -165.317944) (xy 91.837505 -165.262479)
			(xy 91.906497 -165.21335) (xy 91.979847 -165.171001) (xy 92.05689 -165.135817) (xy 92.136929 -165.108115)
			(xy 92.219238 -165.088147) (xy 92.303073 -165.076094) (xy 92.387674 -165.072064) (xy 92.472275 -165.076094)
			(xy 92.55611 -165.088147) (xy 92.638419 -165.108115) (xy 92.718458 -165.135817) (xy 92.795501 -165.171001)
			(xy 92.868851 -165.21335) (xy 92.937843 -165.262479) (xy 93.001853 -165.317944) (xy 93.060301 -165.379242)
			(xy 93.112657 -165.445818) (xy 93.158447 -165.51707) (xy 93.197258 -165.592351) (xy 93.228737 -165.670981)
			(xy 93.252598 -165.752248) (xy 93.268627 -165.835414) (xy 93.276678 -165.919728) (xy 93.277182 -165.962076)
			(xy 93.276678 -166.004424) (xy 93.268627 -166.088738) (xy 93.252598 -166.171904) (xy 93.228737 -166.253171)
			(xy 93.197258 -166.331801) (xy 93.158447 -166.407082) (xy 93.112657 -166.478334) (xy 93.060301 -166.54491)
			(xy 93.001853 -166.606208) (xy 92.937843 -166.661673) (xy 92.868851 -166.710802) (xy 92.795501 -166.753151)
			(xy 92.718458 -166.788335) (xy 92.638419 -166.816037) (xy 92.55611 -166.836005) (xy 92.472275 -166.848058)
			(xy 92.387674 -166.852089) (xy 92.303073 -166.848058) (xy 92.219238 -166.836005) (xy 92.136929 -166.816037)
			(xy 92.05689 -166.788335) (xy 91.979847 -166.753151) (xy 91.906497 -166.710802) (xy 91.837505 -166.661673)
			(xy 91.773495 -166.606208) (xy 91.715047 -166.54491) (xy 91.662691 -166.478334) (xy 91.616901 -166.407082)
			(xy 91.57809 -166.331801) (xy 91.546611 -166.253171) (xy 91.52275 -166.171904) (xy 91.506721 -166.088738)
			(xy 91.49867 -166.004424) (xy 83.878678 -166.004424) (xy 83.870627 -166.088738) (xy 83.854598 -166.171904)
			(xy 83.830737 -166.253171) (xy 83.799258 -166.331801) (xy 83.760447 -166.407082) (xy 83.714657 -166.478334)
			(xy 83.662301 -166.54491) (xy 83.603853 -166.606208) (xy 83.539843 -166.661673) (xy 83.470851 -166.710802)
			(xy 83.397501 -166.753151) (xy 83.320458 -166.788335) (xy 83.240419 -166.816037) (xy 83.15811 -166.836005)
			(xy 83.074275 -166.848058) (xy 82.989674 -166.852089) (xy 82.905073 -166.848058) (xy 82.821238 -166.836005)
			(xy 82.738929 -166.816037) (xy 82.65889 -166.788335) (xy 82.581847 -166.753151) (xy 82.508497 -166.710802)
			(xy 82.439505 -166.661673) (xy 82.375495 -166.606208) (xy 82.317047 -166.54491) (xy 82.264691 -166.478334)
			(xy 82.218901 -166.407082) (xy 82.18009 -166.331801) (xy 82.148611 -166.253171) (xy 82.12475 -166.171904)
			(xy 82.108721 -166.088738) (xy 82.10067 -166.004424) (xy 81.22412 -166.004424) (xy 81.22412 -168.504546)
			(xy 82.10067 -168.504546) (xy 82.10067 -168.41985) (xy 82.108721 -168.335536) (xy 82.12475 -168.25237)
			(xy 82.148611 -168.171103) (xy 82.18009 -168.092473) (xy 82.218901 -168.017192) (xy 82.264691 -167.94594)
			(xy 82.317047 -167.879364) (xy 82.375495 -167.818066) (xy 82.439505 -167.762601) (xy 82.508497 -167.713472)
			(xy 82.581847 -167.671123) (xy 82.65889 -167.635939) (xy 82.738929 -167.608237) (xy 82.821238 -167.588269)
			(xy 82.905073 -167.576216) (xy 82.989674 -167.572186) (xy 83.074275 -167.576216) (xy 83.15811 -167.588269)
			(xy 83.240419 -167.608237) (xy 83.320458 -167.635939) (xy 83.397501 -167.671123) (xy 83.470851 -167.713472)
			(xy 83.539843 -167.762601) (xy 83.603853 -167.818066) (xy 83.662301 -167.879364) (xy 83.714657 -167.94594)
			(xy 83.760447 -168.017192) (xy 83.799258 -168.092473) (xy 83.830737 -168.171103) (xy 83.854598 -168.25237)
			(xy 83.870627 -168.335536) (xy 83.878678 -168.41985) (xy 83.879182 -168.462198) (xy 83.878678 -168.504546)
			(xy 91.49867 -168.504546) (xy 91.49867 -168.41985) (xy 91.506721 -168.335536) (xy 91.52275 -168.25237)
			(xy 91.546611 -168.171103) (xy 91.57809 -168.092473) (xy 91.616901 -168.017192) (xy 91.662691 -167.94594)
			(xy 91.715047 -167.879364) (xy 91.773495 -167.818066) (xy 91.837505 -167.762601) (xy 91.906497 -167.713472)
			(xy 91.979847 -167.671123) (xy 92.05689 -167.635939) (xy 92.136929 -167.608237) (xy 92.219238 -167.588269)
			(xy 92.303073 -167.576216) (xy 92.387674 -167.572186) (xy 92.472275 -167.576216) (xy 92.55611 -167.588269)
			(xy 92.638419 -167.608237) (xy 92.718458 -167.635939) (xy 92.795501 -167.671123) (xy 92.868851 -167.713472)
			(xy 92.937843 -167.762601) (xy 93.001853 -167.818066) (xy 93.060301 -167.879364) (xy 93.112657 -167.94594)
			(xy 93.158447 -168.017192) (xy 93.197258 -168.092473) (xy 93.228737 -168.171103) (xy 93.252598 -168.25237)
			(xy 93.268627 -168.335536) (xy 93.276678 -168.41985) (xy 93.277182 -168.462198) (xy 93.276678 -168.504546)
			(xy 93.268627 -168.58886) (xy 93.252598 -168.672026) (xy 93.228737 -168.753293) (xy 93.197258 -168.831923)
			(xy 93.158447 -168.907204) (xy 93.112657 -168.978456) (xy 93.060301 -169.045032) (xy 93.001853 -169.10633)
			(xy 92.937843 -169.161795) (xy 92.868851 -169.210924) (xy 92.795501 -169.253273) (xy 92.718458 -169.288457)
			(xy 92.638419 -169.316159) (xy 92.55611 -169.336127) (xy 92.472275 -169.34818) (xy 92.387674 -169.352211)
			(xy 92.303073 -169.34818) (xy 92.219238 -169.336127) (xy 92.136929 -169.316159) (xy 92.05689 -169.288457)
			(xy 91.979847 -169.253273) (xy 91.906497 -169.210924) (xy 91.837505 -169.161795) (xy 91.773495 -169.10633)
			(xy 91.715047 -169.045032) (xy 91.662691 -168.978456) (xy 91.616901 -168.907204) (xy 91.57809 -168.831923)
			(xy 91.546611 -168.753293) (xy 91.52275 -168.672026) (xy 91.506721 -168.58886) (xy 91.49867 -168.504546)
			(xy 83.878678 -168.504546) (xy 83.870627 -168.58886) (xy 83.854598 -168.672026) (xy 83.830737 -168.753293)
			(xy 83.799258 -168.831923) (xy 83.760447 -168.907204) (xy 83.714657 -168.978456) (xy 83.662301 -169.045032)
			(xy 83.603853 -169.10633) (xy 83.539843 -169.161795) (xy 83.470851 -169.210924) (xy 83.397501 -169.253273)
			(xy 83.320458 -169.288457) (xy 83.240419 -169.316159) (xy 83.15811 -169.336127) (xy 83.074275 -169.34818)
			(xy 82.989674 -169.352211) (xy 82.905073 -169.34818) (xy 82.821238 -169.336127) (xy 82.738929 -169.316159)
			(xy 82.65889 -169.288457) (xy 82.581847 -169.253273) (xy 82.508497 -169.210924) (xy 82.439505 -169.161795)
			(xy 82.375495 -169.10633) (xy 82.317047 -169.045032) (xy 82.264691 -168.978456) (xy 82.218901 -168.907204)
			(xy 82.18009 -168.831923) (xy 82.148611 -168.753293) (xy 82.12475 -168.672026) (xy 82.108721 -168.58886)
			(xy 82.10067 -168.504546) (xy 81.22412 -168.504546) (xy 81.22412 -173.359318) (xy 81.224531 -173.369389)
			(xy 81.232261 -173.387987) (xy 81.239106 -173.395386) (xy 85.03031 -177.18659) (xy 85.047535 -177.204698)
			(xy 85.075277 -177.246257) (xy 85.094385 -177.292428) (xy 85.104123 -177.341438) (xy 85.104732 -177.366422)
			(xy 85.104732 -178.33594) (xy 90.375486 -178.33594) (xy 90.375972 -178.308689) (xy 90.383728 -178.254741)
			(xy 90.399083 -178.202446) (xy 90.421725 -178.152869) (xy 90.451191 -178.107019) (xy 90.486882 -178.065828)
			(xy 90.528073 -178.030137) (xy 90.573923 -178.000671) (xy 90.6235 -177.978029) (xy 90.675795 -177.962674)
			(xy 90.729743 -177.954918) (xy 90.784245 -177.954918) (xy 90.838193 -177.962674) (xy 90.890488 -177.978029)
			(xy 90.940065 -178.000671) (xy 90.985915 -178.030137) (xy 91.027106 -178.065828) (xy 91.062797 -178.107019)
			(xy 91.092263 -178.152869) (xy 91.114905 -178.202446) (xy 91.13026 -178.254741) (xy 91.138016 -178.308689)
			(xy 91.138502 -178.33594) (xy 91.137843 -178.367503) (xy 91.127455 -178.429768) (xy 91.106969 -178.489477)
			(xy 91.092528 -178.51755) (xy 91.087702 -178.52644) (xy 91.08567 -178.545998) (xy 91.10853 -178.624484)
			(xy 91.111774 -178.633906) (xy 91.124187 -178.649467) (xy 91.13266 -178.65471) (xy 91.140026 -178.658774)
			(xy 91.149932 -178.664616) (xy 91.171776 -178.666648) (xy 91.266518 -178.63312) (xy 91.282266 -178.617626)
			(xy 91.28633 -178.607212) (xy 91.297074 -178.580456) (xy 91.325355 -178.530215) (xy 91.360878 -178.484806)
			(xy 91.402832 -178.445262) (xy 91.450263 -178.412485) (xy 91.502087 -178.387224) (xy 91.557124 -178.370053)
			(xy 91.614119 -178.361365) (xy 91.642946 -178.360832) (xy 91.670198 -178.361241) (xy 91.724146 -178.369004)
			(xy 91.776441 -178.384364) (xy 91.826018 -178.407011) (xy 91.871867 -178.436481) (xy 91.913056 -178.472176)
			(xy 91.948746 -178.51337) (xy 91.978212 -178.559223) (xy 92.000852 -178.608802) (xy 92.016206 -178.661099)
			(xy 92.023962 -178.715048) (xy 92.023962 -178.769552) (xy 92.016206 -178.823501) (xy 92.000852 -178.875798)
			(xy 91.978212 -178.925377) (xy 91.948746 -178.97123) (xy 91.913056 -179.012424) (xy 91.871867 -179.048119)
			(xy 91.826018 -179.077589) (xy 91.776441 -179.100236) (xy 91.724146 -179.115596) (xy 91.670198 -179.123359)
			(xy 91.642946 -179.123848) (xy 91.642692 -179.123848) (xy 91.617488 -179.123454) (xy 91.56752 -179.116813)
			(xy 91.518865 -179.103635) (xy 91.472376 -179.08415) (xy 91.450414 -179.071778) (xy 91.440508 -179.065936)
			(xy 91.418664 -179.063904) (xy 91.323922 -179.097432) (xy 91.308174 -179.112926) (xy 91.30411 -179.12334)
			(xy 91.293443 -179.150129) (xy 91.26515 -179.20037) (xy 91.229616 -179.245779) (xy 91.187649 -179.28532)
			(xy 91.140208 -179.318092) (xy 91.088373 -179.343348) (xy 91.033327 -179.360511) (xy 90.976324 -179.369192)
			(xy 90.947494 -179.36972) (xy 90.920243 -179.369228) (xy 90.866296 -179.361471) (xy 90.814002 -179.346116)
			(xy 90.764426 -179.323475) (xy 90.718576 -179.294009) (xy 90.677386 -179.258318) (xy 90.641695 -179.217129)
			(xy 90.612228 -179.171279) (xy 90.589587 -179.121703) (xy 90.57423 -179.06941) (xy 90.566473 -179.015463)
			(xy 90.565986 -178.988212) (xy 90.566628 -178.956648) (xy 90.577023 -178.894383) (xy 90.597515 -178.834674)
			(xy 90.61196 -178.806602) (xy 90.616786 -178.797712) (xy 90.618818 -178.778154) (xy 90.595958 -178.699668)
			(xy 90.592738 -178.690236) (xy 90.580308 -178.674681) (xy 90.571828 -178.669442) (xy 90.546724 -178.654899)
			(xy 90.50084 -178.619396) (xy 90.460864 -178.577351) (xy 90.427719 -178.529737) (xy 90.402168 -178.477651)
			(xy 90.384803 -178.422295) (xy 90.376024 -178.364948) (xy 90.375486 -178.33594) (xy 85.104732 -178.33594)
			(xy 85.104732 -178.440334) (xy 85.104128 -178.465318) (xy 85.094383 -178.514327) (xy 85.075274 -178.560496)
			(xy 85.047533 -178.602057) (xy 85.03031 -178.620166) (xy 84.688426 -178.96205) (xy 85.20633 -178.96205)
			(xy 85.210401 -178.906428) (xy 85.222527 -178.851991) (xy 85.24245 -178.7999) (xy 85.269746 -178.751265)
			(xy 85.303832 -178.707122) (xy 85.343981 -178.668413) (xy 85.389339 -178.635962) (xy 85.438939 -178.610461)
			(xy 85.491723 -178.592454) (xy 85.546566 -178.582324) (xy 85.6023 -178.580287) (xy 85.657737 -178.586387)
			(xy 85.711694 -178.600493) (xy 85.763023 -178.622305) (xy 85.810629 -178.651359) (xy 85.853497 -178.687034)
			(xy 85.890714 -178.728571) (xy 85.921487 -178.775084) (xy 85.945159 -178.825581) (xy 85.961227 -178.878988)
			(xy 85.969347 -178.934164) (xy 85.969856 -178.96205) (xy 85.969347 -178.989936) (xy 85.961227 -179.045112)
			(xy 85.945159 -179.098519) (xy 85.921487 -179.149016) (xy 85.890714 -179.195529) (xy 85.853497 -179.237066)
			(xy 85.810629 -179.272741) (xy 85.763023 -179.301795) (xy 85.711694 -179.323607) (xy 85.657737 -179.337713)
			(xy 85.6023 -179.343813) (xy 85.546566 -179.341776) (xy 85.491723 -179.331646) (xy 85.438939 -179.313639)
			(xy 85.389339 -179.288138) (xy 85.343981 -179.255687) (xy 85.303832 -179.216978) (xy 85.269746 -179.172835)
			(xy 85.24245 -179.1242) (xy 85.222527 -179.072109) (xy 85.210401 -179.017672) (xy 85.20633 -178.96205)
			(xy 84.688426 -178.96205) (xy 84.614766 -179.03571) (xy 84.610956 -179.046886) (xy 84.602042 -179.071654)
			(xy 84.578334 -179.118653) (xy 84.548387 -179.161944) (xy 84.512771 -179.200705) (xy 84.472162 -179.234199)
			(xy 84.427332 -179.261789) (xy 84.379134 -179.282951) (xy 84.328483 -179.297283) (xy 84.276342 -179.304513)
			(xy 84.250022 -179.30495) (xy 84.222773 -179.304401) (xy 84.16883 -179.296649) (xy 84.116539 -179.281299)
			(xy 84.066965 -179.258663) (xy 84.021116 -179.229203) (xy 83.979927 -179.193518) (xy 83.944235 -179.152335)
			(xy 83.914767 -179.106491) (xy 83.892124 -179.056921) (xy 83.876765 -179.004633) (xy 83.869003 -178.950691)
			(xy 83.868514 -178.923442) (xy 83.869022 -178.895968) (xy 83.876908 -178.841589) (xy 83.892523 -178.788907)
			(xy 83.915543 -178.739014) (xy 83.94549 -178.692944) (xy 83.963256 -178.671982) (xy 83.96351 -178.671728)
			(xy 83.969092 -178.664638) (xy 83.975341 -178.647724) (xy 83.975702 -178.638708) (xy 83.975702 -178.571144)
			(xy 83.975324 -178.562129) (xy 83.969091 -178.545212) (xy 83.96351 -178.538124) (xy 83.963002 -178.537616)
			(xy 83.94528 -178.51666) (xy 83.915396 -178.47063) (xy 83.892427 -178.420787) (xy 83.87685 -178.368164)
			(xy 83.868986 -178.31385) (xy 83.868514 -178.28641) (xy 83.869076 -178.257339) (xy 83.87791 -178.199873)
			(xy 83.89536 -178.144411) (xy 83.921022 -178.092239) (xy 83.954302 -178.044564) (xy 83.994429 -178.00249)
			(xy 84.040475 -177.96699) (xy 84.091374 -177.938886) (xy 84.145946 -177.91883) (xy 84.17433 -177.912522)
			(xy 84.174584 -177.912522) (xy 84.18589 -177.909595) (xy 84.204349 -177.895334) (xy 84.21464 -177.874401)
			(xy 84.215224 -177.862738) (xy 84.215224 -177.650902) (xy 84.214818 -177.64083) (xy 84.207086 -177.622231)
			(xy 84.200238 -177.614834) (xy 80.409034 -173.82363) (xy 80.391809 -173.805523) (xy 80.364069 -173.763962)
			(xy 80.344963 -173.717791) (xy 80.335223 -173.668782) (xy 80.334612 -173.643798) (xy 77.589183 -173.643798)
			(xy 77.597907 -173.656984) (xy 77.621579 -173.707481) (xy 77.637647 -173.760888) (xy 77.645767 -173.816064)
			(xy 77.646276 -173.84395) (xy 77.645767 -173.871836) (xy 77.637647 -173.927012) (xy 77.621579 -173.980419)
			(xy 77.597907 -174.030916) (xy 77.567134 -174.077429) (xy 77.529917 -174.118966) (xy 77.487049 -174.154641)
			(xy 77.439443 -174.183695) (xy 77.388114 -174.205507) (xy 77.334157 -174.219613) (xy 77.27872 -174.225713)
			(xy 77.222986 -174.223676) (xy 77.168143 -174.213546) (xy 77.115359 -174.195539) (xy 77.065759 -174.170038)
			(xy 77.020401 -174.137587) (xy 76.980252 -174.098878) (xy 76.946166 -174.054735) (xy 76.91887 -174.0061)
			(xy 76.898947 -173.954009) (xy 76.886821 -173.899572) (xy 76.88275 -173.84395) (xy 76.305831 -173.84395)
			(xy 76.299708 -173.886541) (xy 76.284353 -173.938836) (xy 76.261711 -173.988413) (xy 76.232245 -174.034263)
			(xy 76.196554 -174.075454) (xy 76.155363 -174.111145) (xy 76.109513 -174.140611) (xy 76.059936 -174.163253)
			(xy 76.007641 -174.178608) (xy 75.953693 -174.186364) (xy 75.899191 -174.186364) (xy 75.845243 -174.178608)
			(xy 75.792948 -174.163253) (xy 75.743371 -174.140611) (xy 75.697521 -174.111145) (xy 75.65633 -174.075454)
			(xy 75.620639 -174.034263) (xy 75.591173 -173.988413) (xy 75.568531 -173.938836) (xy 75.553176 -173.886541)
			(xy 75.54542 -173.832593) (xy 75.544934 -173.805342) (xy 75.286028 -173.805342) (xy 75.280024 -173.825792)
			(xy 75.257384 -173.875369) (xy 75.227919 -173.92122) (xy 75.192229 -173.962411) (xy 75.151041 -173.998104)
			(xy 75.105192 -174.027571) (xy 75.055617 -174.050215) (xy 75.003324 -174.065573) (xy 74.949377 -174.073332)
			(xy 74.922126 -174.07382) (xy 74.921872 -174.07382) (xy 74.896668 -174.073438) (xy 74.846699 -174.066794)
			(xy 74.798044 -174.053613) (xy 74.751555 -174.034124) (xy 74.729594 -174.02175) (xy 74.719688 -174.015908)
			(xy 74.697844 -174.013876) (xy 74.603102 -174.047404) (xy 74.587354 -174.062898) (xy 74.58329 -174.073312)
			(xy 74.572625 -174.100102) (xy 74.544334 -174.150345) (xy 74.5088 -174.195755) (xy 74.466833 -174.235297)
			(xy 74.419391 -174.268069) (xy 74.367556 -174.293325) (xy 74.312508 -174.310487) (xy 74.255504 -174.319165)
			(xy 74.226674 -174.319692) (xy 74.199421 -174.319246) (xy 74.145471 -174.311486) (xy 74.093175 -174.296127)
			(xy 74.043597 -174.273481) (xy 73.997745 -174.244011) (xy 73.956555 -174.208315) (xy 73.920864 -174.167121)
			(xy 73.891399 -174.121267) (xy 73.868759 -174.071686) (xy 73.853405 -174.019388) (xy 73.845651 -173.965437)
			(xy 73.845166 -173.938184) (xy 73.845839 -173.906622) (xy 73.856221 -173.844357) (xy 73.876701 -173.784648)
			(xy 73.89114 -173.756574) (xy 73.895966 -173.747684) (xy 73.897998 -173.728126) (xy 73.875138 -173.64964)
			(xy 73.871936 -173.6402) (xy 73.859493 -173.624649) (xy 73.851008 -173.619414) (xy 73.825887 -173.604898)
			(xy 73.780004 -173.56939) (xy 73.74003 -173.527341) (xy 73.706886 -173.479721) (xy 73.681339 -173.427631)
			(xy 73.663977 -173.372272) (xy 73.655202 -173.314921) (xy 73.654666 -173.285912) (xy 50.56124 -173.285912)
			(xy 50.56124 -173.749716) (xy 50.562256 -173.759368) (xy 50.563886 -173.76661) (xy 50.570733 -173.779774)
			(xy 50.575718 -173.785276) (xy 52.350416 -175.559974) (xy 69.868542 -175.559974) (xy 69.869044 -175.532401)
			(xy 69.876987 -175.477829) (xy 69.892704 -175.424969) (xy 69.915867 -175.374922) (xy 69.945994 -175.328732)
			(xy 69.982457 -175.28736) (xy 70.003162 -175.269144) (xy 70.011228 -175.26158) (xy 70.020585 -175.241575)
			(xy 70.021196 -175.230536) (xy 70.021196 -175.152812) (xy 70.020622 -175.141763) (xy 70.011261 -175.121742)
			(xy 70.003162 -175.114204) (xy 69.982442 -175.096003) (xy 69.945974 -175.054631) (xy 69.915844 -175.008439)
			(xy 69.89268 -174.958389) (xy 69.876965 -174.905525) (xy 69.869027 -174.850949) (xy 69.868542 -174.823374)
			(xy 69.869044 -174.795801) (xy 69.876987 -174.741229) (xy 69.892704 -174.688369) (xy 69.915867 -174.638322)
			(xy 69.945994 -174.592132) (xy 69.982457 -174.55076) (xy 70.003162 -174.532544) (xy 70.011228 -174.52498)
			(xy 70.020585 -174.504975) (xy 70.021196 -174.493936) (xy 70.021196 -174.416212) (xy 70.020622 -174.405163)
			(xy 70.011261 -174.385142) (xy 70.003162 -174.377604) (xy 69.982442 -174.359403) (xy 69.945974 -174.318031)
			(xy 69.915844 -174.271839) (xy 69.89268 -174.221789) (xy 69.876965 -174.168925) (xy 69.869027 -174.114349)
			(xy 69.868542 -174.086774) (xy 69.868931 -174.059518) (xy 69.876693 -174.005562) (xy 69.892055 -173.95326)
			(xy 69.914704 -173.903676) (xy 69.944179 -173.857821) (xy 69.979881 -173.816627) (xy 70.021081 -173.780934)
			(xy 70.066943 -173.751467) (xy 70.116531 -173.728828) (xy 70.168836 -173.713476) (xy 70.222794 -173.705725)
			(xy 70.25005 -173.705266) (xy 70.277905 -173.705769) (xy 70.333021 -173.713899) (xy 70.38637 -173.72995)
			(xy 70.436822 -173.75358) (xy 70.483305 -173.78429) (xy 70.524834 -173.821426) (xy 70.560527 -173.864202)
			(xy 70.589627 -173.91171) (xy 70.611517 -173.962941) (xy 70.619112 -173.989746) (xy 70.621398 -173.998636)
			(xy 70.632066 -174.013876) (xy 70.703948 -174.061628) (xy 70.721982 -174.065692) (xy 70.731126 -174.064422)
			(xy 70.744142 -174.062752) (xy 70.770327 -174.060973) (xy 70.78345 -174.060866) (xy 70.797599 -174.060965)
			(xy 70.825822 -174.062996) (xy 70.839838 -174.06493) (xy 70.849744 -174.066454) (xy 70.869556 -174.061628)
			(xy 70.943978 -174.005748) (xy 70.954138 -173.988222) (xy 70.955408 -173.978062) (xy 70.959477 -173.950905)
			(xy 70.974451 -173.898073) (xy 70.996843 -173.847933) (xy 71.026193 -173.801521) (xy 71.061892 -173.759796)
			(xy 71.103204 -173.72362) (xy 71.149276 -173.693739) (xy 71.199155 -173.670772) (xy 71.251811 -173.655192)
			(xy 71.306158 -173.647322) (xy 71.333614 -173.646846) (xy 71.360864 -173.647365) (xy 71.414808 -173.655122)
			(xy 71.467099 -173.670476) (xy 71.516673 -173.693116) (xy 71.562521 -173.722579) (xy 71.60371 -173.758267)
			(xy 71.639401 -173.799453) (xy 71.668869 -173.845299) (xy 71.691512 -173.894871) (xy 71.706871 -173.947161)
			(xy 71.714633 -174.001105) (xy 71.715122 -174.028354) (xy 71.714617 -174.055927) (xy 71.706671 -174.110498)
			(xy 71.690954 -174.163357) (xy 71.667791 -174.213403) (xy 71.637666 -174.259593) (xy 71.601206 -174.300967)
			(xy 71.580502 -174.319184) (xy 71.572434 -174.326746) (xy 71.563076 -174.346752) (xy 71.562468 -174.357792)
			(xy 71.562468 -174.435516) (xy 71.563061 -174.446563) (xy 71.572406 -174.466586) (xy 71.580502 -174.474124)
			(xy 71.601228 -174.492319) (xy 71.637697 -174.533691) (xy 71.667828 -174.579884) (xy 71.690991 -174.629936)
			(xy 71.706704 -174.682801) (xy 71.714639 -174.737378) (xy 71.714673 -174.7393) (xy 76.30363 -174.7393)
			(xy 76.307701 -174.683678) (xy 76.319827 -174.629241) (xy 76.33975 -174.57715) (xy 76.367046 -174.528515)
			(xy 76.401132 -174.484372) (xy 76.441281 -174.445663) (xy 76.486639 -174.413212) (xy 76.536239 -174.387711)
			(xy 76.589023 -174.369704) (xy 76.643866 -174.359574) (xy 76.6996 -174.357537) (xy 76.755037 -174.363637)
			(xy 76.808994 -174.377743) (xy 76.860323 -174.399555) (xy 76.907929 -174.428609) (xy 76.950797 -174.464284)
			(xy 76.988014 -174.505821) (xy 77.018787 -174.552334) (xy 77.042459 -174.602831) (xy 77.058527 -174.656238)
			(xy 77.066647 -174.711414) (xy 77.067156 -174.7393) (xy 77.066647 -174.767186) (xy 77.058527 -174.822362)
			(xy 77.042459 -174.875769) (xy 77.018787 -174.926266) (xy 76.988014 -174.972779) (xy 76.950797 -175.014316)
			(xy 76.907929 -175.049991) (xy 76.860323 -175.079045) (xy 76.808994 -175.100857) (xy 76.755037 -175.114963)
			(xy 76.6996 -175.121063) (xy 76.643866 -175.119026) (xy 76.589023 -175.108896) (xy 76.536239 -175.090889)
			(xy 76.486639 -175.065388) (xy 76.441281 -175.032937) (xy 76.401132 -174.994228) (xy 76.367046 -174.950085)
			(xy 76.33975 -174.90145) (xy 76.319827 -174.849359) (xy 76.307701 -174.794922) (xy 76.30363 -174.7393)
			(xy 71.714673 -174.7393) (xy 71.715122 -174.764954) (xy 71.714602 -174.792205) (xy 71.706852 -174.846153)
			(xy 71.691502 -174.898449) (xy 71.668866 -174.948028) (xy 71.639404 -174.993881) (xy 71.603716 -175.035074)
			(xy 71.562529 -175.070768) (xy 71.516681 -175.100237) (xy 71.467105 -175.122881) (xy 71.414812 -175.138239)
			(xy 71.360865 -175.145998) (xy 71.333614 -175.146462) (xy 71.333106 -175.146462) (xy 71.299324 -175.144938)
			(xy 71.289164 -175.143922) (xy 71.26986 -175.150018) (xy 71.206868 -175.20285) (xy 71.199574 -175.209569)
			(xy 71.190295 -175.227077) (xy 71.188834 -175.236886) (xy 71.188834 -175.237648) (xy 71.185864 -175.265807)
			(xy 71.172657 -175.320866) (xy 71.151455 -175.373367) (xy 71.122725 -175.422157) (xy 71.087096 -175.466162)
			(xy 71.045353 -175.504417) (xy 70.998413 -175.53608) (xy 70.947307 -175.560454) (xy 70.89316 -175.577006)
			(xy 70.83716 -175.585369) (xy 70.80885 -175.585882) (xy 70.790831 -175.585663) (xy 70.754956 -175.582227)
			(xy 70.737222 -175.579024) (xy 70.72757 -175.577246) (xy 70.70852 -175.580802) (xy 70.63359 -175.628808)
			(xy 70.62216 -175.644556) (xy 70.619874 -175.653954) (xy 70.612491 -175.681002) (xy 70.59086 -175.732729)
			(xy 70.561894 -175.780735) (xy 70.526216 -175.823987) (xy 70.484595 -175.861553) (xy 70.437926 -175.892627)
			(xy 70.387213 -175.916539) (xy 70.333547 -175.932774) (xy 70.278084 -175.940984) (xy 70.25005 -175.941482)
			(xy 70.222797 -175.940998) (xy 70.168846 -175.933247) (xy 70.116547 -175.917896) (xy 70.066965 -175.895258)
			(xy 70.02111 -175.865792) (xy 69.979916 -175.830101) (xy 69.944222 -175.788909) (xy 69.914754 -175.743056)
			(xy 69.892112 -175.693476) (xy 69.876758 -175.641178) (xy 69.869004 -175.587227) (xy 69.868542 -175.559974)
			(xy 52.350416 -175.559974) (xy 53.899562 -177.10912) (xy 71.51116 -177.10912) (xy 71.511618 -177.081545)
			(xy 71.51957 -177.026971) (xy 71.535295 -176.97411) (xy 71.558466 -176.924064) (xy 71.588601 -176.877874)
			(xy 71.625071 -176.836505) (xy 71.64578 -176.81829) (xy 71.653873 -176.810751) (xy 71.663214 -176.790727)
			(xy 71.663814 -176.779682) (xy 71.663814 -176.701958) (xy 71.663241 -176.690909) (xy 71.653882 -176.670886)
			(xy 71.64578 -176.66335) (xy 71.625086 -176.645121) (xy 71.588615 -176.603755) (xy 71.558481 -176.557569)
			(xy 71.535313 -176.507525) (xy 71.519592 -176.454666) (xy 71.511648 -176.400094) (xy 71.51116 -176.37252)
			(xy 71.51163 -176.346404) (xy 71.518765 -176.294662) (xy 71.53289 -176.244376) (xy 71.553741 -176.196487)
			(xy 71.58093 -176.151889) (xy 71.613946 -176.111416) (xy 71.652175 -176.075824) (xy 71.6949 -176.045779)
			(xy 71.717916 -176.03343) (xy 71.727929 -176.027709) (xy 71.741808 -176.009317) (xy 71.744586 -175.998124)
			(xy 71.76262 -175.90897) (xy 71.757032 -175.886872) (xy 71.749666 -175.877982) (xy 71.733387 -175.857795)
			(xy 71.705983 -175.81377) (xy 71.684951 -175.766368) (xy 71.670699 -175.716507) (xy 71.663502 -175.665151)
			(xy 71.663052 -175.639222) (xy 71.663577 -175.612608) (xy 71.671149 -175.55992) (xy 71.686142 -175.508847)
			(xy 71.708251 -175.460427) (xy 71.737025 -175.415647) (xy 71.77188 -175.375417) (xy 71.812105 -175.340557)
			(xy 71.856881 -175.311776) (xy 71.905298 -175.28966) (xy 71.95637 -175.27466) (xy 72.009056 -175.267081)
			(xy 72.03567 -175.266604) (xy 72.062091 -175.267078) (xy 72.114406 -175.274524) (xy 72.165144 -175.289285)
			(xy 72.213289 -175.311065) (xy 72.257874 -175.339428) (xy 72.27824 -175.356266) (xy 72.285098 -175.362108)
			(xy 72.302116 -175.368458) (xy 72.386444 -175.368458) (xy 72.403462 -175.362108) (xy 72.41032 -175.356266)
			(xy 72.430686 -175.339427) (xy 72.475272 -175.311062) (xy 72.523416 -175.289275) (xy 72.574153 -175.274504)
			(xy 72.626468 -175.267044) (xy 72.679312 -175.267044) (xy 72.731627 -175.274504) (xy 72.782364 -175.289275)
			(xy 72.830508 -175.311062) (xy 72.875094 -175.339427) (xy 72.89546 -175.356266) (xy 72.902318 -175.362108)
			(xy 72.919336 -175.368458) (xy 73.003664 -175.368458) (xy 73.020682 -175.362108) (xy 73.02754 -175.356266)
			(xy 73.047899 -175.339419) (xy 73.09249 -175.311063) (xy 73.140636 -175.289285) (xy 73.191374 -175.274519)
			(xy 73.243688 -175.267063) (xy 73.27011 -175.266604) (xy 73.297996 -175.267082) (xy 73.353145 -175.275395)
			(xy 73.406439 -175.291836) (xy 73.456687 -175.316035) (xy 73.502767 -175.347453) (xy 73.543651 -175.385389)
			(xy 73.578423 -175.428993) (xy 73.606309 -175.477293) (xy 73.626684 -175.52921) (xy 73.639095 -175.583584)
			(xy 73.643263 -175.6392) (xy 73.639095 -175.694816) (xy 73.626684 -175.74919) (xy 73.606309 -175.801107)
			(xy 73.578423 -175.849407) (xy 73.543651 -175.893011) (xy 73.502767 -175.930947) (xy 73.456687 -175.962365)
			(xy 73.406439 -175.986564) (xy 73.353145 -176.003005) (xy 73.297996 -176.011318) (xy 73.27011 -176.01184)
			(xy 73.243689 -176.011367) (xy 73.191374 -176.003919) (xy 73.140636 -175.989157) (xy 73.092492 -175.967377)
			(xy 73.047906 -175.939016) (xy 73.02754 -175.922178) (xy 73.020682 -175.916336) (xy 73.003664 -175.909986)
			(xy 72.919336 -175.909986) (xy 72.902318 -175.916336) (xy 72.89546 -175.922178) (xy 72.875094 -175.939017)
			(xy 72.830508 -175.967382) (xy 72.782364 -175.989169) (xy 72.731627 -176.00394) (xy 72.679312 -176.0114)
			(xy 72.626468 -176.0114) (xy 72.574153 -176.00394) (xy 72.523416 -175.989169) (xy 72.475272 -175.967382)
			(xy 72.430686 -175.939017) (xy 72.41032 -175.922178) (xy 72.403462 -175.916336) (xy 72.386444 -175.909986)
			(xy 72.302116 -175.909986) (xy 72.285098 -175.916336) (xy 72.27824 -175.922178) (xy 72.262606 -175.935184)
			(xy 72.229003 -175.958095) (xy 72.211184 -175.967898) (xy 72.20077 -175.973486) (xy 72.187308 -175.991774)
			(xy 72.170544 -176.081182) (xy 72.16891 -176.092584) (xy 72.174845 -176.11481) (xy 72.181974 -176.123854)
			(xy 72.199282 -176.14471) (xy 72.228443 -176.190393) (xy 72.250844 -176.239745) (xy 72.266032 -176.29177)
			(xy 72.273702 -176.345421) (xy 72.274176 -176.37252) (xy 72.273664 -176.400093) (xy 72.265722 -176.454664)
			(xy 72.250007 -176.507523) (xy 72.226845 -176.55757) (xy 72.196721 -176.603761) (xy 72.185618 -176.61636)
			(xy 77.262482 -176.61636) (xy 77.262953 -176.588448) (xy 77.271093 -176.533222) (xy 77.287194 -176.479771)
			(xy 77.310911 -176.429236) (xy 77.341739 -176.382697) (xy 77.360018 -176.361598) (xy 77.365918 -176.354423)
			(xy 77.372567 -176.337096) (xy 77.372972 -176.327816) (xy 77.372972 -176.250092) (xy 77.366368 -176.23282)
			(xy 77.360018 -176.225708) (xy 77.341725 -176.204621) (xy 77.310899 -176.158079) (xy 77.287187 -176.107542)
			(xy 77.271094 -176.054087) (xy 77.262964 -175.998858) (xy 77.262482 -175.970946) (xy 77.262968 -175.943695)
			(xy 77.270724 -175.889747) (xy 77.286079 -175.837452) (xy 77.308721 -175.787875) (xy 77.338187 -175.742025)
			(xy 77.373878 -175.700834) (xy 77.415069 -175.665143) (xy 77.460919 -175.635677) (xy 77.510496 -175.613035)
			(xy 77.562791 -175.59768) (xy 77.616739 -175.589924) (xy 77.671241 -175.589924) (xy 77.725189 -175.59768)
			(xy 77.777484 -175.613035) (xy 77.827061 -175.635677) (xy 77.872911 -175.665143) (xy 77.914102 -175.700834)
			(xy 77.949793 -175.742025) (xy 77.979259 -175.787875) (xy 78.001901 -175.837452) (xy 78.017256 -175.889747)
			(xy 78.025012 -175.943695) (xy 78.025498 -175.970946) (xy 78.025011 -175.998857) (xy 78.016871 -176.054082)
			(xy 78.000773 -176.107532) (xy 77.97706 -176.158066) (xy 77.946238 -176.204607) (xy 77.927962 -176.225708)
			(xy 77.922057 -176.232879) (xy 77.915412 -176.250209) (xy 77.915008 -176.25949) (xy 77.915008 -176.337214)
			(xy 77.921612 -176.354486) (xy 77.927962 -176.361598) (xy 77.946223 -176.382711) (xy 77.977051 -176.429247)
			(xy 78.000768 -176.479778) (xy 78.016869 -176.533226) (xy 78.025009 -176.58845) (xy 78.025498 -176.61636)
			(xy 78.025012 -176.643611) (xy 78.017256 -176.697559) (xy 78.001901 -176.749854) (xy 77.979259 -176.799431)
			(xy 77.949793 -176.845281) (xy 77.914102 -176.886472) (xy 77.872911 -176.922163) (xy 77.827061 -176.951629)
			(xy 77.777484 -176.974271) (xy 77.725189 -176.989626) (xy 77.671241 -176.997382) (xy 77.616739 -176.997382)
			(xy 77.562791 -176.989626) (xy 77.510496 -176.974271) (xy 77.460919 -176.951629) (xy 77.415069 -176.922163)
			(xy 77.373878 -176.886472) (xy 77.338187 -176.845281) (xy 77.308721 -176.799431) (xy 77.286079 -176.749854)
			(xy 77.270724 -176.697559) (xy 77.262968 -176.643611) (xy 77.262482 -176.61636) (xy 72.185618 -176.61636)
			(xy 72.16026 -176.645133) (xy 72.139556 -176.66335) (xy 72.131451 -176.670878) (xy 72.122115 -176.69091)
			(xy 72.121522 -176.701958) (xy 72.121522 -176.779682) (xy 72.122093 -176.790731) (xy 72.131456 -176.810753)
			(xy 72.139556 -176.81829) (xy 72.160257 -176.836513) (xy 72.19673 -176.877878) (xy 72.226864 -176.924065)
			(xy 72.250032 -176.974111) (xy 72.26575 -177.026972) (xy 72.273691 -177.081546) (xy 72.274176 -177.10912)
			(xy 72.27369 -177.136371) (xy 72.265934 -177.190319) (xy 72.250579 -177.242614) (xy 72.227937 -177.292191)
			(xy 72.198471 -177.338041) (xy 72.16278 -177.379232) (xy 72.121589 -177.414923) (xy 72.075739 -177.444389)
			(xy 72.026162 -177.467031) (xy 71.973867 -177.482386) (xy 71.919919 -177.490142) (xy 71.865417 -177.490142)
			(xy 71.811469 -177.482386) (xy 71.759174 -177.467031) (xy 71.709597 -177.444389) (xy 71.663747 -177.414923)
			(xy 71.622556 -177.379232) (xy 71.586865 -177.338041) (xy 71.557399 -177.292191) (xy 71.534757 -177.242614)
			(xy 71.519402 -177.190319) (xy 71.511646 -177.136371) (xy 71.51116 -177.10912) (xy 53.899562 -177.10912)
			(xy 55.588916 -178.798474) (xy 78.471522 -178.798474) (xy 78.472085 -178.769559) (xy 78.480804 -178.712389)
			(xy 78.498052 -178.657191) (xy 78.523435 -178.605229) (xy 78.556371 -178.557694) (xy 78.596106 -178.515675)
			(xy 78.618588 -178.497484) (xy 78.627391 -178.489872) (xy 78.637577 -178.468975) (xy 78.638146 -178.457352)
			(xy 78.638146 -178.377596) (xy 78.637614 -178.365963) (xy 78.627422 -178.345052) (xy 78.618588 -178.337464)
			(xy 78.596085 -178.319296) (xy 78.556351 -178.277271) (xy 78.523415 -178.229732) (xy 78.49803 -178.177766)
			(xy 78.480778 -178.122564) (xy 78.472054 -178.065391) (xy 78.471522 -178.036474) (xy 78.471931 -178.009219)
			(xy 78.479692 -177.955265) (xy 78.495053 -177.902964) (xy 78.517701 -177.853382) (xy 78.547174 -177.807527)
			(xy 78.582874 -177.766334) (xy 78.624072 -177.730641) (xy 78.669931 -177.701174) (xy 78.719516 -177.678533)
			(xy 78.771819 -177.66318) (xy 78.825775 -177.655427) (xy 78.85303 -177.654966) (xy 78.880667 -177.655461)
			(xy 78.935359 -177.663462) (xy 78.988327 -177.679262) (xy 79.038464 -177.702533) (xy 79.084723 -177.732788)
			(xy 79.126137 -177.769395) (xy 79.161843 -177.81159) (xy 79.191093 -177.85849) (xy 79.213277 -177.909117)
			(xy 79.221076 -177.935636) (xy 79.223616 -177.94478) (xy 79.234792 -177.96002) (xy 79.308706 -178.00701)
			(xy 79.327248 -178.010566) (xy 79.336646 -178.008788) (xy 79.353146 -178.006047) (xy 79.386469 -178.003125)
			(xy 79.403194 -178.002946) (xy 79.430443 -178.003483) (xy 79.484387 -178.011238) (xy 79.536677 -178.02659)
			(xy 79.586252 -178.049227) (xy 79.6321 -178.078688) (xy 79.673289 -178.114374) (xy 79.708981 -178.155558)
			(xy 79.738448 -178.201403) (xy 79.761092 -178.250974) (xy 79.776451 -178.303263) (xy 79.784213 -178.357205)
			(xy 79.784702 -178.384454) (xy 79.784702 -178.384708) (xy 79.784361 -178.404012) (xy 81.978246 -178.404012)
			(xy 81.978732 -178.376761) (xy 81.986488 -178.322813) (xy 82.001843 -178.270518) (xy 82.024485 -178.220941)
			(xy 82.053951 -178.175091) (xy 82.089642 -178.1339) (xy 82.130833 -178.098209) (xy 82.176683 -178.068743)
			(xy 82.22626 -178.046101) (xy 82.278555 -178.030746) (xy 82.332503 -178.02299) (xy 82.387005 -178.02299)
			(xy 82.440953 -178.030746) (xy 82.493248 -178.046101) (xy 82.542825 -178.068743) (xy 82.588675 -178.098209)
			(xy 82.629866 -178.1339) (xy 82.665557 -178.175091) (xy 82.695023 -178.220941) (xy 82.717665 -178.270518)
			(xy 82.73302 -178.322813) (xy 82.740776 -178.376761) (xy 82.741262 -178.404012) (xy 82.740596 -178.435575)
			(xy 82.730212 -178.49784) (xy 82.709729 -178.557549) (xy 82.695288 -178.585622) (xy 82.690462 -178.594512)
			(xy 82.68843 -178.61407) (xy 82.71129 -178.692556) (xy 82.71452 -178.701984) (xy 82.726944 -178.71754)
			(xy 82.73542 -178.722782) (xy 82.742786 -178.726846) (xy 82.752692 -178.732688) (xy 82.774536 -178.73472)
			(xy 82.869278 -178.701192) (xy 82.885026 -178.685698) (xy 82.88909 -178.675284) (xy 82.899769 -178.6485)
			(xy 82.928059 -178.598258) (xy 82.963592 -178.552849) (xy 83.005556 -178.513307) (xy 83.052996 -178.480534)
			(xy 83.104829 -178.455277) (xy 83.159874 -178.438113) (xy 83.216876 -178.429432) (xy 83.245706 -178.428904)
			(xy 83.272958 -178.429366) (xy 83.326907 -178.437124) (xy 83.379202 -178.45248) (xy 83.42878 -178.475122)
			(xy 83.474631 -178.504589) (xy 83.515822 -178.540282) (xy 83.551514 -178.581473) (xy 83.580981 -178.627325)
			(xy 83.603622 -178.676903) (xy 83.618978 -178.729199) (xy 83.626734 -178.783148) (xy 83.626734 -178.837652)
			(xy 83.618978 -178.891601) (xy 83.603622 -178.943897) (xy 83.580981 -178.993475) (xy 83.551514 -179.039327)
			(xy 83.515822 -179.080518) (xy 83.474631 -179.116211) (xy 83.42878 -179.145678) (xy 83.379202 -179.16832)
			(xy 83.326907 -179.183676) (xy 83.272958 -179.191434) (xy 83.245706 -179.19192) (xy 83.245452 -179.19192)
			(xy 83.220249 -179.191503) (xy 83.170281 -179.184869) (xy 83.121627 -179.171698) (xy 83.075136 -179.15222)
			(xy 83.053174 -179.13985) (xy 83.043268 -179.134008) (xy 83.021424 -179.131976) (xy 82.926682 -179.165504)
			(xy 82.910934 -179.180998) (xy 82.90687 -179.191412) (xy 82.896139 -179.218173) (xy 82.867855 -179.268413)
			(xy 82.83233 -179.313822) (xy 82.790373 -179.353365) (xy 82.742941 -179.38614) (xy 82.691115 -179.411401)
			(xy 82.636077 -179.428571) (xy 82.579081 -179.437259) (xy 82.550254 -179.437792) (xy 82.523001 -179.437365)
			(xy 82.46905 -179.429602) (xy 82.416753 -179.41424) (xy 82.367175 -179.391592) (xy 82.321324 -179.36212)
			(xy 82.280134 -179.326422) (xy 82.244443 -179.285226) (xy 82.214978 -179.239371) (xy 82.192338 -179.189788)
			(xy 82.176985 -179.137489) (xy 82.169231 -179.083537) (xy 82.168746 -179.056284) (xy 82.169409 -179.024721)
			(xy 82.179794 -178.962456) (xy 82.200279 -178.902747) (xy 82.21472 -178.874674) (xy 82.219546 -178.865784)
			(xy 82.221578 -178.846226) (xy 82.198718 -178.76774) (xy 82.195487 -178.758313) (xy 82.183063 -178.742757)
			(xy 82.174588 -178.737514) (xy 82.149462 -178.723006) (xy 82.10358 -178.687496) (xy 82.063607 -178.645445)
			(xy 82.030465 -178.597824) (xy 82.004918 -178.545733) (xy 81.987557 -178.490372) (xy 81.978782 -178.433021)
			(xy 81.978246 -178.404012) (xy 79.784361 -178.404012) (xy 79.784257 -178.409868) (xy 79.777623 -178.45975)
			(xy 79.764495 -178.508329) (xy 79.745103 -178.554764) (xy 79.719781 -178.59825) (xy 79.704692 -178.618388)
			(xy 79.696818 -178.628294) (xy 79.6925 -178.65344) (xy 79.727298 -178.757834) (xy 79.745586 -178.775106)
			(xy 79.758032 -178.778408) (xy 79.784565 -178.786174) (xy 79.835211 -178.808337) (xy 79.882129 -178.837577)
			(xy 79.924337 -178.87328) (xy 79.960951 -178.914701) (xy 79.991205 -178.960971) (xy 80.014465 -179.011123)
			(xy 80.030246 -179.064106) (xy 80.038215 -179.118812) (xy 80.038702 -179.146454) (xy 80.038204 -179.174027)
			(xy 80.030258 -179.228599) (xy 80.014539 -179.281458) (xy 79.991375 -179.331504) (xy 79.961249 -179.377694)
			(xy 79.924787 -179.419067) (xy 79.904082 -179.437284) (xy 79.896011 -179.444843) (xy 79.886655 -179.464852)
			(xy 79.886048 -179.475892) (xy 79.886048 -179.553616) (xy 79.886648 -179.564662) (xy 79.895989 -179.584684)
			(xy 79.904082 -179.592224) (xy 79.924804 -179.610423) (xy 79.961275 -179.651794) (xy 79.991406 -179.697986)
			(xy 80.01457 -179.748037) (xy 80.030283 -179.800902) (xy 80.038219 -179.855478) (xy 80.038253 -179.8574)
			(xy 84.62721 -179.8574) (xy 84.631281 -179.801778) (xy 84.643407 -179.747341) (xy 84.66333 -179.69525)
			(xy 84.690626 -179.646615) (xy 84.724712 -179.602472) (xy 84.764861 -179.563763) (xy 84.810219 -179.531312)
			(xy 84.859819 -179.505811) (xy 84.912603 -179.487804) (xy 84.967446 -179.477674) (xy 85.02318 -179.475637)
			(xy 85.078617 -179.481737) (xy 85.132574 -179.495843) (xy 85.183903 -179.517655) (xy 85.231509 -179.546709)
			(xy 85.274377 -179.582384) (xy 85.311594 -179.623921) (xy 85.342367 -179.670434) (xy 85.366039 -179.720931)
			(xy 85.382107 -179.774338) (xy 85.390227 -179.829514) (xy 85.390736 -179.8574) (xy 85.390227 -179.885286)
			(xy 85.382107 -179.940462) (xy 85.366039 -179.993869) (xy 85.342367 -180.044366) (xy 85.311594 -180.090879)
			(xy 85.274377 -180.132416) (xy 85.231509 -180.168091) (xy 85.183903 -180.197145) (xy 85.132574 -180.218957)
			(xy 85.078617 -180.233063) (xy 85.02318 -180.239163) (xy 84.967446 -180.237126) (xy 84.912603 -180.226996)
			(xy 84.859819 -180.208989) (xy 84.810219 -180.183488) (xy 84.764861 -180.151037) (xy 84.724712 -180.112328)
			(xy 84.690626 -180.068185) (xy 84.66333 -180.01955) (xy 84.643407 -179.967459) (xy 84.631281 -179.913022)
			(xy 84.62721 -179.8574) (xy 80.038253 -179.8574) (xy 80.038702 -179.883054) (xy 80.038202 -179.910306)
			(xy 80.030451 -179.964256) (xy 80.015101 -180.016553) (xy 79.992463 -180.066134) (xy 79.962999 -180.111987)
			(xy 79.927309 -180.153181) (xy 79.88612 -180.188875) (xy 79.840269 -180.218344) (xy 79.790691 -180.240987)
			(xy 79.738395 -180.256343) (xy 79.684446 -180.264099) (xy 79.657194 -180.264562) (xy 79.656686 -180.264562)
			(xy 79.622904 -180.263038) (xy 79.612744 -180.262022) (xy 79.59344 -180.268118) (xy 79.530448 -180.32095)
			(xy 79.52315 -180.327666) (xy 79.513875 -180.345176) (xy 79.512414 -180.354986) (xy 79.512414 -180.355748)
			(xy 79.509463 -180.383909) (xy 79.496256 -180.43897) (xy 79.475053 -180.491473) (xy 79.44632 -180.540263)
			(xy 79.410689 -180.58427) (xy 79.368944 -180.622524) (xy 79.322001 -180.654186) (xy 79.270893 -180.67856)
			(xy 79.216743 -180.69511) (xy 79.160741 -180.703471) (xy 79.13243 -180.703982) (xy 79.105177 -180.703517)
			(xy 79.051224 -180.695763) (xy 78.998925 -180.68041) (xy 78.949343 -180.657769) (xy 78.903489 -180.628301)
			(xy 78.862295 -180.592608) (xy 78.826601 -180.551414) (xy 78.797133 -180.50556) (xy 78.774492 -180.455979)
			(xy 78.759138 -180.403679) (xy 78.751384 -180.349727) (xy 78.750922 -180.322474) (xy 78.751409 -180.294612)
			(xy 78.759514 -180.23948) (xy 78.775547 -180.186112) (xy 78.799167 -180.135641) (xy 78.829874 -180.089141)
			(xy 78.867014 -180.047598) (xy 78.888082 -180.029358) (xy 78.897226 -180.021738) (xy 78.906624 -180.000656)
			(xy 78.903576 -179.908454) (xy 78.902683 -179.896967) (xy 78.891947 -179.876602) (xy 78.883002 -179.869338)
			(xy 78.882748 -179.869084) (xy 78.862203 -179.853655) (xy 78.825069 -179.818144) (xy 78.793037 -179.777969)
			(xy 78.766688 -179.733859) (xy 78.746498 -179.686611) (xy 78.732833 -179.637081) (xy 78.72594 -179.586164)
			(xy 78.725522 -179.560474) (xy 78.725522 -179.56022) (xy 78.725922 -179.535058) (xy 78.732567 -179.485174)
			(xy 78.745704 -179.436595) (xy 78.765107 -179.390161) (xy 78.790438 -179.346676) (xy 78.805532 -179.32654)
			(xy 78.813406 -179.316634) (xy 78.817724 -179.291488) (xy 78.782926 -179.187094) (xy 78.764638 -179.169822)
			(xy 78.752192 -179.16652) (xy 78.725672 -179.158714) (xy 78.675027 -179.136556) (xy 78.628109 -179.107322)
			(xy 78.585901 -179.071623) (xy 78.549286 -179.030208) (xy 78.51903 -178.983943) (xy 78.495767 -178.933795)
			(xy 78.479984 -178.880816) (xy 78.472011 -178.826114) (xy 78.471522 -178.798474) (xy 55.588916 -178.798474)
			(xy 62.149482 -185.35904) (xy 62.50559 -185.35904) (xy 62.506082 -185.331671) (xy 62.513894 -185.277493)
			(xy 62.529377 -185.22499) (xy 62.552213 -185.175243) (xy 62.581932 -185.129275) (xy 62.59957 -185.108342)
			(xy 62.599824 -185.108088) (xy 62.605424 -185.101011) (xy 62.611662 -185.084087) (xy 62.612016 -185.075068)
			(xy 62.612016 -185.008012) (xy 62.61165 -184.998996) (xy 62.605408 -184.982079) (xy 62.599824 -184.974992)
			(xy 62.59957 -184.974992) (xy 62.59957 -184.974738) (xy 62.581967 -184.953774) (xy 62.552237 -184.907813)
			(xy 62.529387 -184.858072) (xy 62.513885 -184.805574) (xy 62.506052 -184.751399) (xy 62.506048 -184.696661)
			(xy 62.513873 -184.642485) (xy 62.529365 -184.589984) (xy 62.552208 -184.54024) (xy 62.58193 -184.494274)
			(xy 62.59957 -184.473342) (xy 62.599824 -184.473088) (xy 62.605424 -184.466011) (xy 62.611662 -184.449087)
			(xy 62.612016 -184.440068) (xy 62.612016 -184.373012) (xy 62.61165 -184.363996) (xy 62.605408 -184.347079)
			(xy 62.599824 -184.339992) (xy 62.59957 -184.339992) (xy 62.59957 -184.339738) (xy 62.581967 -184.318774)
			(xy 62.552237 -184.272813) (xy 62.529387 -184.223072) (xy 62.513885 -184.170574) (xy 62.506052 -184.116399)
			(xy 62.506048 -184.061661) (xy 62.513873 -184.007485) (xy 62.529365 -183.954984) (xy 62.552208 -183.90524)
			(xy 62.58193 -183.859274) (xy 62.59957 -183.838342) (xy 62.599824 -183.838088) (xy 62.605424 -183.831011)
			(xy 62.611662 -183.814087) (xy 62.612016 -183.805068) (xy 62.612016 -183.738012) (xy 62.61165 -183.728996)
			(xy 62.605408 -183.712079) (xy 62.599824 -183.704992) (xy 62.59957 -183.704992) (xy 62.59957 -183.704738)
			(xy 62.581967 -183.683774) (xy 62.552237 -183.637813) (xy 62.529387 -183.588072) (xy 62.513885 -183.535574)
			(xy 62.506052 -183.481399) (xy 62.506048 -183.426661) (xy 62.513873 -183.372485) (xy 62.529365 -183.319984)
			(xy 62.552208 -183.27024) (xy 62.58193 -183.224274) (xy 62.59957 -183.203342) (xy 62.599824 -183.203088)
			(xy 62.605424 -183.196011) (xy 62.611662 -183.179087) (xy 62.612016 -183.170068) (xy 62.612016 -183.103012)
			(xy 62.61165 -183.093996) (xy 62.605408 -183.077079) (xy 62.599824 -183.069992) (xy 62.59957 -183.069992)
			(xy 62.59957 -183.069738) (xy 62.581967 -183.048774) (xy 62.552237 -183.002813) (xy 62.529387 -182.953072)
			(xy 62.513885 -182.900574) (xy 62.506052 -182.846399) (xy 62.506048 -182.791661) (xy 62.513873 -182.737485)
			(xy 62.529365 -182.684984) (xy 62.552208 -182.63524) (xy 62.58193 -182.589274) (xy 62.59957 -182.568342)
			(xy 62.599824 -182.568088) (xy 62.605424 -182.561011) (xy 62.611662 -182.544087) (xy 62.612016 -182.535068)
			(xy 62.612016 -182.468012) (xy 62.61165 -182.458996) (xy 62.605408 -182.442079) (xy 62.599824 -182.434992)
			(xy 62.59957 -182.434992) (xy 62.59957 -182.434738) (xy 62.581967 -182.413774) (xy 62.552237 -182.367813)
			(xy 62.529387 -182.318072) (xy 62.513885 -182.265574) (xy 62.506052 -182.211399) (xy 62.506048 -182.156661)
			(xy 62.513873 -182.102485) (xy 62.529365 -182.049984) (xy 62.552208 -182.00024) (xy 62.58193 -181.954274)
			(xy 62.59957 -181.933342) (xy 62.599824 -181.933088) (xy 62.605424 -181.926011) (xy 62.611662 -181.909087)
			(xy 62.612016 -181.900068) (xy 62.612016 -181.833012) (xy 62.61165 -181.823996) (xy 62.605408 -181.807079)
			(xy 62.599824 -181.799992) (xy 62.59957 -181.799992) (xy 62.59957 -181.799738) (xy 62.581931 -181.778806)
			(xy 62.55222 -181.732833) (xy 62.529384 -181.683085) (xy 62.513893 -181.630585) (xy 62.506065 -181.576409)
			(xy 62.50559 -181.54904) (xy 62.506085 -181.521365) (xy 62.514084 -181.466597) (xy 62.529919 -181.413562)
			(xy 62.553258 -181.363374) (xy 62.583609 -181.317089) (xy 62.601602 -181.296056) (xy 62.6074 -181.288912)
			(xy 62.613914 -181.271721) (xy 62.614302 -181.262528) (xy 62.614302 -181.19471) (xy 62.613886 -181.185523)
			(xy 62.607376 -181.168339) (xy 62.601602 -181.161182) (xy 62.583608 -181.14015) (xy 62.55326 -181.093863)
			(xy 62.529922 -181.043675) (xy 62.514086 -180.99064) (xy 62.506084 -180.935872) (xy 62.50559 -180.908198)
			(xy 62.506076 -180.880947) (xy 62.513833 -180.826999) (xy 62.529188 -180.774705) (xy 62.551829 -180.725127)
			(xy 62.581295 -180.679277) (xy 62.616987 -180.638087) (xy 62.658177 -180.602395) (xy 62.704027 -180.572929)
			(xy 62.753605 -180.550288) (xy 62.805899 -180.534933) (xy 62.859847 -180.527176) (xy 62.887098 -180.52669)
			(xy 62.914468 -180.52716) (xy 62.968647 -180.534977) (xy 63.02115 -180.550465) (xy 63.070897 -180.573306)
			(xy 63.116864 -180.603029) (xy 63.137796 -180.62067) (xy 63.13805 -180.620924) (xy 63.145145 -180.626498)
			(xy 63.162055 -180.632752) (xy 63.17107 -180.633116) (xy 63.238126 -180.633116) (xy 63.247144 -180.632768)
			(xy 63.26406 -180.626514) (xy 63.271146 -180.620924) (xy 63.271146 -180.62067) (xy 63.2714 -180.62067)
			(xy 63.292333 -180.603029) (xy 63.338301 -180.573305) (xy 63.388047 -180.550459) (xy 63.440549 -180.534963)
			(xy 63.494727 -180.527134) (xy 63.549469 -180.527134) (xy 63.603647 -180.534963) (xy 63.656149 -180.550459)
			(xy 63.705895 -180.573305) (xy 63.751863 -180.603029) (xy 63.772796 -180.62067) (xy 63.77305 -180.620924)
			(xy 63.780145 -180.626498) (xy 63.797055 -180.632752) (xy 63.80607 -180.633116) (xy 63.873126 -180.633116)
			(xy 63.882144 -180.632768) (xy 63.89906 -180.626514) (xy 63.906146 -180.620924) (xy 63.906146 -180.62067)
			(xy 63.9064 -180.62067) (xy 63.927317 -180.603013) (xy 63.973295 -180.573305) (xy 64.023046 -180.550473)
			(xy 64.07555 -180.534986) (xy 64.129728 -180.527162) (xy 64.157098 -180.52669) (xy 64.184349 -180.52718)
			(xy 64.238297 -180.534936) (xy 64.290591 -180.550291) (xy 64.340168 -180.572931) (xy 64.386019 -180.602397)
			(xy 64.427209 -180.638088) (xy 64.4629 -180.679278) (xy 64.492367 -180.725128) (xy 64.515008 -180.774705)
			(xy 64.530363 -180.826999) (xy 64.53812 -180.880947) (xy 64.538606 -180.908198) (xy 64.538119 -180.935497)
			(xy 64.530348 -180.989538) (xy 64.51495 -181.041918) (xy 64.49224 -181.091568) (xy 64.462682 -181.137472)
			(xy 64.445134 -181.158388) (xy 64.439275 -181.165567) (xy 64.432778 -181.182908) (xy 64.432434 -181.19217)
			(xy 64.432688 -181.268116) (xy 64.439038 -181.285134) (xy 64.445134 -181.291992) (xy 64.462849 -181.312952)
			(xy 64.492727 -181.358985) (xy 64.515692 -181.408827) (xy 64.531272 -181.461448) (xy 64.539144 -181.515759)
			(xy 64.539622 -181.543198) (xy 64.539174 -181.570569) (xy 64.531355 -181.62475) (xy 64.515862 -181.677254)
			(xy 64.493016 -181.727) (xy 64.463286 -181.772966) (xy 64.445642 -181.793896) (xy 64.445388 -181.79415)
			(xy 64.439815 -181.801246) (xy 64.43356 -181.818156) (xy 64.433196 -181.82717) (xy 64.433196 -181.894226)
			(xy 64.433542 -181.903244) (xy 64.439797 -181.920161) (xy 64.445388 -181.927246) (xy 64.445642 -181.927246)
			(xy 64.445642 -181.9275) (xy 64.463282 -181.948434) (xy 64.493009 -181.994401) (xy 64.515857 -182.044146)
			(xy 64.531354 -182.096649) (xy 64.539184 -182.150828) (xy 64.539184 -182.205569) (xy 64.531355 -182.259748)
			(xy 64.515858 -182.312251) (xy 64.493011 -182.361997) (xy 64.463284 -182.407964) (xy 64.445642 -182.428896)
			(xy 64.445388 -182.42915) (xy 64.439815 -182.436246) (xy 64.43356 -182.453156) (xy 64.433196 -182.46217)
			(xy 64.433196 -182.529226) (xy 64.433542 -182.538244) (xy 64.439797 -182.555161) (xy 64.445388 -182.562246)
			(xy 64.445642 -182.562246) (xy 64.445642 -182.5625) (xy 64.463282 -182.583434) (xy 64.493009 -182.629401)
			(xy 64.515857 -182.679146) (xy 64.531354 -182.731649) (xy 64.539184 -182.785828) (xy 64.539184 -182.840569)
			(xy 64.531355 -182.894748) (xy 64.515858 -182.947251) (xy 64.493011 -182.996997) (xy 64.463284 -183.042964)
			(xy 64.445642 -183.063896) (xy 64.445388 -183.06415) (xy 64.439815 -183.071246) (xy 64.43356 -183.088156)
			(xy 64.433196 -183.09717) (xy 64.433196 -183.164226) (xy 64.433542 -183.173244) (xy 64.439797 -183.190161)
			(xy 64.445388 -183.197246) (xy 64.445642 -183.197246) (xy 64.445642 -183.1975) (xy 64.463301 -183.218416)
			(xy 64.493009 -183.264394) (xy 64.51584 -183.314145) (xy 64.531327 -183.366649) (xy 64.539151 -183.420828)
			(xy 64.539622 -183.448198) (xy 64.539112 -183.47594) (xy 64.531031 -183.530832) (xy 64.515096 -183.583979)
			(xy 64.491642 -183.634263) (xy 64.461163 -183.680626) (xy 64.443102 -183.70169) (xy 64.442848 -183.701944)
			(xy 64.437164 -183.709065) (xy 64.430779 -183.726115) (xy 64.430402 -183.735218) (xy 64.430148 -183.81218)
			(xy 64.436752 -183.829452) (xy 64.443102 -183.836564) (xy 64.461013 -183.857575) (xy 64.491205 -183.903796)
			(xy 64.514418 -183.953888) (xy 64.530166 -184.006803) (xy 64.53812 -184.061436) (xy 64.538606 -184.08904)
			(xy 64.538103 -184.116409) (xy 64.530294 -184.170586) (xy 64.514813 -184.223089) (xy 64.49198 -184.272836)
			(xy 64.462263 -184.318805) (xy 64.444626 -184.339738) (xy 64.444372 -184.339992) (xy 64.43878 -184.347074)
			(xy 64.432537 -184.363994) (xy 64.43218 -184.373012) (xy 64.43218 -184.440068) (xy 64.432557 -184.449083)
			(xy 64.438791 -184.466) (xy 64.444372 -184.473088) (xy 64.444626 -184.473088) (xy 64.444626 -184.473342)
			(xy 64.462308 -184.494242) (xy 64.492035 -184.540214) (xy 64.51488 -184.589966) (xy 64.530376 -184.642473)
			(xy 64.538202 -184.696657) (xy 64.538197 -184.751403) (xy 64.530363 -184.805586) (xy 64.514859 -184.858091)
			(xy 64.492006 -184.907839) (xy 64.462271 -184.953806) (xy 64.444626 -184.974738) (xy 64.444372 -184.974992)
			(xy 64.43878 -184.982074) (xy 64.432537 -184.998994) (xy 64.43218 -185.008012) (xy 64.43218 -185.075068)
			(xy 64.432557 -185.084083) (xy 64.438791 -185.101) (xy 64.444372 -185.108088) (xy 64.444626 -185.108088)
			(xy 64.444626 -185.108342) (xy 64.462255 -185.129282) (xy 64.491968 -185.175253) (xy 64.514805 -185.224998)
			(xy 64.530299 -185.277497) (xy 64.53813 -185.331671) (xy 64.538606 -185.35904) (xy 64.538159 -185.386292)
			(xy 64.530397 -185.440242) (xy 64.515037 -185.492537) (xy 64.492391 -185.542115) (xy 64.46292 -185.587965)
			(xy 64.427225 -185.629155) (xy 64.386031 -185.664846) (xy 64.340178 -185.694311) (xy 64.290598 -185.716952)
			(xy 64.2383 -185.732306) (xy 64.18435 -185.740062) (xy 64.157098 -185.740548) (xy 64.129727 -185.740096)
			(xy 64.075547 -185.732277) (xy 64.023043 -185.716785) (xy 63.973296 -185.69394) (xy 63.927331 -185.664211)
			(xy 63.9064 -185.646568) (xy 63.906146 -185.646314) (xy 63.899049 -185.640742) (xy 63.88214 -185.634486)
			(xy 63.873126 -185.634122) (xy 63.80607 -185.634122) (xy 63.797051 -185.63446) (xy 63.780134 -185.64072)
			(xy 63.77305 -185.646314) (xy 63.772796 -185.646568) (xy 63.751863 -185.664209) (xy 63.705895 -185.693933)
			(xy 63.656149 -185.716779) (xy 63.603647 -185.732275) (xy 63.549469 -185.740104) (xy 63.494727 -185.740104)
			(xy 63.440549 -185.732275) (xy 63.388047 -185.716779) (xy 63.338301 -185.693933) (xy 63.292333 -185.664209)
			(xy 63.2714 -185.646568) (xy 63.271146 -185.646314) (xy 63.264049 -185.640742) (xy 63.24714 -185.634486)
			(xy 63.238126 -185.634122) (xy 63.17107 -185.634122) (xy 63.162051 -185.63446) (xy 63.145134 -185.64072)
			(xy 63.13805 -185.646314) (xy 63.13805 -185.646568) (xy 63.137796 -185.646568) (xy 63.116872 -185.664217)
			(xy 63.070898 -185.693929) (xy 63.021148 -185.716763) (xy 62.968645 -185.732252) (xy 62.914468 -185.740076)
			(xy 62.887098 -185.740548) (xy 62.859849 -185.740024) (xy 62.805904 -185.732268) (xy 62.753613 -185.716915)
			(xy 62.704038 -185.694277) (xy 62.65819 -185.664814) (xy 62.617 -185.629126) (xy 62.581309 -185.587941)
			(xy 62.551842 -185.542095) (xy 62.529198 -185.492523) (xy 62.51384 -185.440233) (xy 62.506079 -185.386289)
			(xy 62.50559 -185.35904) (xy 62.149482 -185.35904) (xy 64.054482 -187.26404) (xy 66.49339 -187.26404)
			(xy 66.493882 -187.236671) (xy 66.501694 -187.182493) (xy 66.517177 -187.12999) (xy 66.540013 -187.080243)
			(xy 66.569732 -187.034275) (xy 66.58737 -187.013342) (xy 66.587624 -187.013088) (xy 66.593224 -187.006011)
			(xy 66.599462 -186.989087) (xy 66.599816 -186.980068) (xy 66.599816 -186.913012) (xy 66.59945 -186.903996)
			(xy 66.593208 -186.887079) (xy 66.587624 -186.879992) (xy 66.58737 -186.879992) (xy 66.58737 -186.879738)
			(xy 66.569767 -186.858774) (xy 66.540037 -186.812813) (xy 66.517187 -186.763072) (xy 66.501685 -186.710574)
			(xy 66.493852 -186.656399) (xy 66.493848 -186.601661) (xy 66.501673 -186.547485) (xy 66.517165 -186.494984)
			(xy 66.540008 -186.44524) (xy 66.56973 -186.399274) (xy 66.58737 -186.378342) (xy 66.587624 -186.378088)
			(xy 66.593224 -186.371011) (xy 66.599462 -186.354087) (xy 66.599816 -186.345068) (xy 66.599816 -186.278012)
			(xy 66.59945 -186.268996) (xy 66.593208 -186.252079) (xy 66.587624 -186.244992) (xy 66.58737 -186.244992)
			(xy 66.58737 -186.244738) (xy 66.569767 -186.223774) (xy 66.540037 -186.177813) (xy 66.517187 -186.128072)
			(xy 66.501685 -186.075574) (xy 66.493852 -186.021399) (xy 66.493848 -185.966661) (xy 66.501673 -185.912485)
			(xy 66.517165 -185.859984) (xy 66.540008 -185.81024) (xy 66.56973 -185.764274) (xy 66.58737 -185.743342)
			(xy 66.587624 -185.743088) (xy 66.593224 -185.736011) (xy 66.599462 -185.719087) (xy 66.599816 -185.710068)
			(xy 66.599816 -185.643012) (xy 66.59945 -185.633996) (xy 66.593208 -185.617079) (xy 66.587624 -185.609992)
			(xy 66.58737 -185.609992) (xy 66.58737 -185.609738) (xy 66.569767 -185.588774) (xy 66.540037 -185.542813)
			(xy 66.517187 -185.493072) (xy 66.501685 -185.440574) (xy 66.493852 -185.386399) (xy 66.493848 -185.331661)
			(xy 66.501673 -185.277485) (xy 66.517165 -185.224984) (xy 66.540008 -185.17524) (xy 66.56973 -185.129274)
			(xy 66.58737 -185.108342) (xy 66.587624 -185.108088) (xy 66.593224 -185.101011) (xy 66.599462 -185.084087)
			(xy 66.599816 -185.075068) (xy 66.599816 -185.008012) (xy 66.59945 -184.998996) (xy 66.593208 -184.982079)
			(xy 66.587624 -184.974992) (xy 66.58737 -184.974992) (xy 66.58737 -184.974738) (xy 66.569767 -184.953774)
			(xy 66.540037 -184.907813) (xy 66.517187 -184.858072) (xy 66.501685 -184.805574) (xy 66.493852 -184.751399)
			(xy 66.493848 -184.696661) (xy 66.501673 -184.642485) (xy 66.517165 -184.589984) (xy 66.540008 -184.54024)
			(xy 66.56973 -184.494274) (xy 66.58737 -184.473342) (xy 66.587624 -184.473088) (xy 66.593224 -184.466011)
			(xy 66.599462 -184.449087) (xy 66.599816 -184.440068) (xy 66.599816 -184.373012) (xy 66.59945 -184.363996)
			(xy 66.593208 -184.347079) (xy 66.587624 -184.339992) (xy 66.58737 -184.339992) (xy 66.58737 -184.339738)
			(xy 66.569731 -184.318806) (xy 66.54002 -184.272833) (xy 66.517184 -184.223085) (xy 66.501693 -184.170585)
			(xy 66.493865 -184.116409) (xy 66.49339 -184.08904) (xy 66.493912 -184.059765) (xy 66.502886 -184.001906)
			(xy 66.520598 -183.946099) (xy 66.546633 -183.893655) (xy 66.580377 -183.845807) (xy 66.600324 -183.824372)
			(xy 66.600578 -183.824118) (xy 66.606527 -183.817221) (xy 66.613556 -183.800431) (xy 66.614294 -183.791352)
			(xy 66.617596 -183.71439) (xy 66.611754 -183.696864) (xy 66.605912 -183.689498) (xy 66.589705 -183.668984)
			(xy 66.562446 -183.624372) (xy 66.541541 -183.576454) (xy 66.527383 -183.526127) (xy 66.520237 -183.474338)
			(xy 66.519806 -183.448198) (xy 66.520269 -183.420828) (xy 66.528088 -183.366648) (xy 66.543577 -183.314145)
			(xy 66.56642 -183.264398) (xy 66.596145 -183.218432) (xy 66.613786 -183.1975) (xy 66.61404 -183.197246)
			(xy 66.619618 -183.190154) (xy 66.625869 -183.173241) (xy 66.626232 -183.164226) (xy 66.626232 -183.09717)
			(xy 66.625883 -183.088152) (xy 66.619629 -183.071236) (xy 66.61404 -183.06415) (xy 66.613786 -183.06415)
			(xy 66.613786 -183.063896) (xy 66.596145 -183.042964) (xy 66.566423 -182.996995) (xy 66.543581 -182.947248)
			(xy 66.528086 -182.894747) (xy 66.520259 -182.840569) (xy 66.520259 -182.785828) (xy 66.528087 -182.73165)
			(xy 66.543582 -182.679149) (xy 66.566425 -182.629402) (xy 66.596147 -182.583434) (xy 66.613786 -182.5625)
			(xy 66.61404 -182.562246) (xy 66.619618 -182.555154) (xy 66.625869 -182.538241) (xy 66.626232 -182.529226)
			(xy 66.626232 -182.46217) (xy 66.625883 -182.453152) (xy 66.619629 -182.436236) (xy 66.61404 -182.42915)
			(xy 66.613786 -182.42915) (xy 66.613786 -182.428896) (xy 66.596145 -182.407964) (xy 66.566423 -182.361995)
			(xy 66.543581 -182.312248) (xy 66.528086 -182.259747) (xy 66.520259 -182.205569) (xy 66.520259 -182.150828)
			(xy 66.528087 -182.09665) (xy 66.543582 -182.044149) (xy 66.566425 -181.994402) (xy 66.596147 -181.948434)
			(xy 66.613786 -181.9275) (xy 66.61404 -181.927246) (xy 66.619618 -181.920154) (xy 66.625869 -181.903241)
			(xy 66.626232 -181.894226) (xy 66.626232 -181.82717) (xy 66.625883 -181.818152) (xy 66.619629 -181.801236)
			(xy 66.61404 -181.79415) (xy 66.613786 -181.79415) (xy 66.613786 -181.793896) (xy 66.596129 -181.772978)
			(xy 66.566421 -181.727001) (xy 66.543588 -181.67725) (xy 66.528101 -181.624746) (xy 66.520278 -181.570568)
			(xy 66.519806 -181.543198) (xy 66.520287 -181.515899) (xy 66.528059 -181.461858) (xy 66.543458 -181.409477)
			(xy 66.56617 -181.359827) (xy 66.595729 -181.313924) (xy 66.613278 -181.293008) (xy 66.619097 -181.285801)
			(xy 66.625617 -181.268481) (xy 66.625978 -181.259226) (xy 66.625724 -181.18328) (xy 66.619374 -181.166262)
			(xy 66.613278 -181.159404) (xy 66.595563 -181.138444) (xy 66.565685 -181.092411) (xy 66.542719 -181.042569)
			(xy 66.527139 -180.989949) (xy 66.519268 -180.935637) (xy 66.51879 -180.908198) (xy 66.519276 -180.880947)
			(xy 66.527033 -180.826999) (xy 66.542388 -180.774705) (xy 66.565029 -180.725127) (xy 66.594495 -180.679277)
			(xy 66.630187 -180.638087) (xy 66.671377 -180.602395) (xy 66.717227 -180.572929) (xy 66.766805 -180.550288)
			(xy 66.819099 -180.534933) (xy 66.873047 -180.527176) (xy 66.900298 -180.52669) (xy 66.927668 -180.52716)
			(xy 66.981847 -180.534977) (xy 67.03435 -180.550465) (xy 67.084097 -180.573306) (xy 67.130064 -180.603029)
			(xy 67.150996 -180.62067) (xy 67.15125 -180.620924) (xy 67.158345 -180.626498) (xy 67.175255 -180.632752)
			(xy 67.18427 -180.633116) (xy 67.251326 -180.633116) (xy 67.260344 -180.632768) (xy 67.27726 -180.626514)
			(xy 67.284346 -180.620924) (xy 67.284346 -180.62067) (xy 67.2846 -180.62067) (xy 67.305517 -180.603013)
			(xy 67.351495 -180.573305) (xy 67.401246 -180.550473) (xy 67.45375 -180.534986) (xy 67.507928 -180.527162)
			(xy 67.535298 -180.52669) (xy 67.562549 -180.52718) (xy 67.616497 -180.534936) (xy 67.668791 -180.550291)
			(xy 67.718368 -180.572931) (xy 67.764219 -180.602397) (xy 67.805409 -180.638088) (xy 67.8411 -180.679278)
			(xy 67.870567 -180.725128) (xy 67.893208 -180.774705) (xy 67.908563 -180.826999) (xy 67.91632 -180.880947)
			(xy 67.916806 -180.908198) (xy 67.916319 -180.935497) (xy 67.908548 -180.989538) (xy 67.89315 -181.041918)
			(xy 67.87044 -181.091568) (xy 67.840882 -181.137472) (xy 67.823334 -181.158388) (xy 67.817475 -181.165567)
			(xy 67.810978 -181.182908) (xy 67.810634 -181.19217) (xy 67.810888 -181.268116) (xy 67.817238 -181.285134)
			(xy 67.823334 -181.291992) (xy 67.841049 -181.312952) (xy 67.870927 -181.358985) (xy 67.893892 -181.408827)
			(xy 67.909472 -181.461448) (xy 67.917344 -181.515759) (xy 67.917822 -181.543198) (xy 67.917374 -181.570569)
			(xy 67.909555 -181.62475) (xy 67.894062 -181.677254) (xy 67.871216 -181.727) (xy 67.841486 -181.772966)
			(xy 67.823842 -181.793896) (xy 67.823588 -181.79415) (xy 67.818015 -181.801246) (xy 67.81176 -181.818156)
			(xy 67.811396 -181.82717) (xy 67.811396 -181.894226) (xy 67.811742 -181.903244) (xy 67.817997 -181.920161)
			(xy 67.823588 -181.927246) (xy 67.823842 -181.927246) (xy 67.823842 -181.9275) (xy 67.841482 -181.948434)
			(xy 67.871209 -181.994401) (xy 67.894057 -182.044146) (xy 67.909554 -182.096649) (xy 67.917384 -182.150828)
			(xy 67.917384 -182.205569) (xy 67.915356 -182.2196) (xy 79.86014 -182.2196) (xy 79.860592 -182.192025)
			(xy 79.868545 -182.137451) (xy 79.884272 -182.08459) (xy 79.907445 -182.034544) (xy 79.93758 -181.988355)
			(xy 79.974051 -181.946985) (xy 79.99476 -181.92877) (xy 80.002858 -181.921236) (xy 80.012197 -181.901208)
			(xy 80.012794 -181.890162) (xy 80.012794 -181.812438) (xy 80.012207 -181.801391) (xy 80.002855 -181.78137)
			(xy 79.99476 -181.77383) (xy 79.974052 -181.755616) (xy 79.937583 -181.714246) (xy 79.907452 -181.668057)
			(xy 79.884286 -181.61801) (xy 79.868568 -181.565148) (xy 79.860627 -181.510574) (xy 79.86014 -181.483)
			(xy 79.86071 -181.454477) (xy 79.869217 -181.398068) (xy 79.886025 -181.343553) (xy 79.910762 -181.292148)
			(xy 79.942875 -181.244998) (xy 79.981648 -181.203154) (xy 80.026219 -181.167547) (xy 80.05064 -181.1528)
			(xy 80.060546 -181.147212) (xy 80.073246 -181.12867) (xy 80.090264 -181.028848) (xy 80.084168 -181.007258)
			(xy 80.076802 -180.998622) (xy 80.059877 -180.978237) (xy 80.031365 -180.933582) (xy 80.009461 -180.885339)
			(xy 79.994606 -180.834483) (xy 79.9871 -180.782035) (xy 79.986632 -180.755544) (xy 79.987075 -180.728925)
			(xy 79.994647 -180.676228) (xy 80.009642 -180.625146) (xy 80.031755 -180.576718) (xy 80.060537 -180.53193)
			(xy 80.0954 -180.491696) (xy 80.135635 -180.456833) (xy 80.180423 -180.428052) (xy 80.228851 -180.40594)
			(xy 80.279934 -180.390945) (xy 80.332631 -180.383375) (xy 80.35925 -180.382926) (xy 80.385672 -180.383372)
			(xy 80.437987 -180.390828) (xy 80.488725 -180.405596) (xy 80.536869 -180.427382) (xy 80.581454 -180.455748)
			(xy 80.60182 -180.472588) (xy 80.608678 -180.47843) (xy 80.625696 -180.48478) (xy 80.710024 -180.48478)
			(xy 80.727042 -180.47843) (xy 80.7339 -180.472588) (xy 80.754266 -180.455749) (xy 80.798852 -180.427384)
			(xy 80.846996 -180.405597) (xy 80.897733 -180.390826) (xy 80.950048 -180.383366) (xy 81.002892 -180.383366)
			(xy 81.055207 -180.390826) (xy 81.105944 -180.405597) (xy 81.154088 -180.427384) (xy 81.198674 -180.455749)
			(xy 81.21904 -180.472588) (xy 81.225898 -180.47843) (xy 81.242916 -180.48478) (xy 81.327244 -180.48478)
			(xy 81.344262 -180.47843) (xy 81.35112 -180.472588) (xy 81.371477 -180.455739) (xy 81.416069 -180.427386)
			(xy 81.464216 -180.405609) (xy 81.514954 -180.390844) (xy 81.567269 -180.383386) (xy 81.59369 -180.382926)
			(xy 81.621581 -180.383332) (xy 81.676739 -180.391645) (xy 81.730042 -180.408085) (xy 81.780299 -180.432287)
			(xy 81.826388 -180.463709) (xy 81.867279 -180.501649) (xy 81.902059 -180.54526) (xy 81.92995 -180.593567)
			(xy 81.9364 -180.610002) (xy 86.589362 -180.610002) (xy 86.589807 -180.582426) (xy 86.597761 -180.527852)
			(xy 86.613489 -180.474991) (xy 86.636662 -180.424944) (xy 86.6668 -180.378755) (xy 86.703272 -180.337386)
			(xy 86.723982 -180.319172) (xy 86.732067 -180.311625) (xy 86.741416 -180.291608) (xy 86.742016 -180.280564)
			(xy 86.742016 -180.20284) (xy 86.741452 -180.191789) (xy 86.732087 -180.171767) (xy 86.723982 -180.164232)
			(xy 86.70328 -180.146012) (xy 86.666809 -180.104644) (xy 86.636677 -180.058456) (xy 86.613509 -180.00841)
			(xy 86.597791 -179.955549) (xy 86.589849 -179.900976) (xy 86.589362 -179.873402) (xy 86.589807 -179.845826)
			(xy 86.597761 -179.791252) (xy 86.613489 -179.738391) (xy 86.636662 -179.688344) (xy 86.6668 -179.642155)
			(xy 86.703272 -179.600786) (xy 86.723982 -179.582572) (xy 86.732067 -179.575025) (xy 86.741416 -179.555008)
			(xy 86.742016 -179.543964) (xy 86.742016 -179.46624) (xy 86.741452 -179.455189) (xy 86.732087 -179.435167)
			(xy 86.723982 -179.427632) (xy 86.70328 -179.409412) (xy 86.666809 -179.368044) (xy 86.636677 -179.321856)
			(xy 86.613509 -179.27181) (xy 86.597791 -179.218949) (xy 86.589849 -179.164376) (xy 86.589362 -179.136802)
			(xy 86.58988 -179.109552) (xy 86.597635 -179.055607) (xy 86.612988 -179.003315) (xy 86.635627 -178.95374)
			(xy 86.66509 -178.907891) (xy 86.700778 -178.866701) (xy 86.741965 -178.83101) (xy 86.787811 -178.801542)
			(xy 86.837385 -178.7789) (xy 86.889676 -178.763542) (xy 86.94362 -178.755782) (xy 86.97087 -178.755294)
			(xy 86.998724 -178.755849) (xy 87.053838 -178.763968) (xy 87.107187 -178.780009) (xy 87.15764 -178.803632)
			(xy 87.204124 -178.834335) (xy 87.245654 -178.871466) (xy 87.281348 -178.914238) (xy 87.310448 -178.961742)
			(xy 87.332337 -179.01297) (xy 87.339932 -179.039774) (xy 87.342218 -179.048664) (xy 87.352886 -179.063904)
			(xy 87.424768 -179.111656) (xy 87.442802 -179.11572) (xy 87.451946 -179.11445) (xy 87.464962 -179.112778)
			(xy 87.491147 -179.111) (xy 87.50427 -179.110894) (xy 87.518419 -179.110991) (xy 87.546642 -179.113023)
			(xy 87.560658 -179.114958) (xy 87.570564 -179.116482) (xy 87.590376 -179.111656) (xy 87.664798 -179.055776)
			(xy 87.674958 -179.03825) (xy 87.676228 -179.02809) (xy 87.680396 -179.00095) (xy 87.695362 -178.948124)
			(xy 87.717745 -178.897989) (xy 87.747084 -178.851581) (xy 87.782772 -178.809856) (xy 87.824072 -178.773679)
			(xy 87.870132 -178.743795) (xy 87.92 -178.720823) (xy 87.972645 -178.705236) (xy 88.026982 -178.697356)
			(xy 88.054434 -178.696874) (xy 88.081685 -178.697346) (xy 88.135633 -178.705107) (xy 88.187926 -178.720465)
			(xy 88.237503 -178.743109) (xy 88.283352 -178.772577) (xy 88.324541 -178.80827) (xy 88.360232 -178.849461)
			(xy 88.389699 -178.895311) (xy 88.41234 -178.944889) (xy 88.427697 -178.997183) (xy 88.435455 -179.051131)
			(xy 88.435942 -179.078382) (xy 88.435484 -179.105957) (xy 88.427533 -179.160531) (xy 88.411808 -179.213392)
			(xy 88.388636 -179.263438) (xy 88.358501 -179.309628) (xy 88.322031 -179.350997) (xy 88.301322 -179.369212)
			(xy 88.293229 -179.37675) (xy 88.283888 -179.396775) (xy 88.283288 -179.40782) (xy 88.283288 -179.485544)
			(xy 88.283891 -179.496589) (xy 88.293232 -179.51661) (xy 88.301322 -179.524152) (xy 88.322018 -179.54238)
			(xy 88.358488 -179.583746) (xy 88.388622 -179.629932) (xy 88.41179 -179.679977) (xy 88.42751 -179.732836)
			(xy 88.435454 -179.787408) (xy 88.435488 -179.789328) (xy 93.02445 -179.789328) (xy 93.028521 -179.733706)
			(xy 93.040647 -179.679269) (xy 93.06057 -179.627178) (xy 93.087866 -179.578543) (xy 93.121952 -179.5344)
			(xy 93.162101 -179.495691) (xy 93.207459 -179.46324) (xy 93.257059 -179.437739) (xy 93.309843 -179.419732)
			(xy 93.364686 -179.409602) (xy 93.42042 -179.407565) (xy 93.475857 -179.413665) (xy 93.529814 -179.427771)
			(xy 93.581143 -179.449583) (xy 93.628749 -179.478637) (xy 93.671617 -179.514312) (xy 93.708834 -179.555849)
			(xy 93.739607 -179.602362) (xy 93.763279 -179.652859) (xy 93.779347 -179.706266) (xy 93.787467 -179.761442)
			(xy 93.787976 -179.789328) (xy 93.787467 -179.817214) (xy 93.779347 -179.87239) (xy 93.763279 -179.925797)
			(xy 93.739607 -179.976294) (xy 93.708834 -180.022807) (xy 93.671617 -180.064344) (xy 93.628749 -180.100019)
			(xy 93.581143 -180.129073) (xy 93.529814 -180.150885) (xy 93.475857 -180.164991) (xy 93.42042 -180.171091)
			(xy 93.364686 -180.169054) (xy 93.309843 -180.158924) (xy 93.257059 -180.140917) (xy 93.207459 -180.115416)
			(xy 93.162101 -180.082965) (xy 93.121952 -180.044256) (xy 93.087866 -180.000113) (xy 93.06057 -179.951478)
			(xy 93.040647 -179.899387) (xy 93.028521 -179.84495) (xy 93.02445 -179.789328) (xy 88.435488 -179.789328)
			(xy 88.435942 -179.814982) (xy 88.435405 -179.842231) (xy 88.427652 -179.896175) (xy 88.412301 -179.948467)
			(xy 88.389664 -179.998042) (xy 88.360203 -180.043891) (xy 88.324517 -180.08508) (xy 88.283332 -180.120772)
			(xy 88.237487 -180.150239) (xy 88.187916 -180.172883) (xy 88.135626 -180.188241) (xy 88.081683 -180.196001)
			(xy 88.054434 -180.19649) (xy 88.053926 -180.19649) (xy 88.020144 -180.194966) (xy 88.009984 -180.19395)
			(xy 87.99068 -180.200046) (xy 87.927688 -180.252878) (xy 87.920386 -180.259591) (xy 87.911112 -180.277103)
			(xy 87.909654 -180.286914) (xy 87.909654 -180.287676) (xy 87.906688 -180.315835) (xy 87.893478 -180.370892)
			(xy 87.872274 -180.423392) (xy 87.843542 -180.472181) (xy 87.807913 -180.516185) (xy 87.76617 -180.554439)
			(xy 87.71923 -180.586102) (xy 87.668125 -180.610478) (xy 87.613979 -180.62703) (xy 87.55798 -180.635396)
			(xy 87.52967 -180.63591) (xy 87.511651 -180.635689) (xy 87.475776 -180.632255) (xy 87.458042 -180.629052)
			(xy 87.44839 -180.627274) (xy 87.42934 -180.63083) (xy 87.35441 -180.678836) (xy 87.34298 -180.694584)
			(xy 87.340694 -180.703982) (xy 87.333311 -180.73103) (xy 87.311678 -180.782756) (xy 87.28271 -180.83076)
			(xy 87.247032 -180.87401) (xy 87.205411 -180.911576) (xy 87.158743 -180.94265) (xy 87.10803 -180.966562)
			(xy 87.054366 -180.982799) (xy 86.998903 -180.99101) (xy 86.97087 -180.99151) (xy 86.943618 -180.99105)
			(xy 86.88967 -180.98329) (xy 86.837374 -180.967931) (xy 86.787797 -180.945286) (xy 86.741947 -180.915817)
			(xy 86.700757 -180.880123) (xy 86.665066 -180.83893) (xy 86.6356 -180.793078) (xy 86.612959 -180.743499)
			(xy 86.597604 -180.691203) (xy 86.589848 -180.637254) (xy 86.589362 -180.610002) (xy 81.9364 -180.610002)
			(xy 81.950329 -180.645492) (xy 81.962742 -180.699875) (xy 81.966911 -180.7555) (xy 81.962742 -180.811125)
			(xy 81.950329 -180.865508) (xy 81.92995 -180.917433) (xy 81.902059 -180.96574) (xy 81.867279 -181.009351)
			(xy 81.826388 -181.047291) (xy 81.780299 -181.078713) (xy 81.730042 -181.102915) (xy 81.676739 -181.119355)
			(xy 81.621581 -181.127668) (xy 81.59369 -181.128162) (xy 81.567269 -181.127695) (xy 81.514954 -181.120245)
			(xy 81.464216 -181.105482) (xy 81.416072 -181.0837) (xy 81.371486 -181.055338) (xy 81.35112 -181.0385)
			(xy 81.344262 -181.032658) (xy 81.327244 -181.026308) (xy 81.242916 -181.026308) (xy 81.225898 -181.032658)
			(xy 81.21904 -181.0385) (xy 81.198674 -181.055339) (xy 81.154088 -181.083704) (xy 81.105944 -181.105491)
			(xy 81.055207 -181.120262) (xy 81.002892 -181.127722) (xy 80.950048 -181.127722) (xy 80.897733 -181.120262)
			(xy 80.846996 -181.105491) (xy 80.798852 -181.083704) (xy 80.754266 -181.055339) (xy 80.7339 -181.0385)
			(xy 80.727042 -181.032658) (xy 80.710024 -181.026308) (xy 80.625696 -181.026308) (xy 80.608678 -181.032658)
			(xy 80.60182 -181.0385) (xy 80.589745 -181.04857) (xy 80.564186 -181.066884) (xy 80.550766 -181.075076)
			(xy 80.550512 -181.07533) (xy 80.541324 -181.08159) (xy 80.528931 -181.100014) (xy 80.526636 -181.11089)
			(xy 80.51292 -181.19979) (xy 80.51927 -181.22138) (xy 80.52689 -181.229762) (xy 80.544916 -181.250813)
			(xy 80.575348 -181.297128) (xy 80.598751 -181.347362) (xy 80.614633 -181.400456) (xy 80.622659 -181.455291)
			(xy 80.623156 -181.483) (xy 80.622706 -181.510575) (xy 80.614752 -181.56515) (xy 80.599025 -181.61801)
			(xy 80.575852 -181.668057) (xy 80.545716 -181.714246) (xy 80.527895 -181.73446) (xy 85.586062 -181.73446)
			(xy 85.586538 -181.706549) (xy 85.594677 -181.651322) (xy 85.610777 -181.597872) (xy 85.634494 -181.547337)
			(xy 85.66532 -181.500798) (xy 85.683598 -181.479698) (xy 85.689495 -181.472521) (xy 85.696146 -181.455196)
			(xy 85.696552 -181.445916) (xy 85.696552 -181.368192) (xy 85.689948 -181.35092) (xy 85.683598 -181.343808)
			(xy 85.665302 -181.322723) (xy 85.634477 -181.276181) (xy 85.610765 -181.225642) (xy 85.594673 -181.172188)
			(xy 85.586544 -181.116958) (xy 85.586062 -181.089046) (xy 85.586548 -181.061795) (xy 85.594304 -181.007847)
			(xy 85.609659 -180.955552) (xy 85.632301 -180.905975) (xy 85.661767 -180.860125) (xy 85.697458 -180.818934)
			(xy 85.738649 -180.783243) (xy 85.784499 -180.753777) (xy 85.834076 -180.731135) (xy 85.886371 -180.71578)
			(xy 85.940319 -180.708024) (xy 85.994821 -180.708024) (xy 86.048769 -180.71578) (xy 86.101064 -180.731135)
			(xy 86.150641 -180.753777) (xy 86.196491 -180.783243) (xy 86.237682 -180.818934) (xy 86.273373 -180.860125)
			(xy 86.302839 -180.905975) (xy 86.325481 -180.955552) (xy 86.340836 -181.007847) (xy 86.348592 -181.061795)
			(xy 86.349078 -181.089046) (xy 86.348596 -181.116957) (xy 86.340456 -181.172183) (xy 86.324357 -181.225633)
			(xy 86.300643 -181.276167) (xy 86.269818 -181.322707) (xy 86.251542 -181.343808) (xy 86.245635 -181.350978)
			(xy 86.238992 -181.368309) (xy 86.238588 -181.37759) (xy 86.238588 -181.455314) (xy 86.245192 -181.472586)
			(xy 86.251542 -181.479698) (xy 86.2698 -181.500814) (xy 86.300629 -181.547349) (xy 86.324347 -181.597879)
			(xy 86.340449 -181.651327) (xy 86.348589 -181.70655) (xy 86.349078 -181.73446) (xy 86.348592 -181.761711)
			(xy 86.340836 -181.815659) (xy 86.325481 -181.867954) (xy 86.302839 -181.917531) (xy 86.273373 -181.963381)
			(xy 86.237682 -182.004572) (xy 86.196491 -182.040263) (xy 86.150641 -182.069729) (xy 86.101064 -182.092371)
			(xy 86.048769 -182.107726) (xy 85.994821 -182.115482) (xy 85.940319 -182.115482) (xy 85.886371 -182.107726)
			(xy 85.834076 -182.092371) (xy 85.784499 -182.069729) (xy 85.738649 -182.040263) (xy 85.697458 -182.004572)
			(xy 85.661767 -181.963381) (xy 85.632301 -181.917531) (xy 85.609659 -181.867954) (xy 85.594304 -181.815659)
			(xy 85.586548 -181.761711) (xy 85.586062 -181.73446) (xy 80.527895 -181.73446) (xy 80.509245 -181.755615)
			(xy 80.488536 -181.77383) (xy 80.480437 -181.781363) (xy 80.471098 -181.801392) (xy 80.470502 -181.812438)
			(xy 80.470502 -181.890162) (xy 80.471091 -181.901209) (xy 80.480441 -181.92123) (xy 80.488536 -181.92877)
			(xy 80.509243 -181.946985) (xy 80.545712 -181.988354) (xy 80.575844 -182.034543) (xy 80.59901 -182.08459)
			(xy 80.613476 -182.13324) (xy 88.110822 -182.13324) (xy 88.111308 -182.105666) (xy 88.119255 -182.051094)
			(xy 88.134976 -181.998234) (xy 88.158142 -181.948188) (xy 88.188271 -181.901998) (xy 88.224736 -181.860626)
			(xy 88.245442 -181.84241) (xy 88.25352 -181.834857) (xy 88.262871 -181.814844) (xy 88.263476 -181.803802)
			(xy 88.263476 -181.726078) (xy 88.262872 -181.715033) (xy 88.253533 -181.695011) (xy 88.245442 -181.68747)
			(xy 88.224722 -181.669269) (xy 88.18825 -181.627899) (xy 88.158118 -181.581707) (xy 88.134954 -181.531657)
			(xy 88.11924 -181.478792) (xy 88.111305 -181.424215) (xy 88.110822 -181.39664) (xy 88.111224 -181.36959)
			(xy 88.118875 -181.316034) (xy 88.134013 -181.264095) (xy 88.156336 -181.214816) (xy 88.185396 -181.169184)
			(xy 88.220611 -181.128114) (xy 88.261273 -181.09243) (xy 88.306569 -181.062848) (xy 88.355588 -181.03996)
			(xy 88.381332 -181.031642) (xy 88.392508 -181.02834) (xy 88.40978 -181.012084) (xy 88.442546 -180.925978)
			(xy 88.446162 -180.914913) (xy 88.444043 -180.891755) (xy 88.438482 -180.881528) (xy 88.425555 -180.859512)
			(xy 88.405154 -180.812712) (xy 88.391321 -180.763568) (xy 88.384314 -180.712998) (xy 88.383872 -180.687472)
			(xy 88.384331 -180.660856) (xy 88.39191 -180.608165) (xy 88.40691 -180.557089) (xy 88.429026 -180.508668)
			(xy 88.457808 -180.463886) (xy 88.492669 -180.423657) (xy 88.532901 -180.388797) (xy 88.577683 -180.360018)
			(xy 88.626106 -180.337904) (xy 88.677183 -180.322906) (xy 88.729874 -180.315329) (xy 88.75649 -180.314854)
			(xy 88.782911 -180.315328) (xy 88.835225 -180.322776) (xy 88.885963 -180.337538) (xy 88.934108 -180.359318)
			(xy 88.978694 -180.387679) (xy 88.99906 -180.404516) (xy 89.005918 -180.410358) (xy 89.022936 -180.416708)
			(xy 89.107264 -180.416708) (xy 89.124282 -180.410358) (xy 89.13114 -180.404516) (xy 89.151506 -180.387677)
			(xy 89.196092 -180.359312) (xy 89.244236 -180.337525) (xy 89.294973 -180.322754) (xy 89.347288 -180.315294)
			(xy 89.400132 -180.315294) (xy 89.452447 -180.322754) (xy 89.503184 -180.337525) (xy 89.551328 -180.359312)
			(xy 89.595914 -180.387677) (xy 89.61628 -180.404516) (xy 89.623138 -180.410358) (xy 89.640156 -180.416708)
			(xy 89.724484 -180.416708) (xy 89.741502 -180.410358) (xy 89.74836 -180.404516) (xy 89.768742 -180.387699)
			(xy 89.813327 -180.35934) (xy 89.861468 -180.337557) (xy 89.912201 -180.322784) (xy 89.96451 -180.315318)
			(xy 89.99093 -180.314854) (xy 90.018811 -180.315433) (xy 90.07395 -180.323748) (xy 90.127235 -180.340188)
			(xy 90.177474 -180.364385) (xy 90.223545 -180.3958) (xy 90.264421 -180.43373) (xy 90.299186 -180.477328)
			(xy 90.327066 -180.52562) (xy 90.347438 -180.577529) (xy 90.358792 -180.627274) (xy 94.981522 -180.627274)
			(xy 94.982031 -180.599701) (xy 94.989974 -180.54513) (xy 95.00569 -180.49227) (xy 95.028851 -180.442224)
			(xy 95.058977 -180.396033) (xy 95.095438 -180.354661) (xy 95.116142 -180.336444) (xy 95.124205 -180.328878)
			(xy 95.133564 -180.308874) (xy 95.134176 -180.297836) (xy 95.134176 -180.220112) (xy 95.133609 -180.209062)
			(xy 95.124244 -180.189041) (xy 95.116142 -180.181504) (xy 95.095438 -180.163285) (xy 95.058965 -180.121919)
			(xy 95.028831 -180.075731) (xy 95.005664 -180.025684) (xy 94.989947 -179.972823) (xy 94.982007 -179.918248)
			(xy 94.981522 -179.890674) (xy 94.982031 -179.863101) (xy 94.989974 -179.80853) (xy 95.00569 -179.75567)
			(xy 95.028851 -179.705624) (xy 95.058977 -179.659433) (xy 95.095438 -179.618061) (xy 95.116142 -179.599844)
			(xy 95.124205 -179.592278) (xy 95.133564 -179.572274) (xy 95.134176 -179.561236) (xy 95.134176 -179.483512)
			(xy 95.133609 -179.472462) (xy 95.124244 -179.452441) (xy 95.116142 -179.444904) (xy 95.095438 -179.426685)
			(xy 95.058965 -179.385319) (xy 95.028831 -179.339131) (xy 95.005664 -179.289084) (xy 94.989947 -179.236223)
			(xy 94.982007 -179.181648) (xy 94.981522 -179.154074) (xy 94.981931 -179.126819) (xy 94.989692 -179.072865)
			(xy 95.005053 -179.020564) (xy 95.027701 -178.970982) (xy 95.057174 -178.925127) (xy 95.092874 -178.883934)
			(xy 95.134072 -178.848241) (xy 95.179931 -178.818774) (xy 95.229516 -178.796133) (xy 95.281819 -178.78078)
			(xy 95.335775 -178.773027) (xy 95.36303 -178.772566) (xy 95.390885 -178.773087) (xy 95.445999 -178.781214)
			(xy 95.499348 -178.797262) (xy 95.5498 -178.82089) (xy 95.596283 -178.851597) (xy 95.637812 -178.888732)
			(xy 95.673506 -178.931506) (xy 95.702606 -178.979012) (xy 95.724496 -179.030242) (xy 95.732092 -179.057046)
			(xy 95.734378 -179.065936) (xy 95.745046 -179.081176) (xy 95.816928 -179.128928) (xy 95.834962 -179.132992)
			(xy 95.844106 -179.131722) (xy 95.857123 -179.130054) (xy 95.883307 -179.128273) (xy 95.89643 -179.128166)
			(xy 95.910579 -179.128257) (xy 95.938802 -179.130293) (xy 95.952818 -179.13223) (xy 95.962724 -179.133754)
			(xy 95.982536 -179.128928) (xy 96.056958 -179.073048) (xy 96.067118 -179.055522) (xy 96.068388 -179.045362)
			(xy 96.072477 -179.018208) (xy 96.087449 -178.965378) (xy 96.10984 -178.915239) (xy 96.139187 -178.868828)
			(xy 96.174885 -178.827104) (xy 96.216194 -178.790927) (xy 96.262263 -178.761046) (xy 96.31214 -178.738077)
			(xy 96.364794 -178.722496) (xy 96.419138 -178.714624) (xy 96.446594 -178.714146) (xy 96.473843 -178.714683)
			(xy 96.527787 -178.722438) (xy 96.580077 -178.73779) (xy 96.629652 -178.760427) (xy 96.6755 -178.789888)
			(xy 96.716689 -178.825574) (xy 96.752381 -178.866758) (xy 96.781848 -178.912603) (xy 96.804492 -178.962174)
			(xy 96.819851 -179.014463) (xy 96.827613 -179.068405) (xy 96.828102 -179.095654) (xy 96.827604 -179.123227)
			(xy 96.819658 -179.177799) (xy 96.803939 -179.230658) (xy 96.780775 -179.280704) (xy 96.750649 -179.326894)
			(xy 96.714187 -179.368267) (xy 96.693482 -179.386484) (xy 96.685411 -179.394043) (xy 96.676055 -179.414052)
			(xy 96.675448 -179.425092) (xy 96.675448 -179.502816) (xy 96.676048 -179.513862) (xy 96.685389 -179.533884)
			(xy 96.693482 -179.541424) (xy 96.714204 -179.559623) (xy 96.750675 -179.600994) (xy 96.780806 -179.647186)
			(xy 96.80397 -179.697237) (xy 96.819683 -179.750102) (xy 96.827619 -179.804678) (xy 96.827653 -179.8066)
			(xy 101.41661 -179.8066) (xy 101.420681 -179.750978) (xy 101.432807 -179.696541) (xy 101.45273 -179.64445)
			(xy 101.480026 -179.595815) (xy 101.514112 -179.551672) (xy 101.554261 -179.512963) (xy 101.599619 -179.480512)
			(xy 101.649219 -179.455011) (xy 101.702003 -179.437004) (xy 101.756846 -179.426874) (xy 101.81258 -179.424837)
			(xy 101.868017 -179.430937) (xy 101.921974 -179.445043) (xy 101.973303 -179.466855) (xy 102.020909 -179.495909)
			(xy 102.063777 -179.531584) (xy 102.100994 -179.573121) (xy 102.131767 -179.619634) (xy 102.155439 -179.670131)
			(xy 102.171507 -179.723538) (xy 102.179627 -179.778714) (xy 102.180136 -179.8066) (xy 102.179627 -179.834486)
			(xy 102.171507 -179.889662) (xy 102.155439 -179.943069) (xy 102.131767 -179.993566) (xy 102.100994 -180.040079)
			(xy 102.063777 -180.081616) (xy 102.020909 -180.117291) (xy 101.973303 -180.146345) (xy 101.921974 -180.168157)
			(xy 101.868017 -180.182263) (xy 101.81258 -180.188363) (xy 101.756846 -180.186326) (xy 101.702003 -180.176196)
			(xy 101.649219 -180.158189) (xy 101.599619 -180.132688) (xy 101.554261 -180.100237) (xy 101.514112 -180.061528)
			(xy 101.480026 -180.017385) (xy 101.45273 -179.96875) (xy 101.432807 -179.916659) (xy 101.420681 -179.862222)
			(xy 101.41661 -179.8066) (xy 96.827653 -179.8066) (xy 96.828102 -179.832254) (xy 96.827602 -179.859506)
			(xy 96.819851 -179.913456) (xy 96.804501 -179.965753) (xy 96.781863 -180.015334) (xy 96.752399 -180.061187)
			(xy 96.716709 -180.102381) (xy 96.67552 -180.138075) (xy 96.629669 -180.167544) (xy 96.580091 -180.190187)
			(xy 96.527795 -180.205543) (xy 96.473846 -180.213299) (xy 96.446594 -180.213762) (xy 96.446086 -180.213762)
			(xy 96.412304 -180.212238) (xy 96.402144 -180.211222) (xy 96.38284 -180.217318) (xy 96.319848 -180.27015)
			(xy 96.31255 -180.276866) (xy 96.303275 -180.294376) (xy 96.301814 -180.304186) (xy 96.301814 -180.304948)
			(xy 96.298863 -180.333109) (xy 96.285656 -180.38817) (xy 96.264453 -180.440673) (xy 96.23572 -180.489463)
			(xy 96.200089 -180.53347) (xy 96.158344 -180.571724) (xy 96.111401 -180.603386) (xy 96.060293 -180.62776)
			(xy 96.006143 -180.64431) (xy 95.950141 -180.652671) (xy 95.92183 -180.653182) (xy 95.903811 -180.652966)
			(xy 95.867936 -180.649528) (xy 95.850202 -180.646324) (xy 95.84055 -180.644546) (xy 95.8215 -180.648102)
			(xy 95.74657 -180.696108) (xy 95.73514 -180.711856) (xy 95.732854 -180.721254) (xy 95.725489 -180.748308)
			(xy 95.703856 -180.800036) (xy 95.674888 -180.848042) (xy 95.639209 -180.891294) (xy 95.597585 -180.928861)
			(xy 95.550913 -180.959934) (xy 95.500198 -180.983844) (xy 95.44653 -181.000078) (xy 95.391065 -181.008285)
			(xy 95.36303 -181.008782) (xy 95.335777 -181.008317) (xy 95.281824 -181.000563) (xy 95.229525 -180.98521)
			(xy 95.179943 -180.962569) (xy 95.134089 -180.933101) (xy 95.092895 -180.897408) (xy 95.057201 -180.856214)
			(xy 95.027733 -180.81036) (xy 95.005092 -180.760779) (xy 94.989738 -180.708479) (xy 94.981984 -180.654527)
			(xy 94.981522 -180.627274) (xy 90.358792 -180.627274) (xy 90.359846 -180.631893) (xy 90.364013 -180.6875)
			(xy 90.359846 -180.743107) (xy 90.347438 -180.797471) (xy 90.327066 -180.84938) (xy 90.299186 -180.897672)
			(xy 90.264421 -180.94127) (xy 90.223545 -180.9792) (xy 90.177474 -181.010615) (xy 90.127235 -181.034812)
			(xy 90.07395 -181.051252) (xy 90.018811 -181.059567) (xy 89.99093 -181.06009) (xy 89.964509 -181.059617)
			(xy 89.912194 -181.052171) (xy 89.861455 -181.03741) (xy 89.813311 -181.015629) (xy 89.768725 -180.987266)
			(xy 89.74836 -180.970428) (xy 89.741502 -180.964586) (xy 89.724484 -180.958236) (xy 89.640156 -180.958236)
			(xy 89.623138 -180.964586) (xy 89.61628 -180.970428) (xy 89.595914 -180.987267) (xy 89.551328 -181.015632)
			(xy 89.503184 -181.037419) (xy 89.452447 -181.05219) (xy 89.400132 -181.05965) (xy 89.347288 -181.05965)
			(xy 89.294973 -181.05219) (xy 89.244236 -181.037419) (xy 89.196092 -181.015632) (xy 89.151506 -180.987267)
			(xy 89.13114 -180.970428) (xy 89.124282 -180.964586) (xy 89.107264 -180.958236) (xy 89.022936 -180.958236)
			(xy 89.005918 -180.964586) (xy 88.99906 -180.970428) (xy 88.979951 -180.986226) (xy 88.938339 -181.013183)
			(xy 88.893521 -181.034385) (xy 88.870028 -181.04231) (xy 88.858852 -181.045866) (xy 88.842088 -181.062122)
			(xy 88.810338 -181.148736) (xy 88.806937 -181.159888) (xy 88.809429 -181.183038) (xy 88.815164 -181.193186)
			(xy 88.829074 -181.2161) (xy 88.851016 -181.265008) (xy 88.865885 -181.316508) (xy 88.873388 -181.369584)
			(xy 88.873838 -181.396386) (xy 88.873838 -181.39664) (xy 88.873353 -181.424214) (xy 88.865407 -181.478787)
			(xy 88.849688 -181.531647) (xy 88.826521 -181.581694) (xy 88.796391 -181.627884) (xy 88.762452 -181.666388)
			(xy 93.983302 -181.666388) (xy 93.98381 -181.638478) (xy 93.991944 -181.583254) (xy 94.008037 -181.529804)
			(xy 94.031746 -181.479269) (xy 94.062564 -181.432728) (xy 94.080838 -181.411626) (xy 94.086728 -181.404444)
			(xy 94.093382 -181.387122) (xy 94.093792 -181.377844) (xy 94.093792 -181.30012) (xy 94.087188 -181.282848)
			(xy 94.080838 -181.275736) (xy 94.062546 -181.254648) (xy 94.031722 -181.208106) (xy 94.008011 -181.157568)
			(xy 93.991918 -181.104114) (xy 93.983786 -181.048886) (xy 93.983302 -181.020974) (xy 93.983788 -180.993723)
			(xy 93.991544 -180.939775) (xy 94.006899 -180.88748) (xy 94.029541 -180.837903) (xy 94.059007 -180.792053)
			(xy 94.094698 -180.750862) (xy 94.135889 -180.715171) (xy 94.181739 -180.685705) (xy 94.231316 -180.663063)
			(xy 94.283611 -180.647708) (xy 94.337559 -180.639952) (xy 94.392061 -180.639952) (xy 94.446009 -180.647708)
			(xy 94.498304 -180.663063) (xy 94.547881 -180.685705) (xy 94.593731 -180.715171) (xy 94.634922 -180.750862)
			(xy 94.670613 -180.792053) (xy 94.700079 -180.837903) (xy 94.722721 -180.88748) (xy 94.738076 -180.939775)
			(xy 94.745832 -180.993723) (xy 94.746318 -181.020974) (xy 94.745868 -181.048886) (xy 94.737722 -181.104114)
			(xy 94.721617 -181.157565) (xy 94.697895 -181.208099) (xy 94.667063 -181.254637) (xy 94.648782 -181.275736)
			(xy 94.642868 -181.282901) (xy 94.636227 -181.300235) (xy 94.635828 -181.309518) (xy 94.635828 -181.387242)
			(xy 94.642432 -181.404514) (xy 94.648782 -181.411626) (xy 94.667044 -181.432739) (xy 94.697874 -181.479274)
			(xy 94.721593 -181.529805) (xy 94.737693 -181.583253) (xy 94.745831 -181.638478) (xy 94.746318 -181.666388)
			(xy 94.745832 -181.693639) (xy 94.738076 -181.747587) (xy 94.722721 -181.799882) (xy 94.700079 -181.849459)
			(xy 94.670613 -181.895309) (xy 94.634922 -181.9365) (xy 94.593731 -181.972191) (xy 94.547881 -182.001657)
			(xy 94.498304 -182.024299) (xy 94.446009 -182.039654) (xy 94.392061 -182.04741) (xy 94.337559 -182.04741)
			(xy 94.283611 -182.039654) (xy 94.231316 -182.024299) (xy 94.181739 -182.001657) (xy 94.135889 -181.972191)
			(xy 94.094698 -181.9365) (xy 94.059007 -181.895309) (xy 94.029541 -181.849459) (xy 94.006899 -181.799882)
			(xy 93.991544 -181.747587) (xy 93.983788 -181.693639) (xy 93.983302 -181.666388) (xy 88.762452 -181.666388)
			(xy 88.759925 -181.669255) (xy 88.739218 -181.68747) (xy 88.731159 -181.69504) (xy 88.721795 -181.71504)
			(xy 88.721184 -181.726078) (xy 88.721184 -181.803802) (xy 88.72178 -181.814849) (xy 88.731123 -181.834872)
			(xy 88.739218 -181.84241) (xy 88.759941 -181.860608) (xy 88.796409 -181.90198) (xy 88.82654 -181.948173)
			(xy 88.849703 -181.998223) (xy 88.865417 -182.051088) (xy 88.873354 -182.105665) (xy 88.873838 -182.13324)
			(xy 96.59874 -182.13324) (xy 96.599219 -182.105666) (xy 96.607167 -182.051093) (xy 96.622888 -181.998233)
			(xy 96.646056 -181.948186) (xy 96.676187 -181.901997) (xy 96.712653 -181.860626) (xy 96.73336 -181.84241)
			(xy 96.74144 -181.83486) (xy 96.750789 -181.814844) (xy 96.751394 -181.803802) (xy 96.751394 -181.726078)
			(xy 96.750784 -181.715034) (xy 96.741449 -181.695012) (xy 96.73336 -181.68747) (xy 96.712623 -181.669287)
			(xy 96.676157 -181.627911) (xy 96.646029 -181.581715) (xy 96.622868 -181.531662) (xy 96.607156 -181.478795)
			(xy 96.599222 -181.424216) (xy 96.59874 -181.39664) (xy 96.599286 -181.367028) (xy 96.608433 -181.308514)
			(xy 96.626512 -181.252118) (xy 96.653091 -181.199192) (xy 96.68753 -181.151011) (xy 96.729001 -181.10873)
			(xy 96.776508 -181.073367) (xy 96.802448 -181.059074) (xy 96.811846 -181.054248) (xy 96.825308 -181.036976)
			(xy 96.849184 -180.942742) (xy 96.845374 -180.92166) (xy 96.839278 -180.912516) (xy 96.824345 -180.889347)
			(xy 96.800704 -180.839554) (xy 96.784649 -180.786823) (xy 96.77653 -180.732304) (xy 96.776032 -180.704744)
			(xy 96.776475 -180.678125) (xy 96.784047 -180.625428) (xy 96.799042 -180.574346) (xy 96.821155 -180.525918)
			(xy 96.849937 -180.48113) (xy 96.8848 -180.440896) (xy 96.925035 -180.406033) (xy 96.969823 -180.377252)
			(xy 97.018251 -180.35514) (xy 97.069334 -180.340145) (xy 97.122031 -180.332575) (xy 97.14865 -180.332126)
			(xy 97.175072 -180.332572) (xy 97.227387 -180.340028) (xy 97.278125 -180.354796) (xy 97.326269 -180.376582)
			(xy 97.370854 -180.404948) (xy 97.39122 -180.421788) (xy 97.398078 -180.42763) (xy 97.415096 -180.43398)
			(xy 97.499424 -180.43398) (xy 97.516442 -180.42763) (xy 97.5233 -180.421788) (xy 97.543666 -180.404949)
			(xy 97.588252 -180.376584) (xy 97.636396 -180.354797) (xy 97.687133 -180.340026) (xy 97.739448 -180.332566)
			(xy 97.792292 -180.332566) (xy 97.844607 -180.340026) (xy 97.895344 -180.354797) (xy 97.943488 -180.376584)
			(xy 97.988074 -180.404949) (xy 98.00844 -180.421788) (xy 98.015298 -180.42763) (xy 98.032316 -180.43398)
			(xy 98.116644 -180.43398) (xy 98.133662 -180.42763) (xy 98.14052 -180.421788) (xy 98.160877 -180.404939)
			(xy 98.205469 -180.376586) (xy 98.253616 -180.354809) (xy 98.304354 -180.340044) (xy 98.356669 -180.332586)
			(xy 98.38309 -180.332126) (xy 98.410981 -180.332532) (xy 98.466139 -180.340845) (xy 98.519442 -180.357285)
			(xy 98.569699 -180.381487) (xy 98.615788 -180.412909) (xy 98.656679 -180.450849) (xy 98.691459 -180.49446)
			(xy 98.71935 -180.542767) (xy 98.739729 -180.594692) (xy 98.752142 -180.649075) (xy 98.756311 -180.7047)
			(xy 98.752142 -180.760325) (xy 98.739729 -180.814708) (xy 98.71935 -180.866633) (xy 98.691459 -180.91494)
			(xy 98.656679 -180.958551) (xy 98.615788 -180.996491) (xy 98.569699 -181.027913) (xy 98.519442 -181.052115)
			(xy 98.466139 -181.068555) (xy 98.410981 -181.076868) (xy 98.38309 -181.077362) (xy 98.356669 -181.076895)
			(xy 98.304354 -181.069445) (xy 98.253616 -181.054682) (xy 98.205472 -181.0329) (xy 98.160886 -181.004538)
			(xy 98.14052 -180.9877) (xy 98.133662 -180.981858) (xy 98.116644 -180.975508) (xy 98.032316 -180.975508)
			(xy 98.015298 -180.981858) (xy 98.00844 -180.9877) (xy 97.988074 -181.004539) (xy 97.943488 -181.032904)
			(xy 97.895344 -181.054691) (xy 97.844607 -181.069462) (xy 97.792292 -181.076922) (xy 97.739448 -181.076922)
			(xy 97.687133 -181.069462) (xy 97.636396 -181.054691) (xy 97.588252 -181.032904) (xy 97.543666 -181.004539)
			(xy 97.5233 -180.9877) (xy 97.516442 -180.981858) (xy 97.499424 -180.975508) (xy 97.415096 -180.975508)
			(xy 97.398078 -180.981858) (xy 97.39122 -180.9877) (xy 97.376369 -181.000042) (xy 97.344556 -181.021932)
			(xy 97.32772 -181.031388) (xy 97.318579 -181.036981) (xy 97.305692 -181.054081) (xy 97.302828 -181.064408)
			(xy 97.285556 -181.138068) (xy 97.283673 -181.148528) (xy 97.287623 -181.16939) (xy 97.293176 -181.178454)
			(xy 97.29343 -181.178708) (xy 97.309557 -181.202826) (xy 97.33509 -181.254922) (xy 97.352443 -181.310283)
			(xy 97.361218 -181.367632) (xy 97.361756 -181.39664) (xy 97.361264 -181.424214) (xy 97.353319 -181.478786)
			(xy 97.3376 -181.531646) (xy 97.314435 -181.581693) (xy 97.284307 -181.627883) (xy 97.247842 -181.669254)
			(xy 97.231467 -181.68366) (xy 102.375462 -181.68366) (xy 102.375938 -181.655749) (xy 102.384077 -181.600522)
			(xy 102.400177 -181.547072) (xy 102.423894 -181.496537) (xy 102.45472 -181.449998) (xy 102.472998 -181.428898)
			(xy 102.478895 -181.421721) (xy 102.485546 -181.404396) (xy 102.485952 -181.395116) (xy 102.485952 -181.317392)
			(xy 102.479348 -181.30012) (xy 102.472998 -181.293008) (xy 102.454702 -181.271923) (xy 102.423877 -181.225381)
			(xy 102.400165 -181.174842) (xy 102.384073 -181.121388) (xy 102.375944 -181.066158) (xy 102.375462 -181.038246)
			(xy 102.375948 -181.010995) (xy 102.383704 -180.957047) (xy 102.399059 -180.904752) (xy 102.421701 -180.855175)
			(xy 102.451167 -180.809325) (xy 102.486858 -180.768134) (xy 102.528049 -180.732443) (xy 102.573899 -180.702977)
			(xy 102.623476 -180.680335) (xy 102.675771 -180.66498) (xy 102.729719 -180.657224) (xy 102.784221 -180.657224)
			(xy 102.838169 -180.66498) (xy 102.890464 -180.680335) (xy 102.940041 -180.702977) (xy 102.985891 -180.732443)
			(xy 103.027082 -180.768134) (xy 103.062773 -180.809325) (xy 103.092239 -180.855175) (xy 103.114881 -180.904752)
			(xy 103.130236 -180.957047) (xy 103.137992 -181.010995) (xy 103.138478 -181.038246) (xy 103.137996 -181.066157)
			(xy 103.129856 -181.121383) (xy 103.113757 -181.174833) (xy 103.090043 -181.225367) (xy 103.059218 -181.271907)
			(xy 103.040942 -181.293008) (xy 103.035035 -181.300178) (xy 103.028392 -181.317509) (xy 103.027988 -181.32679)
			(xy 103.027988 -181.404514) (xy 103.034592 -181.421786) (xy 103.040942 -181.428898) (xy 103.0592 -181.450014)
			(xy 103.090029 -181.496549) (xy 103.113747 -181.547079) (xy 103.129849 -181.600527) (xy 103.137989 -181.65575)
			(xy 103.138478 -181.68366) (xy 103.137992 -181.710911) (xy 103.130236 -181.764859) (xy 103.114881 -181.817154)
			(xy 103.092239 -181.866731) (xy 103.062773 -181.912581) (xy 103.027082 -181.953772) (xy 102.985891 -181.989463)
			(xy 102.940041 -182.018929) (xy 102.890464 -182.041571) (xy 102.838169 -182.056926) (xy 102.784221 -182.064682)
			(xy 102.729719 -182.064682) (xy 102.675771 -182.056926) (xy 102.623476 -182.041571) (xy 102.573899 -182.018929)
			(xy 102.528049 -181.989463) (xy 102.486858 -181.953772) (xy 102.451167 -181.912581) (xy 102.421701 -181.866731)
			(xy 102.399059 -181.817154) (xy 102.383704 -181.764859) (xy 102.375948 -181.710911) (xy 102.375462 -181.68366)
			(xy 97.231467 -181.68366) (xy 97.227136 -181.68747) (xy 97.219064 -181.695027) (xy 97.20971 -181.715037)
			(xy 97.209102 -181.726078) (xy 97.209102 -181.803802) (xy 97.209724 -181.814845) (xy 97.219051 -181.834866)
			(xy 97.227136 -181.84241) (xy 97.247862 -181.860604) (xy 97.28433 -181.901978) (xy 97.314459 -181.948171)
			(xy 97.337622 -181.998222) (xy 97.353336 -182.051088) (xy 97.361272 -182.105664) (xy 97.361756 -182.13324)
			(xy 97.36127 -182.160491) (xy 97.353514 -182.214439) (xy 97.338159 -182.266734) (xy 97.329525 -182.28564)
			(xy 121.299224 -182.28564) (xy 121.299708 -182.25827) (xy 121.30752 -182.204092) (xy 121.323005 -182.151589)
			(xy 121.345843 -182.101841) (xy 121.375564 -182.055874) (xy 121.393204 -182.034942) (xy 121.393458 -182.034688)
			(xy 121.399063 -182.027614) (xy 121.405297 -182.010687) (xy 121.40565 -182.001668) (xy 121.40565 -181.934612)
			(xy 121.405298 -181.925594) (xy 121.399048 -181.908677) (xy 121.393458 -181.901592) (xy 121.393204 -181.901592)
			(xy 121.393204 -181.901338) (xy 121.375603 -181.880373) (xy 121.345879 -181.83441) (xy 121.323032 -181.784669)
			(xy 121.307534 -181.732172) (xy 121.299702 -181.677999) (xy 121.299698 -181.623262) (xy 121.307521 -181.569087)
			(xy 121.323011 -181.516587) (xy 121.34585 -181.466843) (xy 121.375567 -181.420875) (xy 121.393204 -181.399942)
			(xy 121.393458 -181.399688) (xy 121.399063 -181.392614) (xy 121.405297 -181.375687) (xy 121.40565 -181.366668)
			(xy 121.40565 -181.299612) (xy 121.405298 -181.290594) (xy 121.399048 -181.273677) (xy 121.393458 -181.266592)
			(xy 121.393204 -181.266592) (xy 121.393204 -181.266338) (xy 121.375603 -181.245373) (xy 121.345879 -181.19941)
			(xy 121.323032 -181.149669) (xy 121.307534 -181.097172) (xy 121.299702 -181.042999) (xy 121.299698 -180.988262)
			(xy 121.307521 -180.934087) (xy 121.323011 -180.881587) (xy 121.34585 -180.831843) (xy 121.375567 -180.785875)
			(xy 121.393204 -180.764942) (xy 121.393458 -180.764688) (xy 121.399063 -180.757614) (xy 121.405297 -180.740687)
			(xy 121.40565 -180.731668) (xy 121.40565 -180.664612) (xy 121.405298 -180.655594) (xy 121.399048 -180.638677)
			(xy 121.393458 -180.631592) (xy 121.393204 -180.631592) (xy 121.393204 -180.631338) (xy 121.375603 -180.610373)
			(xy 121.345879 -180.56441) (xy 121.323032 -180.514669) (xy 121.307534 -180.462172) (xy 121.299702 -180.407999)
			(xy 121.299698 -180.353262) (xy 121.307521 -180.299087) (xy 121.323011 -180.246587) (xy 121.34585 -180.196843)
			(xy 121.375567 -180.150875) (xy 121.393204 -180.129942) (xy 121.393458 -180.129688) (xy 121.399063 -180.122614)
			(xy 121.405297 -180.105687) (xy 121.40565 -180.096668) (xy 121.40565 -180.029612) (xy 121.405298 -180.020594)
			(xy 121.399048 -180.003677) (xy 121.393458 -179.996592) (xy 121.393204 -179.996592) (xy 121.393204 -179.996338)
			(xy 121.375603 -179.975373) (xy 121.345879 -179.92941) (xy 121.323032 -179.879669) (xy 121.307534 -179.827172)
			(xy 121.299702 -179.772999) (xy 121.299698 -179.718262) (xy 121.307521 -179.664087) (xy 121.323011 -179.611587)
			(xy 121.34585 -179.561843) (xy 121.375567 -179.515875) (xy 121.393204 -179.494942) (xy 121.393458 -179.494688)
			(xy 121.399063 -179.487614) (xy 121.405297 -179.470687) (xy 121.40565 -179.461668) (xy 121.40565 -179.394612)
			(xy 121.405298 -179.385594) (xy 121.399048 -179.368677) (xy 121.393458 -179.361592) (xy 121.393204 -179.361592)
			(xy 121.393204 -179.361338) (xy 121.375603 -179.340373) (xy 121.345879 -179.29441) (xy 121.323032 -179.244669)
			(xy 121.307534 -179.192172) (xy 121.299702 -179.137999) (xy 121.299698 -179.083262) (xy 121.307521 -179.029087)
			(xy 121.323011 -178.976587) (xy 121.34585 -178.926843) (xy 121.375567 -178.880875) (xy 121.393204 -178.859942)
			(xy 121.393458 -178.859688) (xy 121.399063 -178.852614) (xy 121.405297 -178.835687) (xy 121.40565 -178.826668)
			(xy 121.40565 -178.759612) (xy 121.405298 -178.750594) (xy 121.399048 -178.733677) (xy 121.393458 -178.726592)
			(xy 121.393204 -178.726592) (xy 121.393204 -178.726338) (xy 121.375603 -178.705373) (xy 121.345879 -178.65941)
			(xy 121.323032 -178.609669) (xy 121.307534 -178.557172) (xy 121.299702 -178.502999) (xy 121.299698 -178.448262)
			(xy 121.307521 -178.394087) (xy 121.323011 -178.341587) (xy 121.34585 -178.291843) (xy 121.375567 -178.245875)
			(xy 121.393204 -178.224942) (xy 121.393458 -178.224688) (xy 121.399063 -178.217614) (xy 121.405297 -178.200687)
			(xy 121.40565 -178.191668) (xy 121.40565 -178.124612) (xy 121.405298 -178.115594) (xy 121.399048 -178.098677)
			(xy 121.393458 -178.091592) (xy 121.393204 -178.091592) (xy 121.393204 -178.091338) (xy 121.37557 -178.070402)
			(xy 121.345857 -178.02443) (xy 121.32302 -177.974684) (xy 121.307528 -177.922184) (xy 121.299699 -177.868009)
			(xy 121.299224 -177.84064) (xy 121.29977 -177.811474) (xy 121.308667 -177.753823) (xy 121.326243 -177.698201)
			(xy 121.352088 -177.645906) (xy 121.385599 -177.59816) (xy 121.405396 -177.576734) (xy 121.411739 -177.569387)
			(xy 121.418931 -177.551377) (xy 121.419366 -177.541682) (xy 121.419366 -177.461164) (xy 121.412254 -177.44313)
			(xy 121.405396 -177.436018) (xy 121.385611 -177.414586) (xy 121.352127 -177.366827) (xy 121.326295 -177.314532)
			(xy 121.308716 -177.258917) (xy 121.299799 -177.201275) (xy 121.299224 -177.172112) (xy 121.299667 -177.144858)
			(xy 121.307423 -177.090905) (xy 121.322779 -177.038604) (xy 121.345422 -176.989022) (xy 121.374892 -176.943168)
			(xy 121.410588 -176.901974) (xy 121.451784 -176.86628) (xy 121.49764 -176.836813) (xy 121.547223 -176.814172)
			(xy 121.599524 -176.798818) (xy 121.653478 -176.791065) (xy 121.680732 -176.790604) (xy 121.708103 -176.79105)
			(xy 121.762283 -176.798873) (xy 121.814786 -176.814366) (xy 121.864533 -176.837213) (xy 121.910499 -176.866941)
			(xy 121.93143 -176.884584) (xy 121.931684 -176.884838) (xy 121.938768 -176.890428) (xy 121.955687 -176.896672)
			(xy 121.964704 -176.89703) (xy 122.03176 -176.89703) (xy 122.040774 -176.896647) (xy 122.057691 -176.890417)
			(xy 122.06478 -176.884838) (xy 122.06478 -176.884584) (xy 122.065034 -176.884584) (xy 122.085967 -176.866943)
			(xy 122.131935 -176.837219) (xy 122.181681 -176.814373) (xy 122.234183 -176.798877) (xy 122.288361 -176.791048)
			(xy 122.343103 -176.791048) (xy 122.397281 -176.798877) (xy 122.449783 -176.814373) (xy 122.499529 -176.837219)
			(xy 122.545497 -176.866943) (xy 122.56643 -176.884584) (xy 122.566684 -176.884838) (xy 122.573768 -176.890428)
			(xy 122.590687 -176.896672) (xy 122.599704 -176.89703) (xy 122.66676 -176.89703) (xy 122.675774 -176.896647)
			(xy 122.692691 -176.890417) (xy 122.69978 -176.884838) (xy 122.69978 -176.884584) (xy 122.700034 -176.884584)
			(xy 122.720978 -176.86696) (xy 122.766948 -176.837246) (xy 122.816692 -176.814408) (xy 122.86919 -176.798913)
			(xy 122.923364 -176.791081) (xy 122.950732 -176.790604) (xy 122.977985 -176.791048) (xy 123.031934 -176.798809)
			(xy 123.084231 -176.814169) (xy 123.133809 -176.836815) (xy 123.17966 -176.866286) (xy 123.22085 -176.901981)
			(xy 123.256541 -176.943176) (xy 123.286006 -176.98903) (xy 123.308646 -177.038611) (xy 123.324 -177.090909)
			(xy 123.331755 -177.144859) (xy 123.33224 -177.172112) (xy 125.312424 -177.172112) (xy 125.312867 -177.144858)
			(xy 125.320623 -177.090905) (xy 125.335979 -177.038604) (xy 125.358622 -176.989022) (xy 125.388092 -176.943168)
			(xy 125.423788 -176.901974) (xy 125.464984 -176.86628) (xy 125.51084 -176.836813) (xy 125.560423 -176.814172)
			(xy 125.612724 -176.798818) (xy 125.666678 -176.791065) (xy 125.693932 -176.790604) (xy 125.721303 -176.79105)
			(xy 125.775483 -176.798873) (xy 125.827986 -176.814366) (xy 125.877733 -176.837213) (xy 125.923699 -176.866941)
			(xy 125.94463 -176.884584) (xy 125.944884 -176.884838) (xy 125.951968 -176.890428) (xy 125.968887 -176.896672)
			(xy 125.977904 -176.89703) (xy 126.04496 -176.89703) (xy 126.053974 -176.896647) (xy 126.070891 -176.890417)
			(xy 126.07798 -176.884838) (xy 126.07798 -176.884584) (xy 126.078234 -176.884584) (xy 126.099167 -176.866943)
			(xy 126.145135 -176.837219) (xy 126.194881 -176.814373) (xy 126.247383 -176.798877) (xy 126.301561 -176.791048)
			(xy 126.356303 -176.791048) (xy 126.410481 -176.798877) (xy 126.462983 -176.814373) (xy 126.512729 -176.837219)
			(xy 126.558697 -176.866943) (xy 126.57963 -176.884584) (xy 126.579884 -176.884838) (xy 126.586968 -176.890428)
			(xy 126.603887 -176.896672) (xy 126.612904 -176.89703) (xy 126.67996 -176.89703) (xy 126.688974 -176.896647)
			(xy 126.705891 -176.890417) (xy 126.71298 -176.884838) (xy 126.71298 -176.884584) (xy 126.713234 -176.884584)
			(xy 126.734178 -176.86696) (xy 126.780148 -176.837246) (xy 126.829892 -176.814408) (xy 126.88239 -176.798913)
			(xy 126.936564 -176.791081) (xy 126.963932 -176.790604) (xy 126.991185 -176.791048) (xy 127.045134 -176.798809)
			(xy 127.097431 -176.814169) (xy 127.147009 -176.836815) (xy 127.19286 -176.866286) (xy 127.23405 -176.901981)
			(xy 127.269741 -176.943176) (xy 127.299206 -176.98903) (xy 127.321846 -177.038611) (xy 127.3372 -177.090909)
			(xy 127.344955 -177.144859) (xy 127.34544 -177.172112) (xy 127.344905 -177.201231) (xy 127.336058 -177.258792)
			(xy 127.31857 -177.314341) (xy 127.292849 -177.366591) (xy 127.25949 -177.414327) (xy 127.239776 -177.435764)
			(xy 127.232918 -177.442876) (xy 127.225552 -177.461164) (xy 127.225806 -177.54092) (xy 127.226254 -177.550709)
			(xy 127.233555 -177.568872) (xy 127.24003 -177.576226) (xy 127.259872 -177.59769) (xy 127.293469 -177.64552)
			(xy 127.319378 -177.697914) (xy 127.336993 -177.753647) (xy 127.345901 -177.811415) (xy 127.346456 -177.84064)
			(xy 127.345965 -177.868009) (xy 127.338155 -177.922188) (xy 127.322672 -177.974691) (xy 127.299836 -178.024439)
			(xy 127.270115 -178.070406) (xy 127.252476 -178.091338) (xy 127.252222 -178.091592) (xy 127.246624 -178.09867)
			(xy 127.240386 -178.115594) (xy 127.24003 -178.124612) (xy 127.24003 -178.191668) (xy 127.240396 -178.200684)
			(xy 127.246637 -178.217601) (xy 127.252222 -178.224688) (xy 127.252476 -178.224688) (xy 127.252476 -178.224942)
			(xy 127.270156 -178.245843) (xy 127.299879 -178.291816) (xy 127.322722 -178.341568) (xy 127.338215 -178.394075)
			(xy 127.346039 -178.448258) (xy 127.346035 -178.503003) (xy 127.338202 -178.557184) (xy 127.3227 -178.609689)
			(xy 127.29985 -178.659436) (xy 127.270119 -178.705405) (xy 127.252476 -178.726338) (xy 127.252222 -178.726592)
			(xy 127.246624 -178.73367) (xy 127.240386 -178.750594) (xy 127.24003 -178.759612) (xy 127.24003 -178.826668)
			(xy 127.240396 -178.835684) (xy 127.246637 -178.852601) (xy 127.252222 -178.859688) (xy 127.252476 -178.859688)
			(xy 127.252476 -178.859942) (xy 127.270098 -178.880888) (xy 127.299813 -178.926857) (xy 127.322653 -178.976601)
			(xy 127.338148 -179.029098) (xy 127.34598 -179.083272) (xy 127.346456 -179.11064) (xy 127.34596 -179.13789)
			(xy 127.338199 -179.191835) (xy 127.322841 -179.244126) (xy 127.300199 -179.293701) (xy 127.270733 -179.339549)
			(xy 127.235043 -179.380737) (xy 127.193855 -179.416428) (xy 127.148008 -179.445895) (xy 127.098434 -179.468538)
			(xy 127.046143 -179.483897) (xy 126.992198 -179.491659) (xy 126.964948 -179.492148) (xy 126.935506 -179.4916)
			(xy 126.877322 -179.482559) (xy 126.821217 -179.464683) (xy 126.768527 -179.438398) (xy 126.720501 -179.404329)
			(xy 126.69901 -179.384198) (xy 126.692234 -179.378119) (xy 126.675561 -179.370838) (xy 126.666498 -179.369974)
			(xy 126.590298 -179.36591) (xy 126.573026 -179.371244) (xy 126.56566 -179.377086) (xy 126.545426 -179.392476)
			(xy 126.501634 -179.418299) (xy 126.454801 -179.438076) (xy 126.405755 -179.451457) (xy 126.355367 -179.458203)
			(xy 126.329948 -179.45862) (xy 126.302578 -179.458145) (xy 126.248398 -179.450333) (xy 126.195895 -179.434847)
			(xy 126.146147 -179.412006) (xy 126.100181 -179.382282) (xy 126.07925 -179.36464) (xy 126.078996 -179.364386)
			(xy 126.071916 -179.35879) (xy 126.054994 -179.352549) (xy 126.045976 -179.352194) (xy 125.97892 -179.352194)
			(xy 125.969904 -179.352562) (xy 125.952987 -179.358802) (xy 125.9459 -179.364386) (xy 125.9459 -179.36464)
			(xy 125.945646 -179.36464) (xy 125.924713 -179.382278) (xy 125.87874 -179.411988) (xy 125.828992 -179.434824)
			(xy 125.776492 -179.450316) (xy 125.722317 -179.458145) (xy 125.694948 -179.45862) (xy 125.667697 -179.4581)
			(xy 125.613749 -179.45035) (xy 125.561453 -179.435001) (xy 125.511873 -179.412365) (xy 125.466021 -179.382903)
			(xy 125.424828 -179.347215) (xy 125.389133 -179.306028) (xy 125.359664 -179.260179) (xy 125.33702 -179.210604)
			(xy 125.321663 -179.15831) (xy 125.313904 -179.104363) (xy 125.31344 -179.077112) (xy 125.313903 -179.049742)
			(xy 125.32172 -178.995562) (xy 125.33721 -178.943058) (xy 125.360052 -178.893312) (xy 125.389778 -178.847345)
			(xy 125.40742 -178.826414) (xy 125.407674 -178.82616) (xy 125.41325 -178.819067) (xy 125.419501 -178.802155)
			(xy 125.419866 -178.79314) (xy 125.419866 -178.726084) (xy 125.419524 -178.717065) (xy 125.413267 -178.700148)
			(xy 125.407674 -178.693064) (xy 125.40742 -178.693064) (xy 125.40742 -178.69281) (xy 125.389791 -178.671868)
			(xy 125.360067 -178.625901) (xy 125.337221 -178.576157) (xy 125.321724 -178.523656) (xy 125.313895 -178.469479)
			(xy 125.313893 -178.414739) (xy 125.32172 -178.360562) (xy 125.337215 -178.30806) (xy 125.360058 -178.258315)
			(xy 125.38978 -178.212347) (xy 125.40742 -178.191414) (xy 125.407674 -178.19116) (xy 125.41325 -178.184067)
			(xy 125.419501 -178.167155) (xy 125.419866 -178.15814) (xy 125.419866 -178.091084) (xy 125.419524 -178.082065)
			(xy 125.413267 -178.065148) (xy 125.407674 -178.058064) (xy 125.40742 -178.058064) (xy 125.40742 -178.05781)
			(xy 125.389775 -178.036882) (xy 125.360064 -177.990909) (xy 125.337228 -177.94116) (xy 125.321739 -177.888658)
			(xy 125.313913 -177.834482) (xy 125.31344 -177.807112) (xy 125.313921 -177.779813) (xy 125.321692 -177.725771)
			(xy 125.33709 -177.67339) (xy 125.359802 -177.62374) (xy 125.389362 -177.577837) (xy 125.406912 -177.556922)
			(xy 125.41276 -177.549735) (xy 125.419265 -177.5324) (xy 125.419612 -177.52314) (xy 125.419358 -177.447194)
			(xy 125.413008 -177.430176) (xy 125.406912 -177.423318) (xy 125.389209 -177.402348) (xy 125.359328 -177.356319)
			(xy 125.336359 -177.306479) (xy 125.320777 -177.253861) (xy 125.312903 -177.199551) (xy 125.312424 -177.172112)
			(xy 123.33224 -177.172112) (xy 123.331753 -177.199411) (xy 123.323981 -177.253451) (xy 123.308583 -177.305832)
			(xy 123.285873 -177.355481) (xy 123.256316 -177.401386) (xy 123.238768 -177.422302) (xy 123.23295 -177.42951)
			(xy 123.226428 -177.446829) (xy 123.226068 -177.456084) (xy 123.226322 -177.53203) (xy 123.232672 -177.549048)
			(xy 123.238768 -177.555906) (xy 123.25648 -177.576869) (xy 123.28636 -177.6229) (xy 123.309327 -177.672741)
			(xy 123.324908 -177.725362) (xy 123.332778 -177.779673) (xy 123.333256 -177.807112) (xy 123.332808 -177.834483)
			(xy 123.324987 -177.888663) (xy 123.309495 -177.941167) (xy 123.286649 -177.990914) (xy 123.25692 -178.036879)
			(xy 123.239276 -178.05781) (xy 123.239022 -178.058064) (xy 123.233435 -178.06515) (xy 123.227191 -178.082068)
			(xy 123.22683 -178.091084) (xy 123.22683 -178.15814) (xy 123.227161 -178.16716) (xy 123.233426 -178.184077)
			(xy 123.239022 -178.19116) (xy 123.239276 -178.19116) (xy 123.239276 -178.191414) (xy 123.256928 -178.212337)
			(xy 123.286652 -178.258307) (xy 123.309497 -178.308055) (xy 123.324992 -178.360558) (xy 123.33282 -178.414738)
			(xy 123.332818 -178.46948) (xy 123.324988 -178.52366) (xy 123.309491 -178.576162) (xy 123.286644 -178.625909)
			(xy 123.256917 -178.671877) (xy 123.239276 -178.69281) (xy 123.239022 -178.693064) (xy 123.233435 -178.70015)
			(xy 123.227191 -178.717068) (xy 123.22683 -178.726084) (xy 123.22683 -178.79314) (xy 123.227161 -178.80216)
			(xy 123.233426 -178.819077) (xy 123.239022 -178.82616) (xy 123.239276 -178.82616) (xy 123.239276 -178.826414)
			(xy 123.256928 -178.847337) (xy 123.286652 -178.893307) (xy 123.309497 -178.943055) (xy 123.324992 -178.995558)
			(xy 123.33282 -179.049738) (xy 123.332818 -179.10448) (xy 123.324988 -179.15866) (xy 123.309491 -179.211162)
			(xy 123.286644 -179.260909) (xy 123.256917 -179.306877) (xy 123.239276 -179.32781) (xy 123.239022 -179.328064)
			(xy 123.233435 -179.33515) (xy 123.227191 -179.352068) (xy 123.22683 -179.361084) (xy 123.22683 -179.42814)
			(xy 123.227161 -179.43716) (xy 123.233426 -179.454077) (xy 123.239022 -179.46116) (xy 123.239276 -179.46116)
			(xy 123.239276 -179.461414) (xy 123.256885 -179.482371) (xy 123.286602 -179.528336) (xy 123.309444 -179.578078)
			(xy 123.324942 -179.630573) (xy 123.332778 -179.684744) (xy 123.333256 -179.712112) (xy 123.33272 -179.741337)
			(xy 123.323795 -179.799103) (xy 123.306173 -179.854833) (xy 123.280264 -179.907228) (xy 123.246673 -179.955062)
			(xy 123.22683 -179.976526) (xy 123.22037 -179.983891) (xy 123.213055 -180.002046) (xy 123.212606 -180.011832)
			(xy 123.212352 -180.091588) (xy 123.219718 -180.109876) (xy 123.226576 -180.116988) (xy 123.246304 -180.138413)
			(xy 123.279658 -180.186153) (xy 123.305373 -180.238406) (xy 123.322854 -180.293958) (xy 123.331694 -180.351521)
			(xy 123.33224 -180.38064) (xy 123.331753 -180.40801) (xy 123.323943 -180.462188) (xy 123.308459 -180.514692)
			(xy 123.285622 -180.564439) (xy 123.2559 -180.610406) (xy 123.23826 -180.631338) (xy 123.238006 -180.631592)
			(xy 123.232417 -180.638677) (xy 123.226172 -180.655595) (xy 123.225814 -180.664612) (xy 123.225814 -180.731668)
			(xy 123.226184 -180.740684) (xy 123.232422 -180.757601) (xy 123.238006 -180.764688) (xy 123.23826 -180.764688)
			(xy 123.23826 -180.764942) (xy 123.25594 -180.785843) (xy 123.285665 -180.831816) (xy 123.308508 -180.881567)
			(xy 123.324002 -180.934074) (xy 123.331827 -180.988257) (xy 123.331823 -181.043003) (xy 123.323989 -181.097185)
			(xy 123.308487 -181.149689) (xy 123.285636 -181.199437) (xy 123.255904 -181.245405) (xy 123.23826 -181.266338)
			(xy 123.238006 -181.266592) (xy 123.232417 -181.273677) (xy 123.226172 -181.290595) (xy 123.225814 -181.299612)
			(xy 123.225814 -181.366668) (xy 123.226184 -181.375684) (xy 123.232422 -181.392601) (xy 123.238006 -181.399688)
			(xy 123.23826 -181.399688) (xy 123.23826 -181.399942) (xy 123.255879 -181.42089) (xy 123.285595 -181.466858)
			(xy 123.308436 -181.516601) (xy 123.323931 -181.569099) (xy 123.331764 -181.623272) (xy 123.33224 -181.65064)
			(xy 123.331759 -181.677891) (xy 123.323998 -181.731837) (xy 123.30864 -181.78413) (xy 123.285996 -181.833705)
			(xy 123.256529 -181.879554) (xy 123.220837 -181.920743) (xy 123.179647 -181.956434) (xy 123.133798 -181.9859)
			(xy 123.084222 -182.008543) (xy 123.031929 -182.0239) (xy 122.977983 -182.03166) (xy 122.950732 -182.032148)
			(xy 122.923362 -182.031676) (xy 122.869183 -182.023861) (xy 122.816679 -182.008374) (xy 122.766932 -181.985534)
			(xy 122.720965 -181.955809) (xy 122.700034 -181.938168) (xy 122.69978 -181.937914) (xy 122.692702 -181.932314)
			(xy 122.675779 -181.926075) (xy 122.66676 -181.925722) (xy 122.599704 -181.925722) (xy 122.590687 -181.926076)
			(xy 122.573769 -181.932325) (xy 122.566684 -181.937914) (xy 122.566684 -181.938168) (xy 122.56643 -181.938168)
			(xy 122.545493 -181.955802) (xy 122.499522 -181.985515) (xy 122.449776 -182.008353) (xy 122.397276 -182.023845)
			(xy 122.343101 -182.031674) (xy 122.315732 -182.032148) (xy 122.286254 -182.031603) (xy 122.228001 -182.022537)
			(xy 122.171836 -182.004617) (xy 122.119096 -181.978268) (xy 122.071039 -181.944119) (xy 122.04954 -181.923944)
			(xy 122.042193 -181.917426) (xy 122.024042 -181.909973) (xy 122.014234 -181.909466) (xy 121.960894 -181.909466)
			(xy 121.954036 -181.916832) (xy 121.947486 -181.924154) (xy 121.940052 -181.942324) (xy 121.939558 -181.952138)
			(xy 121.939558 -181.984142) (xy 121.940043 -181.993956) (xy 121.94749 -182.01212) (xy 121.954036 -182.019448)
			(xy 121.97423 -182.040929) (xy 122.008372 -182.088993) (xy 122.034715 -182.141737) (xy 122.052632 -182.197906)
			(xy 122.061694 -182.256162) (xy 122.06224 -182.28564) (xy 122.061754 -182.312891) (xy 122.053998 -182.366839)
			(xy 122.038643 -182.419134) (xy 122.016001 -182.468711) (xy 121.986535 -182.514561) (xy 121.950844 -182.555752)
			(xy 121.909653 -182.591443) (xy 121.863803 -182.620909) (xy 121.814226 -182.643551) (xy 121.761931 -182.658906)
			(xy 121.707983 -182.666662) (xy 121.653481 -182.666662) (xy 121.599533 -182.658906) (xy 121.547238 -182.643551)
			(xy 121.497661 -182.620909) (xy 121.451811 -182.591443) (xy 121.41062 -182.555752) (xy 121.374929 -182.514561)
			(xy 121.345463 -182.468711) (xy 121.322821 -182.419134) (xy 121.307466 -182.366839) (xy 121.29971 -182.312891)
			(xy 121.299224 -182.28564) (xy 97.329525 -182.28564) (xy 97.315517 -182.316311) (xy 97.286051 -182.362161)
			(xy 97.25036 -182.403352) (xy 97.209169 -182.439043) (xy 97.163319 -182.468509) (xy 97.113742 -182.491151)
			(xy 97.061447 -182.506506) (xy 97.007499 -182.514262) (xy 96.952997 -182.514262) (xy 96.899049 -182.506506)
			(xy 96.846754 -182.491151) (xy 96.797177 -182.468509) (xy 96.751327 -182.439043) (xy 96.710136 -182.403352)
			(xy 96.674445 -182.362161) (xy 96.644979 -182.316311) (xy 96.622337 -182.266734) (xy 96.606982 -182.214439)
			(xy 96.599226 -182.160491) (xy 96.59874 -182.13324) (xy 88.873838 -182.13324) (xy 88.873352 -182.160491)
			(xy 88.865596 -182.214439) (xy 88.850241 -182.266734) (xy 88.827599 -182.316311) (xy 88.798133 -182.362161)
			(xy 88.762442 -182.403352) (xy 88.721251 -182.439043) (xy 88.675401 -182.468509) (xy 88.625824 -182.491151)
			(xy 88.573529 -182.506506) (xy 88.519581 -182.514262) (xy 88.465079 -182.514262) (xy 88.411131 -182.506506)
			(xy 88.358836 -182.491151) (xy 88.309259 -182.468509) (xy 88.263409 -182.439043) (xy 88.222218 -182.403352)
			(xy 88.186527 -182.362161) (xy 88.157061 -182.316311) (xy 88.134419 -182.266734) (xy 88.119064 -182.214439)
			(xy 88.111308 -182.160491) (xy 88.110822 -182.13324) (xy 80.613476 -182.13324) (xy 80.614728 -182.137452)
			(xy 80.622669 -182.192026) (xy 80.623156 -182.2196) (xy 80.62267 -182.246851) (xy 80.614914 -182.300799)
			(xy 80.599559 -182.353094) (xy 80.576917 -182.402671) (xy 80.547451 -182.448521) (xy 80.51176 -182.489712)
			(xy 80.470569 -182.525403) (xy 80.424719 -182.554869) (xy 80.375142 -182.577511) (xy 80.322847 -182.592866)
			(xy 80.268899 -182.600622) (xy 80.214397 -182.600622) (xy 80.160449 -182.592866) (xy 80.108154 -182.577511)
			(xy 80.058577 -182.554869) (xy 80.012727 -182.525403) (xy 79.971536 -182.489712) (xy 79.935845 -182.448521)
			(xy 79.906379 -182.402671) (xy 79.883737 -182.353094) (xy 79.868382 -182.300799) (xy 79.860626 -182.246851)
			(xy 79.86014 -182.2196) (xy 67.915356 -182.2196) (xy 67.909555 -182.259748) (xy 67.894058 -182.312251)
			(xy 67.871211 -182.361997) (xy 67.841484 -182.407964) (xy 67.823842 -182.428896) (xy 67.823588 -182.42915)
			(xy 67.818015 -182.436246) (xy 67.81176 -182.453156) (xy 67.811396 -182.46217) (xy 67.811396 -182.529226)
			(xy 67.811742 -182.538244) (xy 67.817997 -182.555161) (xy 67.823588 -182.562246) (xy 67.823842 -182.562246)
			(xy 67.823842 -182.5625) (xy 67.841482 -182.583434) (xy 67.871209 -182.629401) (xy 67.894057 -182.679146)
			(xy 67.909554 -182.731649) (xy 67.917384 -182.785828) (xy 67.917384 -182.840569) (xy 67.909555 -182.894748)
			(xy 67.894058 -182.947251) (xy 67.871211 -182.996997) (xy 67.841484 -183.042964) (xy 67.823842 -183.063896)
			(xy 67.823588 -183.06415) (xy 67.818015 -183.071246) (xy 67.81176 -183.088156) (xy 67.811396 -183.09717)
			(xy 67.811396 -183.164226) (xy 67.811742 -183.173244) (xy 67.817997 -183.190161) (xy 67.823588 -183.197246)
			(xy 67.823842 -183.197246) (xy 67.823842 -183.1975) (xy 67.841501 -183.218416) (xy 67.871209 -183.264394)
			(xy 67.89404 -183.314145) (xy 67.909527 -183.366649) (xy 67.917351 -183.420828) (xy 67.917822 -183.448198)
			(xy 67.917258 -183.477471) (xy 67.908294 -183.535328) (xy 67.890592 -183.591135) (xy 67.864566 -183.643579)
			(xy 67.83083 -183.69143) (xy 67.810888 -183.712866) (xy 67.810634 -183.71312) (xy 67.804671 -183.720007)
			(xy 67.79765 -183.736805) (xy 67.796918 -183.745886) (xy 67.793616 -183.822848) (xy 67.799458 -183.840374)
			(xy 67.8053 -183.84774) (xy 67.821526 -183.86824) (xy 67.848782 -183.912855) (xy 67.869683 -183.960777)
			(xy 67.883836 -184.011107) (xy 67.890978 -184.062899) (xy 67.891406 -184.08904) (xy 67.890903 -184.116409)
			(xy 67.883094 -184.170586) (xy 67.867613 -184.223089) (xy 67.84478 -184.272836) (xy 67.815063 -184.318805)
			(xy 67.797426 -184.339738) (xy 67.797172 -184.339992) (xy 67.79158 -184.347074) (xy 67.785337 -184.363994)
			(xy 67.78498 -184.373012) (xy 67.78498 -184.440068) (xy 67.785357 -184.449083) (xy 67.791591 -184.466)
			(xy 67.797172 -184.473088) (xy 67.797426 -184.473088) (xy 67.797426 -184.473342) (xy 67.815108 -184.494242)
			(xy 67.844835 -184.540214) (xy 67.86768 -184.589966) (xy 67.883176 -184.642473) (xy 67.891002 -184.696657)
			(xy 67.890997 -184.751403) (xy 67.883163 -184.805586) (xy 67.867659 -184.858091) (xy 67.844806 -184.907839)
			(xy 67.815071 -184.953806) (xy 67.797426 -184.974738) (xy 67.797172 -184.974992) (xy 67.79158 -184.982074)
			(xy 67.785337 -184.998994) (xy 67.78498 -185.008012) (xy 67.78498 -185.075068) (xy 67.785357 -185.084083)
			(xy 67.791591 -185.101) (xy 67.797172 -185.108088) (xy 67.797426 -185.108088) (xy 67.797426 -185.108342)
			(xy 67.815108 -185.129242) (xy 67.844835 -185.175214) (xy 67.86768 -185.224966) (xy 67.883176 -185.277473)
			(xy 67.891002 -185.331657) (xy 67.890997 -185.386403) (xy 67.883163 -185.440586) (xy 67.867659 -185.493091)
			(xy 67.844806 -185.542839) (xy 67.815071 -185.588806) (xy 67.797426 -185.609738) (xy 67.797172 -185.609992)
			(xy 67.79158 -185.617074) (xy 67.785337 -185.633994) (xy 67.78498 -185.643012) (xy 67.78498 -185.710068)
			(xy 67.785357 -185.719083) (xy 67.791591 -185.736) (xy 67.797172 -185.743088) (xy 67.797426 -185.743088)
			(xy 67.797426 -185.743342) (xy 67.815108 -185.764242) (xy 67.844835 -185.810214) (xy 67.86768 -185.859966)
			(xy 67.883176 -185.912473) (xy 67.891002 -185.966657) (xy 67.890997 -186.021403) (xy 67.883163 -186.075586)
			(xy 67.867659 -186.128091) (xy 67.844806 -186.177839) (xy 67.815071 -186.223806) (xy 67.797426 -186.244738)
			(xy 67.797172 -186.244992) (xy 67.79158 -186.252074) (xy 67.785337 -186.268994) (xy 67.78498 -186.278012)
			(xy 67.78498 -186.345068) (xy 67.785357 -186.354083) (xy 67.791591 -186.371) (xy 67.797172 -186.378088)
			(xy 67.797426 -186.378088) (xy 67.797426 -186.378342) (xy 67.815108 -186.399242) (xy 67.844835 -186.445214)
			(xy 67.86768 -186.494966) (xy 67.883176 -186.547473) (xy 67.891002 -186.601657) (xy 67.890997 -186.656403)
			(xy 67.883163 -186.710586) (xy 67.867659 -186.763091) (xy 67.844806 -186.812839) (xy 67.815071 -186.858806)
			(xy 67.797426 -186.879738) (xy 67.797172 -186.879992) (xy 67.79158 -186.887074) (xy 67.785337 -186.903994)
			(xy 67.78498 -186.913012) (xy 67.78498 -186.980068) (xy 67.785357 -186.989083) (xy 67.791591 -187.006)
			(xy 67.797172 -187.013088) (xy 67.797426 -187.013088) (xy 67.797426 -187.013342) (xy 67.815055 -187.034282)
			(xy 67.844768 -187.080253) (xy 67.867605 -187.129998) (xy 67.883099 -187.182497) (xy 67.89093 -187.236671)
			(xy 67.891406 -187.26404) (xy 67.890959 -187.291292) (xy 67.883197 -187.345242) (xy 67.867837 -187.397537)
			(xy 67.845191 -187.447115) (xy 67.81572 -187.492965) (xy 67.780025 -187.534155) (xy 67.738831 -187.569846)
			(xy 67.692978 -187.599311) (xy 67.643398 -187.621952) (xy 67.5911 -187.637306) (xy 67.53715 -187.645062)
			(xy 67.509898 -187.645548) (xy 67.482527 -187.645096) (xy 67.428347 -187.637277) (xy 67.375843 -187.621785)
			(xy 67.326096 -187.59894) (xy 67.280131 -187.569211) (xy 67.2592 -187.551568) (xy 67.258946 -187.551314)
			(xy 67.251849 -187.545742) (xy 67.23494 -187.539486) (xy 67.225926 -187.539122) (xy 67.15887 -187.539122)
			(xy 67.149851 -187.53946) (xy 67.132934 -187.54572) (xy 67.12585 -187.551314) (xy 67.12585 -187.551568)
			(xy 67.125596 -187.551568) (xy 67.104672 -187.569217) (xy 67.058698 -187.598929) (xy 67.008948 -187.621763)
			(xy 66.956445 -187.637252) (xy 66.902268 -187.645076) (xy 66.874898 -187.645548) (xy 66.847649 -187.645024)
			(xy 66.793704 -187.637268) (xy 66.741413 -187.621915) (xy 66.691838 -187.599277) (xy 66.64599 -187.569814)
			(xy 66.6048 -187.534126) (xy 66.569109 -187.492941) (xy 66.539642 -187.447095) (xy 66.516998 -187.397523)
			(xy 66.50164 -187.345233) (xy 66.493879 -187.291289) (xy 66.49339 -187.26404) (xy 64.054482 -187.26404)
			(xy 65.172082 -188.38164) (xy 113.076736 -188.38164) (xy 113.077217 -188.35427) (xy 113.08503 -188.300091)
			(xy 113.100515 -188.247588) (xy 113.123354 -188.197841) (xy 113.153076 -188.151874) (xy 113.170716 -188.130942)
			(xy 113.17097 -188.130688) (xy 113.176576 -188.123615) (xy 113.182809 -188.106688) (xy 113.183162 -188.097668)
			(xy 113.183162 -188.030612) (xy 113.182807 -188.021595) (xy 113.176559 -188.004677) (xy 113.17097 -187.997592)
			(xy 113.170716 -187.997592) (xy 113.170716 -187.997338) (xy 113.153115 -187.976373) (xy 113.123389 -187.930411)
			(xy 113.100542 -187.88067) (xy 113.085043 -187.828173) (xy 113.077211 -187.773999) (xy 113.077207 -187.719262)
			(xy 113.085031 -187.665086) (xy 113.100521 -187.612587) (xy 113.12336 -187.562842) (xy 113.153079 -187.516875)
			(xy 113.170716 -187.495942) (xy 113.17097 -187.495688) (xy 113.176576 -187.488615) (xy 113.182809 -187.471688)
			(xy 113.183162 -187.462668) (xy 113.183162 -187.395612) (xy 113.182807 -187.386595) (xy 113.176559 -187.369677)
			(xy 113.17097 -187.362592) (xy 113.170716 -187.362592) (xy 113.170716 -187.362338) (xy 113.153115 -187.341373)
			(xy 113.123389 -187.295411) (xy 113.100542 -187.24567) (xy 113.085043 -187.193173) (xy 113.077211 -187.138999)
			(xy 113.077207 -187.084262) (xy 113.085031 -187.030086) (xy 113.100521 -186.977587) (xy 113.12336 -186.927842)
			(xy 113.153079 -186.881875) (xy 113.170716 -186.860942) (xy 113.17097 -186.860688) (xy 113.176576 -186.853615)
			(xy 113.182809 -186.836688) (xy 113.183162 -186.827668) (xy 113.183162 -186.760612) (xy 113.182807 -186.751595)
			(xy 113.176559 -186.734677) (xy 113.17097 -186.727592) (xy 113.170716 -186.727592) (xy 113.170716 -186.727338)
			(xy 113.153115 -186.706373) (xy 113.123389 -186.660411) (xy 113.100542 -186.61067) (xy 113.085043 -186.558173)
			(xy 113.077211 -186.503999) (xy 113.077207 -186.449262) (xy 113.085031 -186.395086) (xy 113.100521 -186.342587)
			(xy 113.12336 -186.292842) (xy 113.153079 -186.246875) (xy 113.170716 -186.225942) (xy 113.17097 -186.225688)
			(xy 113.176576 -186.218615) (xy 113.182809 -186.201688) (xy 113.183162 -186.192668) (xy 113.183162 -186.125612)
			(xy 113.182807 -186.116595) (xy 113.176559 -186.099677) (xy 113.17097 -186.092592) (xy 113.170716 -186.092592)
			(xy 113.170716 -186.092338) (xy 113.153115 -186.071373) (xy 113.123389 -186.025411) (xy 113.100542 -185.97567)
			(xy 113.085043 -185.923173) (xy 113.077211 -185.868999) (xy 113.077207 -185.814262) (xy 113.085031 -185.760086)
			(xy 113.100521 -185.707587) (xy 113.12336 -185.657842) (xy 113.153079 -185.611875) (xy 113.170716 -185.590942)
			(xy 113.17097 -185.590688) (xy 113.176576 -185.583615) (xy 113.182809 -185.566688) (xy 113.183162 -185.557668)
			(xy 113.183162 -185.490612) (xy 113.182807 -185.481595) (xy 113.176559 -185.464677) (xy 113.17097 -185.457592)
			(xy 113.170716 -185.457592) (xy 113.170716 -185.457338) (xy 113.153115 -185.436373) (xy 113.123389 -185.390411)
			(xy 113.100542 -185.34067) (xy 113.085043 -185.288173) (xy 113.077211 -185.233999) (xy 113.077207 -185.179262)
			(xy 113.085031 -185.125086) (xy 113.100521 -185.072587) (xy 113.12336 -185.022842) (xy 113.153079 -184.976875)
			(xy 113.170716 -184.955942) (xy 113.17097 -184.955688) (xy 113.176576 -184.948615) (xy 113.182809 -184.931688)
			(xy 113.183162 -184.922668) (xy 113.183162 -184.855612) (xy 113.182807 -184.846595) (xy 113.176559 -184.829677)
			(xy 113.17097 -184.822592) (xy 113.170716 -184.822592) (xy 113.170716 -184.822338) (xy 113.153084 -184.8014)
			(xy 113.12337 -184.755429) (xy 113.100533 -184.705683) (xy 113.08504 -184.653184) (xy 113.077211 -184.599009)
			(xy 113.076736 -184.57164) (xy 113.077279 -184.542473) (xy 113.086176 -184.484823) (xy 113.103752 -184.429201)
			(xy 113.129598 -184.376906) (xy 113.163111 -184.32916) (xy 113.182908 -184.307734) (xy 113.189253 -184.300388)
			(xy 113.196443 -184.282378) (xy 113.196878 -184.272682) (xy 113.196878 -184.192164) (xy 113.189766 -184.17413)
			(xy 113.182908 -184.167018) (xy 113.163125 -184.145584) (xy 113.12964 -184.097826) (xy 113.103808 -184.045531)
			(xy 113.086229 -183.989916) (xy 113.077311 -183.932275) (xy 113.076736 -183.903112) (xy 113.077167 -183.875857)
			(xy 113.084923 -183.821903) (xy 113.10028 -183.769602) (xy 113.122924 -183.720019) (xy 113.152395 -183.674164)
			(xy 113.188092 -183.63297) (xy 113.229289 -183.597276) (xy 113.275147 -183.567809) (xy 113.324732 -183.545169)
			(xy 113.377034 -183.529816) (xy 113.430989 -183.522064) (xy 113.458244 -183.521604) (xy 113.485613 -183.522102)
			(xy 113.539791 -183.529912) (xy 113.592294 -183.545393) (xy 113.642041 -183.568228) (xy 113.688009 -183.597946)
			(xy 113.708942 -183.615584) (xy 113.709196 -183.615838) (xy 113.716276 -183.621433) (xy 113.733198 -183.627674)
			(xy 113.742216 -183.62803) (xy 113.809272 -183.62803) (xy 113.818287 -183.627653) (xy 113.835203 -183.621419)
			(xy 113.842292 -183.615838) (xy 113.842292 -183.615584) (xy 113.842546 -183.615584) (xy 113.863479 -183.597943)
			(xy 113.909447 -183.568219) (xy 113.959193 -183.545373) (xy 114.011695 -183.529877) (xy 114.065873 -183.522048)
			(xy 114.120615 -183.522048) (xy 114.174793 -183.529877) (xy 114.227295 -183.545373) (xy 114.277041 -183.568219)
			(xy 114.323009 -183.597943) (xy 114.343942 -183.615584) (xy 114.344196 -183.615838) (xy 114.351276 -183.621433)
			(xy 114.368198 -183.627674) (xy 114.377216 -183.62803) (xy 114.444272 -183.62803) (xy 114.453287 -183.627653)
			(xy 114.470203 -183.621419) (xy 114.477292 -183.615838) (xy 114.477292 -183.615584) (xy 114.477546 -183.615584)
			(xy 114.498486 -183.597954) (xy 114.544457 -183.568242) (xy 114.594202 -183.545404) (xy 114.646701 -183.529911)
			(xy 114.700875 -183.52208) (xy 114.728244 -183.521604) (xy 114.755497 -183.522037) (xy 114.809447 -183.5298)
			(xy 114.861744 -183.545161) (xy 114.911322 -183.567808) (xy 114.957173 -183.59728) (xy 114.998363 -183.632977)
			(xy 115.034053 -183.674172) (xy 115.063519 -183.720027) (xy 115.086159 -183.769609) (xy 115.101512 -183.821908)
			(xy 115.109267 -183.875859) (xy 115.109752 -183.903112) (xy 117.089936 -183.903112) (xy 117.090367 -183.875857)
			(xy 117.098123 -183.821903) (xy 117.11348 -183.769602) (xy 117.136124 -183.720019) (xy 117.165595 -183.674164)
			(xy 117.201292 -183.63297) (xy 117.242489 -183.597276) (xy 117.288347 -183.567809) (xy 117.337932 -183.545169)
			(xy 117.390234 -183.529816) (xy 117.444189 -183.522064) (xy 117.471444 -183.521604) (xy 117.498813 -183.522102)
			(xy 117.552991 -183.529912) (xy 117.605494 -183.545393) (xy 117.655241 -183.568228) (xy 117.701209 -183.597946)
			(xy 117.722142 -183.615584) (xy 117.722396 -183.615838) (xy 117.729476 -183.621433) (xy 117.746398 -183.627674)
			(xy 117.755416 -183.62803) (xy 117.822472 -183.62803) (xy 117.831487 -183.627653) (xy 117.848403 -183.621419)
			(xy 117.855492 -183.615838) (xy 117.855492 -183.615584) (xy 117.855746 -183.615584) (xy 117.876679 -183.597943)
			(xy 117.922647 -183.568219) (xy 117.972393 -183.545373) (xy 118.024895 -183.529877) (xy 118.079073 -183.522048)
			(xy 118.133815 -183.522048) (xy 118.187993 -183.529877) (xy 118.240495 -183.545373) (xy 118.290241 -183.568219)
			(xy 118.336209 -183.597943) (xy 118.357142 -183.615584) (xy 118.357396 -183.615838) (xy 118.364476 -183.621433)
			(xy 118.381398 -183.627674) (xy 118.390416 -183.62803) (xy 118.457472 -183.62803) (xy 118.466487 -183.627653)
			(xy 118.483403 -183.621419) (xy 118.490492 -183.615838) (xy 118.490492 -183.615584) (xy 118.490746 -183.615584)
			(xy 118.511686 -183.597954) (xy 118.557657 -183.568242) (xy 118.607402 -183.545404) (xy 118.659901 -183.529911)
			(xy 118.714075 -183.52208) (xy 118.741444 -183.521604) (xy 118.768697 -183.522037) (xy 118.822647 -183.5298)
			(xy 118.874944 -183.545161) (xy 118.924522 -183.567808) (xy 118.970373 -183.59728) (xy 119.011563 -183.632977)
			(xy 119.047253 -183.674172) (xy 119.076719 -183.720027) (xy 119.099359 -183.769609) (xy 119.114712 -183.821908)
			(xy 119.122467 -183.875859) (xy 119.122952 -183.903112) (xy 119.122414 -183.93223) (xy 119.113567 -183.989791)
			(xy 119.09608 -184.045341) (xy 119.070359 -184.09759) (xy 119.037002 -184.145327) (xy 119.017288 -184.166764)
			(xy 119.01043 -184.173876) (xy 119.003064 -184.192164) (xy 119.003318 -184.27192) (xy 119.003763 -184.28171)
			(xy 119.011066 -184.299872) (xy 119.017542 -184.307226) (xy 119.037386 -184.328688) (xy 119.070982 -184.376519)
			(xy 119.096891 -184.428914) (xy 119.114505 -184.484647) (xy 119.123413 -184.542415) (xy 119.123968 -184.57164)
			(xy 119.123559 -184.598894) (xy 119.115796 -184.652847) (xy 119.100434 -184.705145) (xy 119.077785 -184.754725)
			(xy 119.048311 -184.800577) (xy 119.012612 -184.841768) (xy 118.971413 -184.877459) (xy 118.925555 -184.906924)
			(xy 118.87597 -184.929562) (xy 118.823668 -184.944913) (xy 118.769714 -184.952665) (xy 118.74246 -184.953148)
			(xy 118.716175 -184.952671) (xy 118.664099 -184.945476) (xy 118.613504 -184.931202) (xy 118.565348 -184.910117)
			(xy 118.520541 -184.882622) (xy 118.479933 -184.849236) (xy 118.46179 -184.830212) (xy 118.454727 -184.82329)
			(xy 118.436833 -184.814918) (xy 118.426992 -184.813956) (xy 118.373906 -184.811162) (xy 118.366286 -184.818274)
			(xy 118.366286 -184.871614) (xy 118.366778 -184.881428) (xy 118.374219 -184.899592) (xy 118.380764 -184.90692)
			(xy 118.400949 -184.928409) (xy 118.435092 -184.976472) (xy 118.461436 -185.029214) (xy 118.479354 -185.08538)
			(xy 118.48842 -185.143634) (xy 118.488968 -185.173112) (xy 118.488556 -185.200367) (xy 118.480797 -185.254322)
			(xy 118.465437 -185.306623) (xy 118.44279 -185.356206) (xy 118.413317 -185.402061) (xy 118.377618 -185.443255)
			(xy 118.336419 -185.478948) (xy 118.29056 -185.508415) (xy 118.240974 -185.531055) (xy 118.188671 -185.546408)
			(xy 118.134715 -185.55416) (xy 118.10746 -185.55462) (xy 118.077984 -185.554037) (xy 118.019733 -185.544978)
			(xy 117.963569 -185.527065) (xy 117.910829 -185.500725) (xy 117.862769 -185.466586) (xy 117.841268 -185.446416)
			(xy 117.833937 -185.439877) (xy 117.815774 -185.432434) (xy 117.805962 -185.431938) (xy 117.752622 -185.431938)
			(xy 117.745764 -185.439304) (xy 117.73923 -185.446639) (xy 117.731786 -185.464799) (xy 117.731286 -185.47461)
			(xy 117.731286 -185.506614) (xy 117.731778 -185.516428) (xy 117.739219 -185.534592) (xy 117.745764 -185.54192)
			(xy 117.765949 -185.563409) (xy 117.800092 -185.611472) (xy 117.826436 -185.664214) (xy 117.844354 -185.72038)
			(xy 117.85342 -185.778634) (xy 117.853968 -185.808112) (xy 117.853482 -185.835363) (xy 117.845726 -185.889311)
			(xy 117.830371 -185.941606) (xy 117.807729 -185.991183) (xy 117.778263 -186.037033) (xy 117.742572 -186.078224)
			(xy 117.701381 -186.113915) (xy 117.655531 -186.143381) (xy 117.605954 -186.166023) (xy 117.553659 -186.181378)
			(xy 117.499711 -186.189134) (xy 117.445209 -186.189134) (xy 117.391261 -186.181378) (xy 117.338966 -186.166023)
			(xy 117.289389 -186.143381) (xy 117.243539 -186.113915) (xy 117.202348 -186.078224) (xy 117.166657 -186.037033)
			(xy 117.137191 -185.991183) (xy 117.114549 -185.941606) (xy 117.099194 -185.889311) (xy 117.091438 -185.835363)
			(xy 117.090952 -185.808112) (xy 117.091412 -185.780741) (xy 117.09923 -185.726562) (xy 117.114719 -185.674058)
			(xy 117.137563 -185.624311) (xy 117.167289 -185.578345) (xy 117.184932 -185.557414) (xy 117.185186 -185.55716)
			(xy 117.190752 -185.550059) (xy 117.197012 -185.533153) (xy 117.197378 -185.52414) (xy 117.197378 -185.457084)
			(xy 117.197033 -185.448066) (xy 117.190778 -185.431149) (xy 117.185186 -185.424064) (xy 117.184932 -185.424064)
			(xy 117.184932 -185.42381) (xy 117.167303 -185.402868) (xy 117.137577 -185.356902) (xy 117.114731 -185.307157)
			(xy 117.099233 -185.254656) (xy 117.091404 -185.200479) (xy 117.091402 -185.145739) (xy 117.09923 -185.091561)
			(xy 117.114724 -185.03906) (xy 117.137568 -184.989314) (xy 117.167292 -184.943347) (xy 117.184932 -184.922414)
			(xy 117.185186 -184.92216) (xy 117.190752 -184.915059) (xy 117.197012 -184.898153) (xy 117.197378 -184.88914)
			(xy 117.197378 -184.822084) (xy 117.197033 -184.813066) (xy 117.190778 -184.796149) (xy 117.185186 -184.789064)
			(xy 117.184932 -184.789064) (xy 117.184932 -184.78881) (xy 117.167289 -184.767881) (xy 117.137577 -184.721908)
			(xy 117.114741 -184.67216) (xy 117.099251 -184.619658) (xy 117.091425 -184.565481) (xy 117.090952 -184.538112)
			(xy 117.091455 -184.510814) (xy 117.099223 -184.456774) (xy 117.114618 -184.404394) (xy 117.137324 -184.354744)
			(xy 117.166878 -184.308839) (xy 117.184424 -184.287922) (xy 117.190273 -184.280736) (xy 117.196777 -184.2634)
			(xy 117.197124 -184.25414) (xy 117.19687 -184.178194) (xy 117.19052 -184.161176) (xy 117.184424 -184.154318)
			(xy 117.166722 -184.133347) (xy 117.136841 -184.087318) (xy 117.113872 -184.037479) (xy 117.098289 -183.98486)
			(xy 117.090415 -183.930551) (xy 117.089936 -183.903112) (xy 115.109752 -183.903112) (xy 115.109287 -183.930412)
			(xy 115.101512 -183.984454) (xy 115.08611 -184.036836) (xy 115.063395 -184.086485) (xy 115.033831 -184.132387)
			(xy 115.01628 -184.153302) (xy 115.010464 -184.160512) (xy 115.00394 -184.177829) (xy 115.00358 -184.187084)
			(xy 115.003834 -184.26303) (xy 115.010184 -184.280048) (xy 115.01628 -184.286906) (xy 115.033993 -184.307868)
			(xy 115.063873 -184.353899) (xy 115.08684 -184.403741) (xy 115.10242 -184.456361) (xy 115.110291 -184.510673)
			(xy 115.110768 -184.538112) (xy 115.110317 -184.565483) (xy 115.102497 -184.619663) (xy 115.087004 -184.672166)
			(xy 115.064159 -184.721913) (xy 115.034431 -184.767879) (xy 115.016788 -184.78881) (xy 115.016534 -184.789064)
			(xy 115.010949 -184.796151) (xy 115.004703 -184.813068) (xy 115.004342 -184.822084) (xy 115.004342 -184.88914)
			(xy 115.004671 -184.89816) (xy 115.010937 -184.915077) (xy 115.016534 -184.92216) (xy 115.016788 -184.92216)
			(xy 115.016788 -184.922414) (xy 115.03444 -184.943338) (xy 115.064163 -184.989307) (xy 115.087007 -185.039055)
			(xy 115.102501 -185.091558) (xy 115.110329 -185.145738) (xy 115.110327 -185.20048) (xy 115.102498 -185.254659)
			(xy 115.087 -185.307162) (xy 115.064154 -185.356909) (xy 115.034429 -185.402877) (xy 115.016788 -185.42381)
			(xy 115.016534 -185.424064) (xy 115.010949 -185.431151) (xy 115.004703 -185.448068) (xy 115.004342 -185.457084)
			(xy 115.004342 -185.52414) (xy 115.004671 -185.53316) (xy 115.010937 -185.550077) (xy 115.016534 -185.55716)
			(xy 115.016788 -185.55716) (xy 115.016788 -185.557414) (xy 115.03444 -185.578338) (xy 115.064163 -185.624307)
			(xy 115.087007 -185.674055) (xy 115.102501 -185.726558) (xy 115.110329 -185.780738) (xy 115.110327 -185.83548)
			(xy 115.102498 -185.889659) (xy 115.087 -185.942162) (xy 115.064154 -185.991909) (xy 115.034429 -186.037877)
			(xy 115.016788 -186.05881) (xy 115.016534 -186.059064) (xy 115.010949 -186.066151) (xy 115.004703 -186.083068)
			(xy 115.004342 -186.092084) (xy 115.004342 -186.15914) (xy 115.004671 -186.16816) (xy 115.010937 -186.185077)
			(xy 115.016534 -186.19216) (xy 115.016788 -186.19216) (xy 115.016788 -186.192414) (xy 115.034398 -186.213369)
			(xy 115.064115 -186.259335) (xy 115.086957 -186.309077) (xy 115.102454 -186.361573) (xy 115.11029 -186.415744)
			(xy 115.110768 -186.443112) (xy 115.110228 -186.472337) (xy 115.101304 -186.530102) (xy 115.083683 -186.585833)
			(xy 115.057774 -186.638227) (xy 115.024184 -186.686062) (xy 115.004342 -186.707526) (xy 114.997884 -186.714892)
			(xy 114.990567 -186.733046) (xy 114.990118 -186.742832) (xy 114.989864 -186.822588) (xy 114.99723 -186.840876)
			(xy 115.004088 -186.847988) (xy 115.023818 -186.869411) (xy 115.057171 -186.917152) (xy 115.082886 -186.969405)
			(xy 115.100366 -187.024958) (xy 115.109206 -187.082521) (xy 115.109752 -187.11164) (xy 115.109262 -187.13901)
			(xy 115.101452 -187.193188) (xy 115.085969 -187.245691) (xy 115.063132 -187.295439) (xy 115.033412 -187.341406)
			(xy 115.015772 -187.362338) (xy 115.015518 -187.362592) (xy 115.009931 -187.369678) (xy 115.003684 -187.386595)
			(xy 115.003326 -187.395612) (xy 115.003326 -187.462668) (xy 115.003693 -187.471684) (xy 115.009933 -187.488601)
			(xy 115.015518 -187.495688) (xy 115.015772 -187.495688) (xy 115.015772 -187.495942) (xy 115.033452 -187.516843)
			(xy 115.063175 -187.562816) (xy 115.086018 -187.612568) (xy 115.101511 -187.665075) (xy 115.109336 -187.719258)
			(xy 115.109332 -187.774003) (xy 115.101499 -187.828184) (xy 115.085997 -187.880689) (xy 115.063146 -187.930437)
			(xy 115.033416 -187.976405) (xy 115.015772 -187.997338) (xy 115.015518 -187.997592) (xy 115.009931 -188.004678)
			(xy 115.003684 -188.021595) (xy 115.003326 -188.030612) (xy 115.003326 -188.097668) (xy 115.003693 -188.106684)
			(xy 115.009933 -188.123601) (xy 115.015518 -188.130688) (xy 115.015772 -188.130688) (xy 115.015772 -188.130942)
			(xy 115.033393 -188.151889) (xy 115.063109 -188.197857) (xy 115.085948 -188.247601) (xy 115.101444 -188.300098)
			(xy 115.109276 -188.354272) (xy 115.109752 -188.38164) (xy 115.10926 -188.40889) (xy 115.101499 -188.462835)
			(xy 115.086141 -188.515127) (xy 115.063498 -188.564702) (xy 115.034032 -188.61055) (xy 114.998341 -188.651738)
			(xy 114.957153 -188.687429) (xy 114.911305 -188.716896) (xy 114.861731 -188.739539) (xy 114.809439 -188.754898)
			(xy 114.755494 -188.762659) (xy 114.728244 -188.763148) (xy 114.700874 -188.762669) (xy 114.646695 -188.754856)
			(xy 114.594192 -188.739371) (xy 114.544444 -188.716532) (xy 114.498478 -188.686809) (xy 114.477546 -188.669168)
			(xy 114.477292 -188.668914) (xy 114.470211 -188.663319) (xy 114.45329 -188.657077) (xy 114.444272 -188.656722)
			(xy 114.377216 -188.656722) (xy 114.368199 -188.657082) (xy 114.351282 -188.663327) (xy 114.344196 -188.668914)
			(xy 114.343942 -188.669168) (xy 114.323009 -188.686809) (xy 114.277041 -188.716533) (xy 114.227295 -188.739379)
			(xy 114.174793 -188.754875) (xy 114.120615 -188.762704) (xy 114.065873 -188.762704) (xy 114.011695 -188.754875)
			(xy 113.959193 -188.739379) (xy 113.909447 -188.716533) (xy 113.863479 -188.686809) (xy 113.842546 -188.669168)
			(xy 113.842292 -188.668914) (xy 113.835211 -188.663319) (xy 113.81829 -188.657077) (xy 113.809272 -188.656722)
			(xy 113.742216 -188.656722) (xy 113.733199 -188.657082) (xy 113.716282 -188.663327) (xy 113.709196 -188.668914)
			(xy 113.709196 -188.669168) (xy 113.708942 -188.669168) (xy 113.688001 -188.686796) (xy 113.642031 -188.716511)
			(xy 113.592286 -188.739349) (xy 113.539787 -188.754843) (xy 113.485613 -188.762673) (xy 113.458244 -188.763148)
			(xy 113.430994 -188.762604) (xy 113.377048 -188.754854) (xy 113.324754 -188.739506) (xy 113.275177 -188.716871)
			(xy 113.229325 -188.687411) (xy 113.188133 -188.651726) (xy 113.152439 -188.610542) (xy 113.122969 -188.564697)
			(xy 113.100324 -188.515125) (xy 113.084964 -188.462834) (xy 113.077202 -188.40889) (xy 113.076736 -188.38164)
			(xy 65.172082 -188.38164) (xy 70.239382 -193.44894) (xy 70.81901 -193.44894) (xy 70.819497 -193.42157)
			(xy 70.827309 -193.367392) (xy 70.842793 -193.314889) (xy 70.865631 -193.265142) (xy 70.895351 -193.219174)
			(xy 70.91299 -193.198242) (xy 70.913244 -193.197988) (xy 70.918847 -193.190913) (xy 70.925083 -193.173987)
			(xy 70.925436 -193.164968) (xy 70.925436 -193.097912) (xy 70.925065 -193.088897) (xy 70.918826 -193.07198)
			(xy 70.913244 -193.064892) (xy 70.91299 -193.064892) (xy 70.91299 -193.064638) (xy 70.89539 -193.043673)
			(xy 70.865666 -192.99771) (xy 70.842821 -192.947969) (xy 70.827323 -192.895472) (xy 70.819492 -192.841298)
			(xy 70.819487 -192.786562) (xy 70.82731 -192.732387) (xy 70.8428 -192.679888) (xy 70.865637 -192.630143)
			(xy 70.895354 -192.584175) (xy 70.91299 -192.563242) (xy 70.913244 -192.562988) (xy 70.918847 -192.555913)
			(xy 70.925083 -192.538987) (xy 70.925436 -192.529968) (xy 70.925436 -192.462912) (xy 70.925065 -192.453897)
			(xy 70.918826 -192.43698) (xy 70.913244 -192.429892) (xy 70.91299 -192.429892) (xy 70.91299 -192.429638)
			(xy 70.89539 -192.408673) (xy 70.865666 -192.36271) (xy 70.842821 -192.312969) (xy 70.827323 -192.260472)
			(xy 70.819492 -192.206298) (xy 70.819487 -192.151562) (xy 70.82731 -192.097387) (xy 70.8428 -192.044888)
			(xy 70.865637 -191.995143) (xy 70.895354 -191.949175) (xy 70.91299 -191.928242) (xy 70.913244 -191.927988)
			(xy 70.918847 -191.920913) (xy 70.925083 -191.903987) (xy 70.925436 -191.894968) (xy 70.925436 -191.827912)
			(xy 70.925065 -191.818897) (xy 70.918826 -191.80198) (xy 70.913244 -191.794892) (xy 70.91299 -191.794892)
			(xy 70.91299 -191.794638) (xy 70.89539 -191.773673) (xy 70.865666 -191.72771) (xy 70.842821 -191.677969)
			(xy 70.827323 -191.625472) (xy 70.819492 -191.571298) (xy 70.819487 -191.516562) (xy 70.82731 -191.462387)
			(xy 70.8428 -191.409888) (xy 70.865637 -191.360143) (xy 70.895354 -191.314175) (xy 70.91299 -191.293242)
			(xy 70.913244 -191.292988) (xy 70.918847 -191.285913) (xy 70.925083 -191.268987) (xy 70.925436 -191.259968)
			(xy 70.925436 -191.192912) (xy 70.925065 -191.183897) (xy 70.918826 -191.16698) (xy 70.913244 -191.159892)
			(xy 70.91299 -191.159892) (xy 70.91299 -191.159638) (xy 70.89539 -191.138673) (xy 70.865666 -191.09271)
			(xy 70.842821 -191.042969) (xy 70.827323 -190.990472) (xy 70.819492 -190.936298) (xy 70.819487 -190.881562)
			(xy 70.82731 -190.827387) (xy 70.8428 -190.774888) (xy 70.865637 -190.725143) (xy 70.895354 -190.679175)
			(xy 70.91299 -190.658242) (xy 70.913244 -190.657988) (xy 70.918847 -190.650913) (xy 70.925083 -190.633987)
			(xy 70.925436 -190.624968) (xy 70.925436 -190.557912) (xy 70.925065 -190.548897) (xy 70.918826 -190.53198)
			(xy 70.913244 -190.524892) (xy 70.91299 -190.524892) (xy 70.91299 -190.524638) (xy 70.895354 -190.503704)
			(xy 70.865642 -190.457731) (xy 70.842805 -190.407984) (xy 70.827314 -190.355484) (xy 70.819485 -190.301309)
			(xy 70.81901 -190.27394) (xy 70.81956 -190.244774) (xy 70.828456 -190.187124) (xy 70.846032 -190.131502)
			(xy 70.871876 -190.079207) (xy 70.905386 -190.03146) (xy 70.925182 -190.010034) (xy 70.931536 -190.002696)
			(xy 70.938719 -189.984679) (xy 70.939152 -189.974982) (xy 70.939152 -189.894464) (xy 70.93204 -189.87643)
			(xy 70.925182 -189.869318) (xy 70.905394 -189.847888) (xy 70.871911 -189.800128) (xy 70.84608 -189.747833)
			(xy 70.828502 -189.692217) (xy 70.819585 -189.634575) (xy 70.81901 -189.605412) (xy 70.819467 -189.578159)
			(xy 70.827222 -189.524207) (xy 70.842578 -189.471907) (xy 70.86522 -189.422326) (xy 70.894689 -189.376472)
			(xy 70.930383 -189.335279) (xy 70.971577 -189.299585) (xy 71.017431 -189.270117) (xy 71.067013 -189.247476)
			(xy 71.119312 -189.232121) (xy 71.173265 -189.224366) (xy 71.200518 -189.223904) (xy 71.227889 -189.224359)
			(xy 71.282068 -189.232179) (xy 71.334572 -189.247671) (xy 71.384318 -189.270515) (xy 71.430285 -189.300242)
			(xy 71.451216 -189.317884) (xy 71.45147 -189.318138) (xy 71.458558 -189.323722) (xy 71.475474 -189.329969)
			(xy 71.48449 -189.33033) (xy 71.551546 -189.33033) (xy 71.560559 -189.329941) (xy 71.577476 -189.323715)
			(xy 71.584566 -189.318138) (xy 71.584566 -189.317884) (xy 71.58482 -189.317884) (xy 71.605753 -189.300243)
			(xy 71.651721 -189.270519) (xy 71.701467 -189.247673) (xy 71.753969 -189.232177) (xy 71.808147 -189.224348)
			(xy 71.862889 -189.224348) (xy 71.917067 -189.232177) (xy 71.969569 -189.247673) (xy 72.019315 -189.270519)
			(xy 72.065283 -189.300243) (xy 72.086216 -189.317884) (xy 72.08647 -189.318138) (xy 72.093558 -189.323722)
			(xy 72.110474 -189.329969) (xy 72.11949 -189.33033) (xy 72.186546 -189.33033) (xy 72.195559 -189.329941)
			(xy 72.212476 -189.323715) (xy 72.219566 -189.318138) (xy 72.219566 -189.317884) (xy 72.21982 -189.317884)
			(xy 72.240769 -189.300266) (xy 72.286738 -189.270552) (xy 72.336481 -189.247712) (xy 72.388978 -189.232216)
			(xy 72.44315 -189.224382) (xy 72.470518 -189.223904) (xy 72.49777 -189.224361) (xy 72.55172 -189.23212)
			(xy 72.604016 -189.247478) (xy 72.653594 -189.270122) (xy 72.699445 -189.299592) (xy 72.740635 -189.335286)
			(xy 72.776326 -189.376479) (xy 72.805792 -189.422333) (xy 72.828432 -189.471913) (xy 72.843786 -189.52421)
			(xy 72.851541 -189.57816) (xy 72.852026 -189.605412) (xy 72.851543 -189.632711) (xy 72.84377 -189.686752)
			(xy 72.828371 -189.739132) (xy 72.805661 -189.788782) (xy 72.776102 -189.834686) (xy 72.758554 -189.855602)
			(xy 72.752735 -189.862809) (xy 72.746213 -189.880129) (xy 72.745854 -189.889384) (xy 72.746108 -189.96533)
			(xy 72.752458 -189.982348) (xy 72.758554 -189.989206) (xy 72.776279 -190.010158) (xy 72.806154 -190.056193)
			(xy 72.829118 -190.106037) (xy 72.844695 -190.15866) (xy 72.852565 -190.212972) (xy 72.853042 -190.240412)
			(xy 72.852597 -190.267783) (xy 72.844776 -190.321964) (xy 72.829283 -190.374468) (xy 72.806436 -190.424214)
			(xy 72.776706 -190.47018) (xy 72.759062 -190.49111) (xy 72.758808 -190.491364) (xy 72.753231 -190.498457)
			(xy 72.746978 -190.515369) (xy 72.746616 -190.524384) (xy 72.746616 -190.59144) (xy 72.746951 -190.600459)
			(xy 72.753213 -190.617376) (xy 72.758808 -190.62446) (xy 72.759062 -190.62446) (xy 72.759062 -190.624714)
			(xy 72.776715 -190.645637) (xy 72.80644 -190.691606) (xy 72.829285 -190.741354) (xy 72.844781 -190.793858)
			(xy 72.852609 -190.848038) (xy 72.852608 -190.90278) (xy 72.844777 -190.95696) (xy 72.829279 -191.009463)
			(xy 72.806431 -191.05921) (xy 72.776704 -191.105177) (xy 72.759062 -191.12611) (xy 72.758808 -191.126364)
			(xy 72.753231 -191.133457) (xy 72.746978 -191.150369) (xy 72.746616 -191.159384) (xy 72.746616 -191.22644)
			(xy 72.746951 -191.235459) (xy 72.753213 -191.252376) (xy 72.758808 -191.25946) (xy 72.759062 -191.25946)
			(xy 72.759062 -191.259714) (xy 72.776715 -191.280637) (xy 72.80644 -191.326606) (xy 72.829285 -191.376354)
			(xy 72.844781 -191.428858) (xy 72.852609 -191.483038) (xy 72.852608 -191.53778) (xy 72.844777 -191.59196)
			(xy 72.829279 -191.644463) (xy 72.806431 -191.69421) (xy 72.776704 -191.740177) (xy 72.759062 -191.76111)
			(xy 72.758808 -191.761364) (xy 72.753231 -191.768457) (xy 72.746978 -191.785369) (xy 72.746616 -191.794384)
			(xy 72.746616 -191.86144) (xy 72.746951 -191.870459) (xy 72.753213 -191.887376) (xy 72.758808 -191.89446)
			(xy 72.759062 -191.89446) (xy 72.759062 -191.894714) (xy 72.776668 -191.915673) (xy 72.806386 -191.961637)
			(xy 72.829229 -192.011378) (xy 72.844728 -192.063873) (xy 72.852564 -192.118045) (xy 72.853042 -192.145412)
			(xy 72.852482 -192.174636) (xy 72.84356 -192.232399) (xy 72.825942 -192.288129) (xy 72.800038 -192.340524)
			(xy 72.766455 -192.38836) (xy 72.746616 -192.409826) (xy 72.740168 -192.4172) (xy 72.732844 -192.435348)
			(xy 72.732392 -192.445132) (xy 72.732138 -192.524888) (xy 72.739504 -192.543176) (xy 72.746362 -192.550288)
			(xy 72.766087 -192.571715) (xy 72.799442 -192.619454) (xy 72.825159 -192.671706) (xy 72.84264 -192.727258)
			(xy 72.85148 -192.784821) (xy 72.852026 -192.81394) (xy 72.851543 -192.84131) (xy 72.843732 -192.895489)
			(xy 72.828248 -192.947993) (xy 72.805409 -192.99774) (xy 72.775687 -193.043707) (xy 72.758046 -193.064638)
			(xy 72.757792 -193.064892) (xy 72.752202 -193.071976) (xy 72.745958 -193.088895) (xy 72.7456 -193.097912)
			(xy 72.7456 -193.164968) (xy 72.745972 -193.173983) (xy 72.752209 -193.1909) (xy 72.757792 -193.197988)
			(xy 72.758046 -193.197988) (xy 72.758046 -193.198242) (xy 72.775663 -193.219192) (xy 72.80538 -193.265159)
			(xy 72.828221 -193.314902) (xy 72.843717 -193.367399) (xy 72.85155 -193.421572) (xy 72.852026 -193.44894)
			(xy 72.851559 -193.476191) (xy 72.843798 -193.530139) (xy 72.828439 -193.582433) (xy 72.805794 -193.632009)
			(xy 72.776325 -193.677858) (xy 72.740632 -193.719048) (xy 72.699441 -193.754739) (xy 72.65359 -193.784205)
			(xy 72.604012 -193.806846) (xy 72.551717 -193.822203) (xy 72.497769 -193.829961) (xy 72.470518 -193.830448)
			(xy 72.443148 -193.829984) (xy 72.388968 -193.822168) (xy 72.336464 -193.806679) (xy 72.286717 -193.783836)
			(xy 72.240751 -193.75411) (xy 72.21982 -193.736468) (xy 72.219566 -193.736214) (xy 72.212464 -193.73065)
			(xy 72.195559 -193.724389) (xy 72.186546 -193.724022) (xy 72.11949 -193.724022) (xy 72.110472 -193.724369)
			(xy 72.093555 -193.730623) (xy 72.08647 -193.736214) (xy 72.086216 -193.736468) (xy 72.065283 -193.754109)
			(xy 72.019315 -193.783833) (xy 71.969569 -193.806679) (xy 71.917067 -193.822175) (xy 71.862889 -193.830004)
			(xy 71.808147 -193.830004) (xy 71.753969 -193.822175) (xy 71.701467 -193.806679) (xy 71.651721 -193.783833)
			(xy 71.605753 -193.754109) (xy 71.58482 -193.736468) (xy 71.584566 -193.736214) (xy 71.577464 -193.73065)
			(xy 71.560559 -193.724389) (xy 71.551546 -193.724022) (xy 71.48449 -193.724022) (xy 71.475472 -193.724369)
			(xy 71.458555 -193.730623) (xy 71.45147 -193.736214) (xy 71.45147 -193.736468) (xy 71.451216 -193.736468)
			(xy 71.430285 -193.754108) (xy 71.384312 -193.783821) (xy 71.334565 -193.806657) (xy 71.282063 -193.822148)
			(xy 71.227887 -193.829975) (xy 71.200518 -193.830448) (xy 71.173269 -193.829905) (xy 71.119325 -193.822152)
			(xy 71.067034 -193.806801) (xy 71.01746 -193.784165) (xy 70.971611 -193.754705) (xy 70.930422 -193.719019)
			(xy 70.89473 -193.677835) (xy 70.865263 -193.631991) (xy 70.842619 -193.58242) (xy 70.82726 -193.530131)
			(xy 70.819499 -193.476189) (xy 70.81901 -193.44894) (xy 70.239382 -193.44894) (xy 72.779382 -195.98894)
			(xy 74.83221 -195.98894) (xy 74.832697 -195.96157) (xy 74.840509 -195.907392) (xy 74.855993 -195.854889)
			(xy 74.878831 -195.805142) (xy 74.908551 -195.759174) (xy 74.92619 -195.738242) (xy 74.926444 -195.737988)
			(xy 74.932047 -195.730913) (xy 74.938283 -195.713987) (xy 74.938636 -195.704968) (xy 74.938636 -195.637912)
			(xy 74.938265 -195.628897) (xy 74.932026 -195.61198) (xy 74.926444 -195.604892) (xy 74.92619 -195.604892)
			(xy 74.92619 -195.604638) (xy 74.90859 -195.583673) (xy 74.878866 -195.53771) (xy 74.856021 -195.487969)
			(xy 74.840523 -195.435472) (xy 74.832692 -195.381298) (xy 74.832687 -195.326562) (xy 74.84051 -195.272387)
			(xy 74.856 -195.219888) (xy 74.878837 -195.170143) (xy 74.908554 -195.124175) (xy 74.92619 -195.103242)
			(xy 74.926444 -195.102988) (xy 74.932047 -195.095913) (xy 74.938283 -195.078987) (xy 74.938636 -195.069968)
			(xy 74.938636 -195.002912) (xy 74.938265 -194.993897) (xy 74.932026 -194.97698) (xy 74.926444 -194.969892)
			(xy 74.92619 -194.969892) (xy 74.92619 -194.969638) (xy 74.90859 -194.948673) (xy 74.878866 -194.90271)
			(xy 74.856021 -194.852969) (xy 74.840523 -194.800472) (xy 74.832692 -194.746298) (xy 74.832687 -194.691562)
			(xy 74.84051 -194.637387) (xy 74.856 -194.584888) (xy 74.878837 -194.535143) (xy 74.908554 -194.489175)
			(xy 74.92619 -194.468242) (xy 74.926444 -194.467988) (xy 74.932047 -194.460913) (xy 74.938283 -194.443987)
			(xy 74.938636 -194.434968) (xy 74.938636 -194.367912) (xy 74.938265 -194.358897) (xy 74.932026 -194.34198)
			(xy 74.926444 -194.334892) (xy 74.92619 -194.334892) (xy 74.92619 -194.334638) (xy 74.90859 -194.313673)
			(xy 74.878866 -194.26771) (xy 74.856021 -194.217969) (xy 74.840523 -194.165472) (xy 74.832692 -194.111298)
			(xy 74.832687 -194.056562) (xy 74.84051 -194.002387) (xy 74.856 -193.949888) (xy 74.878837 -193.900143)
			(xy 74.908554 -193.854175) (xy 74.92619 -193.833242) (xy 74.926444 -193.832988) (xy 74.932047 -193.825913)
			(xy 74.938283 -193.808987) (xy 74.938636 -193.799968) (xy 74.938636 -193.732912) (xy 74.938265 -193.723897)
			(xy 74.932026 -193.70698) (xy 74.926444 -193.699892) (xy 74.92619 -193.699892) (xy 74.92619 -193.699638)
			(xy 74.90859 -193.678673) (xy 74.878866 -193.63271) (xy 74.856021 -193.582969) (xy 74.840523 -193.530472)
			(xy 74.832692 -193.476298) (xy 74.832687 -193.421562) (xy 74.84051 -193.367387) (xy 74.856 -193.314888)
			(xy 74.878837 -193.265143) (xy 74.908554 -193.219175) (xy 74.92619 -193.198242) (xy 74.926444 -193.197988)
			(xy 74.932047 -193.190913) (xy 74.938283 -193.173987) (xy 74.938636 -193.164968) (xy 74.938636 -193.097912)
			(xy 74.938265 -193.088897) (xy 74.932026 -193.07198) (xy 74.926444 -193.064892) (xy 74.92619 -193.064892)
			(xy 74.92619 -193.064638) (xy 74.908554 -193.043704) (xy 74.878842 -192.997731) (xy 74.856005 -192.947984)
			(xy 74.840514 -192.895484) (xy 74.832685 -192.841309) (xy 74.83221 -192.81394) (xy 74.832788 -192.784717)
			(xy 74.841703 -192.726953) (xy 74.859317 -192.671223) (xy 74.885216 -192.618828) (xy 74.918798 -192.570992)
			(xy 74.938636 -192.549526) (xy 74.945112 -192.542173) (xy 74.952418 -192.524009) (xy 74.95286 -192.51422)
			(xy 74.953114 -192.434464) (xy 74.945748 -192.416176) (xy 74.93889 -192.409064) (xy 74.919182 -192.387623)
			(xy 74.885826 -192.339886) (xy 74.860107 -192.287638) (xy 74.842622 -192.232089) (xy 74.833776 -192.17453)
			(xy 74.833226 -192.145412) (xy 74.833693 -192.118042) (xy 74.841509 -192.063862) (xy 74.856998 -192.011359)
			(xy 74.87984 -191.961612) (xy 74.909565 -191.915646) (xy 74.927206 -191.894714) (xy 74.92746 -191.89446)
			(xy 74.933035 -191.887366) (xy 74.939287 -191.870455) (xy 74.939652 -191.86144) (xy 74.939652 -191.794384)
			(xy 74.939313 -191.785365) (xy 74.933054 -191.768448) (xy 74.92746 -191.761364) (xy 74.927206 -191.761364)
			(xy 74.927206 -191.76111) (xy 74.909578 -191.740167) (xy 74.879854 -191.694201) (xy 74.857009 -191.644456)
			(xy 74.841513 -191.591956) (xy 74.833684 -191.537779) (xy 74.833683 -191.483039) (xy 74.841509 -191.428862)
			(xy 74.857003 -191.376361) (xy 74.879846 -191.326615) (xy 74.909567 -191.280647) (xy 74.927206 -191.259714)
			(xy 74.92746 -191.25946) (xy 74.933035 -191.252366) (xy 74.939287 -191.235455) (xy 74.939652 -191.22644)
			(xy 74.939652 -191.159384) (xy 74.939313 -191.150365) (xy 74.933054 -191.133448) (xy 74.92746 -191.126364)
			(xy 74.927206 -191.126364) (xy 74.927206 -191.12611) (xy 74.909578 -191.105167) (xy 74.879854 -191.059201)
			(xy 74.857009 -191.009456) (xy 74.841513 -190.956956) (xy 74.833684 -190.902779) (xy 74.833683 -190.848039)
			(xy 74.841509 -190.793862) (xy 74.857003 -190.741361) (xy 74.879846 -190.691615) (xy 74.909567 -190.645647)
			(xy 74.927206 -190.624714) (xy 74.92746 -190.62446) (xy 74.933035 -190.617366) (xy 74.939287 -190.600455)
			(xy 74.939652 -190.59144) (xy 74.939652 -190.524384) (xy 74.939313 -190.515365) (xy 74.933054 -190.498448)
			(xy 74.92746 -190.491364) (xy 74.927206 -190.491364) (xy 74.927206 -190.49111) (xy 74.909559 -190.470184)
			(xy 74.879848 -190.42421) (xy 74.857014 -190.374461) (xy 74.841524 -190.321959) (xy 74.833699 -190.267782)
			(xy 74.833226 -190.240412) (xy 74.833711 -190.213113) (xy 74.841481 -190.159072) (xy 74.856879 -190.106691)
			(xy 74.87959 -190.057041) (xy 74.909149 -190.011138) (xy 74.926698 -189.990222) (xy 74.932544 -189.983033)
			(xy 74.939051 -189.9657) (xy 74.939398 -189.95644) (xy 74.939144 -189.880494) (xy 74.932794 -189.863476)
			(xy 74.926698 -189.856618) (xy 74.908992 -189.83565) (xy 74.879113 -189.78962) (xy 74.856144 -189.73978)
			(xy 74.840562 -189.687161) (xy 74.832689 -189.632851) (xy 74.83221 -189.605412) (xy 74.832667 -189.578159)
			(xy 74.840422 -189.524207) (xy 74.855778 -189.471907) (xy 74.87842 -189.422326) (xy 74.907889 -189.376472)
			(xy 74.943583 -189.335279) (xy 74.984777 -189.299585) (xy 75.030631 -189.270117) (xy 75.080213 -189.247476)
			(xy 75.132512 -189.232121) (xy 75.186465 -189.224366) (xy 75.213718 -189.223904) (xy 75.241089 -189.224359)
			(xy 75.295268 -189.232179) (xy 75.347772 -189.247671) (xy 75.397518 -189.270515) (xy 75.443485 -189.300242)
			(xy 75.464416 -189.317884) (xy 75.46467 -189.318138) (xy 75.471758 -189.323722) (xy 75.488674 -189.329969)
			(xy 75.49769 -189.33033) (xy 75.564746 -189.33033) (xy 75.573759 -189.329941) (xy 75.590676 -189.323715)
			(xy 75.597766 -189.318138) (xy 75.597766 -189.317884) (xy 75.59802 -189.317884) (xy 75.618953 -189.300243)
			(xy 75.664921 -189.270519) (xy 75.714667 -189.247673) (xy 75.767169 -189.232177) (xy 75.821347 -189.224348)
			(xy 75.876089 -189.224348) (xy 75.930267 -189.232177) (xy 75.982769 -189.247673) (xy 76.032515 -189.270519)
			(xy 76.078483 -189.300243) (xy 76.099416 -189.317884) (xy 76.09967 -189.318138) (xy 76.106758 -189.323722)
			(xy 76.123674 -189.329969) (xy 76.13269 -189.33033) (xy 76.199746 -189.33033) (xy 76.208759 -189.329941)
			(xy 76.225676 -189.323715) (xy 76.232766 -189.318138) (xy 76.232766 -189.317884) (xy 76.23302 -189.317884)
			(xy 76.253969 -189.300266) (xy 76.299938 -189.270552) (xy 76.349681 -189.247712) (xy 76.402178 -189.232216)
			(xy 76.45635 -189.224382) (xy 76.483718 -189.223904) (xy 76.51097 -189.224361) (xy 76.56492 -189.23212)
			(xy 76.617216 -189.247478) (xy 76.666794 -189.270122) (xy 76.712645 -189.299592) (xy 76.753835 -189.335286)
			(xy 76.789526 -189.376479) (xy 76.818992 -189.422333) (xy 76.841632 -189.471913) (xy 76.856986 -189.52421)
			(xy 76.864741 -189.57816) (xy 76.865226 -189.605412) (xy 76.864734 -189.632956) (xy 76.856779 -189.687466)
			(xy 76.841065 -189.740265) (xy 76.817919 -189.790255) (xy 76.787823 -189.836394) (xy 76.769976 -189.85738)
			(xy 76.764126 -189.864566) (xy 76.757623 -189.881902) (xy 76.757276 -189.891162) (xy 76.75753 -189.958472)
			(xy 76.757932 -189.967572) (xy 76.7643 -189.984623) (xy 76.769976 -189.991746) (xy 76.77023 -189.992)
			(xy 76.78822 -190.013035) (xy 76.818568 -190.059321) (xy 76.841906 -190.109509) (xy 76.857743 -190.162543)
			(xy 76.865747 -190.21731) (xy 76.866242 -190.244984) (xy 76.865781 -190.272355) (xy 76.857964 -190.326534)
			(xy 76.842474 -190.379038) (xy 76.819631 -190.428785) (xy 76.789905 -190.474751) (xy 76.772262 -190.495682)
			(xy 76.772008 -190.495936) (xy 76.766443 -190.503037) (xy 76.760183 -190.519943) (xy 76.759816 -190.528956)
			(xy 76.759816 -190.596012) (xy 76.760164 -190.60503) (xy 76.766417 -190.621947) (xy 76.772008 -190.629032)
			(xy 76.772262 -190.629032) (xy 76.772262 -190.629286) (xy 76.789887 -190.650231) (xy 76.819614 -190.696197)
			(xy 76.842461 -190.745941) (xy 76.857959 -190.798441) (xy 76.865789 -190.852618) (xy 76.865791 -190.907358)
			(xy 76.857964 -190.961535) (xy 76.842469 -191.014037) (xy 76.819625 -191.063782) (xy 76.789902 -191.10975)
			(xy 76.772262 -191.130682) (xy 76.772008 -191.130936) (xy 76.766443 -191.138037) (xy 76.760183 -191.154943)
			(xy 76.759816 -191.163956) (xy 76.759816 -191.231012) (xy 76.760164 -191.24003) (xy 76.766417 -191.256947)
			(xy 76.772008 -191.264032) (xy 76.772262 -191.264032) (xy 76.772262 -191.264286) (xy 76.789887 -191.285231)
			(xy 76.819614 -191.331197) (xy 76.842461 -191.380941) (xy 76.857959 -191.433441) (xy 76.865789 -191.487618)
			(xy 76.865791 -191.542358) (xy 76.857964 -191.596535) (xy 76.842469 -191.649037) (xy 76.819625 -191.698782)
			(xy 76.789902 -191.74475) (xy 76.772262 -191.765682) (xy 76.772008 -191.765936) (xy 76.766443 -191.773037)
			(xy 76.760183 -191.789943) (xy 76.759816 -191.798956) (xy 76.759816 -191.866012) (xy 76.760164 -191.87503)
			(xy 76.766417 -191.891947) (xy 76.772008 -191.899032) (xy 76.772262 -191.899032) (xy 76.772262 -191.899286)
			(xy 76.789902 -191.920217) (xy 76.819615 -191.96619) (xy 76.842451 -192.015937) (xy 76.857942 -192.068438)
			(xy 76.865769 -192.122615) (xy 76.866242 -192.149984) (xy 76.866242 -192.150238) (xy 76.865665 -192.179187)
			(xy 76.85689 -192.236416) (xy 76.839577 -192.291665) (xy 76.814123 -192.343668) (xy 76.781112 -192.391233)
			(xy 76.761594 -192.41262) (xy 76.75526 -192.419894) (xy 76.748085 -192.437783) (xy 76.747624 -192.447418)
			(xy 76.74737 -192.527174) (xy 76.754482 -192.545208) (xy 76.76134 -192.55232) (xy 76.780724 -192.573687)
			(xy 76.813527 -192.621142) (xy 76.83881 -192.672996) (xy 76.855995 -192.728066) (xy 76.864692 -192.785096)
			(xy 76.865226 -192.81394) (xy 76.864743 -192.84131) (xy 76.856932 -192.895489) (xy 76.841448 -192.947993)
			(xy 76.818609 -192.99774) (xy 76.788887 -193.043707) (xy 76.771246 -193.064638) (xy 76.770992 -193.064892)
			(xy 76.765402 -193.071976) (xy 76.759158 -193.088895) (xy 76.7588 -193.097912) (xy 76.7588 -193.164968)
			(xy 76.759172 -193.173983) (xy 76.765409 -193.1909) (xy 76.770992 -193.197988) (xy 76.771246 -193.197988)
			(xy 76.771246 -193.198242) (xy 76.788927 -193.219142) (xy 76.818652 -193.265115) (xy 76.841497 -193.314867)
			(xy 76.856991 -193.367374) (xy 76.864817 -193.421557) (xy 76.864812 -193.476303) (xy 76.856978 -193.530485)
			(xy 76.841476 -193.58299) (xy 76.818623 -193.632738) (xy 76.788891 -193.678706) (xy 76.771246 -193.699638)
			(xy 76.770992 -193.699892) (xy 76.765402 -193.706976) (xy 76.759158 -193.723895) (xy 76.7588 -193.732912)
			(xy 76.7588 -193.799968) (xy 76.759172 -193.808983) (xy 76.765409 -193.8259) (xy 76.770992 -193.832988)
			(xy 76.771246 -193.832988) (xy 76.771246 -193.833242) (xy 76.788927 -193.854142) (xy 76.818652 -193.900115)
			(xy 76.841497 -193.949867) (xy 76.856991 -194.002374) (xy 76.864817 -194.056557) (xy 76.864812 -194.111303)
			(xy 76.856978 -194.165485) (xy 76.841476 -194.21799) (xy 76.818623 -194.267738) (xy 76.788891 -194.313706)
			(xy 76.771246 -194.334638) (xy 76.770992 -194.334892) (xy 76.765402 -194.341976) (xy 76.759158 -194.358895)
			(xy 76.7588 -194.367912) (xy 76.7588 -194.434968) (xy 76.759172 -194.443983) (xy 76.765409 -194.4609)
			(xy 76.770992 -194.467988) (xy 76.771246 -194.467988) (xy 76.771246 -194.468242) (xy 76.788927 -194.489142)
			(xy 76.818652 -194.535115) (xy 76.841497 -194.584867) (xy 76.856991 -194.637374) (xy 76.864817 -194.691557)
			(xy 76.864812 -194.746303) (xy 76.856978 -194.800485) (xy 76.841476 -194.85299) (xy 76.818623 -194.902738)
			(xy 76.788891 -194.948706) (xy 76.771246 -194.969638) (xy 76.770992 -194.969892) (xy 76.765402 -194.976976)
			(xy 76.759158 -194.993895) (xy 76.7588 -195.002912) (xy 76.7588 -195.069968) (xy 76.759172 -195.078983)
			(xy 76.765409 -195.0959) (xy 76.770992 -195.102988) (xy 76.771246 -195.102988) (xy 76.771246 -195.103242)
			(xy 76.788927 -195.124142) (xy 76.818652 -195.170115) (xy 76.841497 -195.219867) (xy 76.856991 -195.272374)
			(xy 76.864817 -195.326557) (xy 76.864812 -195.381303) (xy 76.856978 -195.435485) (xy 76.841476 -195.48799)
			(xy 76.818623 -195.537738) (xy 76.788891 -195.583706) (xy 76.771246 -195.604638) (xy 76.770992 -195.604892)
			(xy 76.765402 -195.611976) (xy 76.759158 -195.628895) (xy 76.7588 -195.637912) (xy 76.7588 -195.704968)
			(xy 76.759172 -195.713983) (xy 76.765409 -195.7309) (xy 76.770992 -195.737988) (xy 76.771246 -195.737988)
			(xy 76.771246 -195.738242) (xy 76.788863 -195.759192) (xy 76.81858 -195.805159) (xy 76.841421 -195.854902)
			(xy 76.856917 -195.907399) (xy 76.86475 -195.961572) (xy 76.865226 -195.98894) (xy 76.864759 -196.016191)
			(xy 76.856998 -196.070139) (xy 76.841639 -196.122433) (xy 76.818994 -196.172009) (xy 76.789525 -196.217858)
			(xy 76.753832 -196.259048) (xy 76.712641 -196.294739) (xy 76.66679 -196.324205) (xy 76.617212 -196.346846)
			(xy 76.564917 -196.362203) (xy 76.510969 -196.369961) (xy 76.483718 -196.370448) (xy 76.456348 -196.369984)
			(xy 76.402168 -196.362168) (xy 76.349664 -196.346679) (xy 76.299917 -196.323836) (xy 76.253951 -196.29411)
			(xy 76.23302 -196.276468) (xy 76.232766 -196.276214) (xy 76.225664 -196.27065) (xy 76.208759 -196.264389)
			(xy 76.199746 -196.264022) (xy 76.13269 -196.264022) (xy 76.123672 -196.264369) (xy 76.106755 -196.270623)
			(xy 76.09967 -196.276214) (xy 76.099416 -196.276468) (xy 76.078483 -196.294109) (xy 76.032515 -196.323833)
			(xy 75.982769 -196.346679) (xy 75.930267 -196.362175) (xy 75.876089 -196.370004) (xy 75.821347 -196.370004)
			(xy 75.767169 -196.362175) (xy 75.714667 -196.346679) (xy 75.664921 -196.323833) (xy 75.618953 -196.294109)
			(xy 75.59802 -196.276468) (xy 75.597766 -196.276214) (xy 75.590664 -196.27065) (xy 75.573759 -196.264389)
			(xy 75.564746 -196.264022) (xy 75.49769 -196.264022) (xy 75.488672 -196.264369) (xy 75.471755 -196.270623)
			(xy 75.46467 -196.276214) (xy 75.46467 -196.276468) (xy 75.464416 -196.276468) (xy 75.443485 -196.294108)
			(xy 75.397512 -196.323821) (xy 75.347765 -196.346657) (xy 75.295263 -196.362148) (xy 75.241087 -196.369975)
			(xy 75.213718 -196.370448) (xy 75.186469 -196.369905) (xy 75.132525 -196.362152) (xy 75.080234 -196.346801)
			(xy 75.03066 -196.324165) (xy 74.984811 -196.294705) (xy 74.943622 -196.259019) (xy 74.90793 -196.217835)
			(xy 74.878463 -196.171991) (xy 74.855819 -196.12242) (xy 74.84046 -196.070131) (xy 74.832699 -196.016189)
			(xy 74.83221 -195.98894) (xy 72.779382 -195.98894) (xy 77.872082 -201.08164) (xy 79.14259 -201.08164)
			(xy 79.143082 -201.054271) (xy 79.150894 -201.000093) (xy 79.166377 -200.94759) (xy 79.189213 -200.897843)
			(xy 79.218932 -200.851875) (xy 79.23657 -200.830942) (xy 79.236824 -200.830688) (xy 79.242424 -200.823611)
			(xy 79.248662 -200.806687) (xy 79.249016 -200.797668) (xy 79.249016 -200.730612) (xy 79.24865 -200.721596)
			(xy 79.242408 -200.704679) (xy 79.236824 -200.697592) (xy 79.23657 -200.697592) (xy 79.23657 -200.697338)
			(xy 79.218967 -200.676374) (xy 79.189237 -200.630413) (xy 79.166387 -200.580672) (xy 79.150885 -200.528174)
			(xy 79.143052 -200.473999) (xy 79.143048 -200.419261) (xy 79.150873 -200.365085) (xy 79.166365 -200.312584)
			(xy 79.189208 -200.26284) (xy 79.21893 -200.216874) (xy 79.23657 -200.195942) (xy 79.236824 -200.195688)
			(xy 79.242424 -200.188611) (xy 79.248662 -200.171687) (xy 79.249016 -200.162668) (xy 79.249016 -200.095612)
			(xy 79.24865 -200.086596) (xy 79.242408 -200.069679) (xy 79.236824 -200.062592) (xy 79.23657 -200.062592)
			(xy 79.23657 -200.062338) (xy 79.218967 -200.041374) (xy 79.189237 -199.995413) (xy 79.166387 -199.945672)
			(xy 79.150885 -199.893174) (xy 79.143052 -199.838999) (xy 79.143048 -199.784261) (xy 79.150873 -199.730085)
			(xy 79.166365 -199.677584) (xy 79.189208 -199.62784) (xy 79.21893 -199.581874) (xy 79.23657 -199.560942)
			(xy 79.236824 -199.560688) (xy 79.242424 -199.553611) (xy 79.248662 -199.536687) (xy 79.249016 -199.527668)
			(xy 79.249016 -199.460612) (xy 79.24865 -199.451596) (xy 79.242408 -199.434679) (xy 79.236824 -199.427592)
			(xy 79.23657 -199.427592) (xy 79.23657 -199.427338) (xy 79.218967 -199.406374) (xy 79.189237 -199.360413)
			(xy 79.166387 -199.310672) (xy 79.150885 -199.258174) (xy 79.143052 -199.203999) (xy 79.143048 -199.149261)
			(xy 79.150873 -199.095085) (xy 79.166365 -199.042584) (xy 79.189208 -198.99284) (xy 79.21893 -198.946874)
			(xy 79.23657 -198.925942) (xy 79.236824 -198.925688) (xy 79.242424 -198.918611) (xy 79.248662 -198.901687)
			(xy 79.249016 -198.892668) (xy 79.249016 -198.825612) (xy 79.24865 -198.816596) (xy 79.242408 -198.799679)
			(xy 79.236824 -198.792592) (xy 79.23657 -198.792592) (xy 79.23657 -198.792338) (xy 79.218967 -198.771374)
			(xy 79.189237 -198.725413) (xy 79.166387 -198.675672) (xy 79.150885 -198.623174) (xy 79.143052 -198.568999)
			(xy 79.143048 -198.514261) (xy 79.150873 -198.460085) (xy 79.166365 -198.407584) (xy 79.189208 -198.35784)
			(xy 79.21893 -198.311874) (xy 79.23657 -198.290942) (xy 79.236824 -198.290688) (xy 79.242424 -198.283611)
			(xy 79.248662 -198.266687) (xy 79.249016 -198.257668) (xy 79.249016 -198.190612) (xy 79.24865 -198.181596)
			(xy 79.242408 -198.164679) (xy 79.236824 -198.157592) (xy 79.23657 -198.157592) (xy 79.23657 -198.157338)
			(xy 79.218967 -198.136374) (xy 79.189237 -198.090413) (xy 79.166387 -198.040672) (xy 79.150885 -197.988174)
			(xy 79.143052 -197.933999) (xy 79.143048 -197.879261) (xy 79.150873 -197.825085) (xy 79.166365 -197.772584)
			(xy 79.189208 -197.72284) (xy 79.21893 -197.676874) (xy 79.23657 -197.655942) (xy 79.236824 -197.655688)
			(xy 79.242424 -197.648611) (xy 79.248662 -197.631687) (xy 79.249016 -197.622668) (xy 79.249016 -197.555612)
			(xy 79.24865 -197.546596) (xy 79.242408 -197.529679) (xy 79.236824 -197.522592) (xy 79.23657 -197.522592)
			(xy 79.23657 -197.522338) (xy 79.218967 -197.501374) (xy 79.189237 -197.455413) (xy 79.166387 -197.405672)
			(xy 79.150885 -197.353174) (xy 79.143052 -197.298999) (xy 79.143048 -197.244261) (xy 79.150873 -197.190085)
			(xy 79.166365 -197.137584) (xy 79.189208 -197.08784) (xy 79.21893 -197.041874) (xy 79.23657 -197.020942)
			(xy 79.236824 -197.020688) (xy 79.242424 -197.013611) (xy 79.248662 -196.996687) (xy 79.249016 -196.987668)
			(xy 79.249016 -196.920612) (xy 79.24865 -196.911596) (xy 79.242408 -196.894679) (xy 79.236824 -196.887592)
			(xy 79.23657 -196.887592) (xy 79.23657 -196.887338) (xy 79.218967 -196.866374) (xy 79.189237 -196.820413)
			(xy 79.166387 -196.770672) (xy 79.150885 -196.718174) (xy 79.143052 -196.663999) (xy 79.143048 -196.609261)
			(xy 79.150873 -196.555085) (xy 79.166365 -196.502584) (xy 79.189208 -196.45284) (xy 79.21893 -196.406874)
			(xy 79.23657 -196.385942) (xy 79.236824 -196.385688) (xy 79.242424 -196.378611) (xy 79.248662 -196.361687)
			(xy 79.249016 -196.352668) (xy 79.249016 -196.285612) (xy 79.24865 -196.276596) (xy 79.242408 -196.259679)
			(xy 79.236824 -196.252592) (xy 79.23657 -196.252592) (xy 79.23657 -196.252338) (xy 79.218967 -196.231374)
			(xy 79.189237 -196.185413) (xy 79.166387 -196.135672) (xy 79.150885 -196.083174) (xy 79.143052 -196.028999)
			(xy 79.143048 -195.974261) (xy 79.150873 -195.920085) (xy 79.166365 -195.867584) (xy 79.189208 -195.81784)
			(xy 79.21893 -195.771874) (xy 79.23657 -195.750942) (xy 79.236824 -195.750688) (xy 79.242424 -195.743611)
			(xy 79.248662 -195.726687) (xy 79.249016 -195.717668) (xy 79.249016 -195.650612) (xy 79.24865 -195.641596)
			(xy 79.242408 -195.624679) (xy 79.236824 -195.617592) (xy 79.23657 -195.617592) (xy 79.23657 -195.617338)
			(xy 79.218931 -195.596406) (xy 79.18922 -195.550433) (xy 79.166384 -195.500685) (xy 79.150893 -195.448185)
			(xy 79.143065 -195.394009) (xy 79.14259 -195.36664) (xy 79.143079 -195.338836) (xy 79.151154 -195.283818)
			(xy 79.167124 -195.230554) (xy 79.190651 -195.180169) (xy 79.221239 -195.133729) (xy 79.239364 -195.11264)
			(xy 79.245295 -195.105487) (xy 79.251924 -195.088143) (xy 79.252318 -195.078858) (xy 79.252318 -195.011294)
			(xy 79.251894 -195.00202) (xy 79.24524 -194.984701) (xy 79.239364 -194.977512) (xy 79.221245 -194.956417)
			(xy 79.190657 -194.90998) (xy 79.16713 -194.859597) (xy 79.151163 -194.806332) (xy 79.143093 -194.751315)
			(xy 79.14259 -194.723512) (xy 79.143066 -194.69626) (xy 79.150822 -194.642309) (xy 79.166176 -194.590012)
			(xy 79.188817 -194.540432) (xy 79.218284 -194.494579) (xy 79.253976 -194.453386) (xy 79.295167 -194.417692)
			(xy 79.341019 -194.388224) (xy 79.390599 -194.365581) (xy 79.442895 -194.350225) (xy 79.496846 -194.342467)
			(xy 79.524098 -194.342004) (xy 79.551468 -194.34247) (xy 79.605647 -194.350288) (xy 79.658151 -194.365777)
			(xy 79.707897 -194.388619) (xy 79.753864 -194.418343) (xy 79.774796 -194.435984) (xy 79.77505 -194.436238)
			(xy 79.782144 -194.441814) (xy 79.799055 -194.448066) (xy 79.80807 -194.44843) (xy 79.875126 -194.44843)
			(xy 79.884143 -194.448079) (xy 79.90106 -194.441827) (xy 79.908146 -194.436238) (xy 79.908146 -194.435984)
			(xy 79.9084 -194.435984) (xy 79.929333 -194.418343) (xy 79.975301 -194.388619) (xy 80.025047 -194.365773)
			(xy 80.077549 -194.350277) (xy 80.131727 -194.342448) (xy 80.186469 -194.342448) (xy 80.240647 -194.350277)
			(xy 80.293149 -194.365773) (xy 80.342895 -194.388619) (xy 80.388863 -194.418343) (xy 80.409796 -194.435984)
			(xy 80.41005 -194.436238) (xy 80.417144 -194.441814) (xy 80.434055 -194.448066) (xy 80.44307 -194.44843)
			(xy 80.510126 -194.44843) (xy 80.519143 -194.448079) (xy 80.53606 -194.441827) (xy 80.543146 -194.436238)
			(xy 80.543146 -194.435984) (xy 80.5434 -194.435984) (xy 80.564319 -194.418329) (xy 80.610296 -194.38862)
			(xy 80.660047 -194.365787) (xy 80.71255 -194.3503) (xy 80.766728 -194.342476) (xy 80.794098 -194.342004)
			(xy 80.821351 -194.342457) (xy 80.875303 -194.350214) (xy 80.927602 -194.365571) (xy 80.977183 -194.388214)
			(xy 81.023037 -194.417683) (xy 81.06423 -194.453377) (xy 81.099923 -194.494571) (xy 81.129391 -194.540426)
			(xy 81.152033 -194.590007) (xy 81.167388 -194.642307) (xy 81.175143 -194.696259) (xy 81.175606 -194.723512)
			(xy 81.175128 -194.750811) (xy 81.167355 -194.804852) (xy 81.151955 -194.857233) (xy 81.129243 -194.906883)
			(xy 81.099683 -194.952786) (xy 81.082134 -194.973702) (xy 81.076312 -194.980907) (xy 81.069793 -194.998228)
			(xy 81.069434 -195.007484) (xy 81.069688 -195.08343) (xy 81.076038 -195.100448) (xy 81.082134 -195.107306)
			(xy 81.099856 -195.128261) (xy 81.129732 -195.174295) (xy 81.152697 -195.224138) (xy 81.168275 -195.27676)
			(xy 81.176145 -195.331072) (xy 81.176622 -195.358512) (xy 81.176182 -195.385883) (xy 81.168361 -195.440064)
			(xy 81.152867 -195.492568) (xy 81.130019 -195.542315) (xy 81.100287 -195.58828) (xy 81.082642 -195.60921)
			(xy 81.082388 -195.609464) (xy 81.076809 -195.616556) (xy 81.070558 -195.633469) (xy 81.070196 -195.642484)
			(xy 81.070196 -195.70954) (xy 81.070535 -195.718559) (xy 81.076795 -195.735475) (xy 81.082388 -195.74256)
			(xy 81.082642 -195.74256) (xy 81.082642 -195.742814) (xy 81.100296 -195.763737) (xy 81.130022 -195.809705)
			(xy 81.152869 -195.859453) (xy 81.168366 -195.911957) (xy 81.176194 -195.966137) (xy 81.176192 -196.020881)
			(xy 81.168362 -196.075061) (xy 81.152863 -196.127564) (xy 81.130014 -196.17731) (xy 81.100285 -196.223278)
			(xy 81.082642 -196.24421) (xy 81.082388 -196.244464) (xy 81.076809 -196.251556) (xy 81.070558 -196.268469)
			(xy 81.070196 -196.277484) (xy 81.070196 -196.34454) (xy 81.070535 -196.353559) (xy 81.076795 -196.370475)
			(xy 81.082388 -196.37756) (xy 81.082642 -196.37756) (xy 81.082642 -196.377814) (xy 81.100296 -196.398737)
			(xy 81.130022 -196.444705) (xy 81.152869 -196.494453) (xy 81.168366 -196.546957) (xy 81.176194 -196.601137)
			(xy 81.176192 -196.655881) (xy 81.168362 -196.710061) (xy 81.152863 -196.762564) (xy 81.130014 -196.81231)
			(xy 81.100285 -196.858278) (xy 81.082642 -196.87921) (xy 81.082388 -196.879464) (xy 81.076809 -196.886556)
			(xy 81.070558 -196.903469) (xy 81.070196 -196.912484) (xy 81.070196 -196.97954) (xy 81.070535 -196.988559)
			(xy 81.076795 -197.005475) (xy 81.082388 -197.01256) (xy 81.082642 -197.01256) (xy 81.082642 -197.012814)
			(xy 81.100261 -197.033762) (xy 81.129975 -197.079731) (xy 81.152814 -197.129475) (xy 81.16831 -197.181971)
			(xy 81.176145 -197.236144) (xy 81.176622 -197.263512) (xy 81.176097 -197.291386) (xy 81.167994 -197.346541)
			(xy 81.151947 -197.399929) (xy 81.1283 -197.450412) (xy 81.097555 -197.496915) (xy 81.07934 -197.51802)
			(xy 81.073244 -197.524878) (xy 81.06664 -197.54215) (xy 81.066386 -197.628764) (xy 81.07299 -197.646036)
			(xy 81.079086 -197.652894) (xy 81.079086 -197.653148) (xy 81.097179 -197.674189) (xy 81.127696 -197.720538)
			(xy 81.151162 -197.770825) (xy 81.167081 -197.823985) (xy 81.175115 -197.878893) (xy 81.175606 -197.90664)
			(xy 81.175103 -197.934009) (xy 81.167294 -197.988186) (xy 81.151813 -198.040689) (xy 81.12898 -198.090436)
			(xy 81.099263 -198.136405) (xy 81.081626 -198.157338) (xy 81.081372 -198.157592) (xy 81.07578 -198.164674)
			(xy 81.069537 -198.181594) (xy 81.06918 -198.190612) (xy 81.06918 -198.257668) (xy 81.069557 -198.266683)
			(xy 81.075791 -198.2836) (xy 81.081372 -198.290688) (xy 81.081626 -198.290688) (xy 81.081626 -198.290942)
			(xy 81.099308 -198.311842) (xy 81.129035 -198.357814) (xy 81.15188 -198.407566) (xy 81.167376 -198.460073)
			(xy 81.175202 -198.514257) (xy 81.175197 -198.569003) (xy 81.167363 -198.623186) (xy 81.151859 -198.675691)
			(xy 81.129006 -198.725439) (xy 81.099271 -198.771406) (xy 81.081626 -198.792338) (xy 81.081372 -198.792592)
			(xy 81.07578 -198.799674) (xy 81.069537 -198.816594) (xy 81.06918 -198.825612) (xy 81.06918 -198.892668)
			(xy 81.069557 -198.901683) (xy 81.075791 -198.9186) (xy 81.081372 -198.925688) (xy 81.081626 -198.925688)
			(xy 81.081626 -198.925942) (xy 81.099308 -198.946842) (xy 81.129035 -198.992814) (xy 81.15188 -199.042566)
			(xy 81.167376 -199.095073) (xy 81.175202 -199.149257) (xy 81.175197 -199.204003) (xy 81.167363 -199.258186)
			(xy 81.151859 -199.310691) (xy 81.129006 -199.360439) (xy 81.099271 -199.406406) (xy 81.081626 -199.427338)
			(xy 81.081372 -199.427592) (xy 81.07578 -199.434674) (xy 81.069537 -199.451594) (xy 81.06918 -199.460612)
			(xy 81.06918 -199.527668) (xy 81.069557 -199.536683) (xy 81.075791 -199.5536) (xy 81.081372 -199.560688)
			(xy 81.081626 -199.560688) (xy 81.081626 -199.560942) (xy 81.099308 -199.581842) (xy 81.129035 -199.627814)
			(xy 81.15188 -199.677566) (xy 81.167376 -199.730073) (xy 81.175202 -199.784257) (xy 81.175197 -199.839003)
			(xy 81.167363 -199.893186) (xy 81.151859 -199.945691) (xy 81.129006 -199.995439) (xy 81.099271 -200.041406)
			(xy 81.081626 -200.062338) (xy 81.081372 -200.062592) (xy 81.07578 -200.069674) (xy 81.069537 -200.086594)
			(xy 81.06918 -200.095612) (xy 81.06918 -200.162668) (xy 81.069557 -200.171683) (xy 81.075791 -200.1886)
			(xy 81.081372 -200.195688) (xy 81.081626 -200.195688) (xy 81.081626 -200.195942) (xy 81.099308 -200.216842)
			(xy 81.129035 -200.262814) (xy 81.15188 -200.312566) (xy 81.167376 -200.365073) (xy 81.175202 -200.419257)
			(xy 81.175197 -200.474003) (xy 81.167363 -200.528186) (xy 81.151859 -200.580691) (xy 81.129006 -200.630439)
			(xy 81.099271 -200.676406) (xy 81.081626 -200.697338) (xy 81.081372 -200.697592) (xy 81.07578 -200.704674)
			(xy 81.069537 -200.721594) (xy 81.06918 -200.730612) (xy 81.06918 -200.797668) (xy 81.069557 -200.806683)
			(xy 81.075791 -200.8236) (xy 81.081372 -200.830688) (xy 81.081626 -200.830688) (xy 81.081626 -200.830942)
			(xy 81.099255 -200.851882) (xy 81.128968 -200.897853) (xy 81.151805 -200.947598) (xy 81.167299 -201.000097)
			(xy 81.17513 -201.054271) (xy 81.175606 -201.08164) (xy 83.15579 -201.08164) (xy 83.156282 -201.054271)
			(xy 83.164094 -201.000093) (xy 83.179577 -200.94759) (xy 83.202413 -200.897843) (xy 83.232132 -200.851875)
			(xy 83.24977 -200.830942) (xy 83.250024 -200.830688) (xy 83.255624 -200.823611) (xy 83.261862 -200.806687)
			(xy 83.262216 -200.797668) (xy 83.262216 -200.730612) (xy 83.26185 -200.721596) (xy 83.255608 -200.704679)
			(xy 83.250024 -200.697592) (xy 83.24977 -200.697592) (xy 83.24977 -200.697338) (xy 83.232167 -200.676374)
			(xy 83.202437 -200.630413) (xy 83.179587 -200.580672) (xy 83.164085 -200.528174) (xy 83.156252 -200.473999)
			(xy 83.156248 -200.419261) (xy 83.164073 -200.365085) (xy 83.179565 -200.312584) (xy 83.202408 -200.26284)
			(xy 83.23213 -200.216874) (xy 83.24977 -200.195942) (xy 83.250024 -200.195688) (xy 83.255624 -200.188611)
			(xy 83.261862 -200.171687) (xy 83.262216 -200.162668) (xy 83.262216 -200.095612) (xy 83.26185 -200.086596)
			(xy 83.255608 -200.069679) (xy 83.250024 -200.062592) (xy 83.24977 -200.062592) (xy 83.24977 -200.062338)
			(xy 83.232167 -200.041374) (xy 83.202437 -199.995413) (xy 83.179587 -199.945672) (xy 83.164085 -199.893174)
			(xy 83.156252 -199.838999) (xy 83.156248 -199.784261) (xy 83.164073 -199.730085) (xy 83.179565 -199.677584)
			(xy 83.202408 -199.62784) (xy 83.23213 -199.581874) (xy 83.24977 -199.560942) (xy 83.250024 -199.560688)
			(xy 83.255624 -199.553611) (xy 83.261862 -199.536687) (xy 83.262216 -199.527668) (xy 83.262216 -199.460612)
			(xy 83.26185 -199.451596) (xy 83.255608 -199.434679) (xy 83.250024 -199.427592) (xy 83.24977 -199.427592)
			(xy 83.24977 -199.427338) (xy 83.232167 -199.406374) (xy 83.202437 -199.360413) (xy 83.179587 -199.310672)
			(xy 83.164085 -199.258174) (xy 83.156252 -199.203999) (xy 83.156248 -199.149261) (xy 83.164073 -199.095085)
			(xy 83.179565 -199.042584) (xy 83.202408 -198.99284) (xy 83.23213 -198.946874) (xy 83.24977 -198.925942)
			(xy 83.250024 -198.925688) (xy 83.255624 -198.918611) (xy 83.261862 -198.901687) (xy 83.262216 -198.892668)
			(xy 83.262216 -198.825612) (xy 83.26185 -198.816596) (xy 83.255608 -198.799679) (xy 83.250024 -198.792592)
			(xy 83.24977 -198.792592) (xy 83.24977 -198.792338) (xy 83.232167 -198.771374) (xy 83.202437 -198.725413)
			(xy 83.179587 -198.675672) (xy 83.164085 -198.623174) (xy 83.156252 -198.568999) (xy 83.156248 -198.514261)
			(xy 83.164073 -198.460085) (xy 83.179565 -198.407584) (xy 83.202408 -198.35784) (xy 83.23213 -198.311874)
			(xy 83.24977 -198.290942) (xy 83.250024 -198.290688) (xy 83.255624 -198.283611) (xy 83.261862 -198.266687)
			(xy 83.262216 -198.257668) (xy 83.262216 -198.190612) (xy 83.26185 -198.181596) (xy 83.255608 -198.164679)
			(xy 83.250024 -198.157592) (xy 83.24977 -198.157592) (xy 83.24977 -198.157338) (xy 83.232131 -198.136406)
			(xy 83.20242 -198.090433) (xy 83.179584 -198.040685) (xy 83.164093 -197.988185) (xy 83.156265 -197.934009)
			(xy 83.15579 -197.90664) (xy 83.156284 -197.878765) (xy 83.164394 -197.823608) (xy 83.180447 -197.77022)
			(xy 83.204102 -197.719737) (xy 83.234854 -197.673236) (xy 83.253072 -197.652132) (xy 83.259168 -197.645274)
			(xy 83.265772 -197.628002) (xy 83.266026 -197.541388) (xy 83.259422 -197.524116) (xy 83.253326 -197.517258)
			(xy 83.253326 -197.517004) (xy 83.235259 -197.495941) (xy 83.204738 -197.449599) (xy 83.181267 -197.399317)
			(xy 83.165342 -197.346161) (xy 83.157301 -197.291257) (xy 83.156806 -197.263512) (xy 83.157278 -197.236142)
			(xy 83.165094 -197.181963) (xy 83.180582 -197.12946) (xy 83.203422 -197.079713) (xy 83.233145 -197.033746)
			(xy 83.250786 -197.012814) (xy 83.25104 -197.01256) (xy 83.256612 -197.005464) (xy 83.262867 -196.988554)
			(xy 83.263232 -196.97954) (xy 83.263232 -196.912484) (xy 83.262876 -196.903467) (xy 83.256627 -196.886551)
			(xy 83.25104 -196.879464) (xy 83.250786 -196.879464) (xy 83.250786 -196.87921) (xy 83.233159 -196.858267)
			(xy 83.203437 -196.8123) (xy 83.180593 -196.762555) (xy 83.165098 -196.710055) (xy 83.157269 -196.655879)
			(xy 83.157267 -196.601139) (xy 83.165094 -196.546963) (xy 83.180587 -196.494462) (xy 83.203428 -196.444716)
			(xy 83.233148 -196.398748) (xy 83.250786 -196.377814) (xy 83.25104 -196.37756) (xy 83.256612 -196.370464)
			(xy 83.262867 -196.353554) (xy 83.263232 -196.34454) (xy 83.263232 -196.277484) (xy 83.262876 -196.268467)
			(xy 83.256627 -196.251551) (xy 83.25104 -196.244464) (xy 83.250786 -196.244464) (xy 83.250786 -196.24421)
			(xy 83.233159 -196.223267) (xy 83.203437 -196.1773) (xy 83.180593 -196.127555) (xy 83.165098 -196.075055)
			(xy 83.157269 -196.020879) (xy 83.157267 -195.966139) (xy 83.165094 -195.911963) (xy 83.180587 -195.859462)
			(xy 83.203428 -195.809716) (xy 83.233148 -195.763748) (xy 83.250786 -195.742814) (xy 83.25104 -195.74256)
			(xy 83.256612 -195.735464) (xy 83.262867 -195.718554) (xy 83.263232 -195.70954) (xy 83.263232 -195.642484)
			(xy 83.262876 -195.633467) (xy 83.256627 -195.616551) (xy 83.25104 -195.609464) (xy 83.250786 -195.609464)
			(xy 83.250786 -195.60921) (xy 83.233136 -195.588287) (xy 83.203426 -195.542311) (xy 83.180593 -195.492562)
			(xy 83.165104 -195.440059) (xy 83.157279 -195.385882) (xy 83.156806 -195.358512) (xy 83.157296 -195.331213)
			(xy 83.165065 -195.277172) (xy 83.180463 -195.224792) (xy 83.203172 -195.175142) (xy 83.23273 -195.129238)
			(xy 83.250278 -195.108322) (xy 83.256134 -195.101141) (xy 83.262632 -195.083801) (xy 83.262978 -195.07454)
			(xy 83.262724 -194.998594) (xy 83.256374 -194.981576) (xy 83.250278 -194.974718) (xy 83.232569 -194.953753)
			(xy 83.202691 -194.907721) (xy 83.179723 -194.857881) (xy 83.164142 -194.805261) (xy 83.156269 -194.750951)
			(xy 83.15579 -194.723512) (xy 83.156266 -194.69626) (xy 83.164022 -194.642309) (xy 83.179376 -194.590012)
			(xy 83.202017 -194.540432) (xy 83.231484 -194.494579) (xy 83.267176 -194.453386) (xy 83.308367 -194.417692)
			(xy 83.354219 -194.388224) (xy 83.403799 -194.365581) (xy 83.456095 -194.350225) (xy 83.510046 -194.342467)
			(xy 83.537298 -194.342004) (xy 83.564668 -194.34247) (xy 83.618847 -194.350288) (xy 83.671351 -194.365777)
			(xy 83.721097 -194.388619) (xy 83.767064 -194.418343) (xy 83.787996 -194.435984) (xy 83.78825 -194.436238)
			(xy 83.795344 -194.441814) (xy 83.812255 -194.448066) (xy 83.82127 -194.44843) (xy 83.888326 -194.44843)
			(xy 83.897343 -194.448079) (xy 83.91426 -194.441827) (xy 83.921346 -194.436238) (xy 83.921346 -194.435984)
			(xy 83.9216 -194.435984) (xy 83.942533 -194.418343) (xy 83.988501 -194.388619) (xy 84.038247 -194.365773)
			(xy 84.090749 -194.350277) (xy 84.144927 -194.342448) (xy 84.199669 -194.342448) (xy 84.253847 -194.350277)
			(xy 84.306349 -194.365773) (xy 84.356095 -194.388619) (xy 84.402063 -194.418343) (xy 84.422996 -194.435984)
			(xy 84.42325 -194.436238) (xy 84.430344 -194.441814) (xy 84.447255 -194.448066) (xy 84.45627 -194.44843)
			(xy 84.523326 -194.44843) (xy 84.532343 -194.448079) (xy 84.54926 -194.441827) (xy 84.556346 -194.436238)
			(xy 84.556346 -194.435984) (xy 84.5566 -194.435984) (xy 84.577519 -194.418329) (xy 84.623496 -194.38862)
			(xy 84.673247 -194.365787) (xy 84.72575 -194.3503) (xy 84.779928 -194.342476) (xy 84.807298 -194.342004)
			(xy 84.834551 -194.342457) (xy 84.888503 -194.350214) (xy 84.940802 -194.365571) (xy 84.990383 -194.388214)
			(xy 85.036237 -194.417683) (xy 85.07743 -194.453377) (xy 85.113123 -194.494571) (xy 85.142591 -194.540426)
			(xy 85.165233 -194.590007) (xy 85.180588 -194.642307) (xy 85.188343 -194.696259) (xy 85.188806 -194.723512)
			(xy 85.188319 -194.751056) (xy 85.180363 -194.805567) (xy 85.164648 -194.858366) (xy 85.141501 -194.908355)
			(xy 85.111404 -194.954495) (xy 85.093556 -194.97548) (xy 85.087703 -194.982664) (xy 85.081202 -195.000001)
			(xy 85.080856 -195.009262) (xy 85.08111 -195.076572) (xy 85.081517 -195.085671) (xy 85.087882 -195.102722)
			(xy 85.093556 -195.109846) (xy 85.09381 -195.1101) (xy 85.111797 -195.131137) (xy 85.142146 -195.177423)
			(xy 85.165485 -195.22761) (xy 85.181323 -195.280644) (xy 85.189327 -195.33541) (xy 85.189822 -195.363084)
			(xy 85.189366 -195.390455) (xy 85.181548 -195.444635) (xy 85.166058 -195.497139) (xy 85.143214 -195.546886)
			(xy 85.113485 -195.592851) (xy 85.095842 -195.613782) (xy 85.095588 -195.614036) (xy 85.090021 -195.621136)
			(xy 85.083763 -195.638042) (xy 85.083396 -195.647056) (xy 85.083396 -195.714112) (xy 85.083748 -195.723129)
			(xy 85.089999 -195.740046) (xy 85.095588 -195.747132) (xy 85.095842 -195.747132) (xy 85.095842 -195.747386)
			(xy 85.113468 -195.768331) (xy 85.143196 -195.814296) (xy 85.166044 -195.86404) (xy 85.181543 -195.91654)
			(xy 85.189374 -195.970718) (xy 85.189376 -196.025458) (xy 85.181548 -196.079636) (xy 85.166053 -196.132138)
			(xy 85.143208 -196.181883) (xy 85.113483 -196.22785) (xy 85.095842 -196.248782) (xy 85.095588 -196.249036)
			(xy 85.090021 -196.256136) (xy 85.083763 -196.273042) (xy 85.083396 -196.282056) (xy 85.083396 -196.349112)
			(xy 85.083748 -196.358129) (xy 85.089999 -196.375046) (xy 85.095588 -196.382132) (xy 85.095842 -196.382132)
			(xy 85.095842 -196.382386) (xy 85.113468 -196.403331) (xy 85.143196 -196.449296) (xy 85.166044 -196.49904)
			(xy 85.181543 -196.55154) (xy 85.189374 -196.605718) (xy 85.189376 -196.660458) (xy 85.181548 -196.714636)
			(xy 85.166053 -196.767138) (xy 85.143208 -196.816883) (xy 85.113483 -196.86285) (xy 85.095842 -196.883782)
			(xy 85.095588 -196.884036) (xy 85.090021 -196.891136) (xy 85.083763 -196.908042) (xy 85.083396 -196.917056)
			(xy 85.083396 -196.984112) (xy 85.083748 -196.993129) (xy 85.089999 -197.010046) (xy 85.095588 -197.017132)
			(xy 85.095842 -197.017132) (xy 85.095842 -197.017386) (xy 85.113495 -197.038307) (xy 85.143203 -197.084283)
			(xy 85.166036 -197.134034) (xy 85.181524 -197.186537) (xy 85.18935 -197.240714) (xy 85.189822 -197.268084)
			(xy 85.189372 -197.295689) (xy 85.181403 -197.350321) (xy 85.165643 -197.403235) (xy 85.142422 -197.453324)
			(xy 85.112224 -197.499544) (xy 85.094318 -197.52056) (xy 85.094064 -197.520814) (xy 85.088394 -197.527945)
			(xy 85.082 -197.544987) (xy 85.081618 -197.554088) (xy 85.081364 -197.621144) (xy 85.081748 -197.630395)
			(xy 85.088258 -197.647713) (xy 85.094064 -197.654926) (xy 85.111846 -197.675907) (xy 85.1418 -197.722032)
			(xy 85.164824 -197.771978) (xy 85.180441 -197.824712) (xy 85.188329 -197.879141) (xy 85.188806 -197.90664)
			(xy 85.188303 -197.934009) (xy 85.180494 -197.988186) (xy 85.165013 -198.040689) (xy 85.14218 -198.090436)
			(xy 85.112463 -198.136405) (xy 85.094826 -198.157338) (xy 85.094572 -198.157592) (xy 85.08898 -198.164674)
			(xy 85.082737 -198.181594) (xy 85.08238 -198.190612) (xy 85.08238 -198.257668) (xy 85.082757 -198.266683)
			(xy 85.088991 -198.2836) (xy 85.094572 -198.290688) (xy 85.094826 -198.290688) (xy 85.094826 -198.290942)
			(xy 85.112508 -198.311842) (xy 85.142235 -198.357814) (xy 85.16508 -198.407566) (xy 85.180576 -198.460073)
			(xy 85.188402 -198.514257) (xy 85.188397 -198.569003) (xy 85.180563 -198.623186) (xy 85.165059 -198.675691)
			(xy 85.142206 -198.725439) (xy 85.112471 -198.771406) (xy 85.094826 -198.792338) (xy 85.094572 -198.792592)
			(xy 85.08898 -198.799674) (xy 85.082737 -198.816594) (xy 85.08238 -198.825612) (xy 85.08238 -198.892668)
			(xy 85.082757 -198.901683) (xy 85.088991 -198.9186) (xy 85.094572 -198.925688) (xy 85.094826 -198.925688)
			(xy 85.094826 -198.925942) (xy 85.112508 -198.946842) (xy 85.142235 -198.992814) (xy 85.16508 -199.042566)
			(xy 85.180576 -199.095073) (xy 85.188402 -199.149257) (xy 85.188397 -199.204003) (xy 85.180563 -199.258186)
			(xy 85.165059 -199.310691) (xy 85.142206 -199.360439) (xy 85.112471 -199.406406) (xy 85.094826 -199.427338)
			(xy 85.094572 -199.427592) (xy 85.08898 -199.434674) (xy 85.082737 -199.451594) (xy 85.08238 -199.460612)
			(xy 85.08238 -199.527668) (xy 85.082757 -199.536683) (xy 85.088991 -199.5536) (xy 85.094572 -199.560688)
			(xy 85.094826 -199.560688) (xy 85.094826 -199.560942) (xy 85.112508 -199.581842) (xy 85.142235 -199.627814)
			(xy 85.16508 -199.677566) (xy 85.180576 -199.730073) (xy 85.188402 -199.784257) (xy 85.188397 -199.839003)
			(xy 85.180563 -199.893186) (xy 85.165059 -199.945691) (xy 85.142206 -199.995439) (xy 85.112471 -200.041406)
			(xy 85.094826 -200.062338) (xy 85.094572 -200.062592) (xy 85.08898 -200.069674) (xy 85.082737 -200.086594)
			(xy 85.08238 -200.095612) (xy 85.08238 -200.162668) (xy 85.082757 -200.171683) (xy 85.088991 -200.1886)
			(xy 85.094572 -200.195688) (xy 85.094826 -200.195688) (xy 85.094826 -200.195942) (xy 85.112508 -200.216842)
			(xy 85.142235 -200.262814) (xy 85.16508 -200.312566) (xy 85.180576 -200.365073) (xy 85.188402 -200.419257)
			(xy 85.188397 -200.474003) (xy 85.180563 -200.528186) (xy 85.165059 -200.580691) (xy 85.142206 -200.630439)
			(xy 85.112471 -200.676406) (xy 85.094826 -200.697338) (xy 85.094572 -200.697592) (xy 85.08898 -200.704674)
			(xy 85.082737 -200.721594) (xy 85.08238 -200.730612) (xy 85.08238 -200.797668) (xy 85.082757 -200.806683)
			(xy 85.088991 -200.8236) (xy 85.094572 -200.830688) (xy 85.094826 -200.830688) (xy 85.094826 -200.830942)
			(xy 85.112455 -200.851882) (xy 85.142168 -200.897853) (xy 85.165005 -200.947598) (xy 85.180499 -201.000097)
			(xy 85.18833 -201.054271) (xy 85.188355 -201.055732) (xy 87.515446 -201.055732) (xy 87.51592 -201.028362)
			(xy 87.523734 -200.974183) (xy 87.539221 -200.921679) (xy 87.562061 -200.871932) (xy 87.591785 -200.825965)
			(xy 87.609426 -200.805034) (xy 87.60968 -200.80478) (xy 87.61529 -200.79771) (xy 87.621521 -200.78078)
			(xy 87.621872 -200.77176) (xy 87.621872 -200.704704) (xy 87.621519 -200.695687) (xy 87.61527 -200.678769)
			(xy 87.60968 -200.671684) (xy 87.609426 -200.671684) (xy 87.609426 -200.67143) (xy 87.591817 -200.650472)
			(xy 87.562091 -200.604508) (xy 87.539244 -200.554766) (xy 87.523745 -200.502268) (xy 87.515913 -200.448093)
			(xy 87.51591 -200.393355) (xy 87.523735 -200.339179) (xy 87.539227 -200.286679) (xy 87.562067 -200.236934)
			(xy 87.591788 -200.190967) (xy 87.609426 -200.170034) (xy 87.60968 -200.16978) (xy 87.61529 -200.16271)
			(xy 87.621521 -200.14578) (xy 87.621872 -200.13676) (xy 87.621872 -200.069704) (xy 87.621519 -200.060687)
			(xy 87.61527 -200.043769) (xy 87.60968 -200.036684) (xy 87.609426 -200.036684) (xy 87.609426 -200.03643)
			(xy 87.591817 -200.015472) (xy 87.562091 -199.969508) (xy 87.539244 -199.919766) (xy 87.523745 -199.867268)
			(xy 87.515913 -199.813093) (xy 87.51591 -199.758355) (xy 87.523735 -199.704179) (xy 87.539227 -199.651679)
			(xy 87.562067 -199.601934) (xy 87.591788 -199.555967) (xy 87.609426 -199.535034) (xy 87.60968 -199.53478)
			(xy 87.61529 -199.52771) (xy 87.621521 -199.51078) (xy 87.621872 -199.50176) (xy 87.621872 -199.434704)
			(xy 87.621519 -199.425687) (xy 87.61527 -199.408769) (xy 87.60968 -199.401684) (xy 87.609426 -199.401684)
			(xy 87.609426 -199.40143) (xy 87.591817 -199.380472) (xy 87.562091 -199.334508) (xy 87.539244 -199.284766)
			(xy 87.523745 -199.232268) (xy 87.515913 -199.178093) (xy 87.51591 -199.123355) (xy 87.523735 -199.069179)
			(xy 87.539227 -199.016679) (xy 87.562067 -198.966934) (xy 87.591788 -198.920967) (xy 87.609426 -198.900034)
			(xy 87.60968 -198.89978) (xy 87.61529 -198.89271) (xy 87.621521 -198.87578) (xy 87.621872 -198.86676)
			(xy 87.621872 -198.799704) (xy 87.621519 -198.790687) (xy 87.61527 -198.773769) (xy 87.60968 -198.766684)
			(xy 87.609426 -198.766684) (xy 87.609426 -198.76643) (xy 87.591817 -198.745472) (xy 87.562091 -198.699508)
			(xy 87.539244 -198.649766) (xy 87.523745 -198.597268) (xy 87.515913 -198.543093) (xy 87.51591 -198.488355)
			(xy 87.523735 -198.434179) (xy 87.539227 -198.381679) (xy 87.562067 -198.331934) (xy 87.591788 -198.285967)
			(xy 87.609426 -198.265034) (xy 87.60968 -198.26478) (xy 87.61529 -198.25771) (xy 87.621521 -198.24078)
			(xy 87.621872 -198.23176) (xy 87.621872 -198.164704) (xy 87.621519 -198.155687) (xy 87.61527 -198.138769)
			(xy 87.60968 -198.131684) (xy 87.609426 -198.131684) (xy 87.609426 -198.13143) (xy 87.591817 -198.110472)
			(xy 87.562091 -198.064508) (xy 87.539244 -198.014766) (xy 87.523745 -197.962268) (xy 87.515913 -197.908093)
			(xy 87.51591 -197.853355) (xy 87.523735 -197.799179) (xy 87.539227 -197.746679) (xy 87.562067 -197.696934)
			(xy 87.591788 -197.650967) (xy 87.609426 -197.630034) (xy 87.60968 -197.62978) (xy 87.61529 -197.62271)
			(xy 87.621521 -197.60578) (xy 87.621872 -197.59676) (xy 87.621872 -197.529704) (xy 87.621519 -197.520687)
			(xy 87.61527 -197.503769) (xy 87.60968 -197.496684) (xy 87.609426 -197.496684) (xy 87.609426 -197.49643)
			(xy 87.591817 -197.475472) (xy 87.562091 -197.429508) (xy 87.539244 -197.379766) (xy 87.523745 -197.327268)
			(xy 87.515913 -197.273093) (xy 87.51591 -197.218355) (xy 87.523735 -197.164179) (xy 87.539227 -197.111679)
			(xy 87.562067 -197.061934) (xy 87.591788 -197.015967) (xy 87.609426 -196.995034) (xy 87.60968 -196.99478)
			(xy 87.61529 -196.98771) (xy 87.621521 -196.97078) (xy 87.621872 -196.96176) (xy 87.621872 -196.894704)
			(xy 87.621519 -196.885687) (xy 87.61527 -196.868769) (xy 87.60968 -196.861684) (xy 87.609426 -196.861684)
			(xy 87.609426 -196.86143) (xy 87.591817 -196.840472) (xy 87.562091 -196.794508) (xy 87.539244 -196.744766)
			(xy 87.523745 -196.692268) (xy 87.515913 -196.638093) (xy 87.51591 -196.583355) (xy 87.523735 -196.529179)
			(xy 87.539227 -196.476679) (xy 87.562067 -196.426934) (xy 87.591788 -196.380967) (xy 87.609426 -196.360034)
			(xy 87.60968 -196.35978) (xy 87.61529 -196.35271) (xy 87.621521 -196.33578) (xy 87.621872 -196.32676)
			(xy 87.621872 -196.259704) (xy 87.621519 -196.250687) (xy 87.61527 -196.233769) (xy 87.60968 -196.226684)
			(xy 87.609426 -196.226684) (xy 87.609426 -196.22643) (xy 87.591817 -196.205472) (xy 87.562091 -196.159508)
			(xy 87.539244 -196.109766) (xy 87.523745 -196.057268) (xy 87.515913 -196.003093) (xy 87.51591 -195.948355)
			(xy 87.523735 -195.894179) (xy 87.539227 -195.841679) (xy 87.562067 -195.791934) (xy 87.591788 -195.745967)
			(xy 87.609426 -195.725034) (xy 87.60968 -195.72478) (xy 87.61529 -195.71771) (xy 87.621521 -195.70078)
			(xy 87.621872 -195.69176) (xy 87.621872 -195.624704) (xy 87.621519 -195.615687) (xy 87.61527 -195.598769)
			(xy 87.60968 -195.591684) (xy 87.609426 -195.591684) (xy 87.609426 -195.59143) (xy 87.591792 -195.570494)
			(xy 87.562078 -195.524523) (xy 87.539241 -195.474776) (xy 87.523749 -195.422276) (xy 87.51592 -195.368101)
			(xy 87.515446 -195.340732) (xy 87.515995 -195.311637) (xy 87.524837 -195.254122) (xy 87.542322 -195.19862)
			(xy 87.568042 -195.146422) (xy 87.601398 -195.098742) (xy 87.62111 -195.077334) (xy 87.627165 -195.07041)
			(xy 87.634326 -195.053481) (xy 87.63508 -195.044314) (xy 87.63762 -194.97675) (xy 87.637582 -194.967535)
			(xy 87.631725 -194.950081) (xy 87.62619 -194.942714) (xy 87.609969 -194.92217) (xy 87.582655 -194.877518)
			(xy 87.561696 -194.829555) (xy 87.547484 -194.779177) (xy 87.540285 -194.727331) (xy 87.53983 -194.70116)
			(xy 87.540241 -194.673906) (xy 87.548004 -194.619954) (xy 87.563366 -194.567655) (xy 87.586014 -194.518075)
			(xy 87.615488 -194.472223) (xy 87.651188 -194.431032) (xy 87.692386 -194.395342) (xy 87.738244 -194.365877)
			(xy 87.787828 -194.343238) (xy 87.84013 -194.327887) (xy 87.894084 -194.320135) (xy 87.921338 -194.319652)
			(xy 87.948708 -194.320142) (xy 88.002886 -194.327952) (xy 88.055389 -194.343435) (xy 88.105137 -194.366272)
			(xy 88.151104 -194.395992) (xy 88.172036 -194.413632) (xy 88.17229 -194.413886) (xy 88.179376 -194.419473)
			(xy 88.196293 -194.42572) (xy 88.20531 -194.426078) (xy 88.272366 -194.426078) (xy 88.281382 -194.425709)
			(xy 88.298299 -194.41947) (xy 88.305386 -194.413886) (xy 88.305386 -194.413632) (xy 88.30564 -194.413632)
			(xy 88.326573 -194.395991) (xy 88.372541 -194.366267) (xy 88.422287 -194.343421) (xy 88.474789 -194.327925)
			(xy 88.528967 -194.320096) (xy 88.583709 -194.320096) (xy 88.637887 -194.327925) (xy 88.690389 -194.343421)
			(xy 88.740135 -194.366267) (xy 88.786103 -194.395991) (xy 88.807036 -194.413632) (xy 88.80729 -194.413886)
			(xy 88.814376 -194.419473) (xy 88.831293 -194.42572) (xy 88.84031 -194.426078) (xy 88.907366 -194.426078)
			(xy 88.916382 -194.425709) (xy 88.933299 -194.41947) (xy 88.940386 -194.413886) (xy 88.940386 -194.413632)
			(xy 88.94064 -194.413632) (xy 88.961588 -194.396013) (xy 89.007556 -194.366297) (xy 89.057299 -194.343456)
			(xy 89.109797 -194.327961) (xy 89.16397 -194.320128) (xy 89.191338 -194.319652) (xy 89.218588 -194.320142)
			(xy 89.272534 -194.327903) (xy 89.324826 -194.343261) (xy 89.374401 -194.365904) (xy 89.420249 -194.39537)
			(xy 89.461438 -194.431061) (xy 89.497129 -194.472249) (xy 89.526595 -194.518097) (xy 89.549238 -194.567672)
			(xy 89.564597 -194.619964) (xy 89.572358 -194.67391) (xy 89.572846 -194.70116) (xy 91.55303 -194.70116)
			(xy 91.553441 -194.673906) (xy 91.561204 -194.619954) (xy 91.576566 -194.567655) (xy 91.599214 -194.518075)
			(xy 91.628688 -194.472223) (xy 91.664388 -194.431032) (xy 91.705586 -194.395342) (xy 91.751444 -194.365877)
			(xy 91.801028 -194.343238) (xy 91.85333 -194.327887) (xy 91.907284 -194.320135) (xy 91.934538 -194.319652)
			(xy 91.961908 -194.320142) (xy 92.016086 -194.327952) (xy 92.068589 -194.343435) (xy 92.118337 -194.366272)
			(xy 92.164304 -194.395992) (xy 92.185236 -194.413632) (xy 92.18549 -194.413886) (xy 92.192576 -194.419473)
			(xy 92.209493 -194.42572) (xy 92.21851 -194.426078) (xy 92.285566 -194.426078) (xy 92.294582 -194.425709)
			(xy 92.311499 -194.41947) (xy 92.318586 -194.413886) (xy 92.318586 -194.413632) (xy 92.31884 -194.413632)
			(xy 92.339773 -194.395991) (xy 92.385741 -194.366267) (xy 92.435487 -194.343421) (xy 92.487989 -194.327925)
			(xy 92.542167 -194.320096) (xy 92.596909 -194.320096) (xy 92.651087 -194.327925) (xy 92.703589 -194.343421)
			(xy 92.753335 -194.366267) (xy 92.799303 -194.395991) (xy 92.820236 -194.413632) (xy 92.82049 -194.413886)
			(xy 92.827576 -194.419473) (xy 92.844493 -194.42572) (xy 92.85351 -194.426078) (xy 92.920566 -194.426078)
			(xy 92.929582 -194.425709) (xy 92.946499 -194.41947) (xy 92.953586 -194.413886) (xy 92.953586 -194.413632)
			(xy 92.95384 -194.413632) (xy 92.974788 -194.396013) (xy 93.020756 -194.366297) (xy 93.070499 -194.343456)
			(xy 93.122997 -194.327961) (xy 93.17717 -194.320128) (xy 93.204538 -194.319652) (xy 93.231788 -194.320142)
			(xy 93.285734 -194.327903) (xy 93.338026 -194.343261) (xy 93.387601 -194.365904) (xy 93.433449 -194.39537)
			(xy 93.474638 -194.431061) (xy 93.510329 -194.472249) (xy 93.539795 -194.518097) (xy 93.562438 -194.567672)
			(xy 93.577797 -194.619964) (xy 93.585558 -194.67391) (xy 93.586046 -194.70116) (xy 93.585518 -194.728702)
			(xy 93.577571 -194.783211) (xy 93.561865 -194.83601) (xy 93.538727 -194.886) (xy 93.508639 -194.932141)
			(xy 93.490796 -194.953128) (xy 93.484971 -194.960331) (xy 93.478452 -194.977653) (xy 93.478096 -194.98691)
			(xy 93.47835 -195.05422) (xy 93.478725 -195.063323) (xy 93.485112 -195.080373) (xy 93.490796 -195.087494)
			(xy 93.49105 -195.087748) (xy 93.509019 -195.1088) (xy 93.539369 -195.155082) (xy 93.562711 -195.205266)
			(xy 93.578553 -195.258296) (xy 93.586563 -195.313059) (xy 93.587062 -195.340732) (xy 93.586624 -195.368103)
			(xy 93.578801 -195.422284) (xy 93.563306 -195.474788) (xy 93.540457 -195.524534) (xy 93.510726 -195.5705)
			(xy 93.493082 -195.59143) (xy 93.492828 -195.591684) (xy 93.487234 -195.598765) (xy 93.480994 -195.615686)
			(xy 93.480636 -195.624704) (xy 93.480636 -195.69176) (xy 93.481004 -195.700776) (xy 93.487243 -195.717693)
			(xy 93.492828 -195.72478) (xy 93.493082 -195.72478) (xy 93.493082 -195.725034) (xy 93.510754 -195.745942)
			(xy 93.540476 -195.791914) (xy 93.563319 -195.841664) (xy 93.578813 -195.89417) (xy 93.586638 -195.948352)
			(xy 93.586635 -196.003096) (xy 93.578803 -196.057277) (xy 93.563302 -196.109781) (xy 93.540453 -196.159528)
			(xy 93.510725 -196.205497) (xy 93.493082 -196.22643) (xy 93.492828 -196.226684) (xy 93.487234 -196.233765)
			(xy 93.480994 -196.250686) (xy 93.480636 -196.259704) (xy 93.480636 -196.32676) (xy 93.481004 -196.335776)
			(xy 93.487243 -196.352693) (xy 93.492828 -196.35978) (xy 93.493082 -196.35978) (xy 93.493082 -196.360034)
			(xy 93.510754 -196.380942) (xy 93.540476 -196.426914) (xy 93.563319 -196.476664) (xy 93.578813 -196.52917)
			(xy 93.586638 -196.583352) (xy 93.586635 -196.638096) (xy 93.578803 -196.692277) (xy 93.563302 -196.744781)
			(xy 93.540453 -196.794528) (xy 93.510725 -196.840497) (xy 93.493082 -196.86143) (xy 93.492828 -196.861684)
			(xy 93.487234 -196.868765) (xy 93.480994 -196.885686) (xy 93.480636 -196.894704) (xy 93.480636 -196.96176)
			(xy 93.481004 -196.970776) (xy 93.487243 -196.987693) (xy 93.492828 -196.99478) (xy 93.493082 -196.99478)
			(xy 93.493082 -196.995034) (xy 93.510754 -197.015942) (xy 93.540476 -197.061914) (xy 93.563319 -197.111664)
			(xy 93.578813 -197.16417) (xy 93.586638 -197.218352) (xy 93.586635 -197.273096) (xy 93.578803 -197.327277)
			(xy 93.563302 -197.379781) (xy 93.540453 -197.429528) (xy 93.510725 -197.475497) (xy 93.493082 -197.49643)
			(xy 93.492828 -197.496684) (xy 93.487234 -197.503765) (xy 93.480994 -197.520686) (xy 93.480636 -197.529704)
			(xy 93.480636 -197.59676) (xy 93.481004 -197.605776) (xy 93.487243 -197.622693) (xy 93.492828 -197.62978)
			(xy 93.493082 -197.62978) (xy 93.493082 -197.630034) (xy 93.510754 -197.650942) (xy 93.540476 -197.696914)
			(xy 93.563319 -197.746664) (xy 93.578813 -197.79917) (xy 93.586638 -197.853352) (xy 93.586635 -197.908096)
			(xy 93.578803 -197.962277) (xy 93.563302 -198.014781) (xy 93.540453 -198.064528) (xy 93.510725 -198.110497)
			(xy 93.493082 -198.13143) (xy 93.492828 -198.131684) (xy 93.487234 -198.138765) (xy 93.480994 -198.155686)
			(xy 93.480636 -198.164704) (xy 93.480636 -198.23176) (xy 93.481004 -198.240776) (xy 93.487243 -198.257693)
			(xy 93.492828 -198.26478) (xy 93.493082 -198.26478) (xy 93.493082 -198.265034) (xy 93.510754 -198.285942)
			(xy 93.540476 -198.331914) (xy 93.563319 -198.381664) (xy 93.578813 -198.43417) (xy 93.586638 -198.488352)
			(xy 93.586635 -198.543096) (xy 93.578803 -198.597277) (xy 93.563302 -198.649781) (xy 93.540453 -198.699528)
			(xy 93.510725 -198.745497) (xy 93.493082 -198.76643) (xy 93.492828 -198.766684) (xy 93.487234 -198.773765)
			(xy 93.480994 -198.790686) (xy 93.480636 -198.799704) (xy 93.480636 -198.86676) (xy 93.481004 -198.875776)
			(xy 93.487243 -198.892693) (xy 93.492828 -198.89978) (xy 93.493082 -198.89978) (xy 93.493082 -198.900034)
			(xy 93.510754 -198.920942) (xy 93.540476 -198.966914) (xy 93.563319 -199.016664) (xy 93.578813 -199.06917)
			(xy 93.586638 -199.123352) (xy 93.586635 -199.178096) (xy 93.578803 -199.232277) (xy 93.563302 -199.284781)
			(xy 93.540453 -199.334528) (xy 93.510725 -199.380497) (xy 93.493082 -199.40143) (xy 93.492828 -199.401684)
			(xy 93.487234 -199.408765) (xy 93.480994 -199.425686) (xy 93.480636 -199.434704) (xy 93.480636 -199.50176)
			(xy 93.481004 -199.510776) (xy 93.487243 -199.527693) (xy 93.492828 -199.53478) (xy 93.493082 -199.53478)
			(xy 93.493082 -199.535034) (xy 93.510754 -199.555942) (xy 93.540476 -199.601914) (xy 93.563319 -199.651664)
			(xy 93.578813 -199.70417) (xy 93.586638 -199.758352) (xy 93.586635 -199.813096) (xy 93.578803 -199.867277)
			(xy 93.563302 -199.919781) (xy 93.540453 -199.969528) (xy 93.510725 -200.015497) (xy 93.493082 -200.03643)
			(xy 93.492828 -200.036684) (xy 93.487234 -200.043765) (xy 93.480994 -200.060686) (xy 93.480636 -200.069704)
			(xy 93.480636 -200.13676) (xy 93.481004 -200.145776) (xy 93.487243 -200.162693) (xy 93.492828 -200.16978)
			(xy 93.493082 -200.16978) (xy 93.493082 -200.170034) (xy 93.510754 -200.190942) (xy 93.540476 -200.236914)
			(xy 93.563319 -200.286664) (xy 93.578813 -200.33917) (xy 93.586638 -200.393352) (xy 93.586635 -200.448096)
			(xy 93.578803 -200.502277) (xy 93.563302 -200.554781) (xy 93.540453 -200.604528) (xy 93.510725 -200.650497)
			(xy 93.493082 -200.67143) (xy 93.492828 -200.671684) (xy 93.487234 -200.678765) (xy 93.480994 -200.695686)
			(xy 93.480636 -200.704704) (xy 93.480636 -200.77176) (xy 93.481004 -200.780776) (xy 93.487243 -200.797693)
			(xy 93.492828 -200.80478) (xy 93.493082 -200.80478) (xy 93.493082 -200.805034) (xy 93.510701 -200.825982)
			(xy 93.540416 -200.87195) (xy 93.563256 -200.921694) (xy 93.578752 -200.974191) (xy 93.586585 -201.028364)
			(xy 93.586628 -201.03084) (xy 95.93199 -201.03084) (xy 95.932482 -201.003471) (xy 95.940294 -200.949293)
			(xy 95.955777 -200.89679) (xy 95.978613 -200.847043) (xy 96.008332 -200.801075) (xy 96.02597 -200.780142)
			(xy 96.026224 -200.779888) (xy 96.031824 -200.772811) (xy 96.038062 -200.755887) (xy 96.038416 -200.746868)
			(xy 96.038416 -200.679812) (xy 96.03805 -200.670796) (xy 96.031808 -200.653879) (xy 96.026224 -200.646792)
			(xy 96.02597 -200.646792) (xy 96.02597 -200.646538) (xy 96.008367 -200.625574) (xy 95.978637 -200.579613)
			(xy 95.955787 -200.529872) (xy 95.940285 -200.477374) (xy 95.932452 -200.423199) (xy 95.932448 -200.368461)
			(xy 95.940273 -200.314285) (xy 95.955765 -200.261784) (xy 95.978608 -200.21204) (xy 96.00833 -200.166074)
			(xy 96.02597 -200.145142) (xy 96.026224 -200.144888) (xy 96.031824 -200.137811) (xy 96.038062 -200.120887)
			(xy 96.038416 -200.111868) (xy 96.038416 -200.044812) (xy 96.03805 -200.035796) (xy 96.031808 -200.018879)
			(xy 96.026224 -200.011792) (xy 96.02597 -200.011792) (xy 96.02597 -200.011538) (xy 96.008367 -199.990574)
			(xy 95.978637 -199.944613) (xy 95.955787 -199.894872) (xy 95.940285 -199.842374) (xy 95.932452 -199.788199)
			(xy 95.932448 -199.733461) (xy 95.940273 -199.679285) (xy 95.955765 -199.626784) (xy 95.978608 -199.57704)
			(xy 96.00833 -199.531074) (xy 96.02597 -199.510142) (xy 96.026224 -199.509888) (xy 96.031824 -199.502811)
			(xy 96.038062 -199.485887) (xy 96.038416 -199.476868) (xy 96.038416 -199.409812) (xy 96.03805 -199.400796)
			(xy 96.031808 -199.383879) (xy 96.026224 -199.376792) (xy 96.02597 -199.376792) (xy 96.02597 -199.376538)
			(xy 96.008367 -199.355574) (xy 95.978637 -199.309613) (xy 95.955787 -199.259872) (xy 95.940285 -199.207374)
			(xy 95.932452 -199.153199) (xy 95.932448 -199.098461) (xy 95.940273 -199.044285) (xy 95.955765 -198.991784)
			(xy 95.978608 -198.94204) (xy 96.00833 -198.896074) (xy 96.02597 -198.875142) (xy 96.026224 -198.874888)
			(xy 96.031824 -198.867811) (xy 96.038062 -198.850887) (xy 96.038416 -198.841868) (xy 96.038416 -198.774812)
			(xy 96.03805 -198.765796) (xy 96.031808 -198.748879) (xy 96.026224 -198.741792) (xy 96.02597 -198.741792)
			(xy 96.02597 -198.741538) (xy 96.008367 -198.720574) (xy 95.978637 -198.674613) (xy 95.955787 -198.624872)
			(xy 95.940285 -198.572374) (xy 95.932452 -198.518199) (xy 95.932448 -198.463461) (xy 95.940273 -198.409285)
			(xy 95.955765 -198.356784) (xy 95.978608 -198.30704) (xy 96.00833 -198.261074) (xy 96.02597 -198.240142)
			(xy 96.026224 -198.239888) (xy 96.031824 -198.232811) (xy 96.038062 -198.215887) (xy 96.038416 -198.206868)
			(xy 96.038416 -198.139812) (xy 96.03805 -198.130796) (xy 96.031808 -198.113879) (xy 96.026224 -198.106792)
			(xy 96.02597 -198.106792) (xy 96.02597 -198.106538) (xy 96.008367 -198.085574) (xy 95.978637 -198.039613)
			(xy 95.955787 -197.989872) (xy 95.940285 -197.937374) (xy 95.932452 -197.883199) (xy 95.932448 -197.828461)
			(xy 95.940273 -197.774285) (xy 95.955765 -197.721784) (xy 95.978608 -197.67204) (xy 96.00833 -197.626074)
			(xy 96.02597 -197.605142) (xy 96.026224 -197.604888) (xy 96.031824 -197.597811) (xy 96.038062 -197.580887)
			(xy 96.038416 -197.571868) (xy 96.038416 -197.504812) (xy 96.03805 -197.495796) (xy 96.031808 -197.478879)
			(xy 96.026224 -197.471792) (xy 96.02597 -197.471792) (xy 96.02597 -197.471538) (xy 96.008367 -197.450574)
			(xy 95.978637 -197.404613) (xy 95.955787 -197.354872) (xy 95.940285 -197.302374) (xy 95.932452 -197.248199)
			(xy 95.932448 -197.193461) (xy 95.940273 -197.139285) (xy 95.955765 -197.086784) (xy 95.978608 -197.03704)
			(xy 96.00833 -196.991074) (xy 96.02597 -196.970142) (xy 96.026224 -196.969888) (xy 96.031824 -196.962811)
			(xy 96.038062 -196.945887) (xy 96.038416 -196.936868) (xy 96.038416 -196.869812) (xy 96.03805 -196.860796)
			(xy 96.031808 -196.843879) (xy 96.026224 -196.836792) (xy 96.02597 -196.836792) (xy 96.02597 -196.836538)
			(xy 96.008367 -196.815574) (xy 95.978637 -196.769613) (xy 95.955787 -196.719872) (xy 95.940285 -196.667374)
			(xy 95.932452 -196.613199) (xy 95.932448 -196.558461) (xy 95.940273 -196.504285) (xy 95.955765 -196.451784)
			(xy 95.978608 -196.40204) (xy 96.00833 -196.356074) (xy 96.02597 -196.335142) (xy 96.026224 -196.334888)
			(xy 96.031824 -196.327811) (xy 96.038062 -196.310887) (xy 96.038416 -196.301868) (xy 96.038416 -196.234812)
			(xy 96.03805 -196.225796) (xy 96.031808 -196.208879) (xy 96.026224 -196.201792) (xy 96.02597 -196.201792)
			(xy 96.02597 -196.201538) (xy 96.008367 -196.180574) (xy 95.978637 -196.134613) (xy 95.955787 -196.084872)
			(xy 95.940285 -196.032374) (xy 95.932452 -195.978199) (xy 95.932448 -195.923461) (xy 95.940273 -195.869285)
			(xy 95.955765 -195.816784) (xy 95.978608 -195.76704) (xy 96.00833 -195.721074) (xy 96.02597 -195.700142)
			(xy 96.026224 -195.699888) (xy 96.031824 -195.692811) (xy 96.038062 -195.675887) (xy 96.038416 -195.666868)
			(xy 96.038416 -195.599812) (xy 96.03805 -195.590796) (xy 96.031808 -195.573879) (xy 96.026224 -195.566792)
			(xy 96.02597 -195.566792) (xy 96.02597 -195.566538) (xy 96.008331 -195.545606) (xy 95.97862 -195.499633)
			(xy 95.955784 -195.449885) (xy 95.940293 -195.397385) (xy 95.932465 -195.343209) (xy 95.93199 -195.31584)
			(xy 95.932479 -195.288036) (xy 95.940554 -195.233018) (xy 95.956524 -195.179754) (xy 95.980051 -195.129369)
			(xy 96.010639 -195.082929) (xy 96.028764 -195.06184) (xy 96.034695 -195.054687) (xy 96.041324 -195.037343)
			(xy 96.041718 -195.028058) (xy 96.041718 -194.960494) (xy 96.041294 -194.95122) (xy 96.03464 -194.933901)
			(xy 96.028764 -194.926712) (xy 96.010645 -194.905617) (xy 95.980057 -194.85918) (xy 95.95653 -194.808797)
			(xy 95.940563 -194.755532) (xy 95.932493 -194.700515) (xy 95.93199 -194.672712) (xy 95.932466 -194.64546)
			(xy 95.940222 -194.591509) (xy 95.955576 -194.539212) (xy 95.978217 -194.489632) (xy 96.007684 -194.443779)
			(xy 96.043376 -194.402586) (xy 96.084567 -194.366892) (xy 96.130419 -194.337424) (xy 96.179999 -194.314781)
			(xy 96.232295 -194.299425) (xy 96.286246 -194.291667) (xy 96.313498 -194.291204) (xy 96.340868 -194.29167)
			(xy 96.395047 -194.299488) (xy 96.447551 -194.314977) (xy 96.497297 -194.337819) (xy 96.543264 -194.367543)
			(xy 96.564196 -194.385184) (xy 96.56445 -194.385438) (xy 96.571544 -194.391014) (xy 96.588455 -194.397266)
			(xy 96.59747 -194.39763) (xy 96.664526 -194.39763) (xy 96.673543 -194.397279) (xy 96.69046 -194.391027)
			(xy 96.697546 -194.385438) (xy 96.697546 -194.385184) (xy 96.6978 -194.385184) (xy 96.718733 -194.367543)
			(xy 96.764701 -194.337819) (xy 96.814447 -194.314973) (xy 96.866949 -194.299477) (xy 96.921127 -194.291648)
			(xy 96.975869 -194.291648) (xy 97.030047 -194.299477) (xy 97.082549 -194.314973) (xy 97.132295 -194.337819)
			(xy 97.178263 -194.367543) (xy 97.199196 -194.385184) (xy 97.19945 -194.385438) (xy 97.206544 -194.391014)
			(xy 97.223455 -194.397266) (xy 97.23247 -194.39763) (xy 97.299526 -194.39763) (xy 97.308543 -194.397279)
			(xy 97.32546 -194.391027) (xy 97.332546 -194.385438) (xy 97.332546 -194.385184) (xy 97.3328 -194.385184)
			(xy 97.353719 -194.367529) (xy 97.399696 -194.33782) (xy 97.449447 -194.314987) (xy 97.50195 -194.2995)
			(xy 97.556128 -194.291676) (xy 97.583498 -194.291204) (xy 97.610751 -194.291657) (xy 97.664703 -194.299414)
			(xy 97.717002 -194.314771) (xy 97.766583 -194.337414) (xy 97.812437 -194.366883) (xy 97.85363 -194.402577)
			(xy 97.889323 -194.443771) (xy 97.918791 -194.489626) (xy 97.941433 -194.539207) (xy 97.956788 -194.591507)
			(xy 97.964543 -194.645459) (xy 97.965006 -194.672712) (xy 97.964528 -194.700011) (xy 97.956755 -194.754052)
			(xy 97.941355 -194.806433) (xy 97.918643 -194.856083) (xy 97.889083 -194.901986) (xy 97.871534 -194.922902)
			(xy 97.865712 -194.930107) (xy 97.859193 -194.947428) (xy 97.858834 -194.956684) (xy 97.859088 -195.03263)
			(xy 97.865438 -195.049648) (xy 97.871534 -195.056506) (xy 97.889256 -195.077461) (xy 97.919132 -195.123495)
			(xy 97.942097 -195.173338) (xy 97.957675 -195.22596) (xy 97.965545 -195.280272) (xy 97.966022 -195.307712)
			(xy 97.965582 -195.335083) (xy 97.957761 -195.389264) (xy 97.942267 -195.441768) (xy 97.919419 -195.491515)
			(xy 97.889687 -195.53748) (xy 97.872042 -195.55841) (xy 97.871788 -195.558664) (xy 97.866209 -195.565756)
			(xy 97.859958 -195.582669) (xy 97.859596 -195.591684) (xy 97.859596 -195.65874) (xy 97.859935 -195.667759)
			(xy 97.866195 -195.684675) (xy 97.871788 -195.69176) (xy 97.872042 -195.69176) (xy 97.872042 -195.692014)
			(xy 97.889696 -195.712937) (xy 97.919422 -195.758905) (xy 97.942269 -195.808653) (xy 97.957766 -195.861157)
			(xy 97.965594 -195.915337) (xy 97.965592 -195.970081) (xy 97.957762 -196.024261) (xy 97.942263 -196.076764)
			(xy 97.919414 -196.12651) (xy 97.889685 -196.172478) (xy 97.872042 -196.19341) (xy 97.871788 -196.193664)
			(xy 97.866209 -196.200756) (xy 97.859958 -196.217669) (xy 97.859596 -196.226684) (xy 97.859596 -196.29374)
			(xy 97.859935 -196.302759) (xy 97.866195 -196.319675) (xy 97.871788 -196.32676) (xy 97.872042 -196.32676)
			(xy 97.872042 -196.327014) (xy 97.889696 -196.347937) (xy 97.919422 -196.393905) (xy 97.942269 -196.443653)
			(xy 97.957766 -196.496157) (xy 97.965594 -196.550337) (xy 97.965592 -196.605081) (xy 97.957762 -196.659261)
			(xy 97.942263 -196.711764) (xy 97.919414 -196.76151) (xy 97.889685 -196.807478) (xy 97.872042 -196.82841)
			(xy 97.871788 -196.828664) (xy 97.866209 -196.835756) (xy 97.859958 -196.852669) (xy 97.859596 -196.861684)
			(xy 97.859596 -196.92874) (xy 97.859935 -196.937759) (xy 97.866195 -196.954675) (xy 97.871788 -196.96176)
			(xy 97.872042 -196.96176) (xy 97.872042 -196.962014) (xy 97.889661 -196.982962) (xy 97.919375 -197.028931)
			(xy 97.942214 -197.078675) (xy 97.95771 -197.131171) (xy 97.965545 -197.185344) (xy 97.966022 -197.212712)
			(xy 97.965497 -197.240586) (xy 97.957394 -197.295741) (xy 97.941347 -197.349129) (xy 97.9177 -197.399612)
			(xy 97.886955 -197.446115) (xy 97.86874 -197.46722) (xy 97.862644 -197.474078) (xy 97.85604 -197.49135)
			(xy 97.855786 -197.577964) (xy 97.86239 -197.595236) (xy 97.868486 -197.602094) (xy 97.868486 -197.602348)
			(xy 97.886579 -197.623389) (xy 97.917096 -197.669738) (xy 97.940562 -197.720025) (xy 97.956481 -197.773185)
			(xy 97.964515 -197.828093) (xy 97.965006 -197.85584) (xy 97.964503 -197.883209) (xy 97.956694 -197.937386)
			(xy 97.941213 -197.989889) (xy 97.91838 -198.039636) (xy 97.888663 -198.085605) (xy 97.871026 -198.106538)
			(xy 97.870772 -198.106792) (xy 97.86518 -198.113874) (xy 97.858937 -198.130794) (xy 97.85858 -198.139812)
			(xy 97.85858 -198.206868) (xy 97.858957 -198.215883) (xy 97.865191 -198.2328) (xy 97.870772 -198.239888)
			(xy 97.871026 -198.239888) (xy 97.871026 -198.240142) (xy 97.888708 -198.261042) (xy 97.918435 -198.307014)
			(xy 97.94128 -198.356766) (xy 97.956776 -198.409273) (xy 97.964602 -198.463457) (xy 97.964597 -198.518203)
			(xy 97.956763 -198.572386) (xy 97.941259 -198.624891) (xy 97.918406 -198.674639) (xy 97.888671 -198.720606)
			(xy 97.871026 -198.741538) (xy 97.870772 -198.741792) (xy 97.86518 -198.748874) (xy 97.858937 -198.765794)
			(xy 97.85858 -198.774812) (xy 97.85858 -198.841868) (xy 97.858957 -198.850883) (xy 97.865191 -198.8678)
			(xy 97.870772 -198.874888) (xy 97.871026 -198.874888) (xy 97.871026 -198.875142) (xy 97.888708 -198.896042)
			(xy 97.918435 -198.942014) (xy 97.94128 -198.991766) (xy 97.956776 -199.044273) (xy 97.964602 -199.098457)
			(xy 97.964597 -199.153203) (xy 97.956763 -199.207386) (xy 97.941259 -199.259891) (xy 97.918406 -199.309639)
			(xy 97.888671 -199.355606) (xy 97.871026 -199.376538) (xy 97.870772 -199.376792) (xy 97.86518 -199.383874)
			(xy 97.858937 -199.400794) (xy 97.85858 -199.409812) (xy 97.85858 -199.476868) (xy 97.858957 -199.485883)
			(xy 97.865191 -199.5028) (xy 97.870772 -199.509888) (xy 97.871026 -199.509888) (xy 97.871026 -199.510142)
			(xy 97.888708 -199.531042) (xy 97.918435 -199.577014) (xy 97.94128 -199.626766) (xy 97.956776 -199.679273)
			(xy 97.964602 -199.733457) (xy 97.964597 -199.788203) (xy 97.956763 -199.842386) (xy 97.941259 -199.894891)
			(xy 97.918406 -199.944639) (xy 97.888671 -199.990606) (xy 97.871026 -200.011538) (xy 97.870772 -200.011792)
			(xy 97.86518 -200.018874) (xy 97.858937 -200.035794) (xy 97.85858 -200.044812) (xy 97.85858 -200.111868)
			(xy 97.858957 -200.120883) (xy 97.865191 -200.1378) (xy 97.870772 -200.144888) (xy 97.871026 -200.144888)
			(xy 97.871026 -200.145142) (xy 97.888708 -200.166042) (xy 97.918435 -200.212014) (xy 97.94128 -200.261766)
			(xy 97.956776 -200.314273) (xy 97.964602 -200.368457) (xy 97.964597 -200.42124) (xy 99.94519 -200.42124)
			(xy 99.945682 -200.393871) (xy 99.953494 -200.339693) (xy 99.968977 -200.28719) (xy 99.991813 -200.237443)
			(xy 100.021532 -200.191475) (xy 100.03917 -200.170542) (xy 100.039424 -200.170288) (xy 100.045024 -200.163211)
			(xy 100.051262 -200.146287) (xy 100.051616 -200.137268) (xy 100.051616 -200.070212) (xy 100.05125 -200.061196)
			(xy 100.045008 -200.044279) (xy 100.039424 -200.037192) (xy 100.03917 -200.037192) (xy 100.03917 -200.036938)
			(xy 100.021567 -200.015974) (xy 99.991837 -199.970013) (xy 99.968987 -199.920272) (xy 99.953485 -199.867774)
			(xy 99.945652 -199.813599) (xy 99.945648 -199.758861) (xy 99.953473 -199.704685) (xy 99.968965 -199.652184)
			(xy 99.991808 -199.60244) (xy 100.02153 -199.556474) (xy 100.03917 -199.535542) (xy 100.039424 -199.535288)
			(xy 100.045024 -199.528211) (xy 100.051262 -199.511287) (xy 100.051616 -199.502268) (xy 100.051616 -199.435212)
			(xy 100.05125 -199.426196) (xy 100.045008 -199.409279) (xy 100.039424 -199.402192) (xy 100.03917 -199.402192)
			(xy 100.03917 -199.401938) (xy 100.021567 -199.380974) (xy 99.991837 -199.335013) (xy 99.968987 -199.285272)
			(xy 99.953485 -199.232774) (xy 99.945652 -199.178599) (xy 99.945648 -199.123861) (xy 99.953473 -199.069685)
			(xy 99.968965 -199.017184) (xy 99.991808 -198.96744) (xy 100.02153 -198.921474) (xy 100.03917 -198.900542)
			(xy 100.039424 -198.900288) (xy 100.045024 -198.893211) (xy 100.051262 -198.876287) (xy 100.051616 -198.867268)
			(xy 100.051616 -198.800212) (xy 100.05125 -198.791196) (xy 100.045008 -198.774279) (xy 100.039424 -198.767192)
			(xy 100.03917 -198.767192) (xy 100.03917 -198.766938) (xy 100.021567 -198.745974) (xy 99.991837 -198.700013)
			(xy 99.968987 -198.650272) (xy 99.953485 -198.597774) (xy 99.945652 -198.543599) (xy 99.945648 -198.488861)
			(xy 99.953473 -198.434685) (xy 99.968965 -198.382184) (xy 99.991808 -198.33244) (xy 100.02153 -198.286474)
			(xy 100.03917 -198.265542) (xy 100.039424 -198.265288) (xy 100.045024 -198.258211) (xy 100.051262 -198.241287)
			(xy 100.051616 -198.232268) (xy 100.051616 -198.165212) (xy 100.05125 -198.156196) (xy 100.045008 -198.139279)
			(xy 100.039424 -198.132192) (xy 100.03917 -198.132192) (xy 100.03917 -198.131938) (xy 100.021531 -198.111006)
			(xy 99.99182 -198.065033) (xy 99.968984 -198.015285) (xy 99.953493 -197.962785) (xy 99.945665 -197.908609)
			(xy 99.94519 -197.88124) (xy 99.945773 -197.852017) (xy 99.954688 -197.794254) (xy 99.972301 -197.738525)
			(xy 99.998199 -197.686129) (xy 100.031779 -197.638292) (xy 100.051616 -197.616826) (xy 100.05809 -197.609471)
			(xy 100.065398 -197.591309) (xy 100.06584 -197.58152) (xy 100.066094 -197.501764) (xy 100.058728 -197.483476)
			(xy 100.05187 -197.476364) (xy 100.032158 -197.454926) (xy 99.998803 -197.407188) (xy 99.973086 -197.354939)
			(xy 99.955601 -197.29939) (xy 99.946755 -197.24183) (xy 99.946206 -197.212712) (xy 99.946678 -197.185342)
			(xy 99.954494 -197.131163) (xy 99.969982 -197.07866) (xy 99.992822 -197.028913) (xy 100.022545 -196.982946)
			(xy 100.040186 -196.962014) (xy 100.04044 -196.96176) (xy 100.046012 -196.954664) (xy 100.052267 -196.937754)
			(xy 100.052632 -196.92874) (xy 100.052632 -196.861684) (xy 100.052276 -196.852667) (xy 100.046027 -196.835751)
			(xy 100.04044 -196.828664) (xy 100.040186 -196.828664) (xy 100.040186 -196.82841) (xy 100.022559 -196.807467)
			(xy 99.992837 -196.7615) (xy 99.969993 -196.711755) (xy 99.954498 -196.659255) (xy 99.946669 -196.605079)
			(xy 99.946667 -196.550339) (xy 99.954494 -196.496163) (xy 99.969987 -196.443662) (xy 99.992828 -196.393916)
			(xy 100.022548 -196.347948) (xy 100.040186 -196.327014) (xy 100.04044 -196.32676) (xy 100.046012 -196.319664)
			(xy 100.052267 -196.302754) (xy 100.052632 -196.29374) (xy 100.052632 -196.226684) (xy 100.052276 -196.217667)
			(xy 100.046027 -196.200751) (xy 100.04044 -196.193664) (xy 100.040186 -196.193664) (xy 100.040186 -196.19341)
			(xy 100.022559 -196.172467) (xy 99.992837 -196.1265) (xy 99.969993 -196.076755) (xy 99.954498 -196.024255)
			(xy 99.946669 -195.970079) (xy 99.946667 -195.915339) (xy 99.954494 -195.861163) (xy 99.969987 -195.808662)
			(xy 99.992828 -195.758916) (xy 100.022548 -195.712948) (xy 100.040186 -195.692014) (xy 100.04044 -195.69176)
			(xy 100.046012 -195.684664) (xy 100.052267 -195.667754) (xy 100.052632 -195.65874) (xy 100.052632 -195.591684)
			(xy 100.052276 -195.582667) (xy 100.046027 -195.565751) (xy 100.04044 -195.558664) (xy 100.040186 -195.558664)
			(xy 100.040186 -195.55841) (xy 100.022536 -195.537487) (xy 99.992826 -195.491511) (xy 99.969993 -195.441762)
			(xy 99.954504 -195.389259) (xy 99.946679 -195.335082) (xy 99.946206 -195.307712) (xy 99.946696 -195.280413)
			(xy 99.954465 -195.226372) (xy 99.969863 -195.173992) (xy 99.992572 -195.124342) (xy 100.02213 -195.078438)
			(xy 100.039678 -195.057522) (xy 100.045534 -195.050341) (xy 100.052032 -195.033001) (xy 100.052378 -195.02374)
			(xy 100.052124 -194.947794) (xy 100.045774 -194.930776) (xy 100.039678 -194.923918) (xy 100.021969 -194.902953)
			(xy 99.992091 -194.856921) (xy 99.969123 -194.807081) (xy 99.953542 -194.754461) (xy 99.945669 -194.700151)
			(xy 99.94519 -194.672712) (xy 99.945666 -194.64546) (xy 99.953422 -194.591509) (xy 99.968776 -194.539212)
			(xy 99.991417 -194.489632) (xy 100.020884 -194.443779) (xy 100.056576 -194.402586) (xy 100.097767 -194.366892)
			(xy 100.143619 -194.337424) (xy 100.193199 -194.314781) (xy 100.245495 -194.299425) (xy 100.299446 -194.291667)
			(xy 100.326698 -194.291204) (xy 100.354068 -194.29167) (xy 100.408247 -194.299488) (xy 100.460751 -194.314977)
			(xy 100.510497 -194.337819) (xy 100.556464 -194.367543) (xy 100.577396 -194.385184) (xy 100.57765 -194.385438)
			(xy 100.584744 -194.391014) (xy 100.601655 -194.397266) (xy 100.61067 -194.39763) (xy 100.677726 -194.39763)
			(xy 100.686743 -194.397279) (xy 100.70366 -194.391027) (xy 100.710746 -194.385438) (xy 100.710746 -194.385184)
			(xy 100.711 -194.385184) (xy 100.731933 -194.367543) (xy 100.777901 -194.337819) (xy 100.827647 -194.314973)
			(xy 100.880149 -194.299477) (xy 100.934327 -194.291648) (xy 100.989069 -194.291648) (xy 101.043247 -194.299477)
			(xy 101.095749 -194.314973) (xy 101.145495 -194.337819) (xy 101.191463 -194.367543) (xy 101.212396 -194.385184)
			(xy 101.21265 -194.385438) (xy 101.219744 -194.391014) (xy 101.236655 -194.397266) (xy 101.24567 -194.39763)
			(xy 101.312726 -194.39763) (xy 101.321743 -194.397279) (xy 101.33866 -194.391027) (xy 101.345746 -194.385438)
			(xy 101.345746 -194.385184) (xy 101.346 -194.385184) (xy 101.366919 -194.367529) (xy 101.412896 -194.33782)
			(xy 101.462647 -194.314987) (xy 101.51515 -194.2995) (xy 101.569328 -194.291676) (xy 101.596698 -194.291204)
			(xy 101.623951 -194.291657) (xy 101.677903 -194.299414) (xy 101.730202 -194.314771) (xy 101.779783 -194.337414)
			(xy 101.825637 -194.366883) (xy 101.86683 -194.402577) (xy 101.902523 -194.443771) (xy 101.931991 -194.489626)
			(xy 101.954633 -194.539207) (xy 101.969988 -194.591507) (xy 101.977743 -194.645459) (xy 101.978206 -194.672712)
			(xy 101.977653 -194.70183) (xy 101.968808 -194.759389) (xy 101.951324 -194.814938) (xy 101.925607 -194.867188)
			(xy 101.892253 -194.914926) (xy 101.872542 -194.936364) (xy 101.865684 -194.943476) (xy 101.858318 -194.961764)
			(xy 101.858572 -195.04152) (xy 101.859029 -195.051308) (xy 101.866325 -195.06947) (xy 101.872796 -195.076826)
			(xy 101.892649 -195.09828) (xy 101.926242 -195.146114) (xy 101.952148 -195.198511) (xy 101.96976 -195.254246)
			(xy 101.978667 -195.312014) (xy 101.979222 -195.34124) (xy 101.97874 -195.36861) (xy 101.970929 -195.422789)
			(xy 101.955445 -195.475293) (xy 101.932606 -195.52504) (xy 101.902883 -195.571007) (xy 101.885242 -195.591938)
			(xy 101.884988 -195.592192) (xy 101.879397 -195.599276) (xy 101.873153 -195.616195) (xy 101.872796 -195.625212)
			(xy 101.872796 -195.692268) (xy 101.873169 -195.701283) (xy 101.879406 -195.7182) (xy 101.884988 -195.725288)
			(xy 101.885242 -195.725288) (xy 101.885242 -195.725542) (xy 101.902923 -195.746442) (xy 101.932649 -195.792415)
			(xy 101.955494 -195.842166) (xy 101.966201 -195.87845) (xy 105.068624 -195.87845) (xy 105.069114 -195.851081)
			(xy 105.076925 -195.796902) (xy 105.092408 -195.744399) (xy 105.115245 -195.694652) (xy 105.144965 -195.648684)
			(xy 105.162604 -195.627752) (xy 105.162858 -195.627498) (xy 105.168458 -195.620421) (xy 105.174695 -195.603497)
			(xy 105.17505 -195.594478) (xy 105.17505 -195.527422) (xy 105.174693 -195.518405) (xy 105.168447 -195.501487)
			(xy 105.162858 -195.494402) (xy 105.162604 -195.494402) (xy 105.162604 -195.494148) (xy 105.145013 -195.473175)
			(xy 105.115288 -195.427214) (xy 105.092441 -195.377474) (xy 105.076942 -195.324978) (xy 105.069109 -195.270806)
			(xy 105.069104 -195.21607) (xy 105.076926 -195.161895) (xy 105.092415 -195.109397) (xy 105.115252 -195.059652)
			(xy 105.144968 -195.013685) (xy 105.162604 -194.992752) (xy 105.162858 -194.992498) (xy 105.168458 -194.985421)
			(xy 105.174695 -194.968497) (xy 105.17505 -194.959478) (xy 105.17505 -194.892422) (xy 105.174693 -194.883405)
			(xy 105.168447 -194.866487) (xy 105.162858 -194.859402) (xy 105.162604 -194.859402) (xy 105.162604 -194.859148)
			(xy 105.145013 -194.838175) (xy 105.115288 -194.792214) (xy 105.092441 -194.742474) (xy 105.076942 -194.689978)
			(xy 105.069109 -194.635806) (xy 105.069104 -194.58107) (xy 105.076926 -194.526895) (xy 105.092415 -194.474397)
			(xy 105.115252 -194.424652) (xy 105.144968 -194.378685) (xy 105.162604 -194.357752) (xy 105.162858 -194.357498)
			(xy 105.168458 -194.350421) (xy 105.174695 -194.333497) (xy 105.17505 -194.324478) (xy 105.17505 -194.257422)
			(xy 105.174693 -194.248405) (xy 105.168447 -194.231487) (xy 105.162858 -194.224402) (xy 105.162604 -194.224402)
			(xy 105.162604 -194.224148) (xy 105.145013 -194.203175) (xy 105.115288 -194.157214) (xy 105.092441 -194.107474)
			(xy 105.076942 -194.054978) (xy 105.069109 -194.000806) (xy 105.069104 -193.94607) (xy 105.076926 -193.891895)
			(xy 105.092415 -193.839397) (xy 105.115252 -193.789652) (xy 105.144968 -193.743685) (xy 105.162604 -193.722752)
			(xy 105.162858 -193.722498) (xy 105.168458 -193.715421) (xy 105.174695 -193.698497) (xy 105.17505 -193.689478)
			(xy 105.17505 -193.622422) (xy 105.174693 -193.613405) (xy 105.168447 -193.596487) (xy 105.162858 -193.589402)
			(xy 105.162604 -193.589402) (xy 105.162604 -193.589148) (xy 105.145013 -193.568175) (xy 105.115288 -193.522214)
			(xy 105.092441 -193.472474) (xy 105.076942 -193.419978) (xy 105.069109 -193.365806) (xy 105.069104 -193.31107)
			(xy 105.076926 -193.256895) (xy 105.092415 -193.204397) (xy 105.115252 -193.154652) (xy 105.144968 -193.108685)
			(xy 105.162604 -193.087752) (xy 105.162858 -193.087498) (xy 105.168458 -193.080421) (xy 105.174695 -193.063497)
			(xy 105.17505 -193.054478) (xy 105.17505 -192.987422) (xy 105.174693 -192.978405) (xy 105.168447 -192.961487)
			(xy 105.162858 -192.954402) (xy 105.162604 -192.954402) (xy 105.162604 -192.954148) (xy 105.145013 -192.933175)
			(xy 105.115288 -192.887214) (xy 105.092441 -192.837474) (xy 105.076942 -192.784978) (xy 105.069109 -192.730806)
			(xy 105.069104 -192.67607) (xy 105.076926 -192.621895) (xy 105.092415 -192.569397) (xy 105.115252 -192.519652)
			(xy 105.144968 -192.473685) (xy 105.162604 -192.452752) (xy 105.162858 -192.452498) (xy 105.168458 -192.445421)
			(xy 105.174695 -192.428497) (xy 105.17505 -192.419478) (xy 105.17505 -192.352422) (xy 105.174693 -192.343405)
			(xy 105.168447 -192.326487) (xy 105.162858 -192.319402) (xy 105.162604 -192.319402) (xy 105.162604 -192.319148)
			(xy 105.145013 -192.298175) (xy 105.115288 -192.252214) (xy 105.092441 -192.202474) (xy 105.076942 -192.149978)
			(xy 105.069109 -192.095806) (xy 105.069104 -192.04107) (xy 105.076926 -191.986895) (xy 105.092415 -191.934397)
			(xy 105.115252 -191.884652) (xy 105.144968 -191.838685) (xy 105.162604 -191.817752) (xy 105.162858 -191.817498)
			(xy 105.168458 -191.810421) (xy 105.174695 -191.793497) (xy 105.17505 -191.784478) (xy 105.17505 -191.717422)
			(xy 105.174693 -191.708405) (xy 105.168447 -191.691487) (xy 105.162858 -191.684402) (xy 105.162604 -191.684402)
			(xy 105.162604 -191.684148) (xy 105.145013 -191.663175) (xy 105.115288 -191.617214) (xy 105.092441 -191.567474)
			(xy 105.076942 -191.514978) (xy 105.069109 -191.460806) (xy 105.069104 -191.40607) (xy 105.076926 -191.351895)
			(xy 105.092415 -191.299397) (xy 105.115252 -191.249652) (xy 105.144968 -191.203685) (xy 105.162604 -191.182752)
			(xy 105.162858 -191.182498) (xy 105.168458 -191.175421) (xy 105.174695 -191.158497) (xy 105.17505 -191.149478)
			(xy 105.17505 -191.082422) (xy 105.174693 -191.073405) (xy 105.168447 -191.056487) (xy 105.162858 -191.049402)
			(xy 105.162604 -191.049402) (xy 105.162604 -191.049148) (xy 105.144975 -191.028208) (xy 105.115261 -190.982238)
			(xy 105.092423 -190.932492) (xy 105.07693 -190.879993) (xy 105.069099 -190.825819) (xy 105.068624 -190.79845)
			(xy 105.069135 -190.770647) (xy 105.077207 -190.715631) (xy 105.093173 -190.662367) (xy 105.116695 -190.611982)
			(xy 105.147276 -190.565541) (xy 105.165398 -190.54445) (xy 105.171316 -190.537288) (xy 105.177954 -190.519951)
			(xy 105.178352 -190.510668) (xy 105.178352 -190.443104) (xy 105.177915 -190.433831) (xy 105.171269 -190.416513)
			(xy 105.165398 -190.409322) (xy 105.14729 -190.388219) (xy 105.116699 -190.341785) (xy 105.093169 -190.291403)
			(xy 105.0772 -190.238141) (xy 105.069128 -190.183125) (xy 105.068624 -190.155322) (xy 105.069076 -190.128068)
			(xy 105.076831 -190.074115) (xy 105.092186 -190.021815) (xy 105.114828 -189.972233) (xy 105.144297 -189.926378)
			(xy 105.179992 -189.885184) (xy 105.221186 -189.849491) (xy 105.267042 -189.820023) (xy 105.316625 -189.797382)
			(xy 105.368925 -189.782029) (xy 105.422878 -189.774275) (xy 105.450132 -189.773814) (xy 105.477503 -189.774258)
			(xy 105.531683 -189.782081) (xy 105.584187 -189.797575) (xy 105.633933 -189.820421) (xy 105.679899 -189.850151)
			(xy 105.70083 -189.867794) (xy 105.701084 -189.868048) (xy 105.708167 -189.87364) (xy 105.725087 -189.879882)
			(xy 105.734104 -189.88024) (xy 105.80116 -189.88024) (xy 105.810177 -189.879877) (xy 105.827094 -189.873635)
			(xy 105.83418 -189.868048) (xy 105.83418 -189.867794) (xy 105.834434 -189.867794) (xy 105.855367 -189.850153)
			(xy 105.901335 -189.820429) (xy 105.951081 -189.797583) (xy 106.003583 -189.782087) (xy 106.057761 -189.774258)
			(xy 106.112503 -189.774258) (xy 106.166681 -189.782087) (xy 106.219183 -189.797583) (xy 106.268929 -189.820429)
			(xy 106.314897 -189.850153) (xy 106.33583 -189.867794) (xy 106.336084 -189.868048) (xy 106.343167 -189.87364)
			(xy 106.360087 -189.879882) (xy 106.369104 -189.88024) (xy 106.43616 -189.88024) (xy 106.445177 -189.879877)
			(xy 106.462094 -189.873635) (xy 106.46918 -189.868048) (xy 106.46918 -189.867794) (xy 106.469434 -189.867794)
			(xy 106.490379 -189.850171) (xy 106.536349 -189.820457) (xy 106.586093 -189.797618) (xy 106.63859 -189.782123)
			(xy 106.692764 -189.774291) (xy 106.720132 -189.773814) (xy 106.747385 -189.774248) (xy 106.801336 -189.78201)
			(xy 106.853633 -189.79737) (xy 106.903212 -189.820016) (xy 106.949063 -189.849488) (xy 106.990253 -189.885185)
			(xy 107.025944 -189.92638) (xy 107.05541 -189.972236) (xy 107.078049 -190.021818) (xy 107.093402 -190.074117)
			(xy 107.101156 -190.128069) (xy 107.10164 -190.155322) (xy 109.081824 -190.155322) (xy 109.082276 -190.128068)
			(xy 109.090031 -190.074115) (xy 109.105386 -190.021815) (xy 109.128028 -189.972233) (xy 109.157497 -189.926378)
			(xy 109.193192 -189.885184) (xy 109.234386 -189.849491) (xy 109.280242 -189.820023) (xy 109.329825 -189.797382)
			(xy 109.382125 -189.782029) (xy 109.436078 -189.774275) (xy 109.463332 -189.773814) (xy 109.490703 -189.774258)
			(xy 109.544883 -189.782081) (xy 109.597387 -189.797575) (xy 109.647133 -189.820421) (xy 109.693099 -189.850151)
			(xy 109.71403 -189.867794) (xy 109.714284 -189.868048) (xy 109.721367 -189.87364) (xy 109.738287 -189.879882)
			(xy 109.747304 -189.88024) (xy 109.81436 -189.88024) (xy 109.823377 -189.879877) (xy 109.840294 -189.873635)
			(xy 109.84738 -189.868048) (xy 109.84738 -189.867794) (xy 109.847634 -189.867794) (xy 109.868579 -189.850171)
			(xy 109.914549 -189.820457) (xy 109.964293 -189.797618) (xy 110.01679 -189.782123) (xy 110.070964 -189.774291)
			(xy 110.098332 -189.773814) (xy 110.125585 -189.774248) (xy 110.179536 -189.78201) (xy 110.231833 -189.79737)
			(xy 110.281412 -189.820016) (xy 110.327263 -189.849488) (xy 110.368453 -189.885185) (xy 110.404144 -189.92638)
			(xy 110.43361 -189.972236) (xy 110.456249 -190.021818) (xy 110.471602 -190.074117) (xy 110.479356 -190.128069)
			(xy 110.47984 -190.155322) (xy 110.479359 -190.182621) (xy 110.471585 -190.236662) (xy 110.456186 -190.289042)
			(xy 110.433475 -190.338692) (xy 110.403916 -190.384596) (xy 110.386368 -190.405512) (xy 110.380546 -190.412717)
			(xy 110.374026 -190.430038) (xy 110.373668 -190.439294) (xy 110.373922 -190.51524) (xy 110.380272 -190.532258)
			(xy 110.386368 -190.539116) (xy 110.404084 -190.560076) (xy 110.433964 -190.606107) (xy 110.45693 -190.655949)
			(xy 110.47251 -190.708571) (xy 110.480379 -190.762882) (xy 110.480856 -190.790322) (xy 110.480414 -190.817693)
			(xy 110.472592 -190.871874) (xy 110.457098 -190.924378) (xy 110.43425 -190.974124) (xy 110.40452 -191.020089)
			(xy 110.386876 -191.04102) (xy 110.386622 -191.041274) (xy 110.381031 -191.048357) (xy 110.374789 -191.065277)
			(xy 110.37443 -191.074294) (xy 110.37443 -191.14135) (xy 110.374804 -191.150365) (xy 110.381039 -191.167283)
			(xy 110.386622 -191.17437) (xy 110.386876 -191.17437) (xy 110.386876 -191.174624) (xy 110.404538 -191.195539)
			(xy 110.434262 -191.24151) (xy 110.457106 -191.291259) (xy 110.4726 -191.343764) (xy 110.480427 -191.397945)
			(xy 110.480424 -191.452688) (xy 110.472593 -191.506868) (xy 110.457094 -191.559372) (xy 110.434246 -191.609119)
			(xy 110.404518 -191.655087) (xy 110.386876 -191.67602) (xy 110.386622 -191.676274) (xy 110.381031 -191.683357)
			(xy 110.374789 -191.700277) (xy 110.37443 -191.709294) (xy 110.37443 -191.77635) (xy 110.374804 -191.785365)
			(xy 110.381039 -191.802283) (xy 110.386622 -191.80937) (xy 110.386876 -191.80937) (xy 110.386876 -191.809624)
			(xy 110.404489 -191.830577) (xy 110.434206 -191.876544) (xy 110.457047 -191.926286) (xy 110.472544 -191.978782)
			(xy 110.480379 -192.032954) (xy 110.480856 -192.060322) (xy 110.480343 -192.087572) (xy 110.472585 -192.141516)
			(xy 110.457229 -192.193807) (xy 110.434589 -192.243381) (xy 110.405125 -192.289229) (xy 110.369436 -192.330418)
			(xy 110.32825 -192.366109) (xy 110.282404 -192.395576) (xy 110.232832 -192.41822) (xy 110.180541 -192.433579)
			(xy 110.126598 -192.441341) (xy 110.099348 -192.44183) (xy 110.069871 -192.441279) (xy 110.011617 -192.432216)
			(xy 109.955452 -192.414297) (xy 109.902712 -192.387949) (xy 109.854655 -192.353801) (xy 109.833156 -192.333626)
			(xy 109.825839 -192.327069) (xy 109.807665 -192.319639) (xy 109.79785 -192.319148) (xy 109.74451 -192.319148)
			(xy 109.737652 -192.326514) (xy 109.731112 -192.333844) (xy 109.723671 -192.352008) (xy 109.723174 -192.36182)
			(xy 109.723174 -192.393824) (xy 109.723664 -192.403638) (xy 109.731107 -192.421802) (xy 109.737652 -192.42913)
			(xy 109.75784 -192.450617) (xy 109.791983 -192.49868) (xy 109.818326 -192.551422) (xy 109.836244 -192.607589)
			(xy 109.845309 -192.665844) (xy 109.845856 -192.695322) (xy 109.84537 -192.722573) (xy 109.837614 -192.776521)
			(xy 109.822259 -192.828816) (xy 109.799617 -192.878393) (xy 109.770151 -192.924243) (xy 109.73446 -192.965434)
			(xy 109.693269 -193.001125) (xy 109.647419 -193.030591) (xy 109.597842 -193.053233) (xy 109.545547 -193.068588)
			(xy 109.491599 -193.076344) (xy 109.437097 -193.076344) (xy 109.383149 -193.068588) (xy 109.330854 -193.053233)
			(xy 109.281277 -193.030591) (xy 109.235427 -193.001125) (xy 109.194236 -192.965434) (xy 109.158545 -192.924243)
			(xy 109.129079 -192.878393) (xy 109.106437 -192.828816) (xy 109.091082 -192.776521) (xy 109.083326 -192.722573)
			(xy 109.08284 -192.695322) (xy 109.083309 -192.667952) (xy 109.091125 -192.613772) (xy 109.106613 -192.561269)
			(xy 109.129454 -192.511522) (xy 109.159179 -192.465555) (xy 109.17682 -192.444624) (xy 109.177074 -192.44437)
			(xy 109.182646 -192.437274) (xy 109.1889 -192.420364) (xy 109.189266 -192.41135) (xy 109.189266 -192.344294)
			(xy 109.188919 -192.335276) (xy 109.182666 -192.318359) (xy 109.177074 -192.311274) (xy 109.17682 -192.311274)
			(xy 109.17682 -192.31102) (xy 109.159201 -192.29007) (xy 109.129476 -192.244105) (xy 109.10663 -192.194361)
			(xy 109.091132 -192.141862) (xy 109.083302 -192.087686) (xy 109.083299 -192.032947) (xy 109.091125 -191.97877)
			(xy 109.106618 -191.92627) (xy 109.12946 -191.876524) (xy 109.159181 -191.830557) (xy 109.17682 -191.809624)
			(xy 109.177074 -191.80937) (xy 109.182646 -191.802274) (xy 109.1889 -191.785364) (xy 109.189266 -191.77635)
			(xy 109.189266 -191.709294) (xy 109.188919 -191.700276) (xy 109.182666 -191.683359) (xy 109.177074 -191.676274)
			(xy 109.17682 -191.676274) (xy 109.17682 -191.67602) (xy 109.159201 -191.65507) (xy 109.129476 -191.609105)
			(xy 109.10663 -191.559361) (xy 109.091132 -191.506862) (xy 109.083302 -191.452686) (xy 109.083299 -191.397947)
			(xy 109.091125 -191.34377) (xy 109.106618 -191.29127) (xy 109.12946 -191.241524) (xy 109.159181 -191.195557)
			(xy 109.17682 -191.174624) (xy 109.177074 -191.17437) (xy 109.182646 -191.167274) (xy 109.1889 -191.150364)
			(xy 109.189266 -191.14135) (xy 109.189266 -191.074294) (xy 109.188919 -191.065276) (xy 109.182666 -191.048359)
			(xy 109.177074 -191.041274) (xy 109.17682 -191.041274) (xy 109.17682 -191.04102) (xy 109.15918 -191.020089)
			(xy 109.129468 -190.974116) (xy 109.106631 -190.924368) (xy 109.091141 -190.871867) (xy 109.083313 -190.817691)
			(xy 109.08284 -190.790322) (xy 109.083269 -190.763021) (xy 109.091052 -190.708977) (xy 109.106463 -190.656595)
			(xy 109.129186 -190.606947) (xy 109.158757 -190.561046) (xy 109.176312 -190.540132) (xy 109.182155 -190.532942)
			(xy 109.188663 -190.515609) (xy 109.189012 -190.50635) (xy 109.188758 -190.430404) (xy 109.182408 -190.413386)
			(xy 109.176312 -190.406528) (xy 109.158566 -190.385592) (xy 109.128692 -190.339554) (xy 109.105731 -190.289705)
			(xy 109.090159 -190.237079) (xy 109.082297 -190.182763) (xy 109.081824 -190.155322) (xy 107.10164 -190.155322)
			(xy 107.101159 -190.182621) (xy 107.093385 -190.236662) (xy 107.077986 -190.289042) (xy 107.055275 -190.338692)
			(xy 107.025716 -190.384596) (xy 107.008168 -190.405512) (xy 107.002346 -190.412717) (xy 106.995826 -190.430038)
			(xy 106.995468 -190.439294) (xy 106.995722 -190.51524) (xy 107.002072 -190.532258) (xy 107.008168 -190.539116)
			(xy 107.025884 -190.560076) (xy 107.055764 -190.606107) (xy 107.07873 -190.655949) (xy 107.09431 -190.708571)
			(xy 107.102179 -190.762882) (xy 107.102656 -190.790322) (xy 107.102214 -190.817693) (xy 107.094392 -190.871874)
			(xy 107.078898 -190.924378) (xy 107.05605 -190.974124) (xy 107.02632 -191.020089) (xy 107.008676 -191.04102)
			(xy 107.008422 -191.041274) (xy 107.002831 -191.048357) (xy 106.996589 -191.065277) (xy 106.99623 -191.074294)
			(xy 106.99623 -191.14135) (xy 106.996604 -191.150365) (xy 107.002839 -191.167283) (xy 107.008422 -191.17437)
			(xy 107.008676 -191.17437) (xy 107.008676 -191.174624) (xy 107.026338 -191.195539) (xy 107.056062 -191.24151)
			(xy 107.078906 -191.291259) (xy 107.0944 -191.343764) (xy 107.102227 -191.397945) (xy 107.102224 -191.452688)
			(xy 107.094393 -191.506868) (xy 107.078894 -191.559372) (xy 107.056046 -191.609119) (xy 107.026318 -191.655087)
			(xy 107.008676 -191.67602) (xy 107.008422 -191.676274) (xy 107.002831 -191.683357) (xy 106.996589 -191.700277)
			(xy 106.99623 -191.709294) (xy 106.99623 -191.77635) (xy 106.996604 -191.785365) (xy 107.002839 -191.802283)
			(xy 107.008422 -191.80937) (xy 107.008676 -191.80937) (xy 107.008676 -191.809624) (xy 107.026338 -191.830539)
			(xy 107.056062 -191.87651) (xy 107.078906 -191.926259) (xy 107.0944 -191.978764) (xy 107.102227 -192.032945)
			(xy 107.102224 -192.087688) (xy 107.094393 -192.141868) (xy 107.078894 -192.194372) (xy 107.056046 -192.244119)
			(xy 107.026318 -192.290087) (xy 107.008676 -192.31102) (xy 107.008422 -192.311274) (xy 107.002831 -192.318357)
			(xy 106.996589 -192.335277) (xy 106.99623 -192.344294) (xy 106.99623 -192.41135) (xy 106.996604 -192.420365)
			(xy 107.002839 -192.437283) (xy 107.008422 -192.44437) (xy 107.008676 -192.44437) (xy 107.008676 -192.444624)
			(xy 107.026289 -192.465577) (xy 107.056006 -192.511544) (xy 107.078847 -192.561286) (xy 107.094344 -192.613782)
			(xy 107.102179 -192.667954) (xy 107.102656 -192.695322) (xy 107.102128 -192.723196) (xy 107.094024 -192.77835)
			(xy 107.077978 -192.831738) (xy 107.054332 -192.882221) (xy 107.023588 -192.928725) (xy 107.005374 -192.94983)
			(xy 106.999278 -192.956688) (xy 106.992674 -192.97396) (xy 106.99242 -193.060574) (xy 106.999024 -193.077846)
			(xy 107.00512 -193.084704) (xy 107.00512 -193.084958) (xy 107.023207 -193.106005) (xy 107.053727 -193.152351)
			(xy 107.077195 -193.202636) (xy 107.093115 -193.255796) (xy 107.101149 -193.310704) (xy 107.10164 -193.33845)
			(xy 107.101159 -193.36582) (xy 107.093347 -193.419999) (xy 107.077862 -193.472502) (xy 107.055024 -193.52225)
			(xy 107.025301 -193.568216) (xy 107.00766 -193.589148) (xy 107.007406 -193.589402) (xy 107.001813 -193.596484)
			(xy 106.99557 -193.613404) (xy 106.995214 -193.622422) (xy 106.995214 -193.689478) (xy 106.995578 -193.698494)
			(xy 107.00182 -193.715411) (xy 107.007406 -193.722498) (xy 107.00766 -193.722498) (xy 107.00766 -193.722752)
			(xy 107.02535 -193.743645) (xy 107.055074 -193.789619) (xy 107.077917 -193.839372) (xy 107.09341 -193.89188)
			(xy 107.101234 -193.946065) (xy 107.101229 -194.000811) (xy 107.093394 -194.054993) (xy 107.077891 -194.107499)
			(xy 107.055038 -194.157247) (xy 107.025305 -194.203215) (xy 107.00766 -194.224148) (xy 107.007406 -194.224402)
			(xy 107.001813 -194.231484) (xy 106.99557 -194.248404) (xy 106.995214 -194.257422) (xy 106.995214 -194.324478)
			(xy 106.995578 -194.333494) (xy 107.00182 -194.350411) (xy 107.007406 -194.357498) (xy 107.00766 -194.357498)
			(xy 107.00766 -194.357752) (xy 107.025284 -194.378696) (xy 107.054999 -194.424665) (xy 107.077839 -194.47441)
			(xy 107.093333 -194.526908) (xy 107.101165 -194.581082) (xy 107.10164 -194.60845) (xy 107.101098 -194.6357)
			(xy 107.093349 -194.689647) (xy 107.078001 -194.741941) (xy 107.055367 -194.791519) (xy 107.025907 -194.837371)
			(xy 106.990221 -194.878563) (xy 106.949036 -194.914258) (xy 106.903191 -194.943727) (xy 106.853618 -194.966372)
			(xy 106.801327 -194.981732) (xy 106.747382 -194.989492) (xy 106.720132 -194.989958) (xy 106.690655 -194.98941)
			(xy 106.632401 -194.980344) (xy 106.576236 -194.962424) (xy 106.523497 -194.936077) (xy 106.475439 -194.901929)
			(xy 106.45394 -194.881754) (xy 106.446592 -194.875237) (xy 106.428442 -194.867783) (xy 106.418634 -194.867276)
			(xy 106.365294 -194.867276) (xy 106.358436 -194.874642) (xy 106.351881 -194.881961) (xy 106.34445 -194.900134)
			(xy 106.343958 -194.909948) (xy 106.343958 -194.941952) (xy 106.344438 -194.951767) (xy 106.351888 -194.96993)
			(xy 106.358436 -194.977258) (xy 106.378587 -194.998778) (xy 106.412735 -195.046832) (xy 106.439086 -195.099566)
			(xy 106.457013 -195.155726) (xy 106.466088 -195.213974) (xy 106.46664 -195.24345) (xy 106.466098 -195.2707)
			(xy 106.458349 -195.324647) (xy 106.443001 -195.376941) (xy 106.420367 -195.426519) (xy 106.390907 -195.472371)
			(xy 106.355221 -195.513563) (xy 106.314036 -195.549258) (xy 106.268191 -195.578727) (xy 106.218618 -195.601372)
			(xy 106.166327 -195.616732) (xy 106.112382 -195.624492) (xy 106.085132 -195.624958) (xy 106.055655 -195.62441)
			(xy 105.997401 -195.615344) (xy 105.941236 -195.597424) (xy 105.888497 -195.571077) (xy 105.840439 -195.536929)
			(xy 105.81894 -195.516754) (xy 105.811592 -195.510237) (xy 105.793442 -195.502783) (xy 105.783634 -195.502276)
			(xy 105.730294 -195.502276) (xy 105.723436 -195.509642) (xy 105.716881 -195.516961) (xy 105.70945 -195.535134)
			(xy 105.708958 -195.544948) (xy 105.708958 -195.576952) (xy 105.709438 -195.586767) (xy 105.716888 -195.60493)
			(xy 105.723436 -195.612258) (xy 105.743587 -195.633778) (xy 105.777735 -195.681832) (xy 105.804086 -195.734566)
			(xy 105.822013 -195.790726) (xy 105.831088 -195.848974) (xy 105.83164 -195.87845) (xy 105.831154 -195.905701)
			(xy 105.823398 -195.959649) (xy 105.808043 -196.011944) (xy 105.785401 -196.061521) (xy 105.755935 -196.107371)
			(xy 105.720244 -196.148562) (xy 105.679053 -196.184253) (xy 105.633203 -196.213719) (xy 105.583626 -196.236361)
			(xy 105.531331 -196.251716) (xy 105.477383 -196.259472) (xy 105.422881 -196.259472) (xy 105.368933 -196.251716)
			(xy 105.316638 -196.236361) (xy 105.267061 -196.213719) (xy 105.221211 -196.184253) (xy 105.18002 -196.148562)
			(xy 105.144329 -196.107371) (xy 105.114863 -196.061521) (xy 105.092221 -196.011944) (xy 105.076866 -195.959649)
			(xy 105.06911 -195.905701) (xy 105.068624 -195.87845) (xy 101.966201 -195.87845) (xy 101.970988 -195.894674)
			(xy 101.978814 -195.948857) (xy 101.978809 -196.003603) (xy 101.970975 -196.057785) (xy 101.955472 -196.11029)
			(xy 101.93262 -196.160038) (xy 101.902887 -196.206006) (xy 101.885242 -196.226938) (xy 101.884988 -196.227192)
			(xy 101.879397 -196.234276) (xy 101.873153 -196.251195) (xy 101.872796 -196.260212) (xy 101.872796 -196.327268)
			(xy 101.873169 -196.336283) (xy 101.879406 -196.3532) (xy 101.884988 -196.360288) (xy 101.885242 -196.360288)
			(xy 101.885242 -196.360542) (xy 101.902923 -196.381442) (xy 101.932649 -196.427415) (xy 101.955494 -196.477166)
			(xy 101.970988 -196.529674) (xy 101.978814 -196.583857) (xy 101.978809 -196.638603) (xy 101.970975 -196.692785)
			(xy 101.955472 -196.74529) (xy 101.93262 -196.795038) (xy 101.902887 -196.841006) (xy 101.885242 -196.861938)
			(xy 101.884988 -196.862192) (xy 101.879397 -196.869276) (xy 101.873153 -196.886195) (xy 101.872796 -196.895212)
			(xy 101.872796 -196.962268) (xy 101.873169 -196.971283) (xy 101.879406 -196.9882) (xy 101.884988 -196.995288)
			(xy 101.885242 -196.995288) (xy 101.885242 -196.995542) (xy 101.902923 -197.016442) (xy 101.932649 -197.062415)
			(xy 101.955494 -197.112166) (xy 101.970988 -197.164674) (xy 101.978814 -197.218857) (xy 101.978809 -197.273603)
			(xy 101.970975 -197.327785) (xy 101.955472 -197.38029) (xy 101.93262 -197.430038) (xy 101.902887 -197.476006)
			(xy 101.885242 -197.496938) (xy 101.884988 -197.497192) (xy 101.879397 -197.504276) (xy 101.873153 -197.521195)
			(xy 101.872796 -197.530212) (xy 101.872796 -197.597268) (xy 101.873169 -197.606283) (xy 101.879406 -197.6232)
			(xy 101.884988 -197.630288) (xy 101.885242 -197.630288) (xy 101.885242 -197.630542) (xy 101.902923 -197.651442)
			(xy 101.932649 -197.697415) (xy 101.955494 -197.747166) (xy 101.970988 -197.799674) (xy 101.978814 -197.853857)
			(xy 101.978809 -197.908603) (xy 101.970975 -197.962785) (xy 101.955472 -198.01529) (xy 101.93262 -198.065038)
			(xy 101.902887 -198.111006) (xy 101.885242 -198.131938) (xy 101.884988 -198.132192) (xy 101.879397 -198.139276)
			(xy 101.873153 -198.156195) (xy 101.872796 -198.165212) (xy 101.872796 -198.232268) (xy 101.873169 -198.241283)
			(xy 101.879406 -198.2582) (xy 101.884988 -198.265288) (xy 101.885242 -198.265288) (xy 101.885242 -198.265542)
			(xy 101.902923 -198.286442) (xy 101.932649 -198.332415) (xy 101.955494 -198.382166) (xy 101.970988 -198.434674)
			(xy 101.978814 -198.488857) (xy 101.978809 -198.543603) (xy 101.970975 -198.597785) (xy 101.955472 -198.65029)
			(xy 101.93262 -198.700038) (xy 101.902887 -198.746006) (xy 101.885242 -198.766938) (xy 101.884988 -198.767192)
			(xy 101.879397 -198.774276) (xy 101.873153 -198.791195) (xy 101.872796 -198.800212) (xy 101.872796 -198.867268)
			(xy 101.873169 -198.876283) (xy 101.879406 -198.8932) (xy 101.884988 -198.900288) (xy 101.885242 -198.900288)
			(xy 101.885242 -198.900542) (xy 101.902874 -198.921479) (xy 101.932586 -198.967451) (xy 101.955422 -199.017198)
			(xy 101.970915 -199.069697) (xy 101.978747 -199.123871) (xy 101.979222 -199.15124) (xy 101.978759 -199.178492)
			(xy 101.970998 -199.232439) (xy 101.955638 -199.284734) (xy 101.932994 -199.33431) (xy 101.903524 -199.38016)
			(xy 101.867831 -199.421349) (xy 101.826639 -199.45704) (xy 101.780787 -199.486506) (xy 101.731209 -199.509147)
			(xy 101.678914 -199.524503) (xy 101.624966 -199.532261) (xy 101.597714 -199.532748) (xy 101.568166 -199.532171)
			(xy 101.509778 -199.523062) (xy 101.453492 -199.505058) (xy 101.400655 -199.478591) (xy 101.352531 -199.444293)
			(xy 101.331014 -199.424036) (xy 101.323622 -199.417471) (xy 101.305329 -199.410023) (xy 101.295454 -199.409558)
			(xy 101.242368 -199.409558) (xy 101.235002 -199.417432) (xy 101.228461 -199.424762) (xy 101.221019 -199.442926)
			(xy 101.220524 -199.452738) (xy 101.220524 -199.484742) (xy 101.220992 -199.494559) (xy 101.228449 -199.512723)
			(xy 101.235002 -199.520048) (xy 101.25519 -199.541535) (xy 101.289335 -199.589597) (xy 101.315679 -199.642339)
			(xy 101.333597 -199.698507) (xy 101.34266 -199.756762) (xy 101.343206 -199.78624) (xy 101.342759 -199.813492)
			(xy 101.334997 -199.867442) (xy 101.319637 -199.919737) (xy 101.296991 -199.969315) (xy 101.26752 -200.015165)
			(xy 101.231825 -200.056355) (xy 101.190631 -200.092046) (xy 101.144778 -200.121511) (xy 101.095198 -200.144152)
			(xy 101.0429 -200.159506) (xy 100.98895 -200.167262) (xy 100.961698 -200.167748) (xy 100.93222 -200.167224)
			(xy 100.873965 -200.158153) (xy 100.8178 -200.140227) (xy 100.765061 -200.113874) (xy 100.717004 -200.079721)
			(xy 100.695506 -200.059544) (xy 100.68817 -200.053011) (xy 100.67001 -200.045567) (xy 100.6602 -200.045066)
			(xy 100.60686 -200.045066) (xy 100.600002 -200.052432) (xy 100.593461 -200.059762) (xy 100.586019 -200.077926)
			(xy 100.585524 -200.087738) (xy 100.585524 -200.119742) (xy 100.585992 -200.129559) (xy 100.593449 -200.147723)
			(xy 100.600002 -200.155048) (xy 100.62019 -200.176535) (xy 100.654335 -200.224597) (xy 100.680679 -200.277339)
			(xy 100.698597 -200.333507) (xy 100.70766 -200.391762) (xy 100.708206 -200.42124) (xy 100.70772 -200.448491)
			(xy 100.699964 -200.502439) (xy 100.684609 -200.554734) (xy 100.661967 -200.604311) (xy 100.632501 -200.650161)
			(xy 100.59681 -200.691352) (xy 100.555619 -200.727043) (xy 100.509769 -200.756509) (xy 100.460192 -200.779151)
			(xy 100.407897 -200.794506) (xy 100.353949 -200.802262) (xy 100.299447 -200.802262) (xy 100.245499 -200.794506)
			(xy 100.193204 -200.779151) (xy 100.143627 -200.756509) (xy 100.097777 -200.727043) (xy 100.056586 -200.691352)
			(xy 100.020895 -200.650161) (xy 99.991429 -200.604311) (xy 99.968787 -200.554734) (xy 99.953432 -200.502439)
			(xy 99.945676 -200.448491) (xy 99.94519 -200.42124) (xy 97.964597 -200.42124) (xy 97.964597 -200.423203)
			(xy 97.956763 -200.477386) (xy 97.941259 -200.529891) (xy 97.918406 -200.579639) (xy 97.888671 -200.625606)
			(xy 97.871026 -200.646538) (xy 97.870772 -200.646792) (xy 97.86518 -200.653874) (xy 97.858937 -200.670794)
			(xy 97.85858 -200.679812) (xy 97.85858 -200.746868) (xy 97.858957 -200.755883) (xy 97.865191 -200.7728)
			(xy 97.870772 -200.779888) (xy 97.871026 -200.779888) (xy 97.871026 -200.780142) (xy 97.888655 -200.801082)
			(xy 97.918368 -200.847053) (xy 97.941205 -200.896798) (xy 97.956699 -200.949297) (xy 97.96453 -201.003471)
			(xy 97.965006 -201.03084) (xy 97.964559 -201.058092) (xy 97.956797 -201.112042) (xy 97.941437 -201.164337)
			(xy 97.918791 -201.213915) (xy 97.88932 -201.259765) (xy 97.853625 -201.300955) (xy 97.812431 -201.336646)
			(xy 97.766578 -201.366111) (xy 97.716998 -201.388752) (xy 97.6647 -201.404106) (xy 97.61075 -201.411862)
			(xy 97.583498 -201.412348) (xy 97.556127 -201.411896) (xy 97.501947 -201.404077) (xy 97.449443 -201.388585)
			(xy 97.399696 -201.36574) (xy 97.353731 -201.336011) (xy 97.3328 -201.318368) (xy 97.332546 -201.318114)
			(xy 97.325449 -201.312542) (xy 97.30854 -201.306286) (xy 97.299526 -201.305922) (xy 97.23247 -201.305922)
			(xy 97.223451 -201.30626) (xy 97.206534 -201.31252) (xy 97.19945 -201.318114) (xy 97.199196 -201.318368)
			(xy 97.178263 -201.336009) (xy 97.132295 -201.365733) (xy 97.082549 -201.388579) (xy 97.030047 -201.404075)
			(xy 96.975869 -201.411904) (xy 96.921127 -201.411904) (xy 96.866949 -201.404075) (xy 96.814447 -201.388579)
			(xy 96.764701 -201.365733) (xy 96.718733 -201.336009) (xy 96.6978 -201.318368) (xy 96.697546 -201.318114)
			(xy 96.690449 -201.312542) (xy 96.67354 -201.306286) (xy 96.664526 -201.305922) (xy 96.59747 -201.305922)
			(xy 96.588451 -201.30626) (xy 96.571534 -201.31252) (xy 96.56445 -201.318114) (xy 96.56445 -201.318368)
			(xy 96.564196 -201.318368) (xy 96.543272 -201.336017) (xy 96.497298 -201.365729) (xy 96.447548 -201.388563)
			(xy 96.395045 -201.404052) (xy 96.340868 -201.411876) (xy 96.313498 -201.412348) (xy 96.286249 -201.411824)
			(xy 96.232304 -201.404068) (xy 96.180013 -201.388715) (xy 96.130438 -201.366077) (xy 96.08459 -201.336614)
			(xy 96.0434 -201.300926) (xy 96.007709 -201.259741) (xy 95.978242 -201.213895) (xy 95.955598 -201.164323)
			(xy 95.94024 -201.112033) (xy 95.932479 -201.058089) (xy 95.93199 -201.03084) (xy 93.586628 -201.03084)
			(xy 93.587062 -201.055732) (xy 93.586675 -201.082988) (xy 93.578912 -201.136944) (xy 93.56355 -201.189246)
			(xy 93.5409 -201.238829) (xy 93.511425 -201.284685) (xy 93.475723 -201.325878) (xy 93.434522 -201.361571)
			(xy 93.388661 -201.391038) (xy 93.339073 -201.413677) (xy 93.286768 -201.429029) (xy 93.23281 -201.43678)
			(xy 93.205554 -201.43724) (xy 93.178184 -201.436757) (xy 93.124005 -201.428945) (xy 93.071502 -201.413461)
			(xy 93.021755 -201.390623) (xy 92.975788 -201.360901) (xy 92.954856 -201.34326) (xy 92.954602 -201.343006)
			(xy 92.947519 -201.337415) (xy 92.930599 -201.331171) (xy 92.921582 -201.330814) (xy 92.854526 -201.330814)
			(xy 92.84551 -201.33118) (xy 92.828593 -201.337421) (xy 92.821506 -201.343006) (xy 92.821252 -201.34326)
			(xy 92.800319 -201.360901) (xy 92.754351 -201.390625) (xy 92.704605 -201.413471) (xy 92.652103 -201.428967)
			(xy 92.597925 -201.436796) (xy 92.543183 -201.436796) (xy 92.489005 -201.428967) (xy 92.436503 -201.413471)
			(xy 92.386757 -201.390625) (xy 92.340789 -201.360901) (xy 92.319856 -201.34326) (xy 92.319602 -201.343006)
			(xy 92.312519 -201.337415) (xy 92.295599 -201.331171) (xy 92.286582 -201.330814) (xy 92.219526 -201.330814)
			(xy 92.21051 -201.33118) (xy 92.193593 -201.337421) (xy 92.186506 -201.343006) (xy 92.186506 -201.34326)
			(xy 92.186252 -201.34326) (xy 92.165306 -201.360882) (xy 92.119338 -201.390598) (xy 92.069594 -201.413438)
			(xy 92.017096 -201.428933) (xy 91.962922 -201.436764) (xy 91.935554 -201.43724) (xy 91.908303 -201.436765)
			(xy 91.854357 -201.429003) (xy 91.802064 -201.413644) (xy 91.752488 -201.391) (xy 91.70664 -201.361532)
			(xy 91.665451 -201.325839) (xy 91.62976 -201.284649) (xy 91.600294 -201.238799) (xy 91.577651 -201.189223)
			(xy 91.562294 -201.13693) (xy 91.554534 -201.082983) (xy 91.554046 -201.055732) (xy 91.55452 -201.028362)
			(xy 91.562334 -200.974183) (xy 91.577821 -200.921679) (xy 91.600661 -200.871932) (xy 91.630385 -200.825965)
			(xy 91.648026 -200.805034) (xy 91.64828 -200.80478) (xy 91.65389 -200.79771) (xy 91.660121 -200.78078)
			(xy 91.660472 -200.77176) (xy 91.660472 -200.704704) (xy 91.660119 -200.695687) (xy 91.65387 -200.678769)
			(xy 91.64828 -200.671684) (xy 91.648026 -200.671684) (xy 91.648026 -200.67143) (xy 91.630417 -200.650472)
			(xy 91.600691 -200.604508) (xy 91.577844 -200.554766) (xy 91.562345 -200.502268) (xy 91.554513 -200.448093)
			(xy 91.55451 -200.393355) (xy 91.562335 -200.339179) (xy 91.577827 -200.286679) (xy 91.600667 -200.236934)
			(xy 91.630388 -200.190967) (xy 91.648026 -200.170034) (xy 91.64828 -200.16978) (xy 91.65389 -200.16271)
			(xy 91.660121 -200.14578) (xy 91.660472 -200.13676) (xy 91.660472 -200.069704) (xy 91.660119 -200.060687)
			(xy 91.65387 -200.043769) (xy 91.64828 -200.036684) (xy 91.648026 -200.036684) (xy 91.648026 -200.03643)
			(xy 91.630417 -200.015472) (xy 91.600691 -199.969508) (xy 91.577844 -199.919766) (xy 91.562345 -199.867268)
			(xy 91.554513 -199.813093) (xy 91.55451 -199.758355) (xy 91.562335 -199.704179) (xy 91.577827 -199.651679)
			(xy 91.600667 -199.601934) (xy 91.630388 -199.555967) (xy 91.648026 -199.535034) (xy 91.64828 -199.53478)
			(xy 91.65389 -199.52771) (xy 91.660121 -199.51078) (xy 91.660472 -199.50176) (xy 91.660472 -199.434704)
			(xy 91.660119 -199.425687) (xy 91.65387 -199.408769) (xy 91.64828 -199.401684) (xy 91.648026 -199.401684)
			(xy 91.648026 -199.40143) (xy 91.630417 -199.380472) (xy 91.600691 -199.334508) (xy 91.577844 -199.284766)
			(xy 91.562345 -199.232268) (xy 91.554513 -199.178093) (xy 91.55451 -199.123355) (xy 91.562335 -199.069179)
			(xy 91.577827 -199.016679) (xy 91.600667 -198.966934) (xy 91.630388 -198.920967) (xy 91.648026 -198.900034)
			(xy 91.64828 -198.89978) (xy 91.65389 -198.89271) (xy 91.660121 -198.87578) (xy 91.660472 -198.86676)
			(xy 91.660472 -198.799704) (xy 91.660119 -198.790687) (xy 91.65387 -198.773769) (xy 91.64828 -198.766684)
			(xy 91.648026 -198.766684) (xy 91.648026 -198.76643) (xy 91.630417 -198.745472) (xy 91.600691 -198.699508)
			(xy 91.577844 -198.649766) (xy 91.562345 -198.597268) (xy 91.554513 -198.543093) (xy 91.55451 -198.488355)
			(xy 91.562335 -198.434179) (xy 91.577827 -198.381679) (xy 91.600667 -198.331934) (xy 91.630388 -198.285967)
			(xy 91.648026 -198.265034) (xy 91.64828 -198.26478) (xy 91.65389 -198.25771) (xy 91.660121 -198.24078)
			(xy 91.660472 -198.23176) (xy 91.660472 -198.164704) (xy 91.660119 -198.155687) (xy 91.65387 -198.138769)
			(xy 91.64828 -198.131684) (xy 91.648026 -198.131684) (xy 91.648026 -198.13143) (xy 91.630392 -198.110494)
			(xy 91.600678 -198.064523) (xy 91.577841 -198.014776) (xy 91.562349 -197.962276) (xy 91.55452 -197.908101)
			(xy 91.554046 -197.880732) (xy 91.554513 -197.853128) (xy 91.562479 -197.798496) (xy 91.578235 -197.745583)
			(xy 91.601453 -197.695494) (xy 91.631646 -197.649273) (xy 91.64955 -197.628256) (xy 91.655354 -197.621116)
			(xy 91.661863 -197.603921) (xy 91.66225 -197.594728) (xy 91.66225 -197.527164) (xy 91.661846 -197.517976)
			(xy 91.655327 -197.500793) (xy 91.64955 -197.493636) (xy 91.631632 -197.472632) (xy 91.601442 -197.426408)
			(xy 91.578232 -197.376314) (xy 91.562485 -197.323398) (xy 91.554532 -197.268765) (xy 91.554046 -197.24116)
			(xy 91.554536 -197.213791) (xy 91.562346 -197.159612) (xy 91.577829 -197.107109) (xy 91.600666 -197.057361)
			(xy 91.630386 -197.011394) (xy 91.648026 -196.990462) (xy 91.64828 -196.990208) (xy 91.653879 -196.98313)
			(xy 91.660116 -196.966206) (xy 91.660472 -196.957188) (xy 91.660472 -196.890132) (xy 91.660106 -196.881116)
			(xy 91.653865 -196.864199) (xy 91.64828 -196.857112) (xy 91.648026 -196.857112) (xy 91.648026 -196.856858)
			(xy 91.630346 -196.835957) (xy 91.600623 -196.789984) (xy 91.57778 -196.740232) (xy 91.562287 -196.687725)
			(xy 91.554462 -196.633542) (xy 91.554466 -196.578797) (xy 91.5623 -196.524616) (xy 91.577801 -196.472111)
			(xy 91.600652 -196.422363) (xy 91.630383 -196.376395) (xy 91.648026 -196.355462) (xy 91.64828 -196.355208)
			(xy 91.653879 -196.34813) (xy 91.660116 -196.331206) (xy 91.660472 -196.322188) (xy 91.660472 -196.255132)
			(xy 91.660106 -196.246116) (xy 91.653865 -196.229199) (xy 91.64828 -196.222112) (xy 91.648026 -196.222112)
			(xy 91.648026 -196.221858) (xy 91.630346 -196.200957) (xy 91.600623 -196.154984) (xy 91.57778 -196.105232)
			(xy 91.562287 -196.052725) (xy 91.554462 -195.998542) (xy 91.554466 -195.943797) (xy 91.5623 -195.889616)
			(xy 91.577801 -195.837111) (xy 91.600652 -195.787363) (xy 91.630383 -195.741395) (xy 91.648026 -195.720462)
			(xy 91.64828 -195.720208) (xy 91.653879 -195.71313) (xy 91.660116 -195.696206) (xy 91.660472 -195.687188)
			(xy 91.660472 -195.620132) (xy 91.660106 -195.611116) (xy 91.653865 -195.594199) (xy 91.64828 -195.587112)
			(xy 91.648026 -195.587112) (xy 91.648026 -195.586858) (xy 91.630405 -195.565912) (xy 91.600689 -195.519943)
			(xy 91.57785 -195.470199) (xy 91.562354 -195.417702) (xy 91.554522 -195.363528) (xy 91.554046 -195.33616)
			(xy 91.554495 -195.30886) (xy 91.562274 -195.254817) (xy 91.577679 -195.202435) (xy 91.600398 -195.152786)
			(xy 91.629965 -195.106884) (xy 91.647518 -195.08597) (xy 91.653346 -195.078769) (xy 91.659863 -195.061445)
			(xy 91.660218 -195.052188) (xy 91.659964 -194.976242) (xy 91.653614 -194.959224) (xy 91.647518 -194.952366)
			(xy 91.629791 -194.931415) (xy 91.599914 -194.885381) (xy 91.576949 -194.835536) (xy 91.561372 -194.782913)
			(xy 91.553506 -194.7286) (xy 91.55303 -194.70116) (xy 89.572846 -194.70116) (xy 89.572386 -194.728459)
			(xy 89.564607 -194.782501) (xy 89.549202 -194.834882) (xy 89.526487 -194.884531) (xy 89.496924 -194.930434)
			(xy 89.479374 -194.95135) (xy 89.473537 -194.958545) (xy 89.467026 -194.975874) (xy 89.466674 -194.985132)
			(xy 89.466928 -195.061078) (xy 89.473278 -195.078096) (xy 89.479374 -195.084954) (xy 89.497109 -195.105898)
			(xy 89.526985 -195.151934) (xy 89.549948 -195.20178) (xy 89.565523 -195.254405) (xy 89.573388 -195.308719)
			(xy 89.573862 -195.33616) (xy 89.573382 -195.36353) (xy 89.565569 -195.417709) (xy 89.550084 -195.470212)
			(xy 89.527245 -195.519959) (xy 89.497522 -195.565926) (xy 89.479882 -195.586858) (xy 89.479628 -195.587112)
			(xy 89.474022 -195.594185) (xy 89.467789 -195.611112) (xy 89.467436 -195.620132) (xy 89.467436 -195.687188)
			(xy 89.467791 -195.696205) (xy 89.474039 -195.713122) (xy 89.479628 -195.720208) (xy 89.479882 -195.720208)
			(xy 89.479882 -195.720462) (xy 89.497483 -195.741427) (xy 89.527209 -195.787389) (xy 89.550056 -195.83713)
			(xy 89.565555 -195.889627) (xy 89.573387 -195.943801) (xy 89.573391 -195.998539) (xy 89.565568 -196.052714)
			(xy 89.550077 -196.105213) (xy 89.527238 -196.154958) (xy 89.497519 -196.200925) (xy 89.479882 -196.221858)
			(xy 89.479628 -196.222112) (xy 89.474022 -196.229185) (xy 89.467789 -196.246112) (xy 89.467436 -196.255132)
			(xy 89.467436 -196.322188) (xy 89.467791 -196.331205) (xy 89.474039 -196.348122) (xy 89.479628 -196.355208)
			(xy 89.479882 -196.355208) (xy 89.479882 -196.355462) (xy 89.497483 -196.376427) (xy 89.527209 -196.422389)
			(xy 89.550056 -196.47213) (xy 89.565555 -196.524627) (xy 89.573387 -196.578801) (xy 89.573391 -196.633539)
			(xy 89.565568 -196.687714) (xy 89.550077 -196.740213) (xy 89.527238 -196.789958) (xy 89.497519 -196.835925)
			(xy 89.479882 -196.856858) (xy 89.479628 -196.857112) (xy 89.474022 -196.864185) (xy 89.467789 -196.881112)
			(xy 89.467436 -196.890132) (xy 89.467436 -196.957188) (xy 89.467791 -196.966205) (xy 89.474039 -196.983122)
			(xy 89.479628 -196.990208) (xy 89.479882 -196.990208) (xy 89.479882 -196.990462) (xy 89.497514 -197.0114)
			(xy 89.527227 -197.057371) (xy 89.550065 -197.107117) (xy 89.565558 -197.159616) (xy 89.573387 -197.213791)
			(xy 89.573862 -197.24116) (xy 89.57334 -197.270315) (xy 89.564465 -197.327945) (xy 89.546929 -197.383555)
			(xy 89.521142 -197.435853) (xy 89.487703 -197.483621) (xy 89.467944 -197.505066) (xy 89.461803 -197.512032)
			(xy 89.454502 -197.529088) (xy 89.45372 -197.53834) (xy 89.450672 -197.614794) (xy 89.456768 -197.63232)
			(xy 89.46261 -197.639432) (xy 89.478794 -197.659921) (xy 89.505973 -197.704502) (xy 89.526813 -197.752376)
			(xy 89.540923 -197.802646) (xy 89.548039 -197.854371) (xy 89.548462 -197.880478) (xy 89.548462 -197.880732)
			(xy 89.548024 -197.908103) (xy 89.540201 -197.962284) (xy 89.524706 -198.014788) (xy 89.501857 -198.064534)
			(xy 89.472126 -198.1105) (xy 89.454482 -198.13143) (xy 89.454228 -198.131684) (xy 89.448634 -198.138765)
			(xy 89.442394 -198.155686) (xy 89.442036 -198.164704) (xy 89.442036 -198.23176) (xy 89.442404 -198.240776)
			(xy 89.448643 -198.257693) (xy 89.454228 -198.26478) (xy 89.454482 -198.26478) (xy 89.454482 -198.265034)
			(xy 89.472154 -198.285942) (xy 89.501876 -198.331914) (xy 89.524719 -198.381664) (xy 89.540213 -198.43417)
			(xy 89.548038 -198.488352) (xy 89.548035 -198.543096) (xy 89.540203 -198.597277) (xy 89.524702 -198.649781)
			(xy 89.501853 -198.699528) (xy 89.472125 -198.745497) (xy 89.454482 -198.76643) (xy 89.454228 -198.766684)
			(xy 89.448634 -198.773765) (xy 89.442394 -198.790686) (xy 89.442036 -198.799704) (xy 89.442036 -198.86676)
			(xy 89.442404 -198.875776) (xy 89.448643 -198.892693) (xy 89.454228 -198.89978) (xy 89.454482 -198.89978)
			(xy 89.454482 -198.900034) (xy 89.472154 -198.920942) (xy 89.501876 -198.966914) (xy 89.524719 -199.016664)
			(xy 89.540213 -199.06917) (xy 89.548038 -199.123352) (xy 89.548035 -199.178096) (xy 89.540203 -199.232277)
			(xy 89.524702 -199.284781) (xy 89.501853 -199.334528) (xy 89.472125 -199.380497) (xy 89.454482 -199.40143)
			(xy 89.454228 -199.401684) (xy 89.448634 -199.408765) (xy 89.442394 -199.425686) (xy 89.442036 -199.434704)
			(xy 89.442036 -199.50176) (xy 89.442404 -199.510776) (xy 89.448643 -199.527693) (xy 89.454228 -199.53478)
			(xy 89.454482 -199.53478) (xy 89.454482 -199.535034) (xy 89.472154 -199.555942) (xy 89.501876 -199.601914)
			(xy 89.524719 -199.651664) (xy 89.540213 -199.70417) (xy 89.548038 -199.758352) (xy 89.548035 -199.813096)
			(xy 89.540203 -199.867277) (xy 89.524702 -199.919781) (xy 89.501853 -199.969528) (xy 89.472125 -200.015497)
			(xy 89.454482 -200.03643) (xy 89.454228 -200.036684) (xy 89.448634 -200.043765) (xy 89.442394 -200.060686)
			(xy 89.442036 -200.069704) (xy 89.442036 -200.13676) (xy 89.442404 -200.145776) (xy 89.448643 -200.162693)
			(xy 89.454228 -200.16978) (xy 89.454482 -200.16978) (xy 89.454482 -200.170034) (xy 89.472154 -200.190942)
			(xy 89.501876 -200.236914) (xy 89.524719 -200.286664) (xy 89.540213 -200.33917) (xy 89.548038 -200.393352)
			(xy 89.548035 -200.448096) (xy 89.540203 -200.502277) (xy 89.524702 -200.554781) (xy 89.501853 -200.604528)
			(xy 89.472125 -200.650497) (xy 89.454482 -200.67143) (xy 89.454228 -200.671684) (xy 89.448634 -200.678765)
			(xy 89.442394 -200.695686) (xy 89.442036 -200.704704) (xy 89.442036 -200.77176) (xy 89.442404 -200.780776)
			(xy 89.448643 -200.797693) (xy 89.454228 -200.80478) (xy 89.454482 -200.80478) (xy 89.454482 -200.805034)
			(xy 89.472101 -200.825982) (xy 89.501816 -200.87195) (xy 89.524656 -200.921694) (xy 89.540152 -200.974191)
			(xy 89.547985 -201.028364) (xy 89.548462 -201.055732) (xy 89.548075 -201.082988) (xy 89.540312 -201.136944)
			(xy 89.52495 -201.189246) (xy 89.5023 -201.238829) (xy 89.472825 -201.284685) (xy 89.437123 -201.325878)
			(xy 89.395922 -201.361571) (xy 89.350061 -201.391038) (xy 89.300473 -201.413677) (xy 89.248168 -201.429029)
			(xy 89.19421 -201.43678) (xy 89.166954 -201.43724) (xy 89.139584 -201.436757) (xy 89.085405 -201.428945)
			(xy 89.032902 -201.413461) (xy 88.983155 -201.390623) (xy 88.937188 -201.360901) (xy 88.916256 -201.34326)
			(xy 88.916002 -201.343006) (xy 88.908919 -201.337415) (xy 88.891999 -201.331171) (xy 88.882982 -201.330814)
			(xy 88.815926 -201.330814) (xy 88.80691 -201.33118) (xy 88.789993 -201.337421) (xy 88.782906 -201.343006)
			(xy 88.782652 -201.34326) (xy 88.761719 -201.360901) (xy 88.715751 -201.390625) (xy 88.666005 -201.413471)
			(xy 88.613503 -201.428967) (xy 88.559325 -201.436796) (xy 88.504583 -201.436796) (xy 88.450405 -201.428967)
			(xy 88.397903 -201.413471) (xy 88.348157 -201.390625) (xy 88.302189 -201.360901) (xy 88.281256 -201.34326)
			(xy 88.281002 -201.343006) (xy 88.273919 -201.337415) (xy 88.256999 -201.331171) (xy 88.247982 -201.330814)
			(xy 88.180926 -201.330814) (xy 88.17191 -201.33118) (xy 88.154993 -201.337421) (xy 88.147906 -201.343006)
			(xy 88.147906 -201.34326) (xy 88.147652 -201.34326) (xy 88.126706 -201.360882) (xy 88.080738 -201.390598)
			(xy 88.030994 -201.413438) (xy 87.978496 -201.428933) (xy 87.924322 -201.436764) (xy 87.896954 -201.43724)
			(xy 87.869703 -201.436765) (xy 87.815757 -201.429003) (xy 87.763464 -201.413644) (xy 87.713888 -201.391)
			(xy 87.66804 -201.361532) (xy 87.626851 -201.325839) (xy 87.59116 -201.284649) (xy 87.561694 -201.238799)
			(xy 87.539051 -201.189223) (xy 87.523694 -201.13693) (xy 87.515934 -201.082983) (xy 87.515446 -201.055732)
			(xy 85.188355 -201.055732) (xy 85.188806 -201.08164) (xy 85.188359 -201.108892) (xy 85.180597 -201.162842)
			(xy 85.165237 -201.215137) (xy 85.142591 -201.264715) (xy 85.11312 -201.310565) (xy 85.077425 -201.351755)
			(xy 85.036231 -201.387446) (xy 84.990378 -201.416911) (xy 84.940798 -201.439552) (xy 84.8885 -201.454906)
			(xy 84.83455 -201.462662) (xy 84.807298 -201.463148) (xy 84.779927 -201.462696) (xy 84.725747 -201.454877)
			(xy 84.673243 -201.439385) (xy 84.623496 -201.41654) (xy 84.577531 -201.386811) (xy 84.5566 -201.369168)
			(xy 84.556346 -201.368914) (xy 84.549249 -201.363342) (xy 84.53234 -201.357086) (xy 84.523326 -201.356722)
			(xy 84.45627 -201.356722) (xy 84.447251 -201.35706) (xy 84.430334 -201.36332) (xy 84.42325 -201.368914)
			(xy 84.422996 -201.369168) (xy 84.402063 -201.386809) (xy 84.356095 -201.416533) (xy 84.306349 -201.439379)
			(xy 84.253847 -201.454875) (xy 84.199669 -201.462704) (xy 84.144927 -201.462704) (xy 84.090749 -201.454875)
			(xy 84.038247 -201.439379) (xy 83.988501 -201.416533) (xy 83.942533 -201.386809) (xy 83.9216 -201.369168)
			(xy 83.921346 -201.368914) (xy 83.914249 -201.363342) (xy 83.89734 -201.357086) (xy 83.888326 -201.356722)
			(xy 83.82127 -201.356722) (xy 83.812251 -201.35706) (xy 83.795334 -201.36332) (xy 83.78825 -201.368914)
			(xy 83.78825 -201.369168) (xy 83.787996 -201.369168) (xy 83.767072 -201.386817) (xy 83.721098 -201.416529)
			(xy 83.671348 -201.439363) (xy 83.618845 -201.454852) (xy 83.564668 -201.462676) (xy 83.537298 -201.463148)
			(xy 83.510049 -201.462624) (xy 83.456104 -201.454868) (xy 83.403813 -201.439515) (xy 83.354238 -201.416877)
			(xy 83.30839 -201.387414) (xy 83.2672 -201.351726) (xy 83.231509 -201.310541) (xy 83.202042 -201.264695)
			(xy 83.179398 -201.215123) (xy 83.16404 -201.162833) (xy 83.156279 -201.108889) (xy 83.15579 -201.08164)
			(xy 81.175606 -201.08164) (xy 81.175159 -201.108892) (xy 81.167397 -201.162842) (xy 81.152037 -201.215137)
			(xy 81.129391 -201.264715) (xy 81.09992 -201.310565) (xy 81.064225 -201.351755) (xy 81.023031 -201.387446)
			(xy 80.977178 -201.416911) (xy 80.927598 -201.439552) (xy 80.8753 -201.454906) (xy 80.82135 -201.462662)
			(xy 80.794098 -201.463148) (xy 80.766727 -201.462696) (xy 80.712547 -201.454877) (xy 80.660043 -201.439385)
			(xy 80.610296 -201.41654) (xy 80.564331 -201.386811) (xy 80.5434 -201.369168) (xy 80.543146 -201.368914)
			(xy 80.536049 -201.363342) (xy 80.51914 -201.357086) (xy 80.510126 -201.356722) (xy 80.44307 -201.356722)
			(xy 80.434051 -201.35706) (xy 80.417134 -201.36332) (xy 80.41005 -201.368914) (xy 80.409796 -201.369168)
			(xy 80.388863 -201.386809) (xy 80.342895 -201.416533) (xy 80.293149 -201.439379) (xy 80.240647 -201.454875)
			(xy 80.186469 -201.462704) (xy 80.131727 -201.462704) (xy 80.077549 -201.454875) (xy 80.025047 -201.439379)
			(xy 79.975301 -201.416533) (xy 79.929333 -201.386809) (xy 79.9084 -201.369168) (xy 79.908146 -201.368914)
			(xy 79.901049 -201.363342) (xy 79.88414 -201.357086) (xy 79.875126 -201.356722) (xy 79.80807 -201.356722)
			(xy 79.799051 -201.35706) (xy 79.782134 -201.36332) (xy 79.77505 -201.368914) (xy 79.77505 -201.369168)
			(xy 79.774796 -201.369168) (xy 79.753872 -201.386817) (xy 79.707898 -201.416529) (xy 79.658148 -201.439363)
			(xy 79.605645 -201.454852) (xy 79.551468 -201.462676) (xy 79.524098 -201.463148) (xy 79.496849 -201.462624)
			(xy 79.442904 -201.454868) (xy 79.390613 -201.439515) (xy 79.341038 -201.416877) (xy 79.29519 -201.387414)
			(xy 79.254 -201.351726) (xy 79.218309 -201.310541) (xy 79.188842 -201.264695) (xy 79.166198 -201.215123)
			(xy 79.15084 -201.162833) (xy 79.143079 -201.108889) (xy 79.14259 -201.08164) (xy 77.872082 -201.08164)
			(xy 78.725522 -201.93508) (xy 78.732932 -201.941763) (xy 78.751368 -201.94934) (xy 78.761336 -201.949812)
			(xy 96.692974 -201.949812) (xy 96.717566 -201.950268) (xy 96.766144 -201.957961) (xy 96.812919 -201.973162)
			(xy 96.856739 -201.995496) (xy 96.896523 -202.024413) (xy 96.914208 -202.041506) (xy 96.99117 -202.118468)
			(xy 96.998523 -202.125125) (xy 97.016824 -202.132721) (xy 97.02673 -202.1332) (xy 100.978208 -202.1332)
		)
		(stroke
			(width 0)
			(type solid)
		)
		(fill yes)
		(layer "In4.Cu")
		(net "GND")
	)
	(gr_poly
		(pts
			(xy 124.239782 -251.273564) (xy 124.249655 -251.273094) (xy 124.267943 -251.265641) (xy 124.275342 -251.259086)
			(xy 124.275596 -251.258832) (xy 124.626624 -250.907804) (xy 124.631239 -250.902952) (xy 124.637948 -250.891369)
			(xy 124.639832 -250.884944) (xy 124.647306 -250.859416) (xy 124.669828 -250.811234) (xy 124.700354 -250.76768)
			(xy 124.737961 -250.73007) (xy 124.781512 -250.69954) (xy 124.829693 -250.677014) (xy 124.855224 -250.669552)
			(xy 124.861621 -250.667599) (xy 124.873203 -250.660916) (xy 124.878084 -250.656344) (xy 125.135132 -250.399296)
			(xy 125.142371 -250.392585) (xy 125.160576 -250.384997) (xy 125.170438 -250.384564) (xy 125.960124 -250.384564)
			(xy 125.970303 -250.384056) (xy 125.989033 -250.376064) (xy 125.996446 -250.36907) (xy 125.99924 -250.36653)
			(xy 126.048008 -250.298966) (xy 126.049278 -250.296934) (xy 126.054193 -250.288751) (xy 126.058098 -250.270083)
			(xy 126.056898 -250.260612) (xy 126.055374 -250.251722) (xy 126.054358 -250.248674) (xy 126.047384 -250.225741)
			(xy 126.039853 -250.178405) (xy 126.039372 -250.15444) (xy 126.039372 -250.151138) (xy 126.040151 -250.126062)
			(xy 126.048886 -250.076661) (xy 126.06558 -250.029354) (xy 126.089782 -249.985412) (xy 126.120842 -249.946017)
			(xy 126.157925 -249.912229) (xy 126.200032 -249.884958) (xy 126.24603 -249.864938) (xy 126.294682 -249.852705)
			(xy 126.34468 -249.848591) (xy 126.394678 -249.852705) (xy 126.44333 -249.864938) (xy 126.489328 -249.884958)
			(xy 126.531435 -249.912229) (xy 126.568518 -249.946017) (xy 126.599578 -249.985412) (xy 126.62378 -250.029354)
			(xy 126.640474 -250.076661) (xy 126.649209 -250.126062) (xy 126.649988 -250.151138) (xy 126.649988 -250.152662)
			(xy 126.649988 -250.15444) (xy 126.649501 -250.178405) (xy 126.641976 -250.225741) (xy 126.635002 -250.248674)
			(xy 126.633986 -250.251722) (xy 126.632462 -250.260612) (xy 126.63128 -250.27008) (xy 126.635191 -250.288742)
			(xy 126.640082 -250.296934) (xy 126.641352 -250.298966) (xy 126.688088 -250.363482) (xy 126.69266 -250.36907)
			(xy 126.692914 -250.36907) (xy 126.700307 -250.376099) (xy 126.719047 -250.384115) (xy 126.729236 -250.384564)
			(xy 126.900178 -250.384564) (xy 126.910361 -250.384065) (xy 126.929103 -250.376084) (xy 126.9365 -250.36907)
			(xy 126.939294 -250.36653) (xy 126.988062 -250.298966) (xy 126.989332 -250.296934) (xy 126.994243 -250.28875)
			(xy 126.998143 -250.270083) (xy 126.996952 -250.260612) (xy 126.995428 -250.251722) (xy 126.994412 -250.248674)
			(xy 126.987439 -250.225741) (xy 126.979909 -250.178405) (xy 126.979426 -250.15444) (xy 126.979426 -250.151138)
			(xy 126.980205 -250.126062) (xy 126.98894 -250.076661) (xy 127.005634 -250.029354) (xy 127.029836 -249.985412)
			(xy 127.060896 -249.946017) (xy 127.097979 -249.912229) (xy 127.140086 -249.884958) (xy 127.186084 -249.864938)
			(xy 127.234736 -249.852705) (xy 127.284734 -249.848591) (xy 127.334732 -249.852705) (xy 127.383384 -249.864938)
			(xy 127.429382 -249.884958) (xy 127.471489 -249.912229) (xy 127.508572 -249.946017) (xy 127.539632 -249.985412)
			(xy 127.563834 -250.029354) (xy 127.580528 -250.076661) (xy 127.589263 -250.126062) (xy 127.590042 -250.151138)
			(xy 127.590042 -250.152662) (xy 127.590042 -250.15444) (xy 127.589555 -250.178405) (xy 127.582031 -250.225742)
			(xy 127.575056 -250.248674) (xy 127.57404 -250.251722) (xy 127.572516 -250.260612) (xy 127.571334 -250.27008)
			(xy 127.575242 -250.288743) (xy 127.580136 -250.296934) (xy 127.581406 -250.298966) (xy 127.628142 -250.363482)
			(xy 127.632714 -250.36907) (xy 127.632968 -250.36907) (xy 127.640364 -250.37609) (xy 127.659104 -250.384086)
			(xy 127.66929 -250.384564) (xy 127.840232 -250.384564) (xy 127.852303 -250.383897) (xy 127.873787 -250.37289)
			(xy 127.88138 -250.363482) (xy 127.932942 -250.291854) (xy 127.934974 -250.279154) (xy 127.926847 -250.259379)
			(xy 127.915406 -250.218183) (xy 127.909651 -250.175818) (xy 127.90932 -250.15444) (xy 127.909806 -250.12965)
			(xy 127.917562 -250.080682) (xy 127.932883 -250.033529) (xy 127.955392 -249.989354) (xy 127.984534 -249.949243)
			(xy 128.019591 -249.914186) (xy 128.059702 -249.885044) (xy 128.103877 -249.862535) (xy 128.15103 -249.847214)
			(xy 128.199998 -249.839458) (xy 128.249578 -249.839458) (xy 128.298546 -249.847214) (xy 128.345699 -249.862535)
			(xy 128.389874 -249.885044) (xy 128.429985 -249.914186) (xy 128.465042 -249.949243) (xy 128.494184 -249.989354)
			(xy 128.516693 -250.033529) (xy 128.532014 -250.080682) (xy 128.53977 -250.12965) (xy 128.540256 -250.15444)
			(xy 128.539894 -250.175815) (xy 128.53412 -250.218173) (xy 128.522697 -250.259368) (xy 128.514602 -250.279154)
			(xy 128.516634 -250.291854) (xy 128.568196 -250.363482) (xy 128.575806 -250.372869) (xy 128.59728 -250.383879)
			(xy 128.609344 -250.384564) (xy 128.780286 -250.384564) (xy 128.792351 -250.383886) (xy 128.813816 -250.372865)
			(xy 128.821434 -250.363482) (xy 128.86817 -250.298458) (xy 128.869186 -250.297188) (xy 128.874318 -250.288666)
			(xy 128.878249 -250.269184) (xy 128.876806 -250.259342) (xy 128.875536 -250.251722) (xy 128.87452 -250.248674)
			(xy 128.867547 -250.225741) (xy 128.860016 -250.178405) (xy 128.859534 -250.15444) (xy 128.859534 -250.14936)
			(xy 128.860377 -250.125629) (xy 128.868502 -250.078846) (xy 128.883771 -250.033885) (xy 128.905817 -249.99183)
			(xy 128.934108 -249.953695) (xy 128.967963 -249.9204) (xy 129.006563 -249.892747) (xy 129.048979 -249.871404)
			(xy 129.094188 -249.856885) (xy 129.1411 -249.84954) (xy 129.164842 -249.849132) (xy 129.18863 -249.84959)
			(xy 129.235629 -249.856975) (xy 129.280914 -249.871559) (xy 129.32339 -249.89299) (xy 129.362028 -249.92075)
			(xy 129.395893 -249.954165) (xy 129.424166 -249.992429) (xy 129.446164 -250.034614) (xy 129.461352 -250.0797)
			(xy 129.469364 -250.126596) (xy 129.47015 -250.150376) (xy 129.47015 -250.154694) (xy 129.470052 -250.164887)
			(xy 129.468657 -250.185224) (xy 129.467356 -250.195334) (xy 129.465832 -250.206256) (xy 129.472182 -250.227084)
			(xy 129.528824 -250.291854) (xy 129.536359 -250.299654) (xy 129.556092 -250.308603) (xy 129.566924 -250.309126)
			(xy 129.704846 -250.309126) (xy 129.714686 -250.308595) (xy 129.732856 -250.301017) (xy 129.740152 -250.294394)
			(xy 129.797556 -250.23699) (xy 129.804922 -250.21413) (xy 129.803144 -250.201938) (xy 129.801383 -250.190142)
			(xy 129.799476 -250.166366) (xy 129.799334 -250.15444) (xy 129.799777 -250.130446) (xy 129.807279 -250.083048)
			(xy 129.822105 -250.037408) (xy 129.843889 -249.994649) (xy 129.872094 -249.955826) (xy 129.906027 -249.921893)
			(xy 129.944851 -249.893688) (xy 129.98761 -249.871904) (xy 130.03325 -249.857079) (xy 130.080648 -249.849577)
			(xy 130.104642 -249.849132) (xy 130.116568 -249.849264) (xy 130.140345 -249.851172) (xy 130.15214 -249.852942)
			(xy 130.164332 -249.85472) (xy 130.187192 -249.847354) (xy 130.345688 -249.688858) (xy 130.352296 -249.681685)
			(xy 130.36001 -249.66379) (xy 130.360674 -249.65406) (xy 130.362198 -249.585226) (xy 130.362026 -249.575613)
			(xy 130.355354 -249.557599) (xy 130.349244 -249.550174) (xy 130.34899 -249.54992) (xy 130.334109 -249.532968)
			(xy 130.308986 -249.495506) (xy 130.289647 -249.454755) (xy 130.276515 -249.411602) (xy 130.269874 -249.366987)
			(xy 130.269488 -249.344434) (xy 130.269628 -249.331671) (xy 130.271793 -249.306238) (xy 130.273806 -249.293634)
			(xy 130.273552 -249.293634) (xy 130.27831 -249.268503) (xy 130.29509 -249.220188) (xy 130.319689 -249.175347)
			(xy 130.351419 -249.135234) (xy 130.389392 -249.100972) (xy 130.432545 -249.073519) (xy 130.479671 -249.053644)
			(xy 130.504438 -249.047254) (xy 130.52171 -249.04319) (xy 130.543554 -249.015758) (xy 130.543554 -248.783094)
			(xy 130.538728 -248.77268) (xy 130.52425 -248.738898) (xy 130.51917 -248.725944) (xy 130.49758 -248.708926)
			(xy 130.397758 -248.695718) (xy 130.390895 -248.695055) (xy 130.377249 -248.696997) (xy 130.370834 -248.699528)
			(xy 130.364484 -248.702068) (xy 130.354324 -248.71045) (xy 130.350006 -248.716038) (xy 130.335504 -248.734869)
			(xy 130.30165 -248.768229) (xy 130.263037 -248.795942) (xy 130.220598 -248.817341) (xy 130.175357 -248.831907)
			(xy 130.128406 -248.839291) (xy 130.104642 -248.839736) (xy 130.07938 -248.839247) (xy 130.029543 -248.830937)
			(xy 129.981755 -248.814537) (xy 129.937317 -248.790494) (xy 129.897444 -248.759464) (xy 129.863222 -248.722294)
			(xy 129.835586 -248.679998) (xy 129.815289 -248.63373) (xy 129.802885 -248.584752) (xy 129.798712 -248.5344)
			(xy 129.802885 -248.484048) (xy 129.815289 -248.43507) (xy 129.835586 -248.388802) (xy 129.863222 -248.346506)
			(xy 129.897444 -248.309336) (xy 129.937317 -248.278306) (xy 129.981755 -248.254263) (xy 130.029543 -248.237863)
			(xy 130.07938 -248.229553) (xy 130.104642 -248.22912) (xy 130.128408 -248.22957) (xy 130.175365 -248.236932)
			(xy 130.220613 -248.251488) (xy 130.263055 -248.272885) (xy 130.301666 -248.300606) (xy 130.33551 -248.333979)
			(xy 130.350006 -248.352818) (xy 130.354324 -248.358406) (xy 130.364484 -248.366788) (xy 130.370834 -248.369328)
			(xy 130.377243 -248.371874) (xy 130.390893 -248.373796) (xy 130.397758 -248.373138) (xy 130.49758 -248.35993)
			(xy 130.51917 -248.342912) (xy 130.52425 -248.329958) (xy 130.538728 -248.296176) (xy 130.543554 -248.285762)
			(xy 130.543554 -248.053098) (xy 130.52171 -248.025666) (xy 130.504438 -248.021602) (xy 130.481131 -248.015621)
			(xy 130.436626 -247.997332) (xy 130.39554 -247.97229) (xy 130.358889 -247.941116) (xy 130.327579 -247.904581)
			(xy 130.302384 -247.863588) (xy 130.283929 -247.819152) (xy 130.27267 -247.772372) (xy 130.268886 -247.724405)
			(xy 130.272669 -247.676438) (xy 130.283926 -247.629657) (xy 130.30238 -247.585221) (xy 130.327573 -247.544227)
			(xy 130.358881 -247.507691) (xy 130.395532 -247.476516) (xy 130.436617 -247.451473) (xy 130.481121 -247.433182)
			(xy 130.504438 -247.427242) (xy 130.52171 -247.423178) (xy 130.543554 -247.395746) (xy 130.543554 -247.163082)
			(xy 130.538728 -247.152668) (xy 130.52425 -247.118886) (xy 130.51917 -247.105932) (xy 130.49758 -247.088914)
			(xy 130.397758 -247.075706) (xy 130.390895 -247.075043) (xy 130.377249 -247.076985) (xy 130.370834 -247.079516)
			(xy 130.364484 -247.082056) (xy 130.354324 -247.090438) (xy 130.350006 -247.096026) (xy 130.335504 -247.114858)
			(xy 130.30165 -247.148218) (xy 130.263038 -247.175933) (xy 130.220599 -247.197332) (xy 130.175358 -247.211899)
			(xy 130.128406 -247.219283) (xy 130.104642 -247.219724) (xy 130.079381 -247.219235) (xy 130.029546 -247.210925)
			(xy 129.981759 -247.194526) (xy 129.937324 -247.170484) (xy 129.897452 -247.139455) (xy 129.863232 -247.102287)
			(xy 129.835596 -247.059993) (xy 129.8153 -247.013726) (xy 129.802896 -246.96475) (xy 129.798724 -246.9144)
			(xy 129.802896 -246.86405) (xy 129.8153 -246.815074) (xy 129.835596 -246.768807) (xy 129.863232 -246.726513)
			(xy 129.897452 -246.689345) (xy 129.937324 -246.658316) (xy 129.981759 -246.634274) (xy 130.029546 -246.617875)
			(xy 130.079381 -246.609565) (xy 130.104642 -246.609108) (xy 130.128408 -246.609558) (xy 130.175366 -246.61692)
			(xy 130.220614 -246.631476) (xy 130.263057 -246.652872) (xy 130.301668 -246.680592) (xy 130.335514 -246.713965)
			(xy 130.350006 -246.732806) (xy 130.354324 -246.738394) (xy 130.364484 -246.746776) (xy 130.370834 -246.749316)
			(xy 130.377243 -246.751862) (xy 130.390893 -246.753785) (xy 130.397758 -246.753126) (xy 130.49758 -246.739918)
			(xy 130.51917 -246.7229) (xy 130.52425 -246.709946) (xy 130.538728 -246.676164) (xy 130.543554 -246.66575)
			(xy 130.543554 -246.433086) (xy 130.52171 -246.405654) (xy 130.504438 -246.40159) (xy 130.481132 -246.395609)
			(xy 130.436629 -246.37732) (xy 130.395545 -246.352279) (xy 130.358895 -246.321106) (xy 130.327586 -246.284572)
			(xy 130.302393 -246.243581) (xy 130.28394 -246.199146) (xy 130.272681 -246.152367) (xy 130.268897 -246.104402)
			(xy 130.272681 -246.056437) (xy 130.283938 -246.009658) (xy 130.302391 -245.965224) (xy 130.327584 -245.924232)
			(xy 130.358892 -245.887697) (xy 130.395541 -245.856523) (xy 130.436625 -245.831482) (xy 130.481127 -245.813192)
			(xy 130.504438 -245.80723) (xy 130.52171 -245.803166) (xy 130.543554 -245.775734) (xy 130.543554 -245.54307)
			(xy 130.538728 -245.532656) (xy 130.52425 -245.498874) (xy 130.51917 -245.48592) (xy 130.49758 -245.468902)
			(xy 130.397758 -245.455694) (xy 130.390895 -245.455031) (xy 130.377249 -245.456973) (xy 130.370834 -245.459504)
			(xy 130.364484 -245.462044) (xy 130.354324 -245.470426) (xy 130.350006 -245.476014) (xy 130.335501 -245.494841)
			(xy 130.301644 -245.528193) (xy 130.26303 -245.555899) (xy 130.220592 -245.577292) (xy 130.175353 -245.591855)
			(xy 130.128404 -245.599236) (xy 130.104642 -245.599712) (xy 130.079382 -245.599223) (xy 130.029549 -245.590913)
			(xy 129.981764 -245.574515) (xy 129.93733 -245.550474) (xy 129.89746 -245.519446) (xy 129.863241 -245.48228)
			(xy 129.835607 -245.439987) (xy 129.815311 -245.393722) (xy 129.802908 -245.344748) (xy 129.798736 -245.2944)
			(xy 129.802908 -245.244052) (xy 129.815311 -245.195078) (xy 129.835607 -245.148813) (xy 129.863241 -245.10652)
			(xy 129.89746 -245.069354) (xy 129.93733 -245.038326) (xy 129.981764 -245.014285) (xy 130.029549 -244.997887)
			(xy 130.079382 -244.989577) (xy 130.104642 -244.989096) (xy 130.128408 -244.989546) (xy 130.175366 -244.996908)
			(xy 130.220614 -245.011463) (xy 130.263058 -245.032859) (xy 130.30167 -245.060578) (xy 130.335517 -245.09395)
			(xy 130.350006 -245.112794) (xy 130.354324 -245.118382) (xy 130.364484 -245.126764) (xy 130.370834 -245.129304)
			(xy 130.377243 -245.131851) (xy 130.390893 -245.133774) (xy 130.397758 -245.133114) (xy 130.49758 -245.119906)
			(xy 130.51917 -245.102888) (xy 130.52425 -245.089934) (xy 130.538728 -245.056152) (xy 130.543554 -245.045738)
			(xy 130.543554 -244.813074) (xy 130.52171 -244.785642) (xy 130.504438 -244.781578) (xy 130.481133 -244.775597)
			(xy 130.436632 -244.757308) (xy 130.395549 -244.732268) (xy 130.358901 -244.701096) (xy 130.327594 -244.664563)
			(xy 130.302403 -244.623573) (xy 130.28395 -244.57914) (xy 130.272692 -244.532363) (xy 130.268909 -244.4844)
			(xy 130.272693 -244.436436) (xy 130.28395 -244.389659) (xy 130.302403 -244.345226) (xy 130.327595 -244.304236)
			(xy 130.358902 -244.267703) (xy 130.39555 -244.236531) (xy 130.436633 -244.211491) (xy 130.481134 -244.193202)
			(xy 130.504438 -244.187218) (xy 130.52171 -244.183154) (xy 130.543554 -244.155722) (xy 130.543554 -243.923058)
			(xy 130.538728 -243.912644) (xy 130.52425 -243.878862) (xy 130.51917 -243.865908) (xy 130.49758 -243.84889)
			(xy 130.397758 -243.835682) (xy 130.390895 -243.835019) (xy 130.377249 -243.83696) (xy 130.370834 -243.839492)
			(xy 130.364484 -243.842032) (xy 130.354324 -243.850414) (xy 130.350006 -243.856002) (xy 130.335501 -243.87483)
			(xy 130.301645 -243.908183) (xy 130.263031 -243.93589) (xy 130.220593 -243.957284) (xy 130.175354 -243.971847)
			(xy 130.128405 -243.979229) (xy 130.104642 -243.9797) (xy 130.079383 -243.979211) (xy 130.029552 -243.970902)
			(xy 129.981769 -243.954504) (xy 129.937337 -243.930464) (xy 129.897468 -243.899438) (xy 129.863251 -243.862272)
			(xy 129.835618 -243.819981) (xy 129.815323 -243.773718) (xy 129.80292 -243.724746) (xy 129.798748 -243.6744)
			(xy 129.80292 -243.624054) (xy 129.815323 -243.575082) (xy 129.835618 -243.528819) (xy 129.863251 -243.486528)
			(xy 129.897468 -243.449362) (xy 129.937337 -243.418336) (xy 129.981769 -243.394296) (xy 130.029552 -243.377898)
			(xy 130.079383 -243.369589) (xy 130.104642 -243.369084) (xy 130.128408 -243.369534) (xy 130.175367 -243.376896)
			(xy 130.220615 -243.39145) (xy 130.26306 -243.412846) (xy 130.301673 -243.440565) (xy 130.33552 -243.473936)
			(xy 130.350006 -243.492782) (xy 130.354324 -243.49837) (xy 130.364484 -243.506752) (xy 130.370834 -243.509292)
			(xy 130.377243 -243.511839) (xy 130.390893 -243.513763) (xy 130.397758 -243.513102) (xy 130.49758 -243.499894)
			(xy 130.51917 -243.482876) (xy 130.52425 -243.469922) (xy 130.538728 -243.43614) (xy 130.543554 -243.425726)
			(xy 130.543554 -243.193062) (xy 130.52171 -243.16563) (xy 130.504438 -243.161566) (xy 130.481134 -243.155585)
			(xy 130.436635 -243.137296) (xy 130.395554 -243.112257) (xy 130.358908 -243.081085) (xy 130.327602 -243.044553)
			(xy 130.302412 -243.003565) (xy 130.283961 -242.959133) (xy 130.272704 -242.912358) (xy 130.268921 -242.864397)
			(xy 130.272705 -242.816435) (xy 130.283963 -242.769661) (xy 130.302415 -242.72523) (xy 130.327606 -242.684241)
			(xy 130.358912 -242.64771) (xy 130.39556 -242.61654) (xy 130.436641 -242.591501) (xy 130.48114 -242.573213)
			(xy 130.504438 -242.567206) (xy 130.52171 -242.563142) (xy 130.543554 -242.53571) (xy 130.543554 -242.303046)
			(xy 130.538728 -242.292632) (xy 130.52425 -242.25885) (xy 130.51917 -242.245896) (xy 130.49758 -242.228878)
			(xy 130.397758 -242.21567) (xy 130.390895 -242.215007) (xy 130.37725 -242.216951) (xy 130.370834 -242.21948)
			(xy 130.364484 -242.22202) (xy 130.354324 -242.230402) (xy 130.350006 -242.23599) (xy 130.335502 -242.254819)
			(xy 130.301646 -242.288173) (xy 130.263032 -242.315881) (xy 130.220594 -242.337276) (xy 130.175354 -242.35184)
			(xy 130.128405 -242.359222) (xy 130.104642 -242.359688) (xy 130.079384 -242.359199) (xy 130.029555 -242.35089)
			(xy 129.981774 -242.334493) (xy 129.937344 -242.310454) (xy 129.897476 -242.279429) (xy 129.86326 -242.242265)
			(xy 129.835628 -242.199975) (xy 129.815334 -242.153714) (xy 129.802932 -242.104744) (xy 129.79876 -242.0544)
			(xy 129.802932 -242.004056) (xy 129.815334 -241.955086) (xy 129.835628 -241.908825) (xy 129.86326 -241.866535)
			(xy 129.897476 -241.829371) (xy 129.937344 -241.798346) (xy 129.981774 -241.774307) (xy 130.029555 -241.75791)
			(xy 130.079384 -241.749601) (xy 130.104642 -241.749072) (xy 130.128408 -241.749521) (xy 130.175367 -241.756883)
			(xy 130.220616 -241.771437) (xy 130.263061 -241.792832) (xy 130.301675 -241.82055) (xy 130.335524 -241.853921)
			(xy 130.350006 -241.87277) (xy 130.354324 -241.878358) (xy 130.364484 -241.88674) (xy 130.370834 -241.88928)
			(xy 130.377243 -241.891828) (xy 130.390893 -241.893752) (xy 130.397758 -241.89309) (xy 130.49758 -241.879882)
			(xy 130.51917 -241.862864) (xy 130.52425 -241.84991) (xy 130.538728 -241.816128) (xy 130.543554 -241.805714)
			(xy 130.543554 -241.57305) (xy 130.52171 -241.545618) (xy 130.504438 -241.541554) (xy 130.481135 -241.535573)
			(xy 130.436638 -241.517285) (xy 130.395559 -241.492246) (xy 130.358914 -241.461075) (xy 130.32761 -241.424544)
			(xy 130.302421 -241.383557) (xy 130.283971 -241.339127) (xy 130.272715 -241.292354) (xy 130.268933 -241.244394)
			(xy 130.272717 -241.196434) (xy 130.283975 -241.149662) (xy 130.302427 -241.105232) (xy 130.327617 -241.064246)
			(xy 130.358923 -241.027716) (xy 130.395569 -240.996547) (xy 130.436649 -240.97151) (xy 130.481146 -240.953223)
			(xy 130.504438 -240.947194) (xy 130.52171 -240.94313) (xy 130.543554 -240.915698) (xy 130.543554 -240.683034)
			(xy 130.538728 -240.67262) (xy 130.52425 -240.638838) (xy 130.51917 -240.625884) (xy 130.49758 -240.608866)
			(xy 130.397758 -240.595658) (xy 130.390895 -240.594995) (xy 130.37725 -240.596939) (xy 130.370834 -240.599468)
			(xy 130.364484 -240.602008) (xy 130.354324 -240.61039) (xy 130.350006 -240.615978) (xy 130.335502 -240.634807)
			(xy 130.301647 -240.668163) (xy 130.263034 -240.695872) (xy 130.220595 -240.717268) (xy 130.175355 -240.731832)
			(xy 130.128405 -240.739215) (xy 130.104642 -240.739676) (xy 130.079385 -240.739187) (xy 130.029558 -240.730878)
			(xy 129.981779 -240.714482) (xy 129.93735 -240.690443) (xy 129.897485 -240.65942) (xy 129.86327 -240.622257)
			(xy 129.835639 -240.57997) (xy 129.815345 -240.533711) (xy 129.802944 -240.484742) (xy 129.798772 -240.4344)
			(xy 129.802944 -240.384058) (xy 129.815345 -240.335089) (xy 129.835639 -240.28883) (xy 129.86327 -240.246543)
			(xy 129.897485 -240.20938) (xy 129.93735 -240.178357) (xy 129.981779 -240.154318) (xy 130.029558 -240.137922)
			(xy 130.079385 -240.129613) (xy 130.104642 -240.12906) (xy 130.128408 -240.129509) (xy 130.175367 -240.136871)
			(xy 130.220617 -240.151425) (xy 130.263063 -240.172819) (xy 130.301677 -240.200537) (xy 130.335527 -240.233906)
			(xy 130.350006 -240.252758) (xy 130.354324 -240.258346) (xy 130.364484 -240.266728) (xy 130.370834 -240.269268)
			(xy 130.377242 -240.271816) (xy 130.390893 -240.273741) (xy 130.397758 -240.273078) (xy 130.49758 -240.25987)
			(xy 130.51917 -240.242852) (xy 130.52425 -240.229898) (xy 130.538728 -240.196116) (xy 130.543554 -240.185702)
			(xy 130.543554 -239.953038) (xy 130.52171 -239.925606) (xy 130.504438 -239.921542) (xy 130.481136 -239.915561)
			(xy 130.436641 -239.897273) (xy 130.395563 -239.872234) (xy 130.35892 -239.841065) (xy 130.327618 -239.804535)
			(xy 130.30243 -239.763549) (xy 130.283981 -239.719121) (xy 130.272726 -239.672349) (xy 130.268944 -239.624391)
			(xy 130.272729 -239.576434) (xy 130.283987 -239.529663) (xy 130.302438 -239.485235) (xy 130.327628 -239.444251)
			(xy 130.358933 -239.407723) (xy 130.395578 -239.376555) (xy 130.436656 -239.351519) (xy 130.481152 -239.333234)
			(xy 130.504438 -239.327182) (xy 130.52171 -239.323118) (xy 130.543554 -239.295686) (xy 130.543554 -239.048036)
			(xy 130.539236 -239.03813) (xy 130.529584 -239.01527) (xy 130.524504 -239.002062) (xy 130.502914 -238.985044)
			(xy 130.386328 -238.970058) (xy 130.360674 -238.981234) (xy 130.352546 -238.992664) (xy 130.338079 -239.011962)
			(xy 130.304089 -239.046176) (xy 130.265149 -239.074629) (xy 130.222225 -239.096616) (xy 130.176382 -239.111593)
			(xy 130.128756 -239.119186) (xy 130.104642 -239.119664) (xy 130.079386 -239.119175) (xy 130.029561 -239.110867)
			(xy 129.981784 -239.094471) (xy 129.937357 -239.070433) (xy 129.897493 -239.039411) (xy 129.863279 -239.00225)
			(xy 129.835649 -238.959964) (xy 129.815357 -238.913707) (xy 129.802956 -238.86474) (xy 129.798784 -238.8144)
			(xy 129.802956 -238.76406) (xy 129.815357 -238.715093) (xy 129.835649 -238.668836) (xy 129.863279 -238.62655)
			(xy 129.897493 -238.589389) (xy 129.937357 -238.558367) (xy 129.981783 -238.534329) (xy 130.029561 -238.517933)
			(xy 130.079386 -238.509625) (xy 130.104642 -238.509048) (xy 130.117405 -238.509187) (xy 130.142839 -238.511349)
			(xy 130.155442 -238.513366) (xy 130.155442 -238.513112) (xy 130.178897 -238.517537) (xy 130.224154 -238.532695)
			(xy 130.266508 -238.554696) (xy 130.304932 -238.583008) (xy 130.338493 -238.616943) (xy 130.3528 -238.636048)
			(xy 130.360928 -238.647478) (xy 130.386582 -238.658654) (xy 130.502914 -238.643668) (xy 130.524504 -238.62665)
			(xy 130.529584 -238.613442) (xy 130.539236 -238.590582) (xy 130.543554 -238.580676) (xy 130.543554 -238.333026)
			(xy 130.52171 -238.305594) (xy 130.504438 -238.30153) (xy 130.481129 -238.295549) (xy 130.43662 -238.277259)
			(xy 130.395529 -238.252216) (xy 130.358874 -238.22104) (xy 130.32756 -238.184502) (xy 130.302363 -238.143506)
			(xy 130.283906 -238.099067) (xy 130.272644 -238.052283) (xy 130.268858 -238.004312) (xy 130.272641 -237.95634)
			(xy 130.283898 -237.909555) (xy 130.302353 -237.865114) (xy 130.327547 -237.824116) (xy 130.358858 -237.787576)
			(xy 130.395511 -237.756397) (xy 130.436599 -237.731351) (xy 130.481107 -237.713058) (xy 130.504438 -237.70717)
			(xy 130.52171 -237.703106) (xy 130.543554 -237.675674) (xy 130.543554 -237.435644) (xy 130.538982 -237.425484)
			(xy 130.53441 -237.41507) (xy 130.527298 -237.397798) (xy 130.522218 -237.384844) (xy 130.500374 -237.367826)
			(xy 130.398266 -237.354618) (xy 130.391529 -237.354042) (xy 130.378152 -237.355976) (xy 130.37185 -237.358428)
			(xy 130.365246 -237.361222) (xy 130.354832 -237.36935) (xy 130.350768 -237.374938) (xy 130.336274 -237.39391)
			(xy 130.302384 -237.427535) (xy 130.263675 -237.455478) (xy 130.221091 -237.47706) (xy 130.175668 -237.491754)
			(xy 130.128512 -237.499202) (xy 130.104642 -237.499652) (xy 130.079378 -237.499162) (xy 130.029539 -237.490852)
			(xy 129.981748 -237.474451) (xy 129.937309 -237.450407) (xy 129.897433 -237.419376) (xy 129.86321 -237.382204)
			(xy 129.835572 -237.339906) (xy 129.815274 -237.293635) (xy 129.802869 -237.244655) (xy 129.798696 -237.1943)
			(xy 129.802869 -237.143945) (xy 129.815274 -237.094965) (xy 129.835572 -237.048694) (xy 129.86321 -237.006396)
			(xy 129.897433 -236.969224) (xy 129.937309 -236.938193) (xy 129.981748 -236.914149) (xy 130.029539 -236.897748)
			(xy 130.079378 -236.889438) (xy 130.104642 -236.889036) (xy 130.128514 -236.889493) (xy 130.175678 -236.89692)
			(xy 130.221109 -236.911601) (xy 130.2637 -236.933178) (xy 130.30241 -236.961125) (xy 130.336296 -236.994759)
			(xy 130.350768 -237.01375) (xy 130.354832 -237.019338) (xy 130.365246 -237.027466) (xy 130.37185 -237.03026)
			(xy 130.378134 -237.032779) (xy 130.391527 -237.034709) (xy 130.398266 -237.03407) (xy 130.500374 -237.020862)
			(xy 130.522218 -237.003844) (xy 130.527298 -236.99089) (xy 130.53441 -236.973618) (xy 130.538982 -236.963204)
			(xy 130.543554 -236.953044) (xy 130.543554 -236.713014) (xy 130.52171 -236.685582) (xy 130.504438 -236.681518)
			(xy 130.48113 -236.675537) (xy 130.436623 -236.657247) (xy 130.395534 -236.632205) (xy 130.35888 -236.60103)
			(xy 130.327568 -236.564493) (xy 130.302372 -236.523499) (xy 130.283916 -236.479061) (xy 130.272655 -236.432278)
			(xy 130.26887 -236.384309) (xy 130.272653 -236.336339) (xy 130.28391 -236.289556) (xy 130.302364 -236.245117)
			(xy 130.327558 -236.204121) (xy 130.358868 -236.167582) (xy 130.39552 -236.136405) (xy 130.436607 -236.111361)
			(xy 130.481113 -236.093068) (xy 130.504438 -236.087158) (xy 130.52171 -236.083094) (xy 130.543554 -236.055662)
			(xy 130.543554 -235.808012) (xy 130.539236 -235.798106) (xy 130.529584 -235.775246) (xy 130.524504 -235.762038)
			(xy 130.502914 -235.74502) (xy 130.386328 -235.730034) (xy 130.360674 -235.74121) (xy 130.352546 -235.75264)
			(xy 130.33808 -235.771939) (xy 130.304091 -235.806155) (xy 130.265152 -235.834611) (xy 130.222228 -235.8566)
			(xy 130.176383 -235.871578) (xy 130.128756 -235.879172) (xy 130.104642 -235.87964) (xy 130.079379 -235.879151)
			(xy 130.029542 -235.87084) (xy 129.981753 -235.85444) (xy 129.937315 -235.830397) (xy 129.897441 -235.799367)
			(xy 129.863219 -235.762197) (xy 129.835582 -235.7199) (xy 129.815285 -235.673631) (xy 129.802881 -235.624653)
			(xy 129.798708 -235.5743) (xy 129.802881 -235.523947) (xy 129.815285 -235.474969) (xy 129.835582 -235.4287)
			(xy 129.863219 -235.386403) (xy 129.897441 -235.349233) (xy 129.937315 -235.318203) (xy 129.981753 -235.29416)
			(xy 130.029542 -235.27776) (xy 130.079379 -235.269449) (xy 130.104642 -235.269024) (xy 130.117405 -235.269163)
			(xy 130.142839 -235.271325) (xy 130.155442 -235.273342) (xy 130.155442 -235.273088) (xy 130.178897 -235.277512)
			(xy 130.224155 -235.292669) (xy 130.26651 -235.31467) (xy 130.304936 -235.34298) (xy 130.3385 -235.376914)
			(xy 130.3528 -235.396024) (xy 130.360928 -235.407454) (xy 130.386582 -235.41863) (xy 130.502914 -235.403644)
			(xy 130.524504 -235.386626) (xy 130.529584 -235.373418) (xy 130.539236 -235.350558) (xy 130.543554 -235.340652)
			(xy 130.543554 -235.093002) (xy 130.52171 -235.06557) (xy 130.504438 -235.061506) (xy 130.481131 -235.055525)
			(xy 130.436625 -235.037236) (xy 130.395539 -235.012194) (xy 130.358887 -234.98102) (xy 130.327576 -234.944484)
			(xy 130.302381 -234.903491) (xy 130.283926 -234.859054) (xy 130.272667 -234.812274) (xy 130.268882 -234.764306)
			(xy 130.272665 -234.716338) (xy 130.283922 -234.669557) (xy 130.302376 -234.62512) (xy 130.327569 -234.584126)
			(xy 130.358878 -234.547589) (xy 130.395529 -234.516413) (xy 130.436615 -234.49137) (xy 130.481119 -234.473079)
			(xy 130.504438 -234.467146) (xy 130.52171 -234.463082) (xy 130.543554 -234.43565) (xy 130.543554 -234.188)
			(xy 130.539236 -234.178094) (xy 130.529584 -234.155234) (xy 130.524504 -234.142026) (xy 130.502914 -234.125008)
			(xy 130.386328 -234.110022) (xy 130.360674 -234.121198) (xy 130.352546 -234.132628) (xy 130.338081 -234.151928)
			(xy 130.304092 -234.186145) (xy 130.265153 -234.214602) (xy 130.222229 -234.236592) (xy 130.176384 -234.25157)
			(xy 130.128756 -234.259165) (xy 130.104642 -234.259628) (xy 130.07938 -234.259139) (xy 130.029545 -234.250829)
			(xy 129.981758 -234.234429) (xy 129.937322 -234.210387) (xy 129.897449 -234.179358) (xy 129.863229 -234.142189)
			(xy 129.835593 -234.099894) (xy 129.815296 -234.053627) (xy 129.802893 -234.004651) (xy 129.79872 -233.9543)
			(xy 129.802893 -233.903949) (xy 129.815296 -233.854973) (xy 129.835593 -233.808706) (xy 129.863229 -233.766411)
			(xy 129.897449 -233.729242) (xy 129.937322 -233.698213) (xy 129.981758 -233.674171) (xy 130.029545 -233.657771)
			(xy 130.07938 -233.649461) (xy 130.104642 -233.649012) (xy 130.117405 -233.649151) (xy 130.142839 -233.651313)
			(xy 130.155442 -233.65333) (xy 130.155442 -233.653076) (xy 130.178897 -233.6575) (xy 130.224155 -233.672657)
			(xy 130.266512 -233.694657) (xy 130.304938 -233.722967) (xy 130.338503 -233.756899) (xy 130.3528 -233.776012)
			(xy 130.360928 -233.787442) (xy 130.386582 -233.798618) (xy 130.502914 -233.783632) (xy 130.524504 -233.766614)
			(xy 130.529584 -233.753406) (xy 130.539236 -233.730546) (xy 130.543554 -233.72064) (xy 130.543554 -233.47299)
			(xy 130.52171 -233.445558) (xy 130.504438 -233.441494) (xy 130.481132 -233.435513) (xy 130.436628 -233.417224)
			(xy 130.395543 -233.392183) (xy 130.358893 -233.36101) (xy 130.327584 -233.324475) (xy 130.30239 -233.283483)
			(xy 130.283936 -233.239048) (xy 130.272678 -233.192269) (xy 130.268893 -233.144303) (xy 130.272677 -233.096337)
			(xy 130.283934 -233.049558) (xy 130.302387 -233.005123) (xy 130.32758 -232.96413) (xy 130.358888 -232.927595)
			(xy 130.395538 -232.896421) (xy 130.436623 -232.871379) (xy 130.481125 -232.853089) (xy 130.504438 -232.847134)
			(xy 130.52171 -232.84307) (xy 130.543554 -232.815638) (xy 130.543554 -232.575608) (xy 130.538982 -232.565448)
			(xy 130.53441 -232.555034) (xy 130.527298 -232.537762) (xy 130.522218 -232.524808) (xy 130.500374 -232.50779)
			(xy 130.398266 -232.494582) (xy 130.391529 -232.494006) (xy 130.378151 -232.495939) (xy 130.37185 -232.498392)
			(xy 130.365246 -232.501186) (xy 130.354832 -232.509314) (xy 130.350768 -232.514902) (xy 130.336275 -232.533876)
			(xy 130.302387 -232.567504) (xy 130.263679 -232.595451) (xy 130.221094 -232.617035) (xy 130.17567 -232.631731)
			(xy 130.128513 -232.639181) (xy 130.104642 -232.639616) (xy 130.079381 -232.639127) (xy 130.029548 -232.630817)
			(xy 129.981763 -232.614418) (xy 129.937328 -232.590377) (xy 129.897458 -232.559349) (xy 129.863238 -232.522182)
			(xy 129.835603 -232.479889) (xy 129.815308 -232.433624) (xy 129.802904 -232.384649) (xy 129.798732 -232.3343)
			(xy 129.802904 -232.283951) (xy 129.815308 -232.234976) (xy 129.835603 -232.188711) (xy 129.863238 -232.146418)
			(xy 129.897458 -232.109251) (xy 129.937328 -232.078223) (xy 129.981763 -232.054182) (xy 130.029548 -232.037783)
			(xy 130.079381 -232.029473) (xy 130.104642 -232.029) (xy 130.128515 -232.029457) (xy 130.175679 -232.036883)
			(xy 130.221112 -232.051563) (xy 130.263704 -232.073138) (xy 130.302417 -232.101083) (xy 130.336306 -232.134716)
			(xy 130.350768 -232.153714) (xy 130.354832 -232.159302) (xy 130.365246 -232.16743) (xy 130.37185 -232.170224)
			(xy 130.378133 -232.172744) (xy 130.391527 -232.174676) (xy 130.398266 -232.174034) (xy 130.500374 -232.160826)
			(xy 130.522218 -232.143808) (xy 130.527298 -232.130854) (xy 130.53441 -232.113582) (xy 130.538982 -232.103168)
			(xy 130.543554 -232.093008) (xy 130.543554 -231.852978) (xy 130.52171 -231.825546) (xy 130.504438 -231.821482)
			(xy 130.481132 -231.815501) (xy 130.436631 -231.797212) (xy 130.395548 -231.772172) (xy 130.358899 -231.740999)
			(xy 130.327592 -231.704466) (xy 130.3024 -231.663475) (xy 130.283946 -231.619042) (xy 130.272689 -231.572264)
			(xy 130.268905 -231.5243) (xy 130.272689 -231.476337) (xy 130.283946 -231.429559) (xy 130.302399 -231.385125)
			(xy 130.327591 -231.344135) (xy 130.358898 -231.307601) (xy 130.395547 -231.276429) (xy 130.43663 -231.251388)
			(xy 130.481132 -231.233099) (xy 130.504438 -231.227122) (xy 130.52171 -231.223058) (xy 130.543554 -231.195626)
			(xy 130.543554 -230.94823) (xy 130.539236 -230.938324) (xy 130.529584 -230.915464) (xy 130.524504 -230.902256)
			(xy 130.502914 -230.885238) (xy 130.386328 -230.870252) (xy 130.360674 -230.881428) (xy 130.352546 -230.892858)
			(xy 130.33808 -230.912156) (xy 130.30409 -230.946371) (xy 130.26515 -230.974825) (xy 130.222226 -230.996812)
			(xy 130.176382 -231.011789) (xy 130.128756 -231.019382) (xy 130.104642 -231.019858) (xy 130.079378 -231.019368)
			(xy 130.029538 -231.011058) (xy 129.981746 -230.994657) (xy 129.937305 -230.970612) (xy 129.897429 -230.93958)
			(xy 129.863205 -230.902408) (xy 129.835567 -230.860109) (xy 129.815268 -230.813837) (xy 129.802863 -230.764855)
			(xy 129.79869 -230.7145) (xy 129.802863 -230.664144) (xy 129.815268 -230.615163) (xy 129.835567 -230.568891)
			(xy 129.863205 -230.526592) (xy 129.897429 -230.48942) (xy 129.937305 -230.458388) (xy 129.981746 -230.434343)
			(xy 130.029538 -230.417942) (xy 130.079378 -230.409632) (xy 130.104642 -230.409242) (xy 130.117405 -230.409381)
			(xy 130.142839 -230.411543) (xy 130.155442 -230.41356) (xy 130.155442 -230.413306) (xy 130.178897 -230.417731)
			(xy 130.224154 -230.432888) (xy 130.266508 -230.45489) (xy 130.304933 -230.483201) (xy 130.338495 -230.517136)
			(xy 130.3528 -230.536242) (xy 130.360928 -230.547672) (xy 130.386582 -230.558848) (xy 130.502914 -230.543862)
			(xy 130.524504 -230.526844) (xy 130.529584 -230.513636) (xy 130.539236 -230.490776) (xy 130.543554 -230.48087)
			(xy 130.543554 -230.232966) (xy 130.52171 -230.205534) (xy 130.504438 -230.20147) (xy 130.481134 -230.195489)
			(xy 130.436634 -230.1772) (xy 130.395553 -230.15216) (xy 130.358906 -230.120989) (xy 130.3276 -230.084456)
			(xy 130.302409 -230.043467) (xy 130.283957 -229.999035) (xy 130.2727 -229.95226) (xy 130.268917 -229.904298)
			(xy 130.272701 -229.856336) (xy 130.283959 -229.80956) (xy 130.302411 -229.765129) (xy 130.327602 -229.72414)
			(xy 130.358909 -229.687608) (xy 130.395557 -229.656437) (xy 130.436638 -229.631398) (xy 130.481138 -229.61311)
			(xy 130.504438 -229.60711) (xy 130.52171 -229.603046) (xy 130.543554 -229.575614) (xy 130.543554 -229.328218)
			(xy 130.539236 -229.318312) (xy 130.529584 -229.295452) (xy 130.524504 -229.282244) (xy 130.502914 -229.265226)
			(xy 130.386328 -229.25024) (xy 130.360674 -229.261416) (xy 130.352546 -229.272846) (xy 130.33808 -229.292145)
			(xy 130.304091 -229.32636) (xy 130.265151 -229.354816) (xy 130.222227 -229.376804) (xy 130.176383 -229.391781)
			(xy 130.128756 -229.399375) (xy 130.104642 -229.399846) (xy 130.079379 -229.399356) (xy 130.029541 -229.391046)
			(xy 129.981751 -229.374646) (xy 129.937312 -229.350602) (xy 129.897437 -229.319571) (xy 129.863214 -229.2824)
			(xy 129.835577 -229.240103) (xy 129.815279 -229.193833) (xy 129.802875 -229.144854) (xy 129.798702 -229.0945)
			(xy 129.802875 -229.044146) (xy 129.815279 -228.995167) (xy 129.835577 -228.948897) (xy 129.863214 -228.9066)
			(xy 129.897437 -228.869429) (xy 129.937312 -228.838398) (xy 129.981751 -228.814354) (xy 130.029541 -228.797954)
			(xy 130.079379 -228.789644) (xy 130.104642 -228.78923) (xy 130.117405 -228.789369) (xy 130.142839 -228.791531)
			(xy 130.155442 -228.793548) (xy 130.155442 -228.793294) (xy 130.178897 -228.797718) (xy 130.224154 -228.812876)
			(xy 130.26651 -228.834877) (xy 130.304935 -228.863187) (xy 130.338498 -228.897121) (xy 130.3528 -228.91623)
			(xy 130.360928 -228.92766) (xy 130.386582 -228.938836) (xy 130.502914 -228.92385) (xy 130.524504 -228.906832)
			(xy 130.529584 -228.893624) (xy 130.539236 -228.870764) (xy 130.543554 -228.860858) (xy 130.543554 -228.613208)
			(xy 130.52171 -228.585776) (xy 130.504438 -228.581712) (xy 130.48113 -228.575731) (xy 130.436624 -228.557441)
			(xy 130.395536 -228.5324) (xy 130.358883 -228.501225) (xy 130.327572 -228.464689) (xy 130.302377 -228.423695)
			(xy 130.283921 -228.379257) (xy 130.272661 -228.332476) (xy 130.268876 -228.284507) (xy 130.272659 -228.236539)
			(xy 130.283916 -228.189757) (xy 130.30237 -228.145318) (xy 130.327563 -228.104323) (xy 130.358873 -228.067786)
			(xy 130.395524 -228.036609) (xy 130.436611 -228.011565) (xy 130.481116 -227.993273) (xy 130.504438 -227.987352)
			(xy 130.52171 -227.983288) (xy 130.543554 -227.955856) (xy 130.543554 -227.715826) (xy 130.538982 -227.705666)
			(xy 130.53441 -227.695252) (xy 130.527298 -227.67798) (xy 130.522218 -227.665026) (xy 130.500374 -227.648008)
			(xy 130.398266 -227.6348) (xy 130.391529 -227.634224) (xy 130.378152 -227.636158) (xy 130.37185 -227.63861)
			(xy 130.365246 -227.641404) (xy 130.354832 -227.649532) (xy 130.350768 -227.65512) (xy 130.336274 -227.674093)
			(xy 130.302385 -227.707719) (xy 130.263677 -227.735665) (xy 130.221093 -227.757247) (xy 130.175669 -227.771942)
			(xy 130.128513 -227.779392) (xy 130.104642 -227.779834) (xy 130.07938 -227.779345) (xy 130.029544 -227.771035)
			(xy 129.981755 -227.754635) (xy 129.937318 -227.730592) (xy 129.897445 -227.699563) (xy 129.863224 -227.662393)
			(xy 129.835588 -227.620097) (xy 129.815291 -227.573829) (xy 129.802887 -227.524852) (xy 129.798714 -227.4745)
			(xy 129.802887 -227.424148) (xy 129.815291 -227.375171) (xy 129.835588 -227.328903) (xy 129.863224 -227.286607)
			(xy 129.897445 -227.249437) (xy 129.937318 -227.218408) (xy 129.981755 -227.194365) (xy 130.029544 -227.177965)
			(xy 130.07938 -227.169655) (xy 130.104642 -227.169218) (xy 130.128515 -227.169675) (xy 130.175678 -227.177101)
			(xy 130.22111 -227.191782) (xy 130.263702 -227.213358) (xy 130.302414 -227.241304) (xy 130.336301 -227.274938)
			(xy 130.350768 -227.293932) (xy 130.354832 -227.29952) (xy 130.365246 -227.307648) (xy 130.37185 -227.310442)
			(xy 130.378133 -227.312961) (xy 130.391527 -227.314893) (xy 130.398266 -227.314252) (xy 130.500374 -227.301044)
			(xy 130.522218 -227.284026) (xy 130.527298 -227.271072) (xy 130.53441 -227.2538) (xy 130.538982 -227.243386)
			(xy 130.543554 -227.233226) (xy 130.543554 -226.993196) (xy 130.52171 -226.965764) (xy 130.504438 -226.9617)
			(xy 130.481131 -226.955719) (xy 130.436627 -226.93743) (xy 130.395541 -226.912388) (xy 130.35889 -226.881215)
			(xy 130.32758 -226.84468) (xy 130.302386 -226.803687) (xy 130.283931 -226.759251) (xy 130.272672 -226.712471)
			(xy 130.268887 -226.664505) (xy 130.272671 -226.616538) (xy 130.283928 -226.569758) (xy 130.302382 -226.525321)
			(xy 130.327574 -226.484328) (xy 130.358883 -226.447792) (xy 130.395533 -226.416617) (xy 130.436619 -226.391574)
			(xy 130.481122 -226.373284) (xy 130.504438 -226.36734) (xy 130.52171 -226.363276) (xy 130.543554 -226.335844)
			(xy 130.543554 -226.088194) (xy 130.539236 -226.078288) (xy 130.529584 -226.055428) (xy 130.524504 -226.04222)
			(xy 130.502914 -226.025202) (xy 130.386328 -226.010216) (xy 130.360674 -226.021392) (xy 130.352546 -226.032822)
			(xy 130.338081 -226.052122) (xy 130.304093 -226.08634) (xy 130.265153 -226.114798) (xy 130.222229 -226.136788)
			(xy 130.176384 -226.151767) (xy 130.128757 -226.159361) (xy 130.104642 -226.159822) (xy 130.079381 -226.159333)
			(xy 130.029547 -226.151023) (xy 129.98176 -226.134624) (xy 129.937325 -226.110582) (xy 129.897453 -226.079554)
			(xy 129.863233 -226.042386) (xy 129.835598 -226.000092) (xy 129.815302 -225.953826) (xy 129.802898 -225.90485)
			(xy 129.798726 -225.8545) (xy 129.802898 -225.80415) (xy 129.815302 -225.755174) (xy 129.835598 -225.708908)
			(xy 129.863233 -225.666614) (xy 129.897453 -225.629446) (xy 129.937325 -225.598418) (xy 129.98176 -225.574376)
			(xy 130.029547 -225.557977) (xy 130.079381 -225.549667) (xy 130.104642 -225.549206) (xy 130.117405 -225.549345)
			(xy 130.142839 -225.551508) (xy 130.155442 -225.553524) (xy 130.155442 -225.55327) (xy 130.178897 -225.557694)
			(xy 130.224156 -225.572851) (xy 130.266512 -225.59485) (xy 130.304939 -225.62316) (xy 130.338505 -225.657092)
			(xy 130.3528 -225.676206) (xy 130.360928 -225.687636) (xy 130.386582 -225.698812) (xy 130.502914 -225.683826)
			(xy 130.524504 -225.666808) (xy 130.529584 -225.6536) (xy 130.539236 -225.63074) (xy 130.543554 -225.620834)
			(xy 130.543554 -225.373184) (xy 130.52171 -225.345752) (xy 130.504438 -225.341688) (xy 130.481132 -225.335707)
			(xy 130.43663 -225.317418) (xy 130.395546 -225.292377) (xy 130.358896 -225.261204) (xy 130.327588 -225.22467)
			(xy 130.302395 -225.183679) (xy 130.283941 -225.139245) (xy 130.272683 -225.092467) (xy 130.268899 -225.044502)
			(xy 130.272683 -224.996537) (xy 130.28394 -224.949759) (xy 130.302393 -224.905324) (xy 130.327585 -224.864333)
			(xy 130.358893 -224.827798) (xy 130.395543 -224.796625) (xy 130.436626 -224.771584) (xy 130.481128 -224.753294)
			(xy 130.504438 -224.747328) (xy 130.52171 -224.743264) (xy 130.543554 -224.715832) (xy 130.543554 -223.753172)
			(xy 130.52171 -223.72574) (xy 130.504438 -223.721676) (xy 130.481133 -223.715695) (xy 130.436633 -223.697406)
			(xy 130.39555 -223.672366) (xy 130.358902 -223.641194) (xy 130.327595 -223.604661) (xy 130.302404 -223.563671)
			(xy 130.283952 -223.519239) (xy 130.272694 -223.472462) (xy 130.268911 -223.424499) (xy 130.272695 -223.376536)
			(xy 130.283952 -223.32976) (xy 130.302405 -223.285327) (xy 130.327597 -223.244337) (xy 130.358904 -223.207805)
			(xy 130.395552 -223.176633) (xy 130.436634 -223.151593) (xy 130.481135 -223.133304) (xy 130.504438 -223.127316)
			(xy 130.52171 -223.123252) (xy 130.543554 -223.09582) (xy 130.543554 -222.616776) (xy 130.543125 -222.606709)
			(xy 130.535399 -222.588115) (xy 130.528568 -222.580708) (xy 130.172206 -222.224346) (xy 130.165094 -222.21698)
			(xy 130.146298 -222.20936) (xy 127.841502 -222.20936) (xy 127.831433 -222.209784) (xy 127.812834 -222.217505)
			(xy 127.805434 -222.224346) (xy 127.66675 -222.36303) (xy 127.65913 -222.386398) (xy 127.661162 -222.39859)
			(xy 127.668779 -222.447818) (xy 127.677544 -222.547055) (xy 127.678878 -222.64667) (xy 127.672771 -222.746106)
			(xy 127.659259 -222.844809) (xy 127.638417 -222.942228) (xy 127.62484 -222.990156) (xy 127.621284 -223.002348)
			(xy 127.62611 -223.026732) (xy 127.694944 -223.111314) (xy 127.717804 -223.12122) (xy 127.730504 -223.120204)
			(xy 127.754634 -223.119188) (xy 127.779888 -223.119712) (xy 127.829706 -223.128031) (xy 127.877476 -223.144435)
			(xy 127.921894 -223.168477) (xy 127.96175 -223.199502) (xy 127.995956 -223.236664) (xy 128.023579 -223.278948)
			(xy 128.043866 -223.325202) (xy 128.056264 -223.374165) (xy 128.060435 -223.424496) (xy 129.328938 -223.424496)
			(xy 129.332898 -223.375442) (xy 129.344675 -223.327658) (xy 129.363966 -223.282382) (xy 129.390269 -223.240786)
			(xy 129.422904 -223.203949) (xy 129.461025 -223.172824) (xy 129.503646 -223.148217) (xy 129.549662 -223.130765)
			(xy 129.597881 -223.120921) (xy 129.647056 -223.11894) (xy 129.695911 -223.124872) (xy 129.743182 -223.138564)
			(xy 129.787644 -223.159662) (xy 129.828147 -223.187618) (xy 129.86364 -223.22171) (xy 129.893205 -223.261054)
			(xy 129.916076 -223.304631) (xy 129.93166 -223.351312) (xy 129.939555 -223.399889) (xy 129.94005 -223.424496)
			(xy 129.939555 -223.449103) (xy 129.93166 -223.49768) (xy 129.916076 -223.544361) (xy 129.893205 -223.587938)
			(xy 129.86364 -223.627282) (xy 129.828147 -223.661374) (xy 129.787644 -223.68933) (xy 129.743182 -223.710428)
			(xy 129.695911 -223.72412) (xy 129.647056 -223.730052) (xy 129.597881 -223.728071) (xy 129.549662 -223.718227)
			(xy 129.503646 -223.700775) (xy 129.461025 -223.676168) (xy 129.422904 -223.645043) (xy 129.390269 -223.608206)
			(xy 129.363966 -223.56661) (xy 129.344675 -223.521334) (xy 129.332898 -223.47355) (xy 129.328938 -223.424496)
			(xy 128.060435 -223.424496) (xy 128.060435 -223.4245) (xy 128.056264 -223.474835) (xy 128.043866 -223.523798)
			(xy 128.023579 -223.570052) (xy 127.995956 -223.612336) (xy 127.96175 -223.649498) (xy 127.921894 -223.680523)
			(xy 127.877476 -223.704565) (xy 127.829706 -223.720969) (xy 127.779888 -223.729288) (xy 127.754634 -223.729804)
			(xy 127.730504 -223.728788) (xy 127.717804 -223.727772) (xy 127.694944 -223.737678) (xy 127.634238 -223.812354)
			(xy 127.627076 -223.822324) (xy 127.622188 -223.84634) (xy 127.62484 -223.858328) (xy 127.62484 -223.85909)
			(xy 127.639613 -223.91142) (xy 127.66162 -224.017915) (xy 127.674883 -224.125847) (xy 127.679314 -224.234502)
			(xy 127.918984 -224.234502) (xy 127.922944 -224.185448) (xy 127.934721 -224.137664) (xy 127.954012 -224.092388)
			(xy 127.980315 -224.050792) (xy 128.01295 -224.013955) (xy 128.051071 -223.98283) (xy 128.093692 -223.958223)
			(xy 128.139708 -223.940771) (xy 128.187927 -223.930927) (xy 128.237102 -223.928946) (xy 128.285957 -223.934878)
			(xy 128.333228 -223.94857) (xy 128.37769 -223.969668) (xy 128.418193 -223.997624) (xy 128.453686 -224.031716)
			(xy 128.483251 -224.07106) (xy 128.506122 -224.114637) (xy 128.521706 -224.161318) (xy 128.529601 -224.209895)
			(xy 128.530096 -224.234502) (xy 128.859038 -224.234502) (xy 128.862998 -224.185448) (xy 128.874775 -224.137664)
			(xy 128.894066 -224.092388) (xy 128.920369 -224.050792) (xy 128.953004 -224.013955) (xy 128.991125 -223.98283)
			(xy 129.033746 -223.958223) (xy 129.079762 -223.940771) (xy 129.127981 -223.930927) (xy 129.177156 -223.928946)
			(xy 129.226011 -223.934878) (xy 129.273282 -223.94857) (xy 129.317744 -223.969668) (xy 129.358247 -223.997624)
			(xy 129.39374 -224.031716) (xy 129.423305 -224.07106) (xy 129.446176 -224.114637) (xy 129.46176 -224.161318)
			(xy 129.469655 -224.209895) (xy 129.47015 -224.234502) (xy 129.798838 -224.234502) (xy 129.802798 -224.185448)
			(xy 129.814575 -224.137664) (xy 129.833866 -224.092388) (xy 129.860169 -224.050792) (xy 129.892804 -224.013955)
			(xy 129.930925 -223.98283) (xy 129.973546 -223.958223) (xy 130.019562 -223.940771) (xy 130.067781 -223.930927)
			(xy 130.116956 -223.928946) (xy 130.165811 -223.934878) (xy 130.213082 -223.94857) (xy 130.257544 -223.969668)
			(xy 130.298047 -223.997624) (xy 130.33354 -224.031716) (xy 130.363105 -224.07106) (xy 130.385976 -224.114637)
			(xy 130.40156 -224.161318) (xy 130.409455 -224.209895) (xy 130.40995 -224.234502) (xy 130.409455 -224.259109)
			(xy 130.40156 -224.307686) (xy 130.385976 -224.354367) (xy 130.363105 -224.397944) (xy 130.33354 -224.437288)
			(xy 130.298047 -224.47138) (xy 130.257544 -224.499336) (xy 130.213082 -224.520434) (xy 130.165811 -224.534126)
			(xy 130.116956 -224.540058) (xy 130.067781 -224.538077) (xy 130.019562 -224.528233) (xy 129.973546 -224.510781)
			(xy 129.930925 -224.486174) (xy 129.892804 -224.455049) (xy 129.860169 -224.418212) (xy 129.833866 -224.376616)
			(xy 129.814575 -224.33134) (xy 129.802798 -224.283556) (xy 129.798838 -224.234502) (xy 129.47015 -224.234502)
			(xy 129.469655 -224.259109) (xy 129.46176 -224.307686) (xy 129.446176 -224.354367) (xy 129.423305 -224.397944)
			(xy 129.39374 -224.437288) (xy 129.358247 -224.47138) (xy 129.317744 -224.499336) (xy 129.273282 -224.520434)
			(xy 129.226011 -224.534126) (xy 129.177156 -224.540058) (xy 129.127981 -224.538077) (xy 129.079762 -224.528233)
			(xy 129.033746 -224.510781) (xy 128.991125 -224.486174) (xy 128.953004 -224.455049) (xy 128.920369 -224.418212)
			(xy 128.894066 -224.376616) (xy 128.874775 -224.33134) (xy 128.862998 -224.283556) (xy 128.859038 -224.234502)
			(xy 128.530096 -224.234502) (xy 128.529601 -224.259109) (xy 128.521706 -224.307686) (xy 128.506122 -224.354367)
			(xy 128.483251 -224.397944) (xy 128.453686 -224.437288) (xy 128.418193 -224.47138) (xy 128.37769 -224.499336)
			(xy 128.333228 -224.520434) (xy 128.285957 -224.534126) (xy 128.237102 -224.540058) (xy 128.187927 -224.538077)
			(xy 128.139708 -224.528233) (xy 128.093692 -224.510781) (xy 128.051071 -224.486174) (xy 128.01295 -224.455049)
			(xy 127.980315 -224.418212) (xy 127.954012 -224.376616) (xy 127.934721 -224.33134) (xy 127.922944 -224.283556)
			(xy 127.918984 -224.234502) (xy 127.679314 -224.234502) (xy 127.674883 -224.343156) (xy 127.66162 -224.451089)
			(xy 127.639612 -224.557584) (xy 127.62484 -224.609914) (xy 127.62484 -224.610676) (xy 127.622169 -224.622656)
			(xy 127.6271 -224.646661) (xy 127.634238 -224.65665) (xy 127.694944 -224.731326) (xy 127.717804 -224.741232)
			(xy 127.730504 -224.740216) (xy 127.754634 -224.7392) (xy 127.779887 -224.739724) (xy 127.829703 -224.748042)
			(xy 127.877471 -224.764446) (xy 127.921887 -224.788487) (xy 127.961741 -224.819511) (xy 127.995946 -224.856671)
			(xy 128.023568 -224.898954) (xy 128.043855 -224.945206) (xy 128.056253 -224.994167) (xy 128.060423 -225.0445)
			(xy 128.060422 -225.044508) (xy 128.388884 -225.044508) (xy 128.392844 -224.995454) (xy 128.404621 -224.94767)
			(xy 128.423912 -224.902394) (xy 128.450215 -224.860798) (xy 128.48285 -224.823961) (xy 128.520971 -224.792836)
			(xy 128.563592 -224.768229) (xy 128.609608 -224.750777) (xy 128.657827 -224.740933) (xy 128.707002 -224.738952)
			(xy 128.755857 -224.744884) (xy 128.803128 -224.758576) (xy 128.84759 -224.779674) (xy 128.888093 -224.80763)
			(xy 128.923586 -224.841722) (xy 128.953151 -224.881066) (xy 128.976022 -224.924643) (xy 128.991606 -224.971324)
			(xy 128.999501 -225.019901) (xy 128.999996 -225.044508) (xy 129.318507 -225.044508) (xy 129.322602 -224.99378)
			(xy 129.334781 -224.944366) (xy 129.354729 -224.897546) (xy 129.38193 -224.854532) (xy 129.415678 -224.816438)
			(xy 129.4551 -224.784251) (xy 129.499174 -224.758805) (xy 129.54676 -224.740758) (xy 129.596624 -224.730578)
			(xy 129.647476 -224.728529) (xy 129.697997 -224.734663) (xy 129.746881 -224.748823) (xy 129.79286 -224.77064)
			(xy 129.834744 -224.79955) (xy 129.871448 -224.834805) (xy 129.902021 -224.875491) (xy 129.925672 -224.920554)
			(xy 129.941788 -224.968828) (xy 129.949952 -225.019062) (xy 129.950464 -225.044508) (xy 129.949952 -225.069954)
			(xy 129.941788 -225.120188) (xy 129.925672 -225.168462) (xy 129.902021 -225.213525) (xy 129.871448 -225.254211)
			(xy 129.834744 -225.289466) (xy 129.79286 -225.318376) (xy 129.746881 -225.340193) (xy 129.697997 -225.354353)
			(xy 129.647476 -225.360487) (xy 129.596624 -225.358438) (xy 129.54676 -225.348258) (xy 129.499174 -225.330211)
			(xy 129.4551 -225.304765) (xy 129.415678 -225.272578) (xy 129.38193 -225.234484) (xy 129.354729 -225.19147)
			(xy 129.334781 -225.14465) (xy 129.322602 -225.095236) (xy 129.318507 -225.044508) (xy 128.999996 -225.044508)
			(xy 128.999501 -225.069115) (xy 128.991606 -225.117692) (xy 128.976022 -225.164373) (xy 128.953151 -225.20795)
			(xy 128.923586 -225.247294) (xy 128.888093 -225.281386) (xy 128.84759 -225.309342) (xy 128.803128 -225.33044)
			(xy 128.755857 -225.344132) (xy 128.707002 -225.350064) (xy 128.657827 -225.348083) (xy 128.609608 -225.338239)
			(xy 128.563592 -225.320787) (xy 128.520971 -225.29618) (xy 128.48285 -225.265055) (xy 128.450215 -225.228218)
			(xy 128.423912 -225.186622) (xy 128.404621 -225.141346) (xy 128.392844 -225.093562) (xy 128.388884 -225.044508)
			(xy 128.060422 -225.044508) (xy 128.056253 -225.094833) (xy 128.043855 -225.143794) (xy 128.023568 -225.190046)
			(xy 127.995946 -225.232329) (xy 127.961741 -225.269489) (xy 127.921887 -225.300513) (xy 127.877471 -225.324554)
			(xy 127.829703 -225.340958) (xy 127.779887 -225.349276) (xy 127.754634 -225.349816) (xy 127.730504 -225.3488)
			(xy 127.717804 -225.347784) (xy 127.694944 -225.35769) (xy 127.634238 -225.432366) (xy 127.62702 -225.442312)
			(xy 127.621991 -225.466327) (xy 127.624586 -225.47834) (xy 127.62484 -225.478848) (xy 127.62484 -225.479102)
			(xy 127.639533 -225.53112) (xy 127.661459 -225.636975) (xy 127.674745 -225.744257) (xy 127.679305 -225.852262)
			(xy 127.679218 -225.854514) (xy 127.908553 -225.854514) (xy 127.912648 -225.803786) (xy 127.924827 -225.754372)
			(xy 127.944775 -225.707552) (xy 127.971976 -225.664538) (xy 128.005724 -225.626444) (xy 128.045146 -225.594257)
			(xy 128.08922 -225.568811) (xy 128.136806 -225.550764) (xy 128.18667 -225.540584) (xy 128.237522 -225.538535)
			(xy 128.288043 -225.544669) (xy 128.336927 -225.558829) (xy 128.382906 -225.580646) (xy 128.42479 -225.609556)
			(xy 128.461494 -225.644811) (xy 128.492067 -225.685497) (xy 128.515718 -225.73056) (xy 128.531834 -225.778834)
			(xy 128.539998 -225.829068) (xy 128.54051 -225.854514) (xy 128.848607 -225.854514) (xy 128.852702 -225.803786)
			(xy 128.864881 -225.754372) (xy 128.884829 -225.707552) (xy 128.91203 -225.664538) (xy 128.945778 -225.626444)
			(xy 128.9852 -225.594257) (xy 129.029274 -225.568811) (xy 129.07686 -225.550764) (xy 129.126724 -225.540584)
			(xy 129.177576 -225.538535) (xy 129.228097 -225.544669) (xy 129.276981 -225.558829) (xy 129.32296 -225.580646)
			(xy 129.364844 -225.609556) (xy 129.401548 -225.644811) (xy 129.432121 -225.685497) (xy 129.455772 -225.73056)
			(xy 129.471888 -225.778834) (xy 129.480052 -225.829068) (xy 129.480564 -225.854514) (xy 129.480052 -225.87996)
			(xy 129.471888 -225.930194) (xy 129.455772 -225.978468) (xy 129.432121 -226.023531) (xy 129.401548 -226.064217)
			(xy 129.364844 -226.099472) (xy 129.32296 -226.128382) (xy 129.276981 -226.150199) (xy 129.228097 -226.164359)
			(xy 129.177576 -226.170493) (xy 129.126724 -226.168444) (xy 129.07686 -226.158264) (xy 129.029274 -226.140217)
			(xy 128.9852 -226.114771) (xy 128.945778 -226.082584) (xy 128.91203 -226.04449) (xy 128.884829 -226.001476)
			(xy 128.864881 -225.954656) (xy 128.852702 -225.905242) (xy 128.848607 -225.854514) (xy 128.54051 -225.854514)
			(xy 128.539998 -225.87996) (xy 128.531834 -225.930194) (xy 128.515718 -225.978468) (xy 128.492067 -226.023531)
			(xy 128.461494 -226.064217) (xy 128.42479 -226.099472) (xy 128.382906 -226.128382) (xy 128.336927 -226.150199)
			(xy 128.288043 -226.164359) (xy 128.237522 -226.170493) (xy 128.18667 -226.168444) (xy 128.136806 -226.158264)
			(xy 128.08922 -226.140217) (xy 128.045146 -226.114771) (xy 128.005724 -226.082584) (xy 127.971976 -226.04449)
			(xy 127.944775 -226.001476) (xy 127.924827 -225.954656) (xy 127.912648 -225.905242) (xy 127.908553 -225.854514)
			(xy 127.679218 -225.854514) (xy 127.675108 -225.960282) (xy 127.662181 -226.067608) (xy 127.64061 -226.173536)
			(xy 127.62611 -226.225608) (xy 127.62611 -226.225862) (xy 127.625856 -226.22637) (xy 127.622965 -226.238409)
			(xy 127.627889 -226.262646) (xy 127.635254 -226.272598) (xy 127.687832 -226.337622) (xy 127.691823 -226.342241)
			(xy 127.701583 -226.349566) (xy 127.707136 -226.3521) (xy 127.707644 -226.352354) (xy 127.719326 -226.350767)
			(xy 127.742845 -226.349118) (xy 127.754634 -226.349052) (xy 127.77942 -226.349541) (xy 127.828382 -226.357301)
			(xy 127.875527 -226.372623) (xy 127.919695 -226.395132) (xy 127.959798 -226.424273) (xy 127.994849 -226.459328)
			(xy 128.023986 -226.499434) (xy 128.04649 -226.543605) (xy 128.061807 -226.590751) (xy 128.069562 -226.639714)
			(xy 128.069562 -226.66452) (xy 128.388884 -226.66452) (xy 128.392844 -226.615466) (xy 128.404621 -226.567682)
			(xy 128.423912 -226.522406) (xy 128.450215 -226.48081) (xy 128.48285 -226.443973) (xy 128.520971 -226.412848)
			(xy 128.563592 -226.388241) (xy 128.609608 -226.370789) (xy 128.657827 -226.360945) (xy 128.707002 -226.358964)
			(xy 128.755857 -226.364896) (xy 128.803128 -226.378588) (xy 128.84759 -226.399686) (xy 128.888093 -226.427642)
			(xy 128.923586 -226.461734) (xy 128.953151 -226.501078) (xy 128.976022 -226.544655) (xy 128.991606 -226.591336)
			(xy 128.999501 -226.639913) (xy 128.999996 -226.66452) (xy 129.318507 -226.66452) (xy 129.322602 -226.613792)
			(xy 129.334781 -226.564378) (xy 129.354729 -226.517558) (xy 129.38193 -226.474544) (xy 129.415678 -226.43645)
			(xy 129.4551 -226.404263) (xy 129.499174 -226.378817) (xy 129.54676 -226.36077) (xy 129.596624 -226.35059)
			(xy 129.647476 -226.348541) (xy 129.697997 -226.354675) (xy 129.746881 -226.368835) (xy 129.79286 -226.390652)
			(xy 129.834744 -226.419562) (xy 129.871448 -226.454817) (xy 129.902021 -226.495503) (xy 129.925672 -226.540566)
			(xy 129.941788 -226.58884) (xy 129.949952 -226.639074) (xy 129.950464 -226.66452) (xy 129.949952 -226.689966)
			(xy 129.941788 -226.7402) (xy 129.925672 -226.788474) (xy 129.902021 -226.833537) (xy 129.871448 -226.874223)
			(xy 129.834744 -226.909478) (xy 129.79286 -226.938388) (xy 129.746881 -226.960205) (xy 129.697997 -226.974365)
			(xy 129.647476 -226.980499) (xy 129.596624 -226.97845) (xy 129.54676 -226.96827) (xy 129.499174 -226.950223)
			(xy 129.4551 -226.924777) (xy 129.415678 -226.89259) (xy 129.38193 -226.854496) (xy 129.354729 -226.811482)
			(xy 129.334781 -226.764662) (xy 129.322602 -226.715248) (xy 129.318507 -226.66452) (xy 128.999996 -226.66452)
			(xy 128.999501 -226.689127) (xy 128.991606 -226.737704) (xy 128.976022 -226.784385) (xy 128.953151 -226.827962)
			(xy 128.923586 -226.867306) (xy 128.888093 -226.901398) (xy 128.84759 -226.929354) (xy 128.803128 -226.950452)
			(xy 128.755857 -226.964144) (xy 128.707002 -226.970076) (xy 128.657827 -226.968095) (xy 128.609608 -226.958251)
			(xy 128.563592 -226.940799) (xy 128.520971 -226.916192) (xy 128.48285 -226.885067) (xy 128.450215 -226.84823)
			(xy 128.423912 -226.806634) (xy 128.404621 -226.761358) (xy 128.392844 -226.713574) (xy 128.388884 -226.66452)
			(xy 128.069562 -226.66452) (xy 128.069562 -226.689286) (xy 128.061807 -226.738249) (xy 128.04649 -226.785395)
			(xy 128.023986 -226.829566) (xy 127.994849 -226.869672) (xy 127.959798 -226.904727) (xy 127.919695 -226.933868)
			(xy 127.875527 -226.956377) (xy 127.828382 -226.971699) (xy 127.77942 -226.979459) (xy 127.754634 -226.979988)
			(xy 127.742844 -226.97994) (xy 127.719324 -226.978291) (xy 127.707644 -226.976686) (xy 127.707136 -226.97694)
			(xy 127.701605 -226.979511) (xy 127.691849 -226.986828) (xy 127.687832 -226.991418) (xy 127.635254 -227.056442)
			(xy 127.631548 -227.061237) (xy 127.62628 -227.072146) (xy 127.62484 -227.078032) (xy 127.6223 -227.090478)
			(xy 127.637535 -227.14307) (xy 127.660359 -227.250169) (xy 127.674321 -227.358779) (xy 127.679327 -227.468168)
			(xy 127.679096 -227.474526) (xy 127.908553 -227.474526) (xy 127.912648 -227.423798) (xy 127.924827 -227.374384)
			(xy 127.944775 -227.327564) (xy 127.971976 -227.28455) (xy 128.005724 -227.246456) (xy 128.045146 -227.214269)
			(xy 128.08922 -227.188823) (xy 128.136806 -227.170776) (xy 128.18667 -227.160596) (xy 128.237522 -227.158547)
			(xy 128.288043 -227.164681) (xy 128.336927 -227.178841) (xy 128.382906 -227.200658) (xy 128.42479 -227.229568)
			(xy 128.461494 -227.264823) (xy 128.492067 -227.305509) (xy 128.515718 -227.350572) (xy 128.531834 -227.398846)
			(xy 128.539998 -227.44908) (xy 128.54051 -227.474526) (xy 128.848607 -227.474526) (xy 128.852702 -227.423798)
			(xy 128.864881 -227.374384) (xy 128.884829 -227.327564) (xy 128.91203 -227.28455) (xy 128.945778 -227.246456)
			(xy 128.9852 -227.214269) (xy 129.029274 -227.188823) (xy 129.07686 -227.170776) (xy 129.126724 -227.160596)
			(xy 129.177576 -227.158547) (xy 129.228097 -227.164681) (xy 129.276981 -227.178841) (xy 129.32296 -227.200658)
			(xy 129.364844 -227.229568) (xy 129.401548 -227.264823) (xy 129.432121 -227.305509) (xy 129.455772 -227.350572)
			(xy 129.471888 -227.398846) (xy 129.480052 -227.44908) (xy 129.480564 -227.474526) (xy 129.480052 -227.499972)
			(xy 129.471888 -227.550206) (xy 129.455772 -227.59848) (xy 129.432121 -227.643543) (xy 129.401548 -227.684229)
			(xy 129.364844 -227.719484) (xy 129.32296 -227.748394) (xy 129.276981 -227.770211) (xy 129.228097 -227.784371)
			(xy 129.177576 -227.790505) (xy 129.126724 -227.788456) (xy 129.07686 -227.778276) (xy 129.029274 -227.760229)
			(xy 128.9852 -227.734783) (xy 128.945778 -227.702596) (xy 128.91203 -227.664502) (xy 128.884829 -227.621488)
			(xy 128.864881 -227.574668) (xy 128.852702 -227.525254) (xy 128.848607 -227.474526) (xy 128.54051 -227.474526)
			(xy 128.539998 -227.499972) (xy 128.531834 -227.550206) (xy 128.515718 -227.59848) (xy 128.492067 -227.643543)
			(xy 128.461494 -227.684229) (xy 128.42479 -227.719484) (xy 128.382906 -227.748394) (xy 128.336927 -227.770211)
			(xy 128.288043 -227.784371) (xy 128.237522 -227.790505) (xy 128.18667 -227.788456) (xy 128.136806 -227.778276)
			(xy 128.08922 -227.760229) (xy 128.045146 -227.734783) (xy 128.005724 -227.702596) (xy 127.971976 -227.664502)
			(xy 127.944775 -227.621488) (xy 127.924827 -227.574668) (xy 127.912648 -227.525254) (xy 127.908553 -227.474526)
			(xy 127.679096 -227.474526) (xy 127.675344 -227.5776) (xy 127.662397 -227.686335) (xy 127.640575 -227.793642)
			(xy 127.625856 -227.846382) (xy 127.6223 -227.858574) (xy 127.62738 -227.882958) (xy 127.687832 -227.957634)
			(xy 127.691824 -227.962252) (xy 127.701585 -227.969575) (xy 127.707136 -227.972112) (xy 127.707644 -227.972366)
			(xy 127.719326 -227.970779) (xy 127.742845 -227.96913) (xy 127.754634 -227.969064) (xy 127.779419 -227.969553)
			(xy 127.828379 -227.977312) (xy 127.875522 -227.992635) (xy 127.919688 -228.015142) (xy 127.95979 -228.044282)
			(xy 127.99484 -228.079336) (xy 128.023975 -228.119441) (xy 128.046479 -228.163609) (xy 128.061796 -228.210754)
			(xy 128.06955 -228.259715) (xy 128.06955 -228.284532) (xy 128.388884 -228.284532) (xy 128.392844 -228.235478)
			(xy 128.404621 -228.187694) (xy 128.423912 -228.142418) (xy 128.450215 -228.100822) (xy 128.48285 -228.063985)
			(xy 128.520971 -228.03286) (xy 128.563592 -228.008253) (xy 128.609608 -227.990801) (xy 128.657827 -227.980957)
			(xy 128.707002 -227.978976) (xy 128.755857 -227.984908) (xy 128.803128 -227.9986) (xy 128.84759 -228.019698)
			(xy 128.888093 -228.047654) (xy 128.923586 -228.081746) (xy 128.953151 -228.12109) (xy 128.976022 -228.164667)
			(xy 128.991606 -228.211348) (xy 128.999501 -228.259925) (xy 128.999996 -228.284532) (xy 129.318507 -228.284532)
			(xy 129.322602 -228.233804) (xy 129.334781 -228.18439) (xy 129.354729 -228.13757) (xy 129.38193 -228.094556)
			(xy 129.415678 -228.056462) (xy 129.4551 -228.024275) (xy 129.499174 -227.998829) (xy 129.54676 -227.980782)
			(xy 129.596624 -227.970602) (xy 129.647476 -227.968553) (xy 129.697997 -227.974687) (xy 129.746881 -227.988847)
			(xy 129.79286 -228.010664) (xy 129.834744 -228.039574) (xy 129.871448 -228.074829) (xy 129.902021 -228.115515)
			(xy 129.925672 -228.160578) (xy 129.941788 -228.208852) (xy 129.949952 -228.259086) (xy 129.950464 -228.284532)
			(xy 129.949952 -228.309978) (xy 129.941788 -228.360212) (xy 129.925672 -228.408486) (xy 129.902021 -228.453549)
			(xy 129.871448 -228.494235) (xy 129.834744 -228.52949) (xy 129.79286 -228.5584) (xy 129.746881 -228.580217)
			(xy 129.697997 -228.594377) (xy 129.647476 -228.600511) (xy 129.596624 -228.598462) (xy 129.54676 -228.588282)
			(xy 129.499174 -228.570235) (xy 129.4551 -228.544789) (xy 129.415678 -228.512602) (xy 129.38193 -228.474508)
			(xy 129.354729 -228.431494) (xy 129.334781 -228.384674) (xy 129.322602 -228.33526) (xy 129.318507 -228.284532)
			(xy 128.999996 -228.284532) (xy 128.999501 -228.309139) (xy 128.991606 -228.357716) (xy 128.976022 -228.404397)
			(xy 128.953151 -228.447974) (xy 128.923586 -228.487318) (xy 128.888093 -228.52141) (xy 128.84759 -228.549366)
			(xy 128.803128 -228.570464) (xy 128.755857 -228.584156) (xy 128.707002 -228.590088) (xy 128.657827 -228.588107)
			(xy 128.609608 -228.578263) (xy 128.563592 -228.560811) (xy 128.520971 -228.536204) (xy 128.48285 -228.505079)
			(xy 128.450215 -228.468242) (xy 128.423912 -228.426646) (xy 128.404621 -228.38137) (xy 128.392844 -228.333586)
			(xy 128.388884 -228.284532) (xy 128.06955 -228.284532) (xy 128.06955 -228.309285) (xy 128.061796 -228.358246)
			(xy 128.046479 -228.405391) (xy 128.023975 -228.449559) (xy 127.99484 -228.489664) (xy 127.95979 -228.524718)
			(xy 127.919688 -228.553858) (xy 127.875522 -228.576365) (xy 127.828379 -228.591688) (xy 127.779419 -228.599447)
			(xy 127.754634 -228.6) (xy 127.742844 -228.599952) (xy 127.719324 -228.598303) (xy 127.707644 -228.596698)
			(xy 127.707136 -228.596952) (xy 127.701605 -228.599523) (xy 127.691851 -228.606841) (xy 127.687832 -228.61143)
			(xy 127.635254 -228.676454) (xy 127.631549 -228.681249) (xy 127.626283 -228.692159) (xy 127.62484 -228.698044)
			(xy 127.6223 -228.71049) (xy 127.637539 -228.763082) (xy 127.66037 -228.870182) (xy 127.674339 -228.978793)
			(xy 127.679352 -229.088184) (xy 127.679121 -229.094538) (xy 127.908553 -229.094538) (xy 127.912648 -229.04381)
			(xy 127.924827 -228.994396) (xy 127.944775 -228.947576) (xy 127.971976 -228.904562) (xy 128.005724 -228.866468)
			(xy 128.045146 -228.834281) (xy 128.08922 -228.808835) (xy 128.136806 -228.790788) (xy 128.18667 -228.780608)
			(xy 128.237522 -228.778559) (xy 128.288043 -228.784693) (xy 128.336927 -228.798853) (xy 128.382906 -228.82067)
			(xy 128.42479 -228.84958) (xy 128.461494 -228.884835) (xy 128.492067 -228.925521) (xy 128.515718 -228.970584)
			(xy 128.531834 -229.018858) (xy 128.539998 -229.069092) (xy 128.54051 -229.094538) (xy 128.848607 -229.094538)
			(xy 128.852702 -229.04381) (xy 128.864881 -228.994396) (xy 128.884829 -228.947576) (xy 128.91203 -228.904562)
			(xy 128.945778 -228.866468) (xy 128.9852 -228.834281) (xy 129.029274 -228.808835) (xy 129.07686 -228.790788)
			(xy 129.126724 -228.780608) (xy 129.177576 -228.778559) (xy 129.228097 -228.784693) (xy 129.276981 -228.798853)
			(xy 129.32296 -228.82067) (xy 129.364844 -228.84958) (xy 129.401548 -228.884835) (xy 129.432121 -228.925521)
			(xy 129.455772 -228.970584) (xy 129.471888 -229.018858) (xy 129.480052 -229.069092) (xy 129.480564 -229.094538)
			(xy 129.480052 -229.119984) (xy 129.471888 -229.170218) (xy 129.455772 -229.218492) (xy 129.432121 -229.263555)
			(xy 129.401548 -229.304241) (xy 129.364844 -229.339496) (xy 129.32296 -229.368406) (xy 129.276981 -229.390223)
			(xy 129.228097 -229.404383) (xy 129.177576 -229.410517) (xy 129.126724 -229.408468) (xy 129.07686 -229.398288)
			(xy 129.029274 -229.380241) (xy 128.9852 -229.354795) (xy 128.945778 -229.322608) (xy 128.91203 -229.284514)
			(xy 128.884829 -229.2415) (xy 128.864881 -229.19468) (xy 128.852702 -229.145266) (xy 128.848607 -229.094538)
			(xy 128.54051 -229.094538) (xy 128.539998 -229.119984) (xy 128.531834 -229.170218) (xy 128.515718 -229.218492)
			(xy 128.492067 -229.263555) (xy 128.461494 -229.304241) (xy 128.42479 -229.339496) (xy 128.382906 -229.368406)
			(xy 128.336927 -229.390223) (xy 128.288043 -229.404383) (xy 128.237522 -229.410517) (xy 128.18667 -229.408468)
			(xy 128.136806 -229.398288) (xy 128.08922 -229.380241) (xy 128.045146 -229.354795) (xy 128.005724 -229.322608)
			(xy 127.971976 -229.284514) (xy 127.944775 -229.2415) (xy 127.924827 -229.19468) (xy 127.912648 -229.145266)
			(xy 127.908553 -229.094538) (xy 127.679121 -229.094538) (xy 127.675376 -229.197617) (xy 127.662436 -229.306356)
			(xy 127.64062 -229.413666) (xy 127.625856 -229.466394) (xy 127.624332 -229.472236) (xy 127.623824 -229.484174)
			(xy 127.62484 -229.49027) (xy 127.626189 -229.496363) (xy 127.631445 -229.507679) (xy 127.635254 -229.512622)
			(xy 127.688086 -229.577392) (xy 127.692032 -229.581978) (xy 127.701657 -229.589305) (xy 127.707136 -229.59187)
			(xy 127.707644 -229.592124) (xy 127.719321 -229.590469) (xy 127.742841 -229.588691) (xy 127.754634 -229.588568)
			(xy 127.779443 -229.589057) (xy 127.828448 -229.596824) (xy 127.875636 -229.612161) (xy 127.919843 -229.63469)
			(xy 127.959983 -229.663857) (xy 127.995066 -229.698943) (xy 128.024228 -229.739086) (xy 128.046752 -229.783296)
			(xy 128.062084 -229.830485) (xy 128.069845 -229.879491) (xy 128.069845 -229.90429) (xy 128.388884 -229.90429)
			(xy 128.392844 -229.855236) (xy 128.404621 -229.807452) (xy 128.423912 -229.762176) (xy 128.450215 -229.72058)
			(xy 128.48285 -229.683743) (xy 128.520971 -229.652618) (xy 128.563592 -229.628011) (xy 128.609608 -229.610559)
			(xy 128.657827 -229.600715) (xy 128.707002 -229.598734) (xy 128.755857 -229.604666) (xy 128.803128 -229.618358)
			(xy 128.84759 -229.639456) (xy 128.888093 -229.667412) (xy 128.923586 -229.701504) (xy 128.953151 -229.740848)
			(xy 128.976022 -229.784425) (xy 128.991606 -229.831106) (xy 128.999501 -229.879683) (xy 128.999996 -229.90429)
			(xy 129.318507 -229.90429) (xy 129.322602 -229.853562) (xy 129.334781 -229.804148) (xy 129.354729 -229.757328)
			(xy 129.38193 -229.714314) (xy 129.415678 -229.67622) (xy 129.4551 -229.644033) (xy 129.499174 -229.618587)
			(xy 129.54676 -229.60054) (xy 129.596624 -229.59036) (xy 129.647476 -229.588311) (xy 129.697997 -229.594445)
			(xy 129.746881 -229.608605) (xy 129.79286 -229.630422) (xy 129.834744 -229.659332) (xy 129.871448 -229.694587)
			(xy 129.902021 -229.735273) (xy 129.925672 -229.780336) (xy 129.941788 -229.82861) (xy 129.949952 -229.878844)
			(xy 129.950464 -229.90429) (xy 129.949952 -229.929736) (xy 129.941788 -229.97997) (xy 129.925672 -230.028244)
			(xy 129.902021 -230.073307) (xy 129.871448 -230.113993) (xy 129.834744 -230.149248) (xy 129.79286 -230.178158)
			(xy 129.746881 -230.199975) (xy 129.697997 -230.214135) (xy 129.647476 -230.220269) (xy 129.596624 -230.21822)
			(xy 129.54676 -230.20804) (xy 129.499174 -230.189993) (xy 129.4551 -230.164547) (xy 129.415678 -230.13236)
			(xy 129.38193 -230.094266) (xy 129.354729 -230.051252) (xy 129.334781 -230.004432) (xy 129.322602 -229.955018)
			(xy 129.318507 -229.90429) (xy 128.999996 -229.90429) (xy 128.999501 -229.928897) (xy 128.991606 -229.977474)
			(xy 128.976022 -230.024155) (xy 128.953151 -230.067732) (xy 128.923586 -230.107076) (xy 128.888093 -230.141168)
			(xy 128.84759 -230.169124) (xy 128.803128 -230.190222) (xy 128.755857 -230.203914) (xy 128.707002 -230.209846)
			(xy 128.657827 -230.207865) (xy 128.609608 -230.198021) (xy 128.563592 -230.180569) (xy 128.520971 -230.155962)
			(xy 128.48285 -230.124837) (xy 128.450215 -230.088) (xy 128.423912 -230.046404) (xy 128.404621 -230.001128)
			(xy 128.392844 -229.953344) (xy 128.388884 -229.90429) (xy 128.069845 -229.90429) (xy 128.069845 -229.929109)
			(xy 128.062084 -229.978115) (xy 128.046752 -230.025304) (xy 128.024228 -230.069514) (xy 127.995066 -230.109657)
			(xy 127.959983 -230.144743) (xy 127.919843 -230.17391) (xy 127.875636 -230.196439) (xy 127.828448 -230.211776)
			(xy 127.779443 -230.219543) (xy 127.754634 -230.220012) (xy 127.736037 -230.219698) (xy 127.69911 -230.215245)
			(xy 127.680974 -230.211122) (xy 127.672338 -230.213662) (xy 127.604774 -230.270812) (xy 127.596633 -230.2784)
			(xy 127.587265 -230.298559) (xy 127.58674 -230.309674) (xy 127.58674 -230.669592) (xy 127.587248 -230.673148)
			(xy 127.588551 -230.683385) (xy 127.58995 -230.703977) (xy 127.590042 -230.714296) (xy 127.590042 -230.71455)
			(xy 127.908553 -230.71455) (xy 127.912648 -230.663822) (xy 127.924827 -230.614408) (xy 127.944775 -230.567588)
			(xy 127.971976 -230.524574) (xy 128.005724 -230.48648) (xy 128.045146 -230.454293) (xy 128.08922 -230.428847)
			(xy 128.136806 -230.4108) (xy 128.18667 -230.40062) (xy 128.237522 -230.398571) (xy 128.288043 -230.404705)
			(xy 128.336927 -230.418865) (xy 128.382906 -230.440682) (xy 128.42479 -230.469592) (xy 128.461494 -230.504847)
			(xy 128.492067 -230.545533) (xy 128.515718 -230.590596) (xy 128.531834 -230.63887) (xy 128.539998 -230.689104)
			(xy 128.54051 -230.71455) (xy 128.848607 -230.71455) (xy 128.852702 -230.663822) (xy 128.864881 -230.614408)
			(xy 128.884829 -230.567588) (xy 128.91203 -230.524574) (xy 128.945778 -230.48648) (xy 128.9852 -230.454293)
			(xy 129.029274 -230.428847) (xy 129.07686 -230.4108) (xy 129.126724 -230.40062) (xy 129.177576 -230.398571)
			(xy 129.228097 -230.404705) (xy 129.276981 -230.418865) (xy 129.32296 -230.440682) (xy 129.364844 -230.469592)
			(xy 129.401548 -230.504847) (xy 129.432121 -230.545533) (xy 129.455772 -230.590596) (xy 129.471888 -230.63887)
			(xy 129.480052 -230.689104) (xy 129.480564 -230.71455) (xy 129.480052 -230.739996) (xy 129.471888 -230.79023)
			(xy 129.455772 -230.838504) (xy 129.432121 -230.883567) (xy 129.401548 -230.924253) (xy 129.364844 -230.959508)
			(xy 129.32296 -230.988418) (xy 129.276981 -231.010235) (xy 129.228097 -231.024395) (xy 129.177576 -231.030529)
			(xy 129.126724 -231.02848) (xy 129.07686 -231.0183) (xy 129.029274 -231.000253) (xy 128.9852 -230.974807)
			(xy 128.945778 -230.94262) (xy 128.91203 -230.904526) (xy 128.884829 -230.861512) (xy 128.864881 -230.814692)
			(xy 128.852702 -230.765278) (xy 128.848607 -230.71455) (xy 128.54051 -230.71455) (xy 128.539998 -230.739996)
			(xy 128.531834 -230.79023) (xy 128.515718 -230.838504) (xy 128.492067 -230.883567) (xy 128.461494 -230.924253)
			(xy 128.42479 -230.959508) (xy 128.382906 -230.988418) (xy 128.336927 -231.010235) (xy 128.288043 -231.024395)
			(xy 128.237522 -231.030529) (xy 128.18667 -231.02848) (xy 128.136806 -231.0183) (xy 128.08922 -231.000253)
			(xy 128.045146 -230.974807) (xy 128.005724 -230.94262) (xy 127.971976 -230.904526) (xy 127.944775 -230.861512)
			(xy 127.924827 -230.814692) (xy 127.912648 -230.765278) (xy 127.908553 -230.71455) (xy 127.590042 -230.71455)
			(xy 127.589957 -230.72487) (xy 127.588557 -230.745461) (xy 127.587248 -230.755698) (xy 127.58674 -230.759508)
			(xy 127.58674 -230.953818) (xy 127.586312 -230.963885) (xy 127.578586 -230.982479) (xy 127.571754 -230.989886)
			(xy 127.121666 -231.439974) (xy 127.1143 -231.463088) (xy 127.116078 -231.47528) (xy 127.117952 -231.48745)
			(xy 127.119988 -231.51199) (xy 127.120142 -231.524302) (xy 127.438399 -231.524302) (xy 127.442494 -231.473574)
			(xy 127.454673 -231.42416) (xy 127.474621 -231.37734) (xy 127.501822 -231.334326) (xy 127.53557 -231.296232)
			(xy 127.574992 -231.264045) (xy 127.619066 -231.238599) (xy 127.666652 -231.220552) (xy 127.716516 -231.210372)
			(xy 127.767368 -231.208323) (xy 127.817889 -231.214457) (xy 127.866773 -231.228617) (xy 127.912752 -231.250434)
			(xy 127.954636 -231.279344) (xy 127.99134 -231.314599) (xy 128.021913 -231.355285) (xy 128.045564 -231.400348)
			(xy 128.06168 -231.448622) (xy 128.069844 -231.498856) (xy 128.070356 -231.524302) (xy 128.388884 -231.524302)
			(xy 128.392844 -231.475248) (xy 128.404621 -231.427464) (xy 128.423912 -231.382188) (xy 128.450215 -231.340592)
			(xy 128.48285 -231.303755) (xy 128.520971 -231.27263) (xy 128.563592 -231.248023) (xy 128.609608 -231.230571)
			(xy 128.657827 -231.220727) (xy 128.707002 -231.218746) (xy 128.755857 -231.224678) (xy 128.803128 -231.23837)
			(xy 128.84759 -231.259468) (xy 128.888093 -231.287424) (xy 128.923586 -231.321516) (xy 128.953151 -231.36086)
			(xy 128.976022 -231.404437) (xy 128.991606 -231.451118) (xy 128.999501 -231.499695) (xy 128.999996 -231.524302)
			(xy 129.318507 -231.524302) (xy 129.322602 -231.473574) (xy 129.334781 -231.42416) (xy 129.354729 -231.37734)
			(xy 129.38193 -231.334326) (xy 129.415678 -231.296232) (xy 129.4551 -231.264045) (xy 129.499174 -231.238599)
			(xy 129.54676 -231.220552) (xy 129.596624 -231.210372) (xy 129.647476 -231.208323) (xy 129.697997 -231.214457)
			(xy 129.746881 -231.228617) (xy 129.79286 -231.250434) (xy 129.834744 -231.279344) (xy 129.871448 -231.314599)
			(xy 129.902021 -231.355285) (xy 129.925672 -231.400348) (xy 129.941788 -231.448622) (xy 129.949952 -231.498856)
			(xy 129.950464 -231.524302) (xy 129.949952 -231.549748) (xy 129.941788 -231.599982) (xy 129.925672 -231.648256)
			(xy 129.902021 -231.693319) (xy 129.871448 -231.734005) (xy 129.834744 -231.76926) (xy 129.79286 -231.79817)
			(xy 129.746881 -231.819987) (xy 129.697997 -231.834147) (xy 129.647476 -231.840281) (xy 129.596624 -231.838232)
			(xy 129.54676 -231.828052) (xy 129.499174 -231.810005) (xy 129.4551 -231.784559) (xy 129.415678 -231.752372)
			(xy 129.38193 -231.714278) (xy 129.354729 -231.671264) (xy 129.334781 -231.624444) (xy 129.322602 -231.57503)
			(xy 129.318507 -231.524302) (xy 128.999996 -231.524302) (xy 128.999501 -231.548909) (xy 128.991606 -231.597486)
			(xy 128.976022 -231.644167) (xy 128.953151 -231.687744) (xy 128.923586 -231.727088) (xy 128.888093 -231.76118)
			(xy 128.84759 -231.789136) (xy 128.803128 -231.810234) (xy 128.755857 -231.823926) (xy 128.707002 -231.829858)
			(xy 128.657827 -231.827877) (xy 128.609608 -231.818033) (xy 128.563592 -231.800581) (xy 128.520971 -231.775974)
			(xy 128.48285 -231.744849) (xy 128.450215 -231.708012) (xy 128.423912 -231.666416) (xy 128.404621 -231.62114)
			(xy 128.392844 -231.573356) (xy 128.388884 -231.524302) (xy 128.070356 -231.524302) (xy 128.069844 -231.549748)
			(xy 128.06168 -231.599982) (xy 128.045564 -231.648256) (xy 128.021913 -231.693319) (xy 127.99134 -231.734005)
			(xy 127.954636 -231.76926) (xy 127.912752 -231.79817) (xy 127.866773 -231.819987) (xy 127.817889 -231.834147)
			(xy 127.767368 -231.840281) (xy 127.716516 -231.838232) (xy 127.666652 -231.828052) (xy 127.619066 -231.810005)
			(xy 127.574992 -231.784559) (xy 127.53557 -231.752372) (xy 127.501822 -231.714278) (xy 127.474621 -231.671264)
			(xy 127.454673 -231.624444) (xy 127.442494 -231.57503) (xy 127.438399 -231.524302) (xy 127.120142 -231.524302)
			(xy 127.119671 -231.548294) (xy 127.112165 -231.595688) (xy 127.097338 -231.641323) (xy 127.075555 -231.684078)
			(xy 127.047352 -231.722899) (xy 127.013424 -231.756831) (xy 126.974606 -231.785038) (xy 126.931853 -231.806826)
			(xy 126.886219 -231.821658) (xy 126.838826 -231.829169) (xy 126.814834 -231.82961) (xy 126.802521 -231.82947)
			(xy 126.77798 -231.827436) (xy 126.765812 -231.825546) (xy 126.75362 -231.823768) (xy 126.730506 -231.831134)
			(xy 126.573534 -231.988106) (xy 126.566422 -231.995218) (xy 126.558802 -232.012998) (xy 126.55677 -232.103168)
			(xy 126.563628 -232.121202) (xy 126.570232 -232.128568) (xy 126.585154 -232.14553) (xy 126.610352 -232.183027)
			(xy 126.629752 -232.223826) (xy 126.64293 -232.267038) (xy 126.649598 -232.31172) (xy 126.649988 -232.334308)
			(xy 126.97893 -232.334308) (xy 126.98289 -232.285254) (xy 126.994667 -232.23747) (xy 127.013958 -232.192194)
			(xy 127.040261 -232.150598) (xy 127.072896 -232.113761) (xy 127.111017 -232.082636) (xy 127.153638 -232.058029)
			(xy 127.199654 -232.040577) (xy 127.247873 -232.030733) (xy 127.297048 -232.028752) (xy 127.345903 -232.034684)
			(xy 127.393174 -232.048376) (xy 127.437636 -232.069474) (xy 127.478139 -232.09743) (xy 127.513632 -232.131522)
			(xy 127.543197 -232.170866) (xy 127.566068 -232.214443) (xy 127.581652 -232.261124) (xy 127.589547 -232.309701)
			(xy 127.590042 -232.334308) (xy 127.908553 -232.334308) (xy 127.912648 -232.28358) (xy 127.924827 -232.234166)
			(xy 127.944775 -232.187346) (xy 127.971976 -232.144332) (xy 128.005724 -232.106238) (xy 128.045146 -232.074051)
			(xy 128.08922 -232.048605) (xy 128.136806 -232.030558) (xy 128.18667 -232.020378) (xy 128.237522 -232.018329)
			(xy 128.288043 -232.024463) (xy 128.336927 -232.038623) (xy 128.382906 -232.06044) (xy 128.42479 -232.08935)
			(xy 128.461494 -232.124605) (xy 128.492067 -232.165291) (xy 128.515718 -232.210354) (xy 128.531834 -232.258628)
			(xy 128.539998 -232.308862) (xy 128.54051 -232.334308) (xy 128.848607 -232.334308) (xy 128.852702 -232.28358)
			(xy 128.864881 -232.234166) (xy 128.884829 -232.187346) (xy 128.91203 -232.144332) (xy 128.945778 -232.106238)
			(xy 128.9852 -232.074051) (xy 129.029274 -232.048605) (xy 129.07686 -232.030558) (xy 129.126724 -232.020378)
			(xy 129.177576 -232.018329) (xy 129.228097 -232.024463) (xy 129.276981 -232.038623) (xy 129.32296 -232.06044)
			(xy 129.364844 -232.08935) (xy 129.401548 -232.124605) (xy 129.432121 -232.165291) (xy 129.455772 -232.210354)
			(xy 129.471888 -232.258628) (xy 129.480052 -232.308862) (xy 129.480564 -232.334308) (xy 129.480052 -232.359754)
			(xy 129.471888 -232.409988) (xy 129.455772 -232.458262) (xy 129.432121 -232.503325) (xy 129.401548 -232.544011)
			(xy 129.364844 -232.579266) (xy 129.32296 -232.608176) (xy 129.276981 -232.629993) (xy 129.228097 -232.644153)
			(xy 129.177576 -232.650287) (xy 129.126724 -232.648238) (xy 129.07686 -232.638058) (xy 129.029274 -232.620011)
			(xy 128.9852 -232.594565) (xy 128.945778 -232.562378) (xy 128.91203 -232.524284) (xy 128.884829 -232.48127)
			(xy 128.864881 -232.43445) (xy 128.852702 -232.385036) (xy 128.848607 -232.334308) (xy 128.54051 -232.334308)
			(xy 128.539998 -232.359754) (xy 128.531834 -232.409988) (xy 128.515718 -232.458262) (xy 128.492067 -232.503325)
			(xy 128.461494 -232.544011) (xy 128.42479 -232.579266) (xy 128.382906 -232.608176) (xy 128.336927 -232.629993)
			(xy 128.288043 -232.644153) (xy 128.237522 -232.650287) (xy 128.18667 -232.648238) (xy 128.136806 -232.638058)
			(xy 128.08922 -232.620011) (xy 128.045146 -232.594565) (xy 128.005724 -232.562378) (xy 127.971976 -232.524284)
			(xy 127.944775 -232.48127) (xy 127.924827 -232.43445) (xy 127.912648 -232.385036) (xy 127.908553 -232.334308)
			(xy 127.590042 -232.334308) (xy 127.589547 -232.358915) (xy 127.581652 -232.407492) (xy 127.566068 -232.454173)
			(xy 127.543197 -232.49775) (xy 127.513632 -232.537094) (xy 127.478139 -232.571186) (xy 127.437636 -232.599142)
			(xy 127.393174 -232.62024) (xy 127.345903 -232.633932) (xy 127.297048 -232.639864) (xy 127.247873 -232.637883)
			(xy 127.199654 -232.628039) (xy 127.153638 -232.610587) (xy 127.111017 -232.58598) (xy 127.072896 -232.554855)
			(xy 127.040261 -232.518018) (xy 127.013958 -232.476422) (xy 126.994667 -232.431146) (xy 126.98289 -232.383362)
			(xy 126.97893 -232.334308) (xy 126.649988 -232.334308) (xy 126.649541 -232.3583) (xy 126.642033 -232.405694)
			(xy 126.627204 -232.451329) (xy 126.605418 -232.494082) (xy 126.577212 -232.532901) (xy 126.54328 -232.56683)
			(xy 126.504458 -232.595032) (xy 126.461703 -232.616815) (xy 126.416066 -232.63164) (xy 126.368672 -232.639143)
			(xy 126.34468 -232.639616) (xy 126.331917 -232.639478) (xy 126.306483 -232.637317) (xy 126.29388 -232.635298)
			(xy 126.29388 -232.635552) (xy 126.270231 -232.63111) (xy 126.224625 -232.615772) (xy 126.181989 -232.593471)
			(xy 126.143379 -232.564757) (xy 126.109751 -232.530343) (xy 126.081938 -232.491079) (xy 126.060628 -232.447939)
			(xy 126.04635 -232.40199) (xy 126.04242 -232.37825) (xy 126.040739 -232.368595) (xy 126.031198 -232.351494)
			(xy 126.023878 -232.344976) (xy 125.969522 -232.301542) (xy 125.965725 -232.298644) (xy 125.957285 -232.294177)
			(xy 125.952758 -232.292652) (xy 125.944122 -232.289858) (xy 125.90399 -232.292398) (xy 125.903736 -232.292398)
			(xy 125.87478 -232.29316) (xy 125.739906 -232.29316) (xy 125.710442 -232.321862) (xy 125.709934 -232.34269)
			(xy 125.708768 -232.367492) (xy 125.699396 -232.416248) (xy 125.682261 -232.462846) (xy 125.657815 -232.50606)
			(xy 125.626701 -232.54475) (xy 125.58974 -232.577898) (xy 125.547903 -232.604632) (xy 125.502293 -232.624247)
			(xy 125.454111 -232.636226) (xy 125.404626 -232.640255) (xy 125.355141 -232.636226) (xy 125.306959 -232.624247)
			(xy 125.261349 -232.604632) (xy 125.219512 -232.577898) (xy 125.182551 -232.54475) (xy 125.151437 -232.50606)
			(xy 125.126991 -232.462846) (xy 125.109856 -232.416248) (xy 125.100484 -232.367492) (xy 125.099318 -232.34269)
			(xy 125.09881 -232.321862) (xy 125.069346 -232.29316) (xy 124.934726 -232.29316) (xy 124.90577 -232.292398)
			(xy 124.905516 -232.292398) (xy 124.875036 -232.29062) (xy 124.870211 -232.290398) (xy 124.860623 -232.291552)
			(xy 124.855986 -232.292906) (xy 124.847604 -232.295446) (xy 124.778008 -232.351072) (xy 124.76861 -232.367836)
			(xy 124.767086 -232.377488) (xy 124.763193 -232.401427) (xy 124.748826 -232.447749) (xy 124.727316 -232.491216)
			(xy 124.699203 -232.530736) (xy 124.665195 -232.565313) (xy 124.626147 -232.594077) (xy 124.583043 -232.616306)
			(xy 124.536966 -232.631439) (xy 124.489075 -232.639096) (xy 124.464826 -232.639616) (xy 124.440831 -232.639172)
			(xy 124.393432 -232.631668) (xy 124.347791 -232.616842) (xy 124.30503 -232.595058) (xy 124.266204 -232.566853)
			(xy 124.232269 -232.532922) (xy 124.204059 -232.494099) (xy 124.182271 -232.451341) (xy 124.16744 -232.405701)
			(xy 124.159931 -232.358303) (xy 124.159518 -232.334308) (xy 124.160187 -232.305709) (xy 124.170869 -232.249517)
			(xy 124.191807 -232.196288) (xy 124.206508 -232.171748) (xy 124.215906 -232.156508) (xy 124.212096 -232.121456)
			(xy 124.007626 -231.916986) (xy 124.000779 -231.909588) (xy 123.993046 -231.89099) (xy 123.99264 -231.880918)
			(xy 123.99264 -231.85755) (xy 123.968256 -231.829102) (xy 123.94946 -231.826308) (xy 123.925653 -231.822279)
			(xy 123.879625 -231.807702) (xy 123.836464 -231.786064) (xy 123.797246 -231.757904) (xy 123.762947 -231.723923)
			(xy 123.734422 -231.684969) (xy 123.712383 -231.642011) (xy 123.697377 -231.596121) (xy 123.68978 -231.548441)
			(xy 123.68978 -231.50016) (xy 123.697377 -231.45248) (xy 123.712383 -231.406589) (xy 123.734422 -231.363632)
			(xy 123.762946 -231.324677) (xy 123.797245 -231.290697) (xy 123.836464 -231.262536) (xy 123.879625 -231.240898)
			(xy 123.925653 -231.226321) (xy 123.94946 -231.222296) (xy 123.968256 -231.219502) (xy 123.99264 -231.191054)
			(xy 123.99264 -230.808022) (xy 123.992201 -230.797959) (xy 123.98446 -230.779381) (xy 123.977654 -230.771954)
			(xy 123.700286 -230.494586) (xy 123.693174 -230.48722) (xy 123.674378 -230.4796) (xy 123.574302 -230.4796)
			(xy 123.557792 -230.485696) (xy 123.55068 -230.491538) (xy 123.520966 -230.516037) (xy 123.457469 -230.559622)
			(xy 123.389931 -230.596637) (xy 123.319029 -230.626713) (xy 123.245475 -230.649548) (xy 123.170007 -230.664912)
			(xy 123.09338 -230.672651) (xy 123.054872 -230.673148) (xy 122.75693 -230.673148) (xy 122.716878 -230.67259)
			(xy 122.637214 -230.664188) (xy 122.597926 -230.656384) (xy 122.595386 -230.655876) (xy 122.584718 -230.65486)
			(xy 122.574304 -230.655876) (xy 122.571764 -230.656384) (xy 122.532478 -230.664206) (xy 122.452813 -230.672611)
			(xy 122.41276 -230.673148) (xy 122.114818 -230.673148) (xy 122.083322 -230.672386) (xy 122.083068 -230.672386)
			(xy 122.054874 -230.670608) (xy 122.050048 -230.670382) (xy 122.040458 -230.671529) (xy 122.035824 -230.672894)
			(xy 122.027442 -230.675434) (xy 121.957846 -230.73106) (xy 121.948448 -230.747824) (xy 121.946924 -230.757476)
			(xy 121.943047 -230.781432) (xy 121.928705 -230.827789) (xy 121.907212 -230.871296) (xy 121.87911 -230.910855)
			(xy 121.845104 -230.945473) (xy 121.806051 -230.974276) (xy 121.762935 -230.996541) (xy 121.71684 -231.011706)
			(xy 121.668927 -231.019391) (xy 121.644664 -231.019858) (xy 121.620863 -231.0194) (xy 121.57384 -231.012008)
			(xy 121.528532 -230.997408) (xy 121.486039 -230.975955) (xy 121.44739 -230.948168) (xy 121.413521 -230.91472)
			(xy 121.385252 -230.876422) (xy 121.363269 -230.834201) (xy 121.348103 -230.78908) (xy 121.340123 -230.742153)
			(xy 121.339356 -230.71836) (xy 121.339356 -230.714296) (xy 121.339881 -230.688921) (xy 121.348308 -230.638876)
			(xy 121.35612 -230.614728) (xy 121.35612 -230.61422) (xy 121.359408 -230.602534) (xy 121.355955 -230.578539)
			(xy 121.349516 -230.568246) (xy 121.30151 -230.500936) (xy 121.293894 -230.491429) (xy 121.27227 -230.480295)
			(xy 121.260108 -230.4796) (xy 120.763538 -230.4796) (xy 120.754618 -230.479995) (xy 120.737856 -230.486103)
			(xy 120.730772 -230.491538) (xy 120.701058 -230.516037) (xy 120.63756 -230.559621) (xy 120.570022 -230.596636)
			(xy 120.499121 -230.626711) (xy 120.425567 -230.649545) (xy 120.350099 -230.664908) (xy 120.273472 -230.672646)
			(xy 120.234964 -230.673148) (xy 119.936768 -230.673148) (xy 119.896716 -230.672592) (xy 119.817051 -230.664194)
			(xy 119.777764 -230.656384) (xy 119.775224 -230.655876) (xy 119.764556 -230.65486) (xy 119.754142 -230.655876)
			(xy 119.751602 -230.656384) (xy 119.712316 -230.664203) (xy 119.632651 -230.672601) (xy 119.592598 -230.673148)
			(xy 119.294656 -230.673148) (xy 119.2657 -230.672386) (xy 119.265446 -230.672386) (xy 119.234966 -230.670608)
			(xy 119.230141 -230.670383) (xy 119.22055 -230.671532) (xy 119.215916 -230.672894) (xy 119.207534 -230.675434)
			(xy 119.137938 -230.73106) (xy 119.12854 -230.747824) (xy 119.127016 -230.757476) (xy 119.123139 -230.781431)
			(xy 119.108797 -230.827789) (xy 119.087304 -230.871294) (xy 119.059201 -230.910853) (xy 119.025195 -230.94547)
			(xy 118.986143 -230.974272) (xy 118.943026 -230.996536) (xy 118.896931 -231.0117) (xy 118.849018 -231.019384)
			(xy 118.824756 -231.019858) (xy 118.800956 -231.019399) (xy 118.753933 -231.012006) (xy 118.708627 -230.997406)
			(xy 118.666135 -230.975952) (xy 118.627487 -230.948165) (xy 118.593619 -230.914718) (xy 118.565351 -230.87642)
			(xy 118.543368 -230.834199) (xy 118.528203 -230.789079) (xy 118.520223 -230.742152) (xy 118.519448 -230.71836)
			(xy 118.519448 -230.714296) (xy 118.519973 -230.688921) (xy 118.528399 -230.638876) (xy 118.536212 -230.614728)
			(xy 118.536212 -230.61422) (xy 118.5395 -230.602534) (xy 118.536046 -230.578539) (xy 118.529608 -230.568246)
			(xy 118.481602 -230.500936) (xy 118.473986 -230.491431) (xy 118.452362 -230.480299) (xy 118.4402 -230.4796)
			(xy 117.94363 -230.4796) (xy 117.934711 -230.479997) (xy 117.91795 -230.486106) (xy 117.910864 -230.491538)
			(xy 117.88115 -230.516036) (xy 117.817652 -230.55962) (xy 117.750114 -230.596634) (xy 117.679212 -230.626709)
			(xy 117.605659 -230.649541) (xy 117.53019 -230.664904) (xy 117.453564 -230.672642) (xy 117.415056 -230.673148)
			(xy 117.11686 -230.673148) (xy 117.076808 -230.672592) (xy 116.997144 -230.664193) (xy 116.957856 -230.656384)
			(xy 116.955316 -230.655876) (xy 116.944648 -230.65486) (xy 116.934234 -230.655876) (xy 116.931694 -230.656384)
			(xy 116.892408 -230.664203) (xy 116.812743 -230.6726) (xy 116.77269 -230.673148) (xy 116.504974 -230.673148)
			(xy 116.49501 -230.673628) (xy 116.476579 -230.681211) (xy 116.46916 -230.68788) (xy 115.882166 -231.274874)
			(xy 115.877149 -231.279607) (xy 115.865175 -231.28644) (xy 115.858544 -231.288336) (xy 115.848384 -231.290876)
			(xy 115.832128 -231.303322) (xy 115.81003 -231.342184) (xy 115.804476 -231.353343) (xy 115.803826 -231.378233)
			(xy 115.80876 -231.389682) (xy 115.818609 -231.410742) (xy 115.832524 -231.455101) (xy 115.839556 -231.501057)
			(xy 115.840002 -231.524302) (xy 116.168944 -231.524302) (xy 116.172904 -231.475248) (xy 116.184681 -231.427464)
			(xy 116.203972 -231.382188) (xy 116.230275 -231.340592) (xy 116.26291 -231.303755) (xy 116.301031 -231.27263)
			(xy 116.343652 -231.248023) (xy 116.389668 -231.230571) (xy 116.437887 -231.220727) (xy 116.487062 -231.218746)
			(xy 116.535917 -231.224678) (xy 116.583188 -231.23837) (xy 116.62765 -231.259468) (xy 116.668153 -231.287424)
			(xy 116.703646 -231.321516) (xy 116.733211 -231.36086) (xy 116.756082 -231.404437) (xy 116.771666 -231.451118)
			(xy 116.779561 -231.499695) (xy 116.780056 -231.524302) (xy 117.108998 -231.524302) (xy 117.112958 -231.475248)
			(xy 117.124735 -231.427464) (xy 117.144026 -231.382188) (xy 117.170329 -231.340592) (xy 117.202964 -231.303755)
			(xy 117.241085 -231.27263) (xy 117.283706 -231.248023) (xy 117.329722 -231.230571) (xy 117.377941 -231.220727)
			(xy 117.427116 -231.218746) (xy 117.475971 -231.224678) (xy 117.523242 -231.23837) (xy 117.567704 -231.259468)
			(xy 117.608207 -231.287424) (xy 117.6437 -231.321516) (xy 117.673265 -231.36086) (xy 117.696136 -231.404437)
			(xy 117.71172 -231.451118) (xy 117.719615 -231.499695) (xy 117.72011 -231.524302) (xy 118.049052 -231.524302)
			(xy 118.053012 -231.475248) (xy 118.064789 -231.427464) (xy 118.08408 -231.382188) (xy 118.110383 -231.340592)
			(xy 118.143018 -231.303755) (xy 118.181139 -231.27263) (xy 118.22376 -231.248023) (xy 118.269776 -231.230571)
			(xy 118.317995 -231.220727) (xy 118.36717 -231.218746) (xy 118.416025 -231.224678) (xy 118.463296 -231.23837)
			(xy 118.507758 -231.259468) (xy 118.548261 -231.287424) (xy 118.583754 -231.321516) (xy 118.613319 -231.36086)
			(xy 118.63619 -231.404437) (xy 118.651774 -231.451118) (xy 118.659669 -231.499695) (xy 118.660164 -231.524302)
			(xy 118.988852 -231.524302) (xy 118.992812 -231.475248) (xy 119.004589 -231.427464) (xy 119.02388 -231.382188)
			(xy 119.050183 -231.340592) (xy 119.082818 -231.303755) (xy 119.120939 -231.27263) (xy 119.16356 -231.248023)
			(xy 119.209576 -231.230571) (xy 119.257795 -231.220727) (xy 119.30697 -231.218746) (xy 119.355825 -231.224678)
			(xy 119.403096 -231.23837) (xy 119.447558 -231.259468) (xy 119.488061 -231.287424) (xy 119.523554 -231.321516)
			(xy 119.553119 -231.36086) (xy 119.57599 -231.404437) (xy 119.591574 -231.451118) (xy 119.599469 -231.499695)
			(xy 119.599964 -231.524302) (xy 119.928906 -231.524302) (xy 119.932866 -231.475248) (xy 119.944643 -231.427464)
			(xy 119.963934 -231.382188) (xy 119.990237 -231.340592) (xy 120.022872 -231.303755) (xy 120.060993 -231.27263)
			(xy 120.103614 -231.248023) (xy 120.14963 -231.230571) (xy 120.197849 -231.220727) (xy 120.247024 -231.218746)
			(xy 120.295879 -231.224678) (xy 120.34315 -231.23837) (xy 120.387612 -231.259468) (xy 120.428115 -231.287424)
			(xy 120.463608 -231.321516) (xy 120.493173 -231.36086) (xy 120.516044 -231.404437) (xy 120.531628 -231.451118)
			(xy 120.539523 -231.499695) (xy 120.540018 -231.524302) (xy 120.86896 -231.524302) (xy 120.87292 -231.475248)
			(xy 120.884697 -231.427464) (xy 120.903988 -231.382188) (xy 120.930291 -231.340592) (xy 120.962926 -231.303755)
			(xy 121.001047 -231.27263) (xy 121.043668 -231.248023) (xy 121.089684 -231.230571) (xy 121.137903 -231.220727)
			(xy 121.187078 -231.218746) (xy 121.235933 -231.224678) (xy 121.283204 -231.23837) (xy 121.327666 -231.259468)
			(xy 121.368169 -231.287424) (xy 121.403662 -231.321516) (xy 121.433227 -231.36086) (xy 121.456098 -231.404437)
			(xy 121.471682 -231.451118) (xy 121.479577 -231.499695) (xy 121.480072 -231.524302) (xy 121.809014 -231.524302)
			(xy 121.812974 -231.475248) (xy 121.824751 -231.427464) (xy 121.844042 -231.382188) (xy 121.870345 -231.340592)
			(xy 121.90298 -231.303755) (xy 121.941101 -231.27263) (xy 121.983722 -231.248023) (xy 122.029738 -231.230571)
			(xy 122.077957 -231.220727) (xy 122.127132 -231.218746) (xy 122.175987 -231.224678) (xy 122.223258 -231.23837)
			(xy 122.26772 -231.259468) (xy 122.308223 -231.287424) (xy 122.343716 -231.321516) (xy 122.373281 -231.36086)
			(xy 122.396152 -231.404437) (xy 122.411736 -231.451118) (xy 122.419631 -231.499695) (xy 122.420126 -231.524302)
			(xy 122.748814 -231.524302) (xy 122.752774 -231.475248) (xy 122.764551 -231.427464) (xy 122.783842 -231.382188)
			(xy 122.810145 -231.340592) (xy 122.84278 -231.303755) (xy 122.880901 -231.27263) (xy 122.923522 -231.248023)
			(xy 122.969538 -231.230571) (xy 123.017757 -231.220727) (xy 123.066932 -231.218746) (xy 123.115787 -231.224678)
			(xy 123.163058 -231.23837) (xy 123.20752 -231.259468) (xy 123.248023 -231.287424) (xy 123.283516 -231.321516)
			(xy 123.313081 -231.36086) (xy 123.335952 -231.404437) (xy 123.351536 -231.451118) (xy 123.359431 -231.499695)
			(xy 123.359926 -231.524302) (xy 123.359431 -231.548909) (xy 123.351536 -231.597486) (xy 123.335952 -231.644167)
			(xy 123.313081 -231.687744) (xy 123.283516 -231.727088) (xy 123.248023 -231.76118) (xy 123.20752 -231.789136)
			(xy 123.163058 -231.810234) (xy 123.115787 -231.823926) (xy 123.066932 -231.829858) (xy 123.017757 -231.827877)
			(xy 122.969538 -231.818033) (xy 122.923522 -231.800581) (xy 122.880901 -231.775974) (xy 122.84278 -231.744849)
			(xy 122.810145 -231.708012) (xy 122.783842 -231.666416) (xy 122.764551 -231.62114) (xy 122.752774 -231.573356)
			(xy 122.748814 -231.524302) (xy 122.420126 -231.524302) (xy 122.419631 -231.548909) (xy 122.411736 -231.597486)
			(xy 122.396152 -231.644167) (xy 122.373281 -231.687744) (xy 122.343716 -231.727088) (xy 122.308223 -231.76118)
			(xy 122.26772 -231.789136) (xy 122.223258 -231.810234) (xy 122.175987 -231.823926) (xy 122.127132 -231.829858)
			(xy 122.077957 -231.827877) (xy 122.029738 -231.818033) (xy 121.983722 -231.800581) (xy 121.941101 -231.775974)
			(xy 121.90298 -231.744849) (xy 121.870345 -231.708012) (xy 121.844042 -231.666416) (xy 121.824751 -231.62114)
			(xy 121.812974 -231.573356) (xy 121.809014 -231.524302) (xy 121.480072 -231.524302) (xy 121.479577 -231.548909)
			(xy 121.471682 -231.597486) (xy 121.456098 -231.644167) (xy 121.433227 -231.687744) (xy 121.403662 -231.727088)
			(xy 121.368169 -231.76118) (xy 121.327666 -231.789136) (xy 121.283204 -231.810234) (xy 121.235933 -231.823926)
			(xy 121.187078 -231.829858) (xy 121.137903 -231.827877) (xy 121.089684 -231.818033) (xy 121.043668 -231.800581)
			(xy 121.001047 -231.775974) (xy 120.962926 -231.744849) (xy 120.930291 -231.708012) (xy 120.903988 -231.666416)
			(xy 120.884697 -231.62114) (xy 120.87292 -231.573356) (xy 120.86896 -231.524302) (xy 120.540018 -231.524302)
			(xy 120.539523 -231.548909) (xy 120.531628 -231.597486) (xy 120.516044 -231.644167) (xy 120.493173 -231.687744)
			(xy 120.463608 -231.727088) (xy 120.428115 -231.76118) (xy 120.387612 -231.789136) (xy 120.34315 -231.810234)
			(xy 120.295879 -231.823926) (xy 120.247024 -231.829858) (xy 120.197849 -231.827877) (xy 120.14963 -231.818033)
			(xy 120.103614 -231.800581) (xy 120.060993 -231.775974) (xy 120.022872 -231.744849) (xy 119.990237 -231.708012)
			(xy 119.963934 -231.666416) (xy 119.944643 -231.62114) (xy 119.932866 -231.573356) (xy 119.928906 -231.524302)
			(xy 119.599964 -231.524302) (xy 119.599469 -231.548909) (xy 119.591574 -231.597486) (xy 119.57599 -231.644167)
			(xy 119.553119 -231.687744) (xy 119.523554 -231.727088) (xy 119.488061 -231.76118) (xy 119.447558 -231.789136)
			(xy 119.403096 -231.810234) (xy 119.355825 -231.823926) (xy 119.30697 -231.829858) (xy 119.257795 -231.827877)
			(xy 119.209576 -231.818033) (xy 119.16356 -231.800581) (xy 119.120939 -231.775974) (xy 119.082818 -231.744849)
			(xy 119.050183 -231.708012) (xy 119.02388 -231.666416) (xy 119.004589 -231.62114) (xy 118.992812 -231.573356)
			(xy 118.988852 -231.524302) (xy 118.660164 -231.524302) (xy 118.659669 -231.548909) (xy 118.651774 -231.597486)
			(xy 118.63619 -231.644167) (xy 118.613319 -231.687744) (xy 118.583754 -231.727088) (xy 118.548261 -231.76118)
			(xy 118.507758 -231.789136) (xy 118.463296 -231.810234) (xy 118.416025 -231.823926) (xy 118.36717 -231.829858)
			(xy 118.317995 -231.827877) (xy 118.269776 -231.818033) (xy 118.22376 -231.800581) (xy 118.181139 -231.775974)
			(xy 118.143018 -231.744849) (xy 118.110383 -231.708012) (xy 118.08408 -231.666416) (xy 118.064789 -231.62114)
			(xy 118.053012 -231.573356) (xy 118.049052 -231.524302) (xy 117.72011 -231.524302) (xy 117.719615 -231.548909)
			(xy 117.71172 -231.597486) (xy 117.696136 -231.644167) (xy 117.673265 -231.687744) (xy 117.6437 -231.727088)
			(xy 117.608207 -231.76118) (xy 117.567704 -231.789136) (xy 117.523242 -231.810234) (xy 117.475971 -231.823926)
			(xy 117.427116 -231.829858) (xy 117.377941 -231.827877) (xy 117.329722 -231.818033) (xy 117.283706 -231.800581)
			(xy 117.241085 -231.775974) (xy 117.202964 -231.744849) (xy 117.170329 -231.708012) (xy 117.144026 -231.666416)
			(xy 117.124735 -231.62114) (xy 117.112958 -231.573356) (xy 117.108998 -231.524302) (xy 116.780056 -231.524302)
			(xy 116.779561 -231.548909) (xy 116.771666 -231.597486) (xy 116.756082 -231.644167) (xy 116.733211 -231.687744)
			(xy 116.703646 -231.727088) (xy 116.668153 -231.76118) (xy 116.62765 -231.789136) (xy 116.583188 -231.810234)
			(xy 116.535917 -231.823926) (xy 116.487062 -231.829858) (xy 116.437887 -231.827877) (xy 116.389668 -231.818033)
			(xy 116.343652 -231.800581) (xy 116.301031 -231.775974) (xy 116.26291 -231.744849) (xy 116.230275 -231.708012)
			(xy 116.203972 -231.666416) (xy 116.184681 -231.62114) (xy 116.172904 -231.573356) (xy 116.168944 -231.524302)
			(xy 115.840002 -231.524302) (xy 115.839556 -231.548295) (xy 115.832049 -231.59569) (xy 115.81722 -231.641327)
			(xy 115.795434 -231.684082) (xy 115.767229 -231.722903) (xy 115.733297 -231.756834) (xy 115.694475 -231.785038)
			(xy 115.651719 -231.806823) (xy 115.606082 -231.821651) (xy 115.558687 -231.829156) (xy 115.534694 -231.82961)
			(xy 115.521931 -231.829473) (xy 115.496497 -231.827313) (xy 115.483894 -231.825292) (xy 115.483894 -231.825546)
			(xy 115.460262 -231.821104) (xy 115.414688 -231.805774) (xy 115.372079 -231.783492) (xy 115.333489 -231.754808)
			(xy 115.299869 -231.720432) (xy 115.272052 -231.681212) (xy 115.250724 -231.638118) (xy 115.236413 -231.592214)
			(xy 115.232434 -231.568498) (xy 115.232434 -231.568244) (xy 115.230725 -231.558653) (xy 115.221183 -231.541687)
			(xy 115.213892 -231.535224) (xy 115.15979 -231.49179) (xy 115.155923 -231.488891) (xy 115.147361 -231.484413)
			(xy 115.142772 -231.4829) (xy 115.134136 -231.480106) (xy 115.096544 -231.482646) (xy 115.09629 -231.482646)
			(xy 115.064794 -231.483408) (xy 114.766852 -231.483408) (xy 114.7268 -231.482851) (xy 114.647136 -231.474451)
			(xy 114.607848 -231.466644) (xy 114.605308 -231.466136) (xy 114.59464 -231.46512) (xy 114.584226 -231.466136)
			(xy 114.581686 -231.466644) (xy 114.5424 -231.474462) (xy 114.462735 -231.482858) (xy 114.422682 -231.483408)
			(xy 114.124486 -231.483408) (xy 114.085978 -231.482912) (xy 114.009353 -231.475163) (xy 113.933885 -231.459795)
			(xy 113.860332 -231.436961) (xy 113.789429 -231.406889) (xy 113.721887 -231.369882) (xy 113.658382 -231.326309)
			(xy 113.628678 -231.301798) (xy 113.621632 -231.296293) (xy 113.604848 -231.290159) (xy 113.595912 -231.28986)
			(xy 112.111282 -231.28986) (xy 112.101215 -231.290288) (xy 112.082621 -231.298014) (xy 112.075214 -231.304846)
			(xy 111.907066 -231.472994) (xy 111.8997 -231.480106) (xy 111.89208 -231.498902) (xy 111.89208 -232.334308)
			(xy 112.878882 -232.334308) (xy 112.882842 -232.285254) (xy 112.894619 -232.23747) (xy 112.91391 -232.192194)
			(xy 112.940213 -232.150598) (xy 112.972848 -232.113761) (xy 113.010969 -232.082636) (xy 113.05359 -232.058029)
			(xy 113.099606 -232.040577) (xy 113.147825 -232.030733) (xy 113.197 -232.028752) (xy 113.245855 -232.034684)
			(xy 113.293126 -232.048376) (xy 113.337588 -232.069474) (xy 113.378091 -232.09743) (xy 113.413584 -232.131522)
			(xy 113.443149 -232.170866) (xy 113.46602 -232.214443) (xy 113.481604 -232.261124) (xy 113.489499 -232.309701)
			(xy 113.489994 -232.334308) (xy 113.818936 -232.334308) (xy 113.822896 -232.285254) (xy 113.834673 -232.23747)
			(xy 113.853964 -232.192194) (xy 113.880267 -232.150598) (xy 113.912902 -232.113761) (xy 113.951023 -232.082636)
			(xy 113.993644 -232.058029) (xy 114.03966 -232.040577) (xy 114.087879 -232.030733) (xy 114.137054 -232.028752)
			(xy 114.185909 -232.034684) (xy 114.23318 -232.048376) (xy 114.277642 -232.069474) (xy 114.318145 -232.09743)
			(xy 114.353638 -232.131522) (xy 114.383203 -232.170866) (xy 114.406074 -232.214443) (xy 114.421658 -232.261124)
			(xy 114.429553 -232.309701) (xy 114.430048 -232.334308) (xy 114.75899 -232.334308) (xy 114.76295 -232.285254)
			(xy 114.774727 -232.23747) (xy 114.794018 -232.192194) (xy 114.820321 -232.150598) (xy 114.852956 -232.113761)
			(xy 114.891077 -232.082636) (xy 114.933698 -232.058029) (xy 114.979714 -232.040577) (xy 115.027933 -232.030733)
			(xy 115.077108 -232.028752) (xy 115.125963 -232.034684) (xy 115.173234 -232.048376) (xy 115.217696 -232.069474)
			(xy 115.258199 -232.09743) (xy 115.293692 -232.131522) (xy 115.323257 -232.170866) (xy 115.346128 -232.214443)
			(xy 115.361712 -232.261124) (xy 115.369607 -232.309701) (xy 115.370102 -232.334308) (xy 115.699044 -232.334308)
			(xy 115.703004 -232.285254) (xy 115.714781 -232.23747) (xy 115.734072 -232.192194) (xy 115.760375 -232.150598)
			(xy 115.79301 -232.113761) (xy 115.831131 -232.082636) (xy 115.873752 -232.058029) (xy 115.919768 -232.040577)
			(xy 115.967987 -232.030733) (xy 116.017162 -232.028752) (xy 116.066017 -232.034684) (xy 116.113288 -232.048376)
			(xy 116.15775 -232.069474) (xy 116.198253 -232.09743) (xy 116.233746 -232.131522) (xy 116.263311 -232.170866)
			(xy 116.286182 -232.214443) (xy 116.301766 -232.261124) (xy 116.309661 -232.309701) (xy 116.310156 -232.334308)
			(xy 116.638844 -232.334308) (xy 116.642804 -232.285254) (xy 116.654581 -232.23747) (xy 116.673872 -232.192194)
			(xy 116.700175 -232.150598) (xy 116.73281 -232.113761) (xy 116.770931 -232.082636) (xy 116.813552 -232.058029)
			(xy 116.859568 -232.040577) (xy 116.907787 -232.030733) (xy 116.956962 -232.028752) (xy 117.005817 -232.034684)
			(xy 117.053088 -232.048376) (xy 117.09755 -232.069474) (xy 117.138053 -232.09743) (xy 117.173546 -232.131522)
			(xy 117.203111 -232.170866) (xy 117.225982 -232.214443) (xy 117.241566 -232.261124) (xy 117.249461 -232.309701)
			(xy 117.249956 -232.334308) (xy 117.578898 -232.334308) (xy 117.582858 -232.285254) (xy 117.594635 -232.23747)
			(xy 117.613926 -232.192194) (xy 117.640229 -232.150598) (xy 117.672864 -232.113761) (xy 117.710985 -232.082636)
			(xy 117.753606 -232.058029) (xy 117.799622 -232.040577) (xy 117.847841 -232.030733) (xy 117.897016 -232.028752)
			(xy 117.945871 -232.034684) (xy 117.993142 -232.048376) (xy 118.037604 -232.069474) (xy 118.078107 -232.09743)
			(xy 118.1136 -232.131522) (xy 118.143165 -232.170866) (xy 118.166036 -232.214443) (xy 118.18162 -232.261124)
			(xy 118.189515 -232.309701) (xy 118.19001 -232.334308) (xy 118.518952 -232.334308) (xy 118.522912 -232.285254)
			(xy 118.534689 -232.23747) (xy 118.55398 -232.192194) (xy 118.580283 -232.150598) (xy 118.612918 -232.113761)
			(xy 118.651039 -232.082636) (xy 118.69366 -232.058029) (xy 118.739676 -232.040577) (xy 118.787895 -232.030733)
			(xy 118.83707 -232.028752) (xy 118.885925 -232.034684) (xy 118.933196 -232.048376) (xy 118.977658 -232.069474)
			(xy 119.018161 -232.09743) (xy 119.053654 -232.131522) (xy 119.083219 -232.170866) (xy 119.10609 -232.214443)
			(xy 119.121674 -232.261124) (xy 119.129569 -232.309701) (xy 119.130064 -232.334308) (xy 119.459006 -232.334308)
			(xy 119.462966 -232.285254) (xy 119.474743 -232.23747) (xy 119.494034 -232.192194) (xy 119.520337 -232.150598)
			(xy 119.552972 -232.113761) (xy 119.591093 -232.082636) (xy 119.633714 -232.058029) (xy 119.67973 -232.040577)
			(xy 119.727949 -232.030733) (xy 119.777124 -232.028752) (xy 119.825979 -232.034684) (xy 119.87325 -232.048376)
			(xy 119.917712 -232.069474) (xy 119.958215 -232.09743) (xy 119.993708 -232.131522) (xy 120.023273 -232.170866)
			(xy 120.046144 -232.214443) (xy 120.061728 -232.261124) (xy 120.069623 -232.309701) (xy 120.070118 -232.334308)
			(xy 120.398806 -232.334308) (xy 120.402766 -232.285254) (xy 120.414543 -232.23747) (xy 120.433834 -232.192194)
			(xy 120.460137 -232.150598) (xy 120.492772 -232.113761) (xy 120.530893 -232.082636) (xy 120.573514 -232.058029)
			(xy 120.61953 -232.040577) (xy 120.667749 -232.030733) (xy 120.716924 -232.028752) (xy 120.765779 -232.034684)
			(xy 120.81305 -232.048376) (xy 120.857512 -232.069474) (xy 120.898015 -232.09743) (xy 120.933508 -232.131522)
			(xy 120.963073 -232.170866) (xy 120.985944 -232.214443) (xy 121.001528 -232.261124) (xy 121.009423 -232.309701)
			(xy 121.009918 -232.334308) (xy 121.33886 -232.334308) (xy 121.34282 -232.285254) (xy 121.354597 -232.23747)
			(xy 121.373888 -232.192194) (xy 121.400191 -232.150598) (xy 121.432826 -232.113761) (xy 121.470947 -232.082636)
			(xy 121.513568 -232.058029) (xy 121.559584 -232.040577) (xy 121.607803 -232.030733) (xy 121.656978 -232.028752)
			(xy 121.705833 -232.034684) (xy 121.753104 -232.048376) (xy 121.797566 -232.069474) (xy 121.838069 -232.09743)
			(xy 121.873562 -232.131522) (xy 121.903127 -232.170866) (xy 121.925998 -232.214443) (xy 121.941582 -232.261124)
			(xy 121.949477 -232.309701) (xy 121.949972 -232.334308) (xy 122.278914 -232.334308) (xy 122.282874 -232.285254)
			(xy 122.294651 -232.23747) (xy 122.313942 -232.192194) (xy 122.340245 -232.150598) (xy 122.37288 -232.113761)
			(xy 122.411001 -232.082636) (xy 122.453622 -232.058029) (xy 122.499638 -232.040577) (xy 122.547857 -232.030733)
			(xy 122.597032 -232.028752) (xy 122.645887 -232.034684) (xy 122.693158 -232.048376) (xy 122.73762 -232.069474)
			(xy 122.778123 -232.09743) (xy 122.813616 -232.131522) (xy 122.843181 -232.170866) (xy 122.866052 -232.214443)
			(xy 122.881636 -232.261124) (xy 122.889531 -232.309701) (xy 122.890026 -232.334308) (xy 123.218968 -232.334308)
			(xy 123.222928 -232.285254) (xy 123.234705 -232.23747) (xy 123.253996 -232.192194) (xy 123.280299 -232.150598)
			(xy 123.312934 -232.113761) (xy 123.351055 -232.082636) (xy 123.393676 -232.058029) (xy 123.439692 -232.040577)
			(xy 123.487911 -232.030733) (xy 123.537086 -232.028752) (xy 123.585941 -232.034684) (xy 123.633212 -232.048376)
			(xy 123.677674 -232.069474) (xy 123.718177 -232.09743) (xy 123.75367 -232.131522) (xy 123.783235 -232.170866)
			(xy 123.806106 -232.214443) (xy 123.82169 -232.261124) (xy 123.829585 -232.309701) (xy 123.83008 -232.334308)
			(xy 123.829585 -232.358915) (xy 123.82169 -232.407492) (xy 123.806106 -232.454173) (xy 123.783235 -232.49775)
			(xy 123.75367 -232.537094) (xy 123.718177 -232.571186) (xy 123.677674 -232.599142) (xy 123.633212 -232.62024)
			(xy 123.585941 -232.633932) (xy 123.537086 -232.639864) (xy 123.487911 -232.637883) (xy 123.439692 -232.628039)
			(xy 123.393676 -232.610587) (xy 123.351055 -232.58598) (xy 123.312934 -232.554855) (xy 123.280299 -232.518018)
			(xy 123.253996 -232.476422) (xy 123.234705 -232.431146) (xy 123.222928 -232.383362) (xy 123.218968 -232.334308)
			(xy 122.890026 -232.334308) (xy 122.889531 -232.358915) (xy 122.881636 -232.407492) (xy 122.866052 -232.454173)
			(xy 122.843181 -232.49775) (xy 122.813616 -232.537094) (xy 122.778123 -232.571186) (xy 122.73762 -232.599142)
			(xy 122.693158 -232.62024) (xy 122.645887 -232.633932) (xy 122.597032 -232.639864) (xy 122.547857 -232.637883)
			(xy 122.499638 -232.628039) (xy 122.453622 -232.610587) (xy 122.411001 -232.58598) (xy 122.37288 -232.554855)
			(xy 122.340245 -232.518018) (xy 122.313942 -232.476422) (xy 122.294651 -232.431146) (xy 122.282874 -232.383362)
			(xy 122.278914 -232.334308) (xy 121.949972 -232.334308) (xy 121.949477 -232.358915) (xy 121.941582 -232.407492)
			(xy 121.925998 -232.454173) (xy 121.903127 -232.49775) (xy 121.873562 -232.537094) (xy 121.838069 -232.571186)
			(xy 121.797566 -232.599142) (xy 121.753104 -232.62024) (xy 121.705833 -232.633932) (xy 121.656978 -232.639864)
			(xy 121.607803 -232.637883) (xy 121.559584 -232.628039) (xy 121.513568 -232.610587) (xy 121.470947 -232.58598)
			(xy 121.432826 -232.554855) (xy 121.400191 -232.518018) (xy 121.373888 -232.476422) (xy 121.354597 -232.431146)
			(xy 121.34282 -232.383362) (xy 121.33886 -232.334308) (xy 121.009918 -232.334308) (xy 121.009423 -232.358915)
			(xy 121.001528 -232.407492) (xy 120.985944 -232.454173) (xy 120.963073 -232.49775) (xy 120.933508 -232.537094)
			(xy 120.898015 -232.571186) (xy 120.857512 -232.599142) (xy 120.81305 -232.62024) (xy 120.765779 -232.633932)
			(xy 120.716924 -232.639864) (xy 120.667749 -232.637883) (xy 120.61953 -232.628039) (xy 120.573514 -232.610587)
			(xy 120.530893 -232.58598) (xy 120.492772 -232.554855) (xy 120.460137 -232.518018) (xy 120.433834 -232.476422)
			(xy 120.414543 -232.431146) (xy 120.402766 -232.383362) (xy 120.398806 -232.334308) (xy 120.070118 -232.334308)
			(xy 120.069623 -232.358915) (xy 120.061728 -232.407492) (xy 120.046144 -232.454173) (xy 120.023273 -232.49775)
			(xy 119.993708 -232.537094) (xy 119.958215 -232.571186) (xy 119.917712 -232.599142) (xy 119.87325 -232.62024)
			(xy 119.825979 -232.633932) (xy 119.777124 -232.639864) (xy 119.727949 -232.637883) (xy 119.67973 -232.628039)
			(xy 119.633714 -232.610587) (xy 119.591093 -232.58598) (xy 119.552972 -232.554855) (xy 119.520337 -232.518018)
			(xy 119.494034 -232.476422) (xy 119.474743 -232.431146) (xy 119.462966 -232.383362) (xy 119.459006 -232.334308)
			(xy 119.130064 -232.334308) (xy 119.129569 -232.358915) (xy 119.121674 -232.407492) (xy 119.10609 -232.454173)
			(xy 119.083219 -232.49775) (xy 119.053654 -232.537094) (xy 119.018161 -232.571186) (xy 118.977658 -232.599142)
			(xy 118.933196 -232.62024) (xy 118.885925 -232.633932) (xy 118.83707 -232.639864) (xy 118.787895 -232.637883)
			(xy 118.739676 -232.628039) (xy 118.69366 -232.610587) (xy 118.651039 -232.58598) (xy 118.612918 -232.554855)
			(xy 118.580283 -232.518018) (xy 118.55398 -232.476422) (xy 118.534689 -232.431146) (xy 118.522912 -232.383362)
			(xy 118.518952 -232.334308) (xy 118.19001 -232.334308) (xy 118.189515 -232.358915) (xy 118.18162 -232.407492)
			(xy 118.166036 -232.454173) (xy 118.143165 -232.49775) (xy 118.1136 -232.537094) (xy 118.078107 -232.571186)
			(xy 118.037604 -232.599142) (xy 117.993142 -232.62024) (xy 117.945871 -232.633932) (xy 117.897016 -232.639864)
			(xy 117.847841 -232.637883) (xy 117.799622 -232.628039) (xy 117.753606 -232.610587) (xy 117.710985 -232.58598)
			(xy 117.672864 -232.554855) (xy 117.640229 -232.518018) (xy 117.613926 -232.476422) (xy 117.594635 -232.431146)
			(xy 117.582858 -232.383362) (xy 117.578898 -232.334308) (xy 117.249956 -232.334308) (xy 117.249461 -232.358915)
			(xy 117.241566 -232.407492) (xy 117.225982 -232.454173) (xy 117.203111 -232.49775) (xy 117.173546 -232.537094)
			(xy 117.138053 -232.571186) (xy 117.09755 -232.599142) (xy 117.053088 -232.62024) (xy 117.005817 -232.633932)
			(xy 116.956962 -232.639864) (xy 116.907787 -232.637883) (xy 116.859568 -232.628039) (xy 116.813552 -232.610587)
			(xy 116.770931 -232.58598) (xy 116.73281 -232.554855) (xy 116.700175 -232.518018) (xy 116.673872 -232.476422)
			(xy 116.654581 -232.431146) (xy 116.642804 -232.383362) (xy 116.638844 -232.334308) (xy 116.310156 -232.334308)
			(xy 116.309661 -232.358915) (xy 116.301766 -232.407492) (xy 116.286182 -232.454173) (xy 116.263311 -232.49775)
			(xy 116.233746 -232.537094) (xy 116.198253 -232.571186) (xy 116.15775 -232.599142) (xy 116.113288 -232.62024)
			(xy 116.066017 -232.633932) (xy 116.017162 -232.639864) (xy 115.967987 -232.637883) (xy 115.919768 -232.628039)
			(xy 115.873752 -232.610587) (xy 115.831131 -232.58598) (xy 115.79301 -232.554855) (xy 115.760375 -232.518018)
			(xy 115.734072 -232.476422) (xy 115.714781 -232.431146) (xy 115.703004 -232.383362) (xy 115.699044 -232.334308)
			(xy 115.370102 -232.334308) (xy 115.369607 -232.358915) (xy 115.361712 -232.407492) (xy 115.346128 -232.454173)
			(xy 115.323257 -232.49775) (xy 115.293692 -232.537094) (xy 115.258199 -232.571186) (xy 115.217696 -232.599142)
			(xy 115.173234 -232.62024) (xy 115.125963 -232.633932) (xy 115.077108 -232.639864) (xy 115.027933 -232.637883)
			(xy 114.979714 -232.628039) (xy 114.933698 -232.610587) (xy 114.891077 -232.58598) (xy 114.852956 -232.554855)
			(xy 114.820321 -232.518018) (xy 114.794018 -232.476422) (xy 114.774727 -232.431146) (xy 114.76295 -232.383362)
			(xy 114.75899 -232.334308) (xy 114.430048 -232.334308) (xy 114.429553 -232.358915) (xy 114.421658 -232.407492)
			(xy 114.406074 -232.454173) (xy 114.383203 -232.49775) (xy 114.353638 -232.537094) (xy 114.318145 -232.571186)
			(xy 114.277642 -232.599142) (xy 114.23318 -232.62024) (xy 114.185909 -232.633932) (xy 114.137054 -232.639864)
			(xy 114.087879 -232.637883) (xy 114.03966 -232.628039) (xy 113.993644 -232.610587) (xy 113.951023 -232.58598)
			(xy 113.912902 -232.554855) (xy 113.880267 -232.518018) (xy 113.853964 -232.476422) (xy 113.834673 -232.431146)
			(xy 113.822896 -232.383362) (xy 113.818936 -232.334308) (xy 113.489994 -232.334308) (xy 113.489499 -232.358915)
			(xy 113.481604 -232.407492) (xy 113.46602 -232.454173) (xy 113.443149 -232.49775) (xy 113.413584 -232.537094)
			(xy 113.378091 -232.571186) (xy 113.337588 -232.599142) (xy 113.293126 -232.62024) (xy 113.245855 -232.633932)
			(xy 113.197 -232.639864) (xy 113.147825 -232.637883) (xy 113.099606 -232.628039) (xy 113.05359 -232.610587)
			(xy 113.010969 -232.58598) (xy 112.972848 -232.554855) (xy 112.940213 -232.518018) (xy 112.91391 -232.476422)
			(xy 112.894619 -232.431146) (xy 112.882842 -232.383362) (xy 112.878882 -232.334308) (xy 111.89208 -232.334308)
			(xy 111.89208 -233.144314) (xy 113.349036 -233.144314) (xy 113.352996 -233.09526) (xy 113.364773 -233.047476)
			(xy 113.384064 -233.0022) (xy 113.410367 -232.960604) (xy 113.443002 -232.923767) (xy 113.481123 -232.892642)
			(xy 113.523744 -232.868035) (xy 113.56976 -232.850583) (xy 113.617979 -232.840739) (xy 113.667154 -232.838758)
			(xy 113.716009 -232.84469) (xy 113.76328 -232.858382) (xy 113.807742 -232.87948) (xy 113.848245 -232.907436)
			(xy 113.883738 -232.941528) (xy 113.913303 -232.980872) (xy 113.936174 -233.024449) (xy 113.951758 -233.07113)
			(xy 113.959653 -233.119707) (xy 113.960148 -233.144314) (xy 114.288836 -233.144314) (xy 114.292796 -233.09526)
			(xy 114.304573 -233.047476) (xy 114.323864 -233.0022) (xy 114.350167 -232.960604) (xy 114.382802 -232.923767)
			(xy 114.420923 -232.892642) (xy 114.463544 -232.868035) (xy 114.50956 -232.850583) (xy 114.557779 -232.840739)
			(xy 114.606954 -232.838758) (xy 114.655809 -232.84469) (xy 114.70308 -232.858382) (xy 114.747542 -232.87948)
			(xy 114.788045 -232.907436) (xy 114.823538 -232.941528) (xy 114.853103 -232.980872) (xy 114.875974 -233.024449)
			(xy 114.891558 -233.07113) (xy 114.899453 -233.119707) (xy 114.899948 -233.144314) (xy 115.22889 -233.144314)
			(xy 115.23285 -233.09526) (xy 115.244627 -233.047476) (xy 115.263918 -233.0022) (xy 115.290221 -232.960604)
			(xy 115.322856 -232.923767) (xy 115.360977 -232.892642) (xy 115.403598 -232.868035) (xy 115.449614 -232.850583)
			(xy 115.497833 -232.840739) (xy 115.547008 -232.838758) (xy 115.595863 -232.84469) (xy 115.643134 -232.858382)
			(xy 115.687596 -232.87948) (xy 115.728099 -232.907436) (xy 115.763592 -232.941528) (xy 115.793157 -232.980872)
			(xy 115.816028 -233.024449) (xy 115.831612 -233.07113) (xy 115.839507 -233.119707) (xy 115.840002 -233.144314)
			(xy 116.168944 -233.144314) (xy 116.172904 -233.09526) (xy 116.184681 -233.047476) (xy 116.203972 -233.0022)
			(xy 116.230275 -232.960604) (xy 116.26291 -232.923767) (xy 116.301031 -232.892642) (xy 116.343652 -232.868035)
			(xy 116.389668 -232.850583) (xy 116.437887 -232.840739) (xy 116.487062 -232.838758) (xy 116.535917 -232.84469)
			(xy 116.583188 -232.858382) (xy 116.62765 -232.87948) (xy 116.668153 -232.907436) (xy 116.703646 -232.941528)
			(xy 116.733211 -232.980872) (xy 116.756082 -233.024449) (xy 116.771666 -233.07113) (xy 116.779561 -233.119707)
			(xy 116.780056 -233.144314) (xy 117.108998 -233.144314) (xy 117.112958 -233.09526) (xy 117.124735 -233.047476)
			(xy 117.144026 -233.0022) (xy 117.170329 -232.960604) (xy 117.202964 -232.923767) (xy 117.241085 -232.892642)
			(xy 117.283706 -232.868035) (xy 117.329722 -232.850583) (xy 117.377941 -232.840739) (xy 117.427116 -232.838758)
			(xy 117.475971 -232.84469) (xy 117.523242 -232.858382) (xy 117.567704 -232.87948) (xy 117.608207 -232.907436)
			(xy 117.6437 -232.941528) (xy 117.673265 -232.980872) (xy 117.696136 -233.024449) (xy 117.71172 -233.07113)
			(xy 117.719615 -233.119707) (xy 117.72011 -233.144314) (xy 118.049052 -233.144314) (xy 118.053012 -233.09526)
			(xy 118.064789 -233.047476) (xy 118.08408 -233.0022) (xy 118.110383 -232.960604) (xy 118.143018 -232.923767)
			(xy 118.181139 -232.892642) (xy 118.22376 -232.868035) (xy 118.269776 -232.850583) (xy 118.317995 -232.840739)
			(xy 118.36717 -232.838758) (xy 118.416025 -232.84469) (xy 118.463296 -232.858382) (xy 118.507758 -232.87948)
			(xy 118.548261 -232.907436) (xy 118.583754 -232.941528) (xy 118.613319 -232.980872) (xy 118.63619 -233.024449)
			(xy 118.651774 -233.07113) (xy 118.659669 -233.119707) (xy 118.660164 -233.144314) (xy 118.988852 -233.144314)
			(xy 118.992812 -233.09526) (xy 119.004589 -233.047476) (xy 119.02388 -233.0022) (xy 119.050183 -232.960604)
			(xy 119.082818 -232.923767) (xy 119.120939 -232.892642) (xy 119.16356 -232.868035) (xy 119.209576 -232.850583)
			(xy 119.257795 -232.840739) (xy 119.30697 -232.838758) (xy 119.355825 -232.84469) (xy 119.403096 -232.858382)
			(xy 119.447558 -232.87948) (xy 119.488061 -232.907436) (xy 119.523554 -232.941528) (xy 119.553119 -232.980872)
			(xy 119.57599 -233.024449) (xy 119.591574 -233.07113) (xy 119.599469 -233.119707) (xy 119.599964 -233.144314)
			(xy 119.928906 -233.144314) (xy 119.932866 -233.09526) (xy 119.944643 -233.047476) (xy 119.963934 -233.0022)
			(xy 119.990237 -232.960604) (xy 120.022872 -232.923767) (xy 120.060993 -232.892642) (xy 120.103614 -232.868035)
			(xy 120.14963 -232.850583) (xy 120.197849 -232.840739) (xy 120.247024 -232.838758) (xy 120.295879 -232.84469)
			(xy 120.34315 -232.858382) (xy 120.387612 -232.87948) (xy 120.428115 -232.907436) (xy 120.463608 -232.941528)
			(xy 120.493173 -232.980872) (xy 120.516044 -233.024449) (xy 120.531628 -233.07113) (xy 120.539523 -233.119707)
			(xy 120.540018 -233.144314) (xy 120.86896 -233.144314) (xy 120.87292 -233.09526) (xy 120.884697 -233.047476)
			(xy 120.903988 -233.0022) (xy 120.930291 -232.960604) (xy 120.962926 -232.923767) (xy 121.001047 -232.892642)
			(xy 121.043668 -232.868035) (xy 121.089684 -232.850583) (xy 121.137903 -232.840739) (xy 121.187078 -232.838758)
			(xy 121.235933 -232.84469) (xy 121.283204 -232.858382) (xy 121.327666 -232.87948) (xy 121.368169 -232.907436)
			(xy 121.403662 -232.941528) (xy 121.433227 -232.980872) (xy 121.456098 -233.024449) (xy 121.471682 -233.07113)
			(xy 121.479577 -233.119707) (xy 121.480072 -233.144314) (xy 121.809014 -233.144314) (xy 121.812974 -233.09526)
			(xy 121.824751 -233.047476) (xy 121.844042 -233.0022) (xy 121.870345 -232.960604) (xy 121.90298 -232.923767)
			(xy 121.941101 -232.892642) (xy 121.983722 -232.868035) (xy 122.029738 -232.850583) (xy 122.077957 -232.840739)
			(xy 122.127132 -232.838758) (xy 122.175987 -232.84469) (xy 122.223258 -232.858382) (xy 122.26772 -232.87948)
			(xy 122.308223 -232.907436) (xy 122.343716 -232.941528) (xy 122.373281 -232.980872) (xy 122.396152 -233.024449)
			(xy 122.411736 -233.07113) (xy 122.419631 -233.119707) (xy 122.420126 -233.144314) (xy 122.748814 -233.144314)
			(xy 122.752774 -233.09526) (xy 122.764551 -233.047476) (xy 122.783842 -233.0022) (xy 122.810145 -232.960604)
			(xy 122.84278 -232.923767) (xy 122.880901 -232.892642) (xy 122.923522 -232.868035) (xy 122.969538 -232.850583)
			(xy 123.017757 -232.840739) (xy 123.066932 -232.838758) (xy 123.115787 -232.84469) (xy 123.163058 -232.858382)
			(xy 123.20752 -232.87948) (xy 123.248023 -232.907436) (xy 123.283516 -232.941528) (xy 123.313081 -232.980872)
			(xy 123.335952 -233.024449) (xy 123.351536 -233.07113) (xy 123.359431 -233.119707) (xy 123.359926 -233.144314)
			(xy 123.688868 -233.144314) (xy 123.692828 -233.09526) (xy 123.704605 -233.047476) (xy 123.723896 -233.0022)
			(xy 123.750199 -232.960604) (xy 123.782834 -232.923767) (xy 123.820955 -232.892642) (xy 123.863576 -232.868035)
			(xy 123.909592 -232.850583) (xy 123.957811 -232.840739) (xy 124.006986 -232.838758) (xy 124.055841 -232.84469)
			(xy 124.103112 -232.858382) (xy 124.147574 -232.87948) (xy 124.188077 -232.907436) (xy 124.22357 -232.941528)
			(xy 124.253135 -232.980872) (xy 124.276006 -233.024449) (xy 124.29159 -233.07113) (xy 124.299485 -233.119707)
			(xy 124.29998 -233.144314) (xy 124.628922 -233.144314) (xy 124.632882 -233.09526) (xy 124.644659 -233.047476)
			(xy 124.66395 -233.0022) (xy 124.690253 -232.960604) (xy 124.722888 -232.923767) (xy 124.761009 -232.892642)
			(xy 124.80363 -232.868035) (xy 124.849646 -232.850583) (xy 124.897865 -232.840739) (xy 124.94704 -232.838758)
			(xy 124.995895 -232.84469) (xy 125.043166 -232.858382) (xy 125.087628 -232.87948) (xy 125.128131 -232.907436)
			(xy 125.163624 -232.941528) (xy 125.193189 -232.980872) (xy 125.21606 -233.024449) (xy 125.231644 -233.07113)
			(xy 125.239539 -233.119707) (xy 125.240034 -233.144314) (xy 125.568976 -233.144314) (xy 125.572936 -233.09526)
			(xy 125.584713 -233.047476) (xy 125.604004 -233.0022) (xy 125.630307 -232.960604) (xy 125.662942 -232.923767)
			(xy 125.701063 -232.892642) (xy 125.743684 -232.868035) (xy 125.7897 -232.850583) (xy 125.837919 -232.840739)
			(xy 125.887094 -232.838758) (xy 125.935949 -232.84469) (xy 125.98322 -232.858382) (xy 126.027682 -232.87948)
			(xy 126.068185 -232.907436) (xy 126.103678 -232.941528) (xy 126.133243 -232.980872) (xy 126.156114 -233.024449)
			(xy 126.171698 -233.07113) (xy 126.179593 -233.119707) (xy 126.180088 -233.144314) (xy 126.50903 -233.144314)
			(xy 126.51299 -233.09526) (xy 126.524767 -233.047476) (xy 126.544058 -233.0022) (xy 126.570361 -232.960604)
			(xy 126.602996 -232.923767) (xy 126.641117 -232.892642) (xy 126.683738 -232.868035) (xy 126.729754 -232.850583)
			(xy 126.777973 -232.840739) (xy 126.827148 -232.838758) (xy 126.876003 -232.84469) (xy 126.923274 -232.858382)
			(xy 126.967736 -232.87948) (xy 127.008239 -232.907436) (xy 127.043732 -232.941528) (xy 127.073297 -232.980872)
			(xy 127.096168 -233.024449) (xy 127.111752 -233.07113) (xy 127.119647 -233.119707) (xy 127.120142 -233.144314)
			(xy 127.438399 -233.144314) (xy 127.442494 -233.093586) (xy 127.454673 -233.044172) (xy 127.474621 -232.997352)
			(xy 127.501822 -232.954338) (xy 127.53557 -232.916244) (xy 127.574992 -232.884057) (xy 127.619066 -232.858611)
			(xy 127.666652 -232.840564) (xy 127.716516 -232.830384) (xy 127.767368 -232.828335) (xy 127.817889 -232.834469)
			(xy 127.866773 -232.848629) (xy 127.912752 -232.870446) (xy 127.954636 -232.899356) (xy 127.99134 -232.934611)
			(xy 128.021913 -232.975297) (xy 128.045564 -233.02036) (xy 128.06168 -233.068634) (xy 128.069844 -233.118868)
			(xy 128.070356 -233.144314) (xy 128.388884 -233.144314) (xy 128.392844 -233.09526) (xy 128.404621 -233.047476)
			(xy 128.423912 -233.0022) (xy 128.450215 -232.960604) (xy 128.48285 -232.923767) (xy 128.520971 -232.892642)
			(xy 128.563592 -232.868035) (xy 128.609608 -232.850583) (xy 128.657827 -232.840739) (xy 128.707002 -232.838758)
			(xy 128.755857 -232.84469) (xy 128.803128 -232.858382) (xy 128.84759 -232.87948) (xy 128.888093 -232.907436)
			(xy 128.923586 -232.941528) (xy 128.953151 -232.980872) (xy 128.976022 -233.024449) (xy 128.991606 -233.07113)
			(xy 128.999501 -233.119707) (xy 128.999996 -233.144314) (xy 129.318507 -233.144314) (xy 129.322602 -233.093586)
			(xy 129.334781 -233.044172) (xy 129.354729 -232.997352) (xy 129.38193 -232.954338) (xy 129.415678 -232.916244)
			(xy 129.4551 -232.884057) (xy 129.499174 -232.858611) (xy 129.54676 -232.840564) (xy 129.596624 -232.830384)
			(xy 129.647476 -232.828335) (xy 129.697997 -232.834469) (xy 129.746881 -232.848629) (xy 129.79286 -232.870446)
			(xy 129.834744 -232.899356) (xy 129.871448 -232.934611) (xy 129.902021 -232.975297) (xy 129.925672 -233.02036)
			(xy 129.941788 -233.068634) (xy 129.949952 -233.118868) (xy 129.950464 -233.144314) (xy 129.949952 -233.16976)
			(xy 129.941788 -233.219994) (xy 129.925672 -233.268268) (xy 129.902021 -233.313331) (xy 129.871448 -233.354017)
			(xy 129.834744 -233.389272) (xy 129.79286 -233.418182) (xy 129.746881 -233.439999) (xy 129.697997 -233.454159)
			(xy 129.647476 -233.460293) (xy 129.596624 -233.458244) (xy 129.54676 -233.448064) (xy 129.499174 -233.430017)
			(xy 129.4551 -233.404571) (xy 129.415678 -233.372384) (xy 129.38193 -233.33429) (xy 129.354729 -233.291276)
			(xy 129.334781 -233.244456) (xy 129.322602 -233.195042) (xy 129.318507 -233.144314) (xy 128.999996 -233.144314)
			(xy 128.999501 -233.168921) (xy 128.991606 -233.217498) (xy 128.976022 -233.264179) (xy 128.953151 -233.307756)
			(xy 128.923586 -233.3471) (xy 128.888093 -233.381192) (xy 128.84759 -233.409148) (xy 128.803128 -233.430246)
			(xy 128.755857 -233.443938) (xy 128.707002 -233.44987) (xy 128.657827 -233.447889) (xy 128.609608 -233.438045)
			(xy 128.563592 -233.420593) (xy 128.520971 -233.395986) (xy 128.48285 -233.364861) (xy 128.450215 -233.328024)
			(xy 128.423912 -233.286428) (xy 128.404621 -233.241152) (xy 128.392844 -233.193368) (xy 128.388884 -233.144314)
			(xy 128.070356 -233.144314) (xy 128.069844 -233.16976) (xy 128.06168 -233.219994) (xy 128.045564 -233.268268)
			(xy 128.021913 -233.313331) (xy 127.99134 -233.354017) (xy 127.954636 -233.389272) (xy 127.912752 -233.418182)
			(xy 127.866773 -233.439999) (xy 127.817889 -233.454159) (xy 127.767368 -233.460293) (xy 127.716516 -233.458244)
			(xy 127.666652 -233.448064) (xy 127.619066 -233.430017) (xy 127.574992 -233.404571) (xy 127.53557 -233.372384)
			(xy 127.501822 -233.33429) (xy 127.474621 -233.291276) (xy 127.454673 -233.244456) (xy 127.442494 -233.195042)
			(xy 127.438399 -233.144314) (xy 127.120142 -233.144314) (xy 127.119647 -233.168921) (xy 127.111752 -233.217498)
			(xy 127.096168 -233.264179) (xy 127.073297 -233.307756) (xy 127.043732 -233.3471) (xy 127.008239 -233.381192)
			(xy 126.967736 -233.409148) (xy 126.923274 -233.430246) (xy 126.876003 -233.443938) (xy 126.827148 -233.44987)
			(xy 126.777973 -233.447889) (xy 126.729754 -233.438045) (xy 126.683738 -233.420593) (xy 126.641117 -233.395986)
			(xy 126.602996 -233.364861) (xy 126.570361 -233.328024) (xy 126.544058 -233.286428) (xy 126.524767 -233.241152)
			(xy 126.51299 -233.193368) (xy 126.50903 -233.144314) (xy 126.180088 -233.144314) (xy 126.179593 -233.168921)
			(xy 126.171698 -233.217498) (xy 126.156114 -233.264179) (xy 126.133243 -233.307756) (xy 126.103678 -233.3471)
			(xy 126.068185 -233.381192) (xy 126.027682 -233.409148) (xy 125.98322 -233.430246) (xy 125.935949 -233.443938)
			(xy 125.887094 -233.44987) (xy 125.837919 -233.447889) (xy 125.7897 -233.438045) (xy 125.743684 -233.420593)
			(xy 125.701063 -233.395986) (xy 125.662942 -233.364861) (xy 125.630307 -233.328024) (xy 125.604004 -233.286428)
			(xy 125.584713 -233.241152) (xy 125.572936 -233.193368) (xy 125.568976 -233.144314) (xy 125.240034 -233.144314)
			(xy 125.239539 -233.168921) (xy 125.231644 -233.217498) (xy 125.21606 -233.264179) (xy 125.193189 -233.307756)
			(xy 125.163624 -233.3471) (xy 125.128131 -233.381192) (xy 125.087628 -233.409148) (xy 125.043166 -233.430246)
			(xy 124.995895 -233.443938) (xy 124.94704 -233.44987) (xy 124.897865 -233.447889) (xy 124.849646 -233.438045)
			(xy 124.80363 -233.420593) (xy 124.761009 -233.395986) (xy 124.722888 -233.364861) (xy 124.690253 -233.328024)
			(xy 124.66395 -233.286428) (xy 124.644659 -233.241152) (xy 124.632882 -233.193368) (xy 124.628922 -233.144314)
			(xy 124.29998 -233.144314) (xy 124.299485 -233.168921) (xy 124.29159 -233.217498) (xy 124.276006 -233.264179)
			(xy 124.253135 -233.307756) (xy 124.22357 -233.3471) (xy 124.188077 -233.381192) (xy 124.147574 -233.409148)
			(xy 124.103112 -233.430246) (xy 124.055841 -233.443938) (xy 124.006986 -233.44987) (xy 123.957811 -233.447889)
			(xy 123.909592 -233.438045) (xy 123.863576 -233.420593) (xy 123.820955 -233.395986) (xy 123.782834 -233.364861)
			(xy 123.750199 -233.328024) (xy 123.723896 -233.286428) (xy 123.704605 -233.241152) (xy 123.692828 -233.193368)
			(xy 123.688868 -233.144314) (xy 123.359926 -233.144314) (xy 123.359431 -233.168921) (xy 123.351536 -233.217498)
			(xy 123.335952 -233.264179) (xy 123.313081 -233.307756) (xy 123.283516 -233.3471) (xy 123.248023 -233.381192)
			(xy 123.20752 -233.409148) (xy 123.163058 -233.430246) (xy 123.115787 -233.443938) (xy 123.066932 -233.44987)
			(xy 123.017757 -233.447889) (xy 122.969538 -233.438045) (xy 122.923522 -233.420593) (xy 122.880901 -233.395986)
			(xy 122.84278 -233.364861) (xy 122.810145 -233.328024) (xy 122.783842 -233.286428) (xy 122.764551 -233.241152)
			(xy 122.752774 -233.193368) (xy 122.748814 -233.144314) (xy 122.420126 -233.144314) (xy 122.419631 -233.168921)
			(xy 122.411736 -233.217498) (xy 122.396152 -233.264179) (xy 122.373281 -233.307756) (xy 122.343716 -233.3471)
			(xy 122.308223 -233.381192) (xy 122.26772 -233.409148) (xy 122.223258 -233.430246) (xy 122.175987 -233.443938)
			(xy 122.127132 -233.44987) (xy 122.077957 -233.447889) (xy 122.029738 -233.438045) (xy 121.983722 -233.420593)
			(xy 121.941101 -233.395986) (xy 121.90298 -233.364861) (xy 121.870345 -233.328024) (xy 121.844042 -233.286428)
			(xy 121.824751 -233.241152) (xy 121.812974 -233.193368) (xy 121.809014 -233.144314) (xy 121.480072 -233.144314)
			(xy 121.479577 -233.168921) (xy 121.471682 -233.217498) (xy 121.456098 -233.264179) (xy 121.433227 -233.307756)
			(xy 121.403662 -233.3471) (xy 121.368169 -233.381192) (xy 121.327666 -233.409148) (xy 121.283204 -233.430246)
			(xy 121.235933 -233.443938) (xy 121.187078 -233.44987) (xy 121.137903 -233.447889) (xy 121.089684 -233.438045)
			(xy 121.043668 -233.420593) (xy 121.001047 -233.395986) (xy 120.962926 -233.364861) (xy 120.930291 -233.328024)
			(xy 120.903988 -233.286428) (xy 120.884697 -233.241152) (xy 120.87292 -233.193368) (xy 120.86896 -233.144314)
			(xy 120.540018 -233.144314) (xy 120.539523 -233.168921) (xy 120.531628 -233.217498) (xy 120.516044 -233.264179)
			(xy 120.493173 -233.307756) (xy 120.463608 -233.3471) (xy 120.428115 -233.381192) (xy 120.387612 -233.409148)
			(xy 120.34315 -233.430246) (xy 120.295879 -233.443938) (xy 120.247024 -233.44987) (xy 120.197849 -233.447889)
			(xy 120.14963 -233.438045) (xy 120.103614 -233.420593) (xy 120.060993 -233.395986) (xy 120.022872 -233.364861)
			(xy 119.990237 -233.328024) (xy 119.963934 -233.286428) (xy 119.944643 -233.241152) (xy 119.932866 -233.193368)
			(xy 119.928906 -233.144314) (xy 119.599964 -233.144314) (xy 119.599469 -233.168921) (xy 119.591574 -233.217498)
			(xy 119.57599 -233.264179) (xy 119.553119 -233.307756) (xy 119.523554 -233.3471) (xy 119.488061 -233.381192)
			(xy 119.447558 -233.409148) (xy 119.403096 -233.430246) (xy 119.355825 -233.443938) (xy 119.30697 -233.44987)
			(xy 119.257795 -233.447889) (xy 119.209576 -233.438045) (xy 119.16356 -233.420593) (xy 119.120939 -233.395986)
			(xy 119.082818 -233.364861) (xy 119.050183 -233.328024) (xy 119.02388 -233.286428) (xy 119.004589 -233.241152)
			(xy 118.992812 -233.193368) (xy 118.988852 -233.144314) (xy 118.660164 -233.144314) (xy 118.659669 -233.168921)
			(xy 118.651774 -233.217498) (xy 118.63619 -233.264179) (xy 118.613319 -233.307756) (xy 118.583754 -233.3471)
			(xy 118.548261 -233.381192) (xy 118.507758 -233.409148) (xy 118.463296 -233.430246) (xy 118.416025 -233.443938)
			(xy 118.36717 -233.44987) (xy 118.317995 -233.447889) (xy 118.269776 -233.438045) (xy 118.22376 -233.420593)
			(xy 118.181139 -233.395986) (xy 118.143018 -233.364861) (xy 118.110383 -233.328024) (xy 118.08408 -233.286428)
			(xy 118.064789 -233.241152) (xy 118.053012 -233.193368) (xy 118.049052 -233.144314) (xy 117.72011 -233.144314)
			(xy 117.719615 -233.168921) (xy 117.71172 -233.217498) (xy 117.696136 -233.264179) (xy 117.673265 -233.307756)
			(xy 117.6437 -233.3471) (xy 117.608207 -233.381192) (xy 117.567704 -233.409148) (xy 117.523242 -233.430246)
			(xy 117.475971 -233.443938) (xy 117.427116 -233.44987) (xy 117.377941 -233.447889) (xy 117.329722 -233.438045)
			(xy 117.283706 -233.420593) (xy 117.241085 -233.395986) (xy 117.202964 -233.364861) (xy 117.170329 -233.328024)
			(xy 117.144026 -233.286428) (xy 117.124735 -233.241152) (xy 117.112958 -233.193368) (xy 117.108998 -233.144314)
			(xy 116.780056 -233.144314) (xy 116.779561 -233.168921) (xy 116.771666 -233.217498) (xy 116.756082 -233.264179)
			(xy 116.733211 -233.307756) (xy 116.703646 -233.3471) (xy 116.668153 -233.381192) (xy 116.62765 -233.409148)
			(xy 116.583188 -233.430246) (xy 116.535917 -233.443938) (xy 116.487062 -233.44987) (xy 116.437887 -233.447889)
			(xy 116.389668 -233.438045) (xy 116.343652 -233.420593) (xy 116.301031 -233.395986) (xy 116.26291 -233.364861)
			(xy 116.230275 -233.328024) (xy 116.203972 -233.286428) (xy 116.184681 -233.241152) (xy 116.172904 -233.193368)
			(xy 116.168944 -233.144314) (xy 115.840002 -233.144314) (xy 115.839507 -233.168921) (xy 115.831612 -233.217498)
			(xy 115.816028 -233.264179) (xy 115.793157 -233.307756) (xy 115.763592 -233.3471) (xy 115.728099 -233.381192)
			(xy 115.687596 -233.409148) (xy 115.643134 -233.430246) (xy 115.595863 -233.443938) (xy 115.547008 -233.44987)
			(xy 115.497833 -233.447889) (xy 115.449614 -233.438045) (xy 115.403598 -233.420593) (xy 115.360977 -233.395986)
			(xy 115.322856 -233.364861) (xy 115.290221 -233.328024) (xy 115.263918 -233.286428) (xy 115.244627 -233.241152)
			(xy 115.23285 -233.193368) (xy 115.22889 -233.144314) (xy 114.899948 -233.144314) (xy 114.899453 -233.168921)
			(xy 114.891558 -233.217498) (xy 114.875974 -233.264179) (xy 114.853103 -233.307756) (xy 114.823538 -233.3471)
			(xy 114.788045 -233.381192) (xy 114.747542 -233.409148) (xy 114.70308 -233.430246) (xy 114.655809 -233.443938)
			(xy 114.606954 -233.44987) (xy 114.557779 -233.447889) (xy 114.50956 -233.438045) (xy 114.463544 -233.420593)
			(xy 114.420923 -233.395986) (xy 114.382802 -233.364861) (xy 114.350167 -233.328024) (xy 114.323864 -233.286428)
			(xy 114.304573 -233.241152) (xy 114.292796 -233.193368) (xy 114.288836 -233.144314) (xy 113.960148 -233.144314)
			(xy 113.959653 -233.168921) (xy 113.951758 -233.217498) (xy 113.936174 -233.264179) (xy 113.913303 -233.307756)
			(xy 113.883738 -233.3471) (xy 113.848245 -233.381192) (xy 113.807742 -233.409148) (xy 113.76328 -233.430246)
			(xy 113.716009 -233.443938) (xy 113.667154 -233.44987) (xy 113.617979 -233.447889) (xy 113.56976 -233.438045)
			(xy 113.523744 -233.420593) (xy 113.481123 -233.395986) (xy 113.443002 -233.364861) (xy 113.410367 -233.328024)
			(xy 113.384064 -233.286428) (xy 113.364773 -233.241152) (xy 113.352996 -233.193368) (xy 113.349036 -233.144314)
			(xy 111.89208 -233.144314) (xy 111.89208 -233.95432) (xy 112.878882 -233.95432) (xy 112.882842 -233.905266)
			(xy 112.894619 -233.857482) (xy 112.91391 -233.812206) (xy 112.940213 -233.77061) (xy 112.972848 -233.733773)
			(xy 113.010969 -233.702648) (xy 113.05359 -233.678041) (xy 113.099606 -233.660589) (xy 113.147825 -233.650745)
			(xy 113.197 -233.648764) (xy 113.245855 -233.654696) (xy 113.293126 -233.668388) (xy 113.337588 -233.689486)
			(xy 113.378091 -233.717442) (xy 113.413584 -233.751534) (xy 113.443149 -233.790878) (xy 113.46602 -233.834455)
			(xy 113.481604 -233.881136) (xy 113.489499 -233.929713) (xy 113.489994 -233.95432) (xy 113.818936 -233.95432)
			(xy 113.822896 -233.905266) (xy 113.834673 -233.857482) (xy 113.853964 -233.812206) (xy 113.880267 -233.77061)
			(xy 113.912902 -233.733773) (xy 113.951023 -233.702648) (xy 113.993644 -233.678041) (xy 114.03966 -233.660589)
			(xy 114.087879 -233.650745) (xy 114.137054 -233.648764) (xy 114.185909 -233.654696) (xy 114.23318 -233.668388)
			(xy 114.277642 -233.689486) (xy 114.318145 -233.717442) (xy 114.353638 -233.751534) (xy 114.383203 -233.790878)
			(xy 114.406074 -233.834455) (xy 114.421658 -233.881136) (xy 114.429553 -233.929713) (xy 114.430048 -233.95432)
			(xy 114.75899 -233.95432) (xy 114.76295 -233.905266) (xy 114.774727 -233.857482) (xy 114.794018 -233.812206)
			(xy 114.820321 -233.77061) (xy 114.852956 -233.733773) (xy 114.891077 -233.702648) (xy 114.933698 -233.678041)
			(xy 114.979714 -233.660589) (xy 115.027933 -233.650745) (xy 115.077108 -233.648764) (xy 115.125963 -233.654696)
			(xy 115.173234 -233.668388) (xy 115.217696 -233.689486) (xy 115.258199 -233.717442) (xy 115.293692 -233.751534)
			(xy 115.323257 -233.790878) (xy 115.346128 -233.834455) (xy 115.361712 -233.881136) (xy 115.369607 -233.929713)
			(xy 115.370102 -233.95432) (xy 115.699044 -233.95432) (xy 115.703004 -233.905266) (xy 115.714781 -233.857482)
			(xy 115.734072 -233.812206) (xy 115.760375 -233.77061) (xy 115.79301 -233.733773) (xy 115.831131 -233.702648)
			(xy 115.873752 -233.678041) (xy 115.919768 -233.660589) (xy 115.967987 -233.650745) (xy 116.017162 -233.648764)
			(xy 116.066017 -233.654696) (xy 116.113288 -233.668388) (xy 116.15775 -233.689486) (xy 116.198253 -233.717442)
			(xy 116.233746 -233.751534) (xy 116.263311 -233.790878) (xy 116.286182 -233.834455) (xy 116.301766 -233.881136)
			(xy 116.309661 -233.929713) (xy 116.310156 -233.95432) (xy 118.518952 -233.95432) (xy 118.522912 -233.905266)
			(xy 118.534689 -233.857482) (xy 118.55398 -233.812206) (xy 118.580283 -233.77061) (xy 118.612918 -233.733773)
			(xy 118.651039 -233.702648) (xy 118.69366 -233.678041) (xy 118.739676 -233.660589) (xy 118.787895 -233.650745)
			(xy 118.83707 -233.648764) (xy 118.885925 -233.654696) (xy 118.933196 -233.668388) (xy 118.977658 -233.689486)
			(xy 119.018161 -233.717442) (xy 119.053654 -233.751534) (xy 119.083219 -233.790878) (xy 119.10609 -233.834455)
			(xy 119.121674 -233.881136) (xy 119.129569 -233.929713) (xy 119.130064 -233.95432) (xy 121.33886 -233.95432)
			(xy 121.34282 -233.905266) (xy 121.354597 -233.857482) (xy 121.373888 -233.812206) (xy 121.400191 -233.77061)
			(xy 121.432826 -233.733773) (xy 121.470947 -233.702648) (xy 121.513568 -233.678041) (xy 121.559584 -233.660589)
			(xy 121.607803 -233.650745) (xy 121.656978 -233.648764) (xy 121.705833 -233.654696) (xy 121.753104 -233.668388)
			(xy 121.797566 -233.689486) (xy 121.838069 -233.717442) (xy 121.873562 -233.751534) (xy 121.903127 -233.790878)
			(xy 121.925998 -233.834455) (xy 121.941582 -233.881136) (xy 121.949477 -233.929713) (xy 121.949972 -233.95432)
			(xy 124.159022 -233.95432) (xy 124.162982 -233.905266) (xy 124.174759 -233.857482) (xy 124.19405 -233.812206)
			(xy 124.220353 -233.77061) (xy 124.252988 -233.733773) (xy 124.291109 -233.702648) (xy 124.33373 -233.678041)
			(xy 124.379746 -233.660589) (xy 124.427965 -233.650745) (xy 124.47714 -233.648764) (xy 124.525995 -233.654696)
			(xy 124.573266 -233.668388) (xy 124.617728 -233.689486) (xy 124.658231 -233.717442) (xy 124.693724 -233.751534)
			(xy 124.723289 -233.790878) (xy 124.74616 -233.834455) (xy 124.761744 -233.881136) (xy 124.769639 -233.929713)
			(xy 124.770134 -233.95432) (xy 126.97893 -233.95432) (xy 126.98289 -233.905266) (xy 126.994667 -233.857482)
			(xy 127.013958 -233.812206) (xy 127.040261 -233.77061) (xy 127.072896 -233.733773) (xy 127.111017 -233.702648)
			(xy 127.153638 -233.678041) (xy 127.199654 -233.660589) (xy 127.247873 -233.650745) (xy 127.297048 -233.648764)
			(xy 127.345903 -233.654696) (xy 127.393174 -233.668388) (xy 127.437636 -233.689486) (xy 127.478139 -233.717442)
			(xy 127.513632 -233.751534) (xy 127.543197 -233.790878) (xy 127.566068 -233.834455) (xy 127.581652 -233.881136)
			(xy 127.589547 -233.929713) (xy 127.590042 -233.95432) (xy 127.908553 -233.95432) (xy 127.912648 -233.903592)
			(xy 127.924827 -233.854178) (xy 127.944775 -233.807358) (xy 127.971976 -233.764344) (xy 128.005724 -233.72625)
			(xy 128.045146 -233.694063) (xy 128.08922 -233.668617) (xy 128.136806 -233.65057) (xy 128.18667 -233.64039)
			(xy 128.237522 -233.638341) (xy 128.288043 -233.644475) (xy 128.336927 -233.658635) (xy 128.382906 -233.680452)
			(xy 128.42479 -233.709362) (xy 128.461494 -233.744617) (xy 128.492067 -233.785303) (xy 128.515718 -233.830366)
			(xy 128.531834 -233.87864) (xy 128.539998 -233.928874) (xy 128.54051 -233.95432) (xy 128.848607 -233.95432)
			(xy 128.852702 -233.903592) (xy 128.864881 -233.854178) (xy 128.884829 -233.807358) (xy 128.91203 -233.764344)
			(xy 128.945778 -233.72625) (xy 128.9852 -233.694063) (xy 129.029274 -233.668617) (xy 129.07686 -233.65057)
			(xy 129.126724 -233.64039) (xy 129.177576 -233.638341) (xy 129.228097 -233.644475) (xy 129.276981 -233.658635)
			(xy 129.32296 -233.680452) (xy 129.364844 -233.709362) (xy 129.401548 -233.744617) (xy 129.432121 -233.785303)
			(xy 129.455772 -233.830366) (xy 129.471888 -233.87864) (xy 129.480052 -233.928874) (xy 129.480564 -233.95432)
			(xy 129.480052 -233.979766) (xy 129.471888 -234.03) (xy 129.455772 -234.078274) (xy 129.432121 -234.123337)
			(xy 129.401548 -234.164023) (xy 129.364844 -234.199278) (xy 129.32296 -234.228188) (xy 129.276981 -234.250005)
			(xy 129.228097 -234.264165) (xy 129.177576 -234.270299) (xy 129.126724 -234.26825) (xy 129.07686 -234.25807)
			(xy 129.029274 -234.240023) (xy 128.9852 -234.214577) (xy 128.945778 -234.18239) (xy 128.91203 -234.144296)
			(xy 128.884829 -234.101282) (xy 128.864881 -234.054462) (xy 128.852702 -234.005048) (xy 128.848607 -233.95432)
			(xy 128.54051 -233.95432) (xy 128.539998 -233.979766) (xy 128.531834 -234.03) (xy 128.515718 -234.078274)
			(xy 128.492067 -234.123337) (xy 128.461494 -234.164023) (xy 128.42479 -234.199278) (xy 128.382906 -234.228188)
			(xy 128.336927 -234.250005) (xy 128.288043 -234.264165) (xy 128.237522 -234.270299) (xy 128.18667 -234.26825)
			(xy 128.136806 -234.25807) (xy 128.08922 -234.240023) (xy 128.045146 -234.214577) (xy 128.005724 -234.18239)
			(xy 127.971976 -234.144296) (xy 127.944775 -234.101282) (xy 127.924827 -234.054462) (xy 127.912648 -234.005048)
			(xy 127.908553 -233.95432) (xy 127.590042 -233.95432) (xy 127.589547 -233.978927) (xy 127.581652 -234.027504)
			(xy 127.566068 -234.074185) (xy 127.543197 -234.117762) (xy 127.513632 -234.157106) (xy 127.478139 -234.191198)
			(xy 127.437636 -234.219154) (xy 127.393174 -234.240252) (xy 127.345903 -234.253944) (xy 127.297048 -234.259876)
			(xy 127.247873 -234.257895) (xy 127.199654 -234.248051) (xy 127.153638 -234.230599) (xy 127.111017 -234.205992)
			(xy 127.072896 -234.174867) (xy 127.040261 -234.13803) (xy 127.013958 -234.096434) (xy 126.994667 -234.051158)
			(xy 126.98289 -234.003374) (xy 126.97893 -233.95432) (xy 124.770134 -233.95432) (xy 124.769639 -233.978927)
			(xy 124.761744 -234.027504) (xy 124.74616 -234.074185) (xy 124.723289 -234.117762) (xy 124.693724 -234.157106)
			(xy 124.658231 -234.191198) (xy 124.617728 -234.219154) (xy 124.573266 -234.240252) (xy 124.525995 -234.253944)
			(xy 124.47714 -234.259876) (xy 124.427965 -234.257895) (xy 124.379746 -234.248051) (xy 124.33373 -234.230599)
			(xy 124.291109 -234.205992) (xy 124.252988 -234.174867) (xy 124.220353 -234.13803) (xy 124.19405 -234.096434)
			(xy 124.174759 -234.051158) (xy 124.162982 -234.003374) (xy 124.159022 -233.95432) (xy 121.949972 -233.95432)
			(xy 121.949477 -233.978927) (xy 121.941582 -234.027504) (xy 121.925998 -234.074185) (xy 121.903127 -234.117762)
			(xy 121.873562 -234.157106) (xy 121.838069 -234.191198) (xy 121.797566 -234.219154) (xy 121.753104 -234.240252)
			(xy 121.705833 -234.253944) (xy 121.656978 -234.259876) (xy 121.607803 -234.257895) (xy 121.559584 -234.248051)
			(xy 121.513568 -234.230599) (xy 121.470947 -234.205992) (xy 121.432826 -234.174867) (xy 121.400191 -234.13803)
			(xy 121.373888 -234.096434) (xy 121.354597 -234.051158) (xy 121.34282 -234.003374) (xy 121.33886 -233.95432)
			(xy 119.130064 -233.95432) (xy 119.129569 -233.978927) (xy 119.121674 -234.027504) (xy 119.10609 -234.074185)
			(xy 119.083219 -234.117762) (xy 119.053654 -234.157106) (xy 119.018161 -234.191198) (xy 118.977658 -234.219154)
			(xy 118.933196 -234.240252) (xy 118.885925 -234.253944) (xy 118.83707 -234.259876) (xy 118.787895 -234.257895)
			(xy 118.739676 -234.248051) (xy 118.69366 -234.230599) (xy 118.651039 -234.205992) (xy 118.612918 -234.174867)
			(xy 118.580283 -234.13803) (xy 118.55398 -234.096434) (xy 118.534689 -234.051158) (xy 118.522912 -234.003374)
			(xy 118.518952 -233.95432) (xy 116.310156 -233.95432) (xy 116.309661 -233.978927) (xy 116.301766 -234.027504)
			(xy 116.286182 -234.074185) (xy 116.263311 -234.117762) (xy 116.233746 -234.157106) (xy 116.198253 -234.191198)
			(xy 116.15775 -234.219154) (xy 116.113288 -234.240252) (xy 116.066017 -234.253944) (xy 116.017162 -234.259876)
			(xy 115.967987 -234.257895) (xy 115.919768 -234.248051) (xy 115.873752 -234.230599) (xy 115.831131 -234.205992)
			(xy 115.79301 -234.174867) (xy 115.760375 -234.13803) (xy 115.734072 -234.096434) (xy 115.714781 -234.051158)
			(xy 115.703004 -234.003374) (xy 115.699044 -233.95432) (xy 115.370102 -233.95432) (xy 115.369607 -233.978927)
			(xy 115.361712 -234.027504) (xy 115.346128 -234.074185) (xy 115.323257 -234.117762) (xy 115.293692 -234.157106)
			(xy 115.258199 -234.191198) (xy 115.217696 -234.219154) (xy 115.173234 -234.240252) (xy 115.125963 -234.253944)
			(xy 115.077108 -234.259876) (xy 115.027933 -234.257895) (xy 114.979714 -234.248051) (xy 114.933698 -234.230599)
			(xy 114.891077 -234.205992) (xy 114.852956 -234.174867) (xy 114.820321 -234.13803) (xy 114.794018 -234.096434)
			(xy 114.774727 -234.051158) (xy 114.76295 -234.003374) (xy 114.75899 -233.95432) (xy 114.430048 -233.95432)
			(xy 114.429553 -233.978927) (xy 114.421658 -234.027504) (xy 114.406074 -234.074185) (xy 114.383203 -234.117762)
			(xy 114.353638 -234.157106) (xy 114.318145 -234.191198) (xy 114.277642 -234.219154) (xy 114.23318 -234.240252)
			(xy 114.185909 -234.253944) (xy 114.137054 -234.259876) (xy 114.087879 -234.257895) (xy 114.03966 -234.248051)
			(xy 113.993644 -234.230599) (xy 113.951023 -234.205992) (xy 113.912902 -234.174867) (xy 113.880267 -234.13803)
			(xy 113.853964 -234.096434) (xy 113.834673 -234.051158) (xy 113.822896 -234.003374) (xy 113.818936 -233.95432)
			(xy 113.489994 -233.95432) (xy 113.489499 -233.978927) (xy 113.481604 -234.027504) (xy 113.46602 -234.074185)
			(xy 113.443149 -234.117762) (xy 113.413584 -234.157106) (xy 113.378091 -234.191198) (xy 113.337588 -234.219154)
			(xy 113.293126 -234.240252) (xy 113.245855 -234.253944) (xy 113.197 -234.259876) (xy 113.147825 -234.257895)
			(xy 113.099606 -234.248051) (xy 113.05359 -234.230599) (xy 113.010969 -234.205992) (xy 112.972848 -234.174867)
			(xy 112.940213 -234.13803) (xy 112.91391 -234.096434) (xy 112.894619 -234.051158) (xy 112.882842 -234.003374)
			(xy 112.878882 -233.95432) (xy 111.89208 -233.95432) (xy 111.89208 -234.485434) (xy 111.89165 -234.495501)
			(xy 111.883925 -234.514095) (xy 111.877094 -234.521502) (xy 111.63427 -234.764326) (xy 115.22889 -234.764326)
			(xy 115.23285 -234.715272) (xy 115.244627 -234.667488) (xy 115.263918 -234.622212) (xy 115.290221 -234.580616)
			(xy 115.322856 -234.543779) (xy 115.360977 -234.512654) (xy 115.403598 -234.488047) (xy 115.449614 -234.470595)
			(xy 115.497833 -234.460751) (xy 115.547008 -234.45877) (xy 115.595863 -234.464702) (xy 115.643134 -234.478394)
			(xy 115.687596 -234.499492) (xy 115.728099 -234.527448) (xy 115.763592 -234.56154) (xy 115.793157 -234.600884)
			(xy 115.816028 -234.644461) (xy 115.831612 -234.691142) (xy 115.839507 -234.739719) (xy 115.840002 -234.764326)
			(xy 116.168944 -234.764326) (xy 116.172904 -234.715272) (xy 116.184681 -234.667488) (xy 116.203972 -234.622212)
			(xy 116.230275 -234.580616) (xy 116.26291 -234.543779) (xy 116.301031 -234.512654) (xy 116.343652 -234.488047)
			(xy 116.389668 -234.470595) (xy 116.437887 -234.460751) (xy 116.487062 -234.45877) (xy 116.535917 -234.464702)
			(xy 116.583188 -234.478394) (xy 116.62765 -234.499492) (xy 116.668153 -234.527448) (xy 116.703646 -234.56154)
			(xy 116.733211 -234.600884) (xy 116.756082 -234.644461) (xy 116.771666 -234.691142) (xy 116.779561 -234.739719)
			(xy 116.780056 -234.764326) (xy 117.108998 -234.764326) (xy 117.112958 -234.715272) (xy 117.124735 -234.667488)
			(xy 117.144026 -234.622212) (xy 117.170329 -234.580616) (xy 117.202964 -234.543779) (xy 117.241085 -234.512654)
			(xy 117.283706 -234.488047) (xy 117.329722 -234.470595) (xy 117.377941 -234.460751) (xy 117.427116 -234.45877)
			(xy 117.475971 -234.464702) (xy 117.523242 -234.478394) (xy 117.567704 -234.499492) (xy 117.608207 -234.527448)
			(xy 117.6437 -234.56154) (xy 117.673265 -234.600884) (xy 117.696136 -234.644461) (xy 117.71172 -234.691142)
			(xy 117.719615 -234.739719) (xy 117.72011 -234.764326) (xy 118.049052 -234.764326) (xy 118.053012 -234.715272)
			(xy 118.064789 -234.667488) (xy 118.08408 -234.622212) (xy 118.110383 -234.580616) (xy 118.143018 -234.543779)
			(xy 118.181139 -234.512654) (xy 118.22376 -234.488047) (xy 118.269776 -234.470595) (xy 118.317995 -234.460751)
			(xy 118.36717 -234.45877) (xy 118.416025 -234.464702) (xy 118.463296 -234.478394) (xy 118.507758 -234.499492)
			(xy 118.548261 -234.527448) (xy 118.583754 -234.56154) (xy 118.613319 -234.600884) (xy 118.63619 -234.644461)
			(xy 118.651774 -234.691142) (xy 118.659669 -234.739719) (xy 118.660164 -234.764326) (xy 118.988852 -234.764326)
			(xy 118.992812 -234.715272) (xy 119.004589 -234.667488) (xy 119.02388 -234.622212) (xy 119.050183 -234.580616)
			(xy 119.082818 -234.543779) (xy 119.120939 -234.512654) (xy 119.16356 -234.488047) (xy 119.209576 -234.470595)
			(xy 119.257795 -234.460751) (xy 119.30697 -234.45877) (xy 119.355825 -234.464702) (xy 119.403096 -234.478394)
			(xy 119.447558 -234.499492) (xy 119.488061 -234.527448) (xy 119.523554 -234.56154) (xy 119.553119 -234.600884)
			(xy 119.57599 -234.644461) (xy 119.591574 -234.691142) (xy 119.599469 -234.739719) (xy 119.599964 -234.764326)
			(xy 119.928906 -234.764326) (xy 119.932866 -234.715272) (xy 119.944643 -234.667488) (xy 119.963934 -234.622212)
			(xy 119.990237 -234.580616) (xy 120.022872 -234.543779) (xy 120.060993 -234.512654) (xy 120.103614 -234.488047)
			(xy 120.14963 -234.470595) (xy 120.197849 -234.460751) (xy 120.247024 -234.45877) (xy 120.295879 -234.464702)
			(xy 120.34315 -234.478394) (xy 120.387612 -234.499492) (xy 120.428115 -234.527448) (xy 120.463608 -234.56154)
			(xy 120.493173 -234.600884) (xy 120.516044 -234.644461) (xy 120.531628 -234.691142) (xy 120.539523 -234.739719)
			(xy 120.540018 -234.764326) (xy 120.86896 -234.764326) (xy 120.87292 -234.715272) (xy 120.884697 -234.667488)
			(xy 120.903988 -234.622212) (xy 120.930291 -234.580616) (xy 120.962926 -234.543779) (xy 121.001047 -234.512654)
			(xy 121.043668 -234.488047) (xy 121.089684 -234.470595) (xy 121.137903 -234.460751) (xy 121.187078 -234.45877)
			(xy 121.235933 -234.464702) (xy 121.283204 -234.478394) (xy 121.327666 -234.499492) (xy 121.368169 -234.527448)
			(xy 121.403662 -234.56154) (xy 121.433227 -234.600884) (xy 121.456098 -234.644461) (xy 121.471682 -234.691142)
			(xy 121.479577 -234.739719) (xy 121.480072 -234.764326) (xy 121.809014 -234.764326) (xy 121.812974 -234.715272)
			(xy 121.824751 -234.667488) (xy 121.844042 -234.622212) (xy 121.870345 -234.580616) (xy 121.90298 -234.543779)
			(xy 121.941101 -234.512654) (xy 121.983722 -234.488047) (xy 122.029738 -234.470595) (xy 122.077957 -234.460751)
			(xy 122.127132 -234.45877) (xy 122.175987 -234.464702) (xy 122.223258 -234.478394) (xy 122.26772 -234.499492)
			(xy 122.308223 -234.527448) (xy 122.343716 -234.56154) (xy 122.373281 -234.600884) (xy 122.396152 -234.644461)
			(xy 122.411736 -234.691142) (xy 122.419631 -234.739719) (xy 122.420126 -234.764326) (xy 122.748814 -234.764326)
			(xy 122.752774 -234.715272) (xy 122.764551 -234.667488) (xy 122.783842 -234.622212) (xy 122.810145 -234.580616)
			(xy 122.84278 -234.543779) (xy 122.880901 -234.512654) (xy 122.923522 -234.488047) (xy 122.969538 -234.470595)
			(xy 123.017757 -234.460751) (xy 123.066932 -234.45877) (xy 123.115787 -234.464702) (xy 123.163058 -234.478394)
			(xy 123.20752 -234.499492) (xy 123.248023 -234.527448) (xy 123.283516 -234.56154) (xy 123.313081 -234.600884)
			(xy 123.335952 -234.644461) (xy 123.351536 -234.691142) (xy 123.359431 -234.739719) (xy 123.359926 -234.764326)
			(xy 123.688868 -234.764326) (xy 123.692828 -234.715272) (xy 123.704605 -234.667488) (xy 123.723896 -234.622212)
			(xy 123.750199 -234.580616) (xy 123.782834 -234.543779) (xy 123.820955 -234.512654) (xy 123.863576 -234.488047)
			(xy 123.909592 -234.470595) (xy 123.957811 -234.460751) (xy 124.006986 -234.45877) (xy 124.055841 -234.464702)
			(xy 124.103112 -234.478394) (xy 124.147574 -234.499492) (xy 124.188077 -234.527448) (xy 124.22357 -234.56154)
			(xy 124.253135 -234.600884) (xy 124.276006 -234.644461) (xy 124.29159 -234.691142) (xy 124.299485 -234.739719)
			(xy 124.29998 -234.764326) (xy 124.628922 -234.764326) (xy 124.632882 -234.715272) (xy 124.644659 -234.667488)
			(xy 124.66395 -234.622212) (xy 124.690253 -234.580616) (xy 124.722888 -234.543779) (xy 124.761009 -234.512654)
			(xy 124.80363 -234.488047) (xy 124.849646 -234.470595) (xy 124.897865 -234.460751) (xy 124.94704 -234.45877)
			(xy 124.995895 -234.464702) (xy 125.043166 -234.478394) (xy 125.087628 -234.499492) (xy 125.128131 -234.527448)
			(xy 125.163624 -234.56154) (xy 125.193189 -234.600884) (xy 125.21606 -234.644461) (xy 125.231644 -234.691142)
			(xy 125.239539 -234.739719) (xy 125.240034 -234.764326) (xy 125.568976 -234.764326) (xy 125.572936 -234.715272)
			(xy 125.584713 -234.667488) (xy 125.604004 -234.622212) (xy 125.630307 -234.580616) (xy 125.662942 -234.543779)
			(xy 125.701063 -234.512654) (xy 125.743684 -234.488047) (xy 125.7897 -234.470595) (xy 125.837919 -234.460751)
			(xy 125.887094 -234.45877) (xy 125.935949 -234.464702) (xy 125.98322 -234.478394) (xy 126.027682 -234.499492)
			(xy 126.068185 -234.527448) (xy 126.103678 -234.56154) (xy 126.133243 -234.600884) (xy 126.156114 -234.644461)
			(xy 126.171698 -234.691142) (xy 126.179593 -234.739719) (xy 126.180088 -234.764326) (xy 126.50903 -234.764326)
			(xy 126.51299 -234.715272) (xy 126.524767 -234.667488) (xy 126.544058 -234.622212) (xy 126.570361 -234.580616)
			(xy 126.602996 -234.543779) (xy 126.641117 -234.512654) (xy 126.683738 -234.488047) (xy 126.729754 -234.470595)
			(xy 126.777973 -234.460751) (xy 126.827148 -234.45877) (xy 126.876003 -234.464702) (xy 126.923274 -234.478394)
			(xy 126.967736 -234.499492) (xy 127.008239 -234.527448) (xy 127.043732 -234.56154) (xy 127.073297 -234.600884)
			(xy 127.096168 -234.644461) (xy 127.111752 -234.691142) (xy 127.119647 -234.739719) (xy 127.120142 -234.764326)
			(xy 127.438399 -234.764326) (xy 127.442494 -234.713598) (xy 127.454673 -234.664184) (xy 127.474621 -234.617364)
			(xy 127.501822 -234.57435) (xy 127.53557 -234.536256) (xy 127.574992 -234.504069) (xy 127.619066 -234.478623)
			(xy 127.666652 -234.460576) (xy 127.716516 -234.450396) (xy 127.767368 -234.448347) (xy 127.817889 -234.454481)
			(xy 127.866773 -234.468641) (xy 127.912752 -234.490458) (xy 127.954636 -234.519368) (xy 127.99134 -234.554623)
			(xy 128.021913 -234.595309) (xy 128.045564 -234.640372) (xy 128.06168 -234.688646) (xy 128.069844 -234.73888)
			(xy 128.070356 -234.764326) (xy 128.388884 -234.764326) (xy 128.392844 -234.715272) (xy 128.404621 -234.667488)
			(xy 128.423912 -234.622212) (xy 128.450215 -234.580616) (xy 128.48285 -234.543779) (xy 128.520971 -234.512654)
			(xy 128.563592 -234.488047) (xy 128.609608 -234.470595) (xy 128.657827 -234.460751) (xy 128.707002 -234.45877)
			(xy 128.755857 -234.464702) (xy 128.803128 -234.478394) (xy 128.84759 -234.499492) (xy 128.888093 -234.527448)
			(xy 128.923586 -234.56154) (xy 128.953151 -234.600884) (xy 128.976022 -234.644461) (xy 128.991606 -234.691142)
			(xy 128.999501 -234.739719) (xy 128.999996 -234.764326) (xy 129.318507 -234.764326) (xy 129.322602 -234.713598)
			(xy 129.334781 -234.664184) (xy 129.354729 -234.617364) (xy 129.38193 -234.57435) (xy 129.415678 -234.536256)
			(xy 129.4551 -234.504069) (xy 129.499174 -234.478623) (xy 129.54676 -234.460576) (xy 129.596624 -234.450396)
			(xy 129.647476 -234.448347) (xy 129.697997 -234.454481) (xy 129.746881 -234.468641) (xy 129.79286 -234.490458)
			(xy 129.834744 -234.519368) (xy 129.871448 -234.554623) (xy 129.902021 -234.595309) (xy 129.925672 -234.640372)
			(xy 129.941788 -234.688646) (xy 129.949952 -234.73888) (xy 129.950464 -234.764326) (xy 129.949952 -234.789772)
			(xy 129.941788 -234.840006) (xy 129.925672 -234.88828) (xy 129.902021 -234.933343) (xy 129.871448 -234.974029)
			(xy 129.834744 -235.009284) (xy 129.79286 -235.038194) (xy 129.746881 -235.060011) (xy 129.697997 -235.074171)
			(xy 129.647476 -235.080305) (xy 129.596624 -235.078256) (xy 129.54676 -235.068076) (xy 129.499174 -235.050029)
			(xy 129.4551 -235.024583) (xy 129.415678 -234.992396) (xy 129.38193 -234.954302) (xy 129.354729 -234.911288)
			(xy 129.334781 -234.864468) (xy 129.322602 -234.815054) (xy 129.318507 -234.764326) (xy 128.999996 -234.764326)
			(xy 128.999501 -234.788933) (xy 128.991606 -234.83751) (xy 128.976022 -234.884191) (xy 128.953151 -234.927768)
			(xy 128.923586 -234.967112) (xy 128.888093 -235.001204) (xy 128.84759 -235.02916) (xy 128.803128 -235.050258)
			(xy 128.755857 -235.06395) (xy 128.707002 -235.069882) (xy 128.657827 -235.067901) (xy 128.609608 -235.058057)
			(xy 128.563592 -235.040605) (xy 128.520971 -235.015998) (xy 128.48285 -234.984873) (xy 128.450215 -234.948036)
			(xy 128.423912 -234.90644) (xy 128.404621 -234.861164) (xy 128.392844 -234.81338) (xy 128.388884 -234.764326)
			(xy 128.070356 -234.764326) (xy 128.069844 -234.789772) (xy 128.06168 -234.840006) (xy 128.045564 -234.88828)
			(xy 128.021913 -234.933343) (xy 127.99134 -234.974029) (xy 127.954636 -235.009284) (xy 127.912752 -235.038194)
			(xy 127.866773 -235.060011) (xy 127.817889 -235.074171) (xy 127.767368 -235.080305) (xy 127.716516 -235.078256)
			(xy 127.666652 -235.068076) (xy 127.619066 -235.050029) (xy 127.574992 -235.024583) (xy 127.53557 -234.992396)
			(xy 127.501822 -234.954302) (xy 127.474621 -234.911288) (xy 127.454673 -234.864468) (xy 127.442494 -234.815054)
			(xy 127.438399 -234.764326) (xy 127.120142 -234.764326) (xy 127.119647 -234.788933) (xy 127.111752 -234.83751)
			(xy 127.096168 -234.884191) (xy 127.073297 -234.927768) (xy 127.043732 -234.967112) (xy 127.008239 -235.001204)
			(xy 126.967736 -235.02916) (xy 126.923274 -235.050258) (xy 126.876003 -235.06395) (xy 126.827148 -235.069882)
			(xy 126.777973 -235.067901) (xy 126.729754 -235.058057) (xy 126.683738 -235.040605) (xy 126.641117 -235.015998)
			(xy 126.602996 -234.984873) (xy 126.570361 -234.948036) (xy 126.544058 -234.90644) (xy 126.524767 -234.861164)
			(xy 126.51299 -234.81338) (xy 126.50903 -234.764326) (xy 126.180088 -234.764326) (xy 126.179593 -234.788933)
			(xy 126.171698 -234.83751) (xy 126.156114 -234.884191) (xy 126.133243 -234.927768) (xy 126.103678 -234.967112)
			(xy 126.068185 -235.001204) (xy 126.027682 -235.02916) (xy 125.98322 -235.050258) (xy 125.935949 -235.06395)
			(xy 125.887094 -235.069882) (xy 125.837919 -235.067901) (xy 125.7897 -235.058057) (xy 125.743684 -235.040605)
			(xy 125.701063 -235.015998) (xy 125.662942 -234.984873) (xy 125.630307 -234.948036) (xy 125.604004 -234.90644)
			(xy 125.584713 -234.861164) (xy 125.572936 -234.81338) (xy 125.568976 -234.764326) (xy 125.240034 -234.764326)
			(xy 125.239539 -234.788933) (xy 125.231644 -234.83751) (xy 125.21606 -234.884191) (xy 125.193189 -234.927768)
			(xy 125.163624 -234.967112) (xy 125.128131 -235.001204) (xy 125.087628 -235.02916) (xy 125.043166 -235.050258)
			(xy 124.995895 -235.06395) (xy 124.94704 -235.069882) (xy 124.897865 -235.067901) (xy 124.849646 -235.058057)
			(xy 124.80363 -235.040605) (xy 124.761009 -235.015998) (xy 124.722888 -234.984873) (xy 124.690253 -234.948036)
			(xy 124.66395 -234.90644) (xy 124.644659 -234.861164) (xy 124.632882 -234.81338) (xy 124.628922 -234.764326)
			(xy 124.29998 -234.764326) (xy 124.299485 -234.788933) (xy 124.29159 -234.83751) (xy 124.276006 -234.884191)
			(xy 124.253135 -234.927768) (xy 124.22357 -234.967112) (xy 124.188077 -235.001204) (xy 124.147574 -235.02916)
			(xy 124.103112 -235.050258) (xy 124.055841 -235.06395) (xy 124.006986 -235.069882) (xy 123.957811 -235.067901)
			(xy 123.909592 -235.058057) (xy 123.863576 -235.040605) (xy 123.820955 -235.015998) (xy 123.782834 -234.984873)
			(xy 123.750199 -234.948036) (xy 123.723896 -234.90644) (xy 123.704605 -234.861164) (xy 123.692828 -234.81338)
			(xy 123.688868 -234.764326) (xy 123.359926 -234.764326) (xy 123.359431 -234.788933) (xy 123.351536 -234.83751)
			(xy 123.335952 -234.884191) (xy 123.313081 -234.927768) (xy 123.283516 -234.967112) (xy 123.248023 -235.001204)
			(xy 123.20752 -235.02916) (xy 123.163058 -235.050258) (xy 123.115787 -235.06395) (xy 123.066932 -235.069882)
			(xy 123.017757 -235.067901) (xy 122.969538 -235.058057) (xy 122.923522 -235.040605) (xy 122.880901 -235.015998)
			(xy 122.84278 -234.984873) (xy 122.810145 -234.948036) (xy 122.783842 -234.90644) (xy 122.764551 -234.861164)
			(xy 122.752774 -234.81338) (xy 122.748814 -234.764326) (xy 122.420126 -234.764326) (xy 122.419631 -234.788933)
			(xy 122.411736 -234.83751) (xy 122.396152 -234.884191) (xy 122.373281 -234.927768) (xy 122.343716 -234.967112)
			(xy 122.308223 -235.001204) (xy 122.26772 -235.02916) (xy 122.223258 -235.050258) (xy 122.175987 -235.06395)
			(xy 122.127132 -235.069882) (xy 122.077957 -235.067901) (xy 122.029738 -235.058057) (xy 121.983722 -235.040605)
			(xy 121.941101 -235.015998) (xy 121.90298 -234.984873) (xy 121.870345 -234.948036) (xy 121.844042 -234.90644)
			(xy 121.824751 -234.861164) (xy 121.812974 -234.81338) (xy 121.809014 -234.764326) (xy 121.480072 -234.764326)
			(xy 121.479577 -234.788933) (xy 121.471682 -234.83751) (xy 121.456098 -234.884191) (xy 121.433227 -234.927768)
			(xy 121.403662 -234.967112) (xy 121.368169 -235.001204) (xy 121.327666 -235.02916) (xy 121.283204 -235.050258)
			(xy 121.235933 -235.06395) (xy 121.187078 -235.069882) (xy 121.137903 -235.067901) (xy 121.089684 -235.058057)
			(xy 121.043668 -235.040605) (xy 121.001047 -235.015998) (xy 120.962926 -234.984873) (xy 120.930291 -234.948036)
			(xy 120.903988 -234.90644) (xy 120.884697 -234.861164) (xy 120.87292 -234.81338) (xy 120.86896 -234.764326)
			(xy 120.540018 -234.764326) (xy 120.539523 -234.788933) (xy 120.531628 -234.83751) (xy 120.516044 -234.884191)
			(xy 120.493173 -234.927768) (xy 120.463608 -234.967112) (xy 120.428115 -235.001204) (xy 120.387612 -235.02916)
			(xy 120.34315 -235.050258) (xy 120.295879 -235.06395) (xy 120.247024 -235.069882) (xy 120.197849 -235.067901)
			(xy 120.14963 -235.058057) (xy 120.103614 -235.040605) (xy 120.060993 -235.015998) (xy 120.022872 -234.984873)
			(xy 119.990237 -234.948036) (xy 119.963934 -234.90644) (xy 119.944643 -234.861164) (xy 119.932866 -234.81338)
			(xy 119.928906 -234.764326) (xy 119.599964 -234.764326) (xy 119.599469 -234.788933) (xy 119.591574 -234.83751)
			(xy 119.57599 -234.884191) (xy 119.553119 -234.927768) (xy 119.523554 -234.967112) (xy 119.488061 -235.001204)
			(xy 119.447558 -235.02916) (xy 119.403096 -235.050258) (xy 119.355825 -235.06395) (xy 119.30697 -235.069882)
			(xy 119.257795 -235.067901) (xy 119.209576 -235.058057) (xy 119.16356 -235.040605) (xy 119.120939 -235.015998)
			(xy 119.082818 -234.984873) (xy 119.050183 -234.948036) (xy 119.02388 -234.90644) (xy 119.004589 -234.861164)
			(xy 118.992812 -234.81338) (xy 118.988852 -234.764326) (xy 118.660164 -234.764326) (xy 118.659669 -234.788933)
			(xy 118.651774 -234.83751) (xy 118.63619 -234.884191) (xy 118.613319 -234.927768) (xy 118.583754 -234.967112)
			(xy 118.548261 -235.001204) (xy 118.507758 -235.02916) (xy 118.463296 -235.050258) (xy 118.416025 -235.06395)
			(xy 118.36717 -235.069882) (xy 118.317995 -235.067901) (xy 118.269776 -235.058057) (xy 118.22376 -235.040605)
			(xy 118.181139 -235.015998) (xy 118.143018 -234.984873) (xy 118.110383 -234.948036) (xy 118.08408 -234.90644)
			(xy 118.064789 -234.861164) (xy 118.053012 -234.81338) (xy 118.049052 -234.764326) (xy 117.72011 -234.764326)
			(xy 117.719615 -234.788933) (xy 117.71172 -234.83751) (xy 117.696136 -234.884191) (xy 117.673265 -234.927768)
			(xy 117.6437 -234.967112) (xy 117.608207 -235.001204) (xy 117.567704 -235.02916) (xy 117.523242 -235.050258)
			(xy 117.475971 -235.06395) (xy 117.427116 -235.069882) (xy 117.377941 -235.067901) (xy 117.329722 -235.058057)
			(xy 117.283706 -235.040605) (xy 117.241085 -235.015998) (xy 117.202964 -234.984873) (xy 117.170329 -234.948036)
			(xy 117.144026 -234.90644) (xy 117.124735 -234.861164) (xy 117.112958 -234.81338) (xy 117.108998 -234.764326)
			(xy 116.780056 -234.764326) (xy 116.779561 -234.788933) (xy 116.771666 -234.83751) (xy 116.756082 -234.884191)
			(xy 116.733211 -234.927768) (xy 116.703646 -234.967112) (xy 116.668153 -235.001204) (xy 116.62765 -235.02916)
			(xy 116.583188 -235.050258) (xy 116.535917 -235.06395) (xy 116.487062 -235.069882) (xy 116.437887 -235.067901)
			(xy 116.389668 -235.058057) (xy 116.343652 -235.040605) (xy 116.301031 -235.015998) (xy 116.26291 -234.984873)
			(xy 116.230275 -234.948036) (xy 116.203972 -234.90644) (xy 116.184681 -234.861164) (xy 116.172904 -234.81338)
			(xy 116.168944 -234.764326) (xy 115.840002 -234.764326) (xy 115.839507 -234.788933) (xy 115.831612 -234.83751)
			(xy 115.816028 -234.884191) (xy 115.793157 -234.927768) (xy 115.763592 -234.967112) (xy 115.728099 -235.001204)
			(xy 115.687596 -235.02916) (xy 115.643134 -235.050258) (xy 115.595863 -235.06395) (xy 115.547008 -235.069882)
			(xy 115.497833 -235.067901) (xy 115.449614 -235.058057) (xy 115.403598 -235.040605) (xy 115.360977 -235.015998)
			(xy 115.322856 -234.984873) (xy 115.290221 -234.948036) (xy 115.263918 -234.90644) (xy 115.244627 -234.861164)
			(xy 115.23285 -234.81338) (xy 115.22889 -234.764326) (xy 111.63427 -234.764326) (xy 110.824264 -235.574332)
			(xy 112.878882 -235.574332) (xy 112.882842 -235.525278) (xy 112.894619 -235.477494) (xy 112.91391 -235.432218)
			(xy 112.940213 -235.390622) (xy 112.972848 -235.353785) (xy 113.010969 -235.32266) (xy 113.05359 -235.298053)
			(xy 113.099606 -235.280601) (xy 113.147825 -235.270757) (xy 113.197 -235.268776) (xy 113.245855 -235.274708)
			(xy 113.293126 -235.2884) (xy 113.337588 -235.309498) (xy 113.378091 -235.337454) (xy 113.413584 -235.371546)
			(xy 113.443149 -235.41089) (xy 113.46602 -235.454467) (xy 113.481604 -235.501148) (xy 113.489499 -235.549725)
			(xy 113.489994 -235.574332) (xy 113.818936 -235.574332) (xy 113.822896 -235.525278) (xy 113.834673 -235.477494)
			(xy 113.853964 -235.432218) (xy 113.880267 -235.390622) (xy 113.912902 -235.353785) (xy 113.951023 -235.32266)
			(xy 113.993644 -235.298053) (xy 114.03966 -235.280601) (xy 114.087879 -235.270757) (xy 114.137054 -235.268776)
			(xy 114.185909 -235.274708) (xy 114.23318 -235.2884) (xy 114.277642 -235.309498) (xy 114.318145 -235.337454)
			(xy 114.353638 -235.371546) (xy 114.383203 -235.41089) (xy 114.406074 -235.454467) (xy 114.421658 -235.501148)
			(xy 114.429553 -235.549725) (xy 114.430048 -235.574332) (xy 114.75899 -235.574332) (xy 114.76295 -235.525278)
			(xy 114.774727 -235.477494) (xy 114.794018 -235.432218) (xy 114.820321 -235.390622) (xy 114.852956 -235.353785)
			(xy 114.891077 -235.32266) (xy 114.933698 -235.298053) (xy 114.979714 -235.280601) (xy 115.027933 -235.270757)
			(xy 115.077108 -235.268776) (xy 115.125963 -235.274708) (xy 115.173234 -235.2884) (xy 115.217696 -235.309498)
			(xy 115.258199 -235.337454) (xy 115.293692 -235.371546) (xy 115.323257 -235.41089) (xy 115.346128 -235.454467)
			(xy 115.361712 -235.501148) (xy 115.369607 -235.549725) (xy 115.370102 -235.574332) (xy 115.699044 -235.574332)
			(xy 115.703004 -235.525278) (xy 115.714781 -235.477494) (xy 115.734072 -235.432218) (xy 115.760375 -235.390622)
			(xy 115.79301 -235.353785) (xy 115.831131 -235.32266) (xy 115.873752 -235.298053) (xy 115.919768 -235.280601)
			(xy 115.967987 -235.270757) (xy 116.017162 -235.268776) (xy 116.066017 -235.274708) (xy 116.113288 -235.2884)
			(xy 116.15775 -235.309498) (xy 116.198253 -235.337454) (xy 116.233746 -235.371546) (xy 116.263311 -235.41089)
			(xy 116.286182 -235.454467) (xy 116.301766 -235.501148) (xy 116.309661 -235.549725) (xy 116.310156 -235.574332)
			(xy 116.638844 -235.574332) (xy 116.642804 -235.525278) (xy 116.654581 -235.477494) (xy 116.673872 -235.432218)
			(xy 116.700175 -235.390622) (xy 116.73281 -235.353785) (xy 116.770931 -235.32266) (xy 116.813552 -235.298053)
			(xy 116.859568 -235.280601) (xy 116.907787 -235.270757) (xy 116.956962 -235.268776) (xy 117.005817 -235.274708)
			(xy 117.053088 -235.2884) (xy 117.09755 -235.309498) (xy 117.138053 -235.337454) (xy 117.173546 -235.371546)
			(xy 117.203111 -235.41089) (xy 117.225982 -235.454467) (xy 117.241566 -235.501148) (xy 117.249461 -235.549725)
			(xy 117.249956 -235.574332) (xy 117.578898 -235.574332) (xy 117.582858 -235.525278) (xy 117.594635 -235.477494)
			(xy 117.613926 -235.432218) (xy 117.640229 -235.390622) (xy 117.672864 -235.353785) (xy 117.710985 -235.32266)
			(xy 117.753606 -235.298053) (xy 117.799622 -235.280601) (xy 117.847841 -235.270757) (xy 117.897016 -235.268776)
			(xy 117.945871 -235.274708) (xy 117.993142 -235.2884) (xy 118.037604 -235.309498) (xy 118.078107 -235.337454)
			(xy 118.1136 -235.371546) (xy 118.143165 -235.41089) (xy 118.166036 -235.454467) (xy 118.18162 -235.501148)
			(xy 118.189515 -235.549725) (xy 118.19001 -235.574332) (xy 118.518952 -235.574332) (xy 118.522912 -235.525278)
			(xy 118.534689 -235.477494) (xy 118.55398 -235.432218) (xy 118.580283 -235.390622) (xy 118.612918 -235.353785)
			(xy 118.651039 -235.32266) (xy 118.69366 -235.298053) (xy 118.739676 -235.280601) (xy 118.787895 -235.270757)
			(xy 118.83707 -235.268776) (xy 118.885925 -235.274708) (xy 118.933196 -235.2884) (xy 118.977658 -235.309498)
			(xy 119.018161 -235.337454) (xy 119.053654 -235.371546) (xy 119.083219 -235.41089) (xy 119.10609 -235.454467)
			(xy 119.121674 -235.501148) (xy 119.129569 -235.549725) (xy 119.130064 -235.574332) (xy 119.459006 -235.574332)
			(xy 119.462966 -235.525278) (xy 119.474743 -235.477494) (xy 119.494034 -235.432218) (xy 119.520337 -235.390622)
			(xy 119.552972 -235.353785) (xy 119.591093 -235.32266) (xy 119.633714 -235.298053) (xy 119.67973 -235.280601)
			(xy 119.727949 -235.270757) (xy 119.777124 -235.268776) (xy 119.825979 -235.274708) (xy 119.87325 -235.2884)
			(xy 119.917712 -235.309498) (xy 119.958215 -235.337454) (xy 119.993708 -235.371546) (xy 120.023273 -235.41089)
			(xy 120.046144 -235.454467) (xy 120.061728 -235.501148) (xy 120.069623 -235.549725) (xy 120.070118 -235.574332)
			(xy 120.398806 -235.574332) (xy 120.402766 -235.525278) (xy 120.414543 -235.477494) (xy 120.433834 -235.432218)
			(xy 120.460137 -235.390622) (xy 120.492772 -235.353785) (xy 120.530893 -235.32266) (xy 120.573514 -235.298053)
			(xy 120.61953 -235.280601) (xy 120.667749 -235.270757) (xy 120.716924 -235.268776) (xy 120.765779 -235.274708)
			(xy 120.81305 -235.2884) (xy 120.857512 -235.309498) (xy 120.898015 -235.337454) (xy 120.933508 -235.371546)
			(xy 120.963073 -235.41089) (xy 120.985944 -235.454467) (xy 121.001528 -235.501148) (xy 121.009423 -235.549725)
			(xy 121.009918 -235.574332) (xy 121.33886 -235.574332) (xy 121.34282 -235.525278) (xy 121.354597 -235.477494)
			(xy 121.373888 -235.432218) (xy 121.400191 -235.390622) (xy 121.432826 -235.353785) (xy 121.470947 -235.32266)
			(xy 121.513568 -235.298053) (xy 121.559584 -235.280601) (xy 121.607803 -235.270757) (xy 121.656978 -235.268776)
			(xy 121.705833 -235.274708) (xy 121.753104 -235.2884) (xy 121.797566 -235.309498) (xy 121.838069 -235.337454)
			(xy 121.873562 -235.371546) (xy 121.903127 -235.41089) (xy 121.925998 -235.454467) (xy 121.941582 -235.501148)
			(xy 121.949477 -235.549725) (xy 121.949972 -235.574332) (xy 122.278914 -235.574332) (xy 122.282874 -235.525278)
			(xy 122.294651 -235.477494) (xy 122.313942 -235.432218) (xy 122.340245 -235.390622) (xy 122.37288 -235.353785)
			(xy 122.411001 -235.32266) (xy 122.453622 -235.298053) (xy 122.499638 -235.280601) (xy 122.547857 -235.270757)
			(xy 122.597032 -235.268776) (xy 122.645887 -235.274708) (xy 122.693158 -235.2884) (xy 122.73762 -235.309498)
			(xy 122.778123 -235.337454) (xy 122.813616 -235.371546) (xy 122.843181 -235.41089) (xy 122.866052 -235.454467)
			(xy 122.881636 -235.501148) (xy 122.889531 -235.549725) (xy 122.890026 -235.574332) (xy 123.218968 -235.574332)
			(xy 123.222928 -235.525278) (xy 123.234705 -235.477494) (xy 123.253996 -235.432218) (xy 123.280299 -235.390622)
			(xy 123.312934 -235.353785) (xy 123.351055 -235.32266) (xy 123.393676 -235.298053) (xy 123.439692 -235.280601)
			(xy 123.487911 -235.270757) (xy 123.537086 -235.268776) (xy 123.585941 -235.274708) (xy 123.633212 -235.2884)
			(xy 123.677674 -235.309498) (xy 123.718177 -235.337454) (xy 123.75367 -235.371546) (xy 123.783235 -235.41089)
			(xy 123.806106 -235.454467) (xy 123.82169 -235.501148) (xy 123.829585 -235.549725) (xy 123.83008 -235.574332)
			(xy 124.159022 -235.574332) (xy 124.162982 -235.525278) (xy 124.174759 -235.477494) (xy 124.19405 -235.432218)
			(xy 124.220353 -235.390622) (xy 124.252988 -235.353785) (xy 124.291109 -235.32266) (xy 124.33373 -235.298053)
			(xy 124.379746 -235.280601) (xy 124.427965 -235.270757) (xy 124.47714 -235.268776) (xy 124.525995 -235.274708)
			(xy 124.573266 -235.2884) (xy 124.617728 -235.309498) (xy 124.658231 -235.337454) (xy 124.693724 -235.371546)
			(xy 124.723289 -235.41089) (xy 124.74616 -235.454467) (xy 124.761744 -235.501148) (xy 124.769639 -235.549725)
			(xy 124.770134 -235.574332) (xy 125.098822 -235.574332) (xy 125.102782 -235.525278) (xy 125.114559 -235.477494)
			(xy 125.13385 -235.432218) (xy 125.160153 -235.390622) (xy 125.192788 -235.353785) (xy 125.230909 -235.32266)
			(xy 125.27353 -235.298053) (xy 125.319546 -235.280601) (xy 125.367765 -235.270757) (xy 125.41694 -235.268776)
			(xy 125.465795 -235.274708) (xy 125.513066 -235.2884) (xy 125.557528 -235.309498) (xy 125.598031 -235.337454)
			(xy 125.633524 -235.371546) (xy 125.663089 -235.41089) (xy 125.68596 -235.454467) (xy 125.701544 -235.501148)
			(xy 125.709439 -235.549725) (xy 125.709934 -235.574332) (xy 126.038876 -235.574332) (xy 126.042836 -235.525278)
			(xy 126.054613 -235.477494) (xy 126.073904 -235.432218) (xy 126.100207 -235.390622) (xy 126.132842 -235.353785)
			(xy 126.170963 -235.32266) (xy 126.213584 -235.298053) (xy 126.2596 -235.280601) (xy 126.307819 -235.270757)
			(xy 126.356994 -235.268776) (xy 126.405849 -235.274708) (xy 126.45312 -235.2884) (xy 126.497582 -235.309498)
			(xy 126.538085 -235.337454) (xy 126.573578 -235.371546) (xy 126.603143 -235.41089) (xy 126.626014 -235.454467)
			(xy 126.641598 -235.501148) (xy 126.649493 -235.549725) (xy 126.649988 -235.574332) (xy 126.97893 -235.574332)
			(xy 126.98289 -235.525278) (xy 126.994667 -235.477494) (xy 127.013958 -235.432218) (xy 127.040261 -235.390622)
			(xy 127.072896 -235.353785) (xy 127.111017 -235.32266) (xy 127.153638 -235.298053) (xy 127.199654 -235.280601)
			(xy 127.247873 -235.270757) (xy 127.297048 -235.268776) (xy 127.345903 -235.274708) (xy 127.393174 -235.2884)
			(xy 127.437636 -235.309498) (xy 127.478139 -235.337454) (xy 127.513632 -235.371546) (xy 127.543197 -235.41089)
			(xy 127.566068 -235.454467) (xy 127.581652 -235.501148) (xy 127.589547 -235.549725) (xy 127.590042 -235.574332)
			(xy 127.908553 -235.574332) (xy 127.912648 -235.523604) (xy 127.924827 -235.47419) (xy 127.944775 -235.42737)
			(xy 127.971976 -235.384356) (xy 128.005724 -235.346262) (xy 128.045146 -235.314075) (xy 128.08922 -235.288629)
			(xy 128.136806 -235.270582) (xy 128.18667 -235.260402) (xy 128.237522 -235.258353) (xy 128.288043 -235.264487)
			(xy 128.336927 -235.278647) (xy 128.382906 -235.300464) (xy 128.42479 -235.329374) (xy 128.461494 -235.364629)
			(xy 128.492067 -235.405315) (xy 128.515718 -235.450378) (xy 128.531834 -235.498652) (xy 128.539998 -235.548886)
			(xy 128.54051 -235.574332) (xy 128.848607 -235.574332) (xy 128.852702 -235.523604) (xy 128.864881 -235.47419)
			(xy 128.884829 -235.42737) (xy 128.91203 -235.384356) (xy 128.945778 -235.346262) (xy 128.9852 -235.314075)
			(xy 129.029274 -235.288629) (xy 129.07686 -235.270582) (xy 129.126724 -235.260402) (xy 129.177576 -235.258353)
			(xy 129.228097 -235.264487) (xy 129.276981 -235.278647) (xy 129.32296 -235.300464) (xy 129.364844 -235.329374)
			(xy 129.401548 -235.364629) (xy 129.432121 -235.405315) (xy 129.455772 -235.450378) (xy 129.471888 -235.498652)
			(xy 129.480052 -235.548886) (xy 129.480564 -235.574332) (xy 129.480052 -235.599778) (xy 129.471888 -235.650012)
			(xy 129.455772 -235.698286) (xy 129.432121 -235.743349) (xy 129.401548 -235.784035) (xy 129.364844 -235.81929)
			(xy 129.32296 -235.8482) (xy 129.276981 -235.870017) (xy 129.228097 -235.884177) (xy 129.177576 -235.890311)
			(xy 129.126724 -235.888262) (xy 129.07686 -235.878082) (xy 129.029274 -235.860035) (xy 128.9852 -235.834589)
			(xy 128.945778 -235.802402) (xy 128.91203 -235.764308) (xy 128.884829 -235.721294) (xy 128.864881 -235.674474)
			(xy 128.852702 -235.62506) (xy 128.848607 -235.574332) (xy 128.54051 -235.574332) (xy 128.539998 -235.599778)
			(xy 128.531834 -235.650012) (xy 128.515718 -235.698286) (xy 128.492067 -235.743349) (xy 128.461494 -235.784035)
			(xy 128.42479 -235.81929) (xy 128.382906 -235.8482) (xy 128.336927 -235.870017) (xy 128.288043 -235.884177)
			(xy 128.237522 -235.890311) (xy 128.18667 -235.888262) (xy 128.136806 -235.878082) (xy 128.08922 -235.860035)
			(xy 128.045146 -235.834589) (xy 128.005724 -235.802402) (xy 127.971976 -235.764308) (xy 127.944775 -235.721294)
			(xy 127.924827 -235.674474) (xy 127.912648 -235.62506) (xy 127.908553 -235.574332) (xy 127.590042 -235.574332)
			(xy 127.589547 -235.598939) (xy 127.581652 -235.647516) (xy 127.566068 -235.694197) (xy 127.543197 -235.737774)
			(xy 127.513632 -235.777118) (xy 127.478139 -235.81121) (xy 127.437636 -235.839166) (xy 127.393174 -235.860264)
			(xy 127.345903 -235.873956) (xy 127.297048 -235.879888) (xy 127.247873 -235.877907) (xy 127.199654 -235.868063)
			(xy 127.153638 -235.850611) (xy 127.111017 -235.826004) (xy 127.072896 -235.794879) (xy 127.040261 -235.758042)
			(xy 127.013958 -235.716446) (xy 126.994667 -235.67117) (xy 126.98289 -235.623386) (xy 126.97893 -235.574332)
			(xy 126.649988 -235.574332) (xy 126.649493 -235.598939) (xy 126.641598 -235.647516) (xy 126.626014 -235.694197)
			(xy 126.603143 -235.737774) (xy 126.573578 -235.777118) (xy 126.538085 -235.81121) (xy 126.497582 -235.839166)
			(xy 126.45312 -235.860264) (xy 126.405849 -235.873956) (xy 126.356994 -235.879888) (xy 126.307819 -235.877907)
			(xy 126.2596 -235.868063) (xy 126.213584 -235.850611) (xy 126.170963 -235.826004) (xy 126.132842 -235.794879)
			(xy 126.100207 -235.758042) (xy 126.073904 -235.716446) (xy 126.054613 -235.67117) (xy 126.042836 -235.623386)
			(xy 126.038876 -235.574332) (xy 125.709934 -235.574332) (xy 125.709439 -235.598939) (xy 125.701544 -235.647516)
			(xy 125.68596 -235.694197) (xy 125.663089 -235.737774) (xy 125.633524 -235.777118) (xy 125.598031 -235.81121)
			(xy 125.557528 -235.839166) (xy 125.513066 -235.860264) (xy 125.465795 -235.873956) (xy 125.41694 -235.879888)
			(xy 125.367765 -235.877907) (xy 125.319546 -235.868063) (xy 125.27353 -235.850611) (xy 125.230909 -235.826004)
			(xy 125.192788 -235.794879) (xy 125.160153 -235.758042) (xy 125.13385 -235.716446) (xy 125.114559 -235.67117)
			(xy 125.102782 -235.623386) (xy 125.098822 -235.574332) (xy 124.770134 -235.574332) (xy 124.769639 -235.598939)
			(xy 124.761744 -235.647516) (xy 124.74616 -235.694197) (xy 124.723289 -235.737774) (xy 124.693724 -235.777118)
			(xy 124.658231 -235.81121) (xy 124.617728 -235.839166) (xy 124.573266 -235.860264) (xy 124.525995 -235.873956)
			(xy 124.47714 -235.879888) (xy 124.427965 -235.877907) (xy 124.379746 -235.868063) (xy 124.33373 -235.850611)
			(xy 124.291109 -235.826004) (xy 124.252988 -235.794879) (xy 124.220353 -235.758042) (xy 124.19405 -235.716446)
			(xy 124.174759 -235.67117) (xy 124.162982 -235.623386) (xy 124.159022 -235.574332) (xy 123.83008 -235.574332)
			(xy 123.829585 -235.598939) (xy 123.82169 -235.647516) (xy 123.806106 -235.694197) (xy 123.783235 -235.737774)
			(xy 123.75367 -235.777118) (xy 123.718177 -235.81121) (xy 123.677674 -235.839166) (xy 123.633212 -235.860264)
			(xy 123.585941 -235.873956) (xy 123.537086 -235.879888) (xy 123.487911 -235.877907) (xy 123.439692 -235.868063)
			(xy 123.393676 -235.850611) (xy 123.351055 -235.826004) (xy 123.312934 -235.794879) (xy 123.280299 -235.758042)
			(xy 123.253996 -235.716446) (xy 123.234705 -235.67117) (xy 123.222928 -235.623386) (xy 123.218968 -235.574332)
			(xy 122.890026 -235.574332) (xy 122.889531 -235.598939) (xy 122.881636 -235.647516) (xy 122.866052 -235.694197)
			(xy 122.843181 -235.737774) (xy 122.813616 -235.777118) (xy 122.778123 -235.81121) (xy 122.73762 -235.839166)
			(xy 122.693158 -235.860264) (xy 122.645887 -235.873956) (xy 122.597032 -235.879888) (xy 122.547857 -235.877907)
			(xy 122.499638 -235.868063) (xy 122.453622 -235.850611) (xy 122.411001 -235.826004) (xy 122.37288 -235.794879)
			(xy 122.340245 -235.758042) (xy 122.313942 -235.716446) (xy 122.294651 -235.67117) (xy 122.282874 -235.623386)
			(xy 122.278914 -235.574332) (xy 121.949972 -235.574332) (xy 121.949477 -235.598939) (xy 121.941582 -235.647516)
			(xy 121.925998 -235.694197) (xy 121.903127 -235.737774) (xy 121.873562 -235.777118) (xy 121.838069 -235.81121)
			(xy 121.797566 -235.839166) (xy 121.753104 -235.860264) (xy 121.705833 -235.873956) (xy 121.656978 -235.879888)
			(xy 121.607803 -235.877907) (xy 121.559584 -235.868063) (xy 121.513568 -235.850611) (xy 121.470947 -235.826004)
			(xy 121.432826 -235.794879) (xy 121.400191 -235.758042) (xy 121.373888 -235.716446) (xy 121.354597 -235.67117)
			(xy 121.34282 -235.623386) (xy 121.33886 -235.574332) (xy 121.009918 -235.574332) (xy 121.009423 -235.598939)
			(xy 121.001528 -235.647516) (xy 120.985944 -235.694197) (xy 120.963073 -235.737774) (xy 120.933508 -235.777118)
			(xy 120.898015 -235.81121) (xy 120.857512 -235.839166) (xy 120.81305 -235.860264) (xy 120.765779 -235.873956)
			(xy 120.716924 -235.879888) (xy 120.667749 -235.877907) (xy 120.61953 -235.868063) (xy 120.573514 -235.850611)
			(xy 120.530893 -235.826004) (xy 120.492772 -235.794879) (xy 120.460137 -235.758042) (xy 120.433834 -235.716446)
			(xy 120.414543 -235.67117) (xy 120.402766 -235.623386) (xy 120.398806 -235.574332) (xy 120.070118 -235.574332)
			(xy 120.069623 -235.598939) (xy 120.061728 -235.647516) (xy 120.046144 -235.694197) (xy 120.023273 -235.737774)
			(xy 119.993708 -235.777118) (xy 119.958215 -235.81121) (xy 119.917712 -235.839166) (xy 119.87325 -235.860264)
			(xy 119.825979 -235.873956) (xy 119.777124 -235.879888) (xy 119.727949 -235.877907) (xy 119.67973 -235.868063)
			(xy 119.633714 -235.850611) (xy 119.591093 -235.826004) (xy 119.552972 -235.794879) (xy 119.520337 -235.758042)
			(xy 119.494034 -235.716446) (xy 119.474743 -235.67117) (xy 119.462966 -235.623386) (xy 119.459006 -235.574332)
			(xy 119.130064 -235.574332) (xy 119.129569 -235.598939) (xy 119.121674 -235.647516) (xy 119.10609 -235.694197)
			(xy 119.083219 -235.737774) (xy 119.053654 -235.777118) (xy 119.018161 -235.81121) (xy 118.977658 -235.839166)
			(xy 118.933196 -235.860264) (xy 118.885925 -235.873956) (xy 118.83707 -235.879888) (xy 118.787895 -235.877907)
			(xy 118.739676 -235.868063) (xy 118.69366 -235.850611) (xy 118.651039 -235.826004) (xy 118.612918 -235.794879)
			(xy 118.580283 -235.758042) (xy 118.55398 -235.716446) (xy 118.534689 -235.67117) (xy 118.522912 -235.623386)
			(xy 118.518952 -235.574332) (xy 118.19001 -235.574332) (xy 118.189515 -235.598939) (xy 118.18162 -235.647516)
			(xy 118.166036 -235.694197) (xy 118.143165 -235.737774) (xy 118.1136 -235.777118) (xy 118.078107 -235.81121)
			(xy 118.037604 -235.839166) (xy 117.993142 -235.860264) (xy 117.945871 -235.873956) (xy 117.897016 -235.879888)
			(xy 117.847841 -235.877907) (xy 117.799622 -235.868063) (xy 117.753606 -235.850611) (xy 117.710985 -235.826004)
			(xy 117.672864 -235.794879) (xy 117.640229 -235.758042) (xy 117.613926 -235.716446) (xy 117.594635 -235.67117)
			(xy 117.582858 -235.623386) (xy 117.578898 -235.574332) (xy 117.249956 -235.574332) (xy 117.249461 -235.598939)
			(xy 117.241566 -235.647516) (xy 117.225982 -235.694197) (xy 117.203111 -235.737774) (xy 117.173546 -235.777118)
			(xy 117.138053 -235.81121) (xy 117.09755 -235.839166) (xy 117.053088 -235.860264) (xy 117.005817 -235.873956)
			(xy 116.956962 -235.879888) (xy 116.907787 -235.877907) (xy 116.859568 -235.868063) (xy 116.813552 -235.850611)
			(xy 116.770931 -235.826004) (xy 116.73281 -235.794879) (xy 116.700175 -235.758042) (xy 116.673872 -235.716446)
			(xy 116.654581 -235.67117) (xy 116.642804 -235.623386) (xy 116.638844 -235.574332) (xy 116.310156 -235.574332)
			(xy 116.309661 -235.598939) (xy 116.301766 -235.647516) (xy 116.286182 -235.694197) (xy 116.263311 -235.737774)
			(xy 116.233746 -235.777118) (xy 116.198253 -235.81121) (xy 116.15775 -235.839166) (xy 116.113288 -235.860264)
			(xy 116.066017 -235.873956) (xy 116.017162 -235.879888) (xy 115.967987 -235.877907) (xy 115.919768 -235.868063)
			(xy 115.873752 -235.850611) (xy 115.831131 -235.826004) (xy 115.79301 -235.794879) (xy 115.760375 -235.758042)
			(xy 115.734072 -235.716446) (xy 115.714781 -235.67117) (xy 115.703004 -235.623386) (xy 115.699044 -235.574332)
			(xy 115.370102 -235.574332) (xy 115.369607 -235.598939) (xy 115.361712 -235.647516) (xy 115.346128 -235.694197)
			(xy 115.323257 -235.737774) (xy 115.293692 -235.777118) (xy 115.258199 -235.81121) (xy 115.217696 -235.839166)
			(xy 115.173234 -235.860264) (xy 115.125963 -235.873956) (xy 115.077108 -235.879888) (xy 115.027933 -235.877907)
			(xy 114.979714 -235.868063) (xy 114.933698 -235.850611) (xy 114.891077 -235.826004) (xy 114.852956 -235.794879)
			(xy 114.820321 -235.758042) (xy 114.794018 -235.716446) (xy 114.774727 -235.67117) (xy 114.76295 -235.623386)
			(xy 114.75899 -235.574332) (xy 114.430048 -235.574332) (xy 114.429553 -235.598939) (xy 114.421658 -235.647516)
			(xy 114.406074 -235.694197) (xy 114.383203 -235.737774) (xy 114.353638 -235.777118) (xy 114.318145 -235.81121)
			(xy 114.277642 -235.839166) (xy 114.23318 -235.860264) (xy 114.185909 -235.873956) (xy 114.137054 -235.879888)
			(xy 114.087879 -235.877907) (xy 114.03966 -235.868063) (xy 113.993644 -235.850611) (xy 113.951023 -235.826004)
			(xy 113.912902 -235.794879) (xy 113.880267 -235.758042) (xy 113.853964 -235.716446) (xy 113.834673 -235.67117)
			(xy 113.822896 -235.623386) (xy 113.818936 -235.574332) (xy 113.489994 -235.574332) (xy 113.489499 -235.598939)
			(xy 113.481604 -235.647516) (xy 113.46602 -235.694197) (xy 113.443149 -235.737774) (xy 113.413584 -235.777118)
			(xy 113.378091 -235.81121) (xy 113.337588 -235.839166) (xy 113.293126 -235.860264) (xy 113.245855 -235.873956)
			(xy 113.197 -235.879888) (xy 113.147825 -235.877907) (xy 113.099606 -235.868063) (xy 113.05359 -235.850611)
			(xy 113.010969 -235.826004) (xy 112.972848 -235.794879) (xy 112.940213 -235.758042) (xy 112.91391 -235.716446)
			(xy 112.894619 -235.67117) (xy 112.882842 -235.623386) (xy 112.878882 -235.574332) (xy 110.824264 -235.574332)
			(xy 110.47222 -235.926376) (xy 110.465108 -235.932218) (xy 110.428278 -235.957364) (xy 110.419134 -235.968794)
			(xy 110.41634 -235.975652) (xy 110.398491 -236.018207) (xy 110.356432 -236.100355) (xy 110.307411 -236.178548)
			(xy 110.251798 -236.252198) (xy 110.221268 -236.286802) (xy 110.214918 -236.29366) (xy 110.201456 -236.328458)
			(xy 110.20298 -236.33938) (xy 110.204527 -236.350555) (xy 110.206178 -236.373057) (xy 110.206282 -236.384338)
			(xy 113.349036 -236.384338) (xy 113.352996 -236.335284) (xy 113.364773 -236.2875) (xy 113.384064 -236.242224)
			(xy 113.410367 -236.200628) (xy 113.443002 -236.163791) (xy 113.481123 -236.132666) (xy 113.523744 -236.108059)
			(xy 113.56976 -236.090607) (xy 113.617979 -236.080763) (xy 113.667154 -236.078782) (xy 113.716009 -236.084714)
			(xy 113.76328 -236.098406) (xy 113.807742 -236.119504) (xy 113.848245 -236.14746) (xy 113.883738 -236.181552)
			(xy 113.913303 -236.220896) (xy 113.936174 -236.264473) (xy 113.951758 -236.311154) (xy 113.959653 -236.359731)
			(xy 113.960148 -236.384338) (xy 114.288836 -236.384338) (xy 114.292796 -236.335284) (xy 114.304573 -236.2875)
			(xy 114.323864 -236.242224) (xy 114.350167 -236.200628) (xy 114.382802 -236.163791) (xy 114.420923 -236.132666)
			(xy 114.463544 -236.108059) (xy 114.50956 -236.090607) (xy 114.557779 -236.080763) (xy 114.606954 -236.078782)
			(xy 114.655809 -236.084714) (xy 114.70308 -236.098406) (xy 114.747542 -236.119504) (xy 114.788045 -236.14746)
			(xy 114.823538 -236.181552) (xy 114.853103 -236.220896) (xy 114.875974 -236.264473) (xy 114.891558 -236.311154)
			(xy 114.899453 -236.359731) (xy 114.899948 -236.384338) (xy 115.22889 -236.384338) (xy 115.23285 -236.335284)
			(xy 115.244627 -236.2875) (xy 115.263918 -236.242224) (xy 115.290221 -236.200628) (xy 115.322856 -236.163791)
			(xy 115.360977 -236.132666) (xy 115.403598 -236.108059) (xy 115.449614 -236.090607) (xy 115.497833 -236.080763)
			(xy 115.547008 -236.078782) (xy 115.595863 -236.084714) (xy 115.643134 -236.098406) (xy 115.687596 -236.119504)
			(xy 115.728099 -236.14746) (xy 115.763592 -236.181552) (xy 115.793157 -236.220896) (xy 115.816028 -236.264473)
			(xy 115.831612 -236.311154) (xy 115.839507 -236.359731) (xy 115.840002 -236.384338) (xy 118.049052 -236.384338)
			(xy 118.053012 -236.335284) (xy 118.064789 -236.2875) (xy 118.08408 -236.242224) (xy 118.110383 -236.200628)
			(xy 118.143018 -236.163791) (xy 118.181139 -236.132666) (xy 118.22376 -236.108059) (xy 118.269776 -236.090607)
			(xy 118.317995 -236.080763) (xy 118.36717 -236.078782) (xy 118.416025 -236.084714) (xy 118.463296 -236.098406)
			(xy 118.507758 -236.119504) (xy 118.548261 -236.14746) (xy 118.583754 -236.181552) (xy 118.613319 -236.220896)
			(xy 118.63619 -236.264473) (xy 118.651774 -236.311154) (xy 118.659669 -236.359731) (xy 118.660164 -236.384338)
			(xy 120.86896 -236.384338) (xy 120.87292 -236.335284) (xy 120.884697 -236.2875) (xy 120.903988 -236.242224)
			(xy 120.930291 -236.200628) (xy 120.962926 -236.163791) (xy 121.001047 -236.132666) (xy 121.043668 -236.108059)
			(xy 121.089684 -236.090607) (xy 121.137903 -236.080763) (xy 121.187078 -236.078782) (xy 121.235933 -236.084714)
			(xy 121.283204 -236.098406) (xy 121.327666 -236.119504) (xy 121.368169 -236.14746) (xy 121.403662 -236.181552)
			(xy 121.433227 -236.220896) (xy 121.456098 -236.264473) (xy 121.471682 -236.311154) (xy 121.479577 -236.359731)
			(xy 121.480072 -236.384338) (xy 121.809014 -236.384338) (xy 121.812974 -236.335284) (xy 121.824751 -236.2875)
			(xy 121.844042 -236.242224) (xy 121.870345 -236.200628) (xy 121.90298 -236.163791) (xy 121.941101 -236.132666)
			(xy 121.983722 -236.108059) (xy 122.029738 -236.090607) (xy 122.077957 -236.080763) (xy 122.127132 -236.078782)
			(xy 122.175987 -236.084714) (xy 122.223258 -236.098406) (xy 122.26772 -236.119504) (xy 122.308223 -236.14746)
			(xy 122.343716 -236.181552) (xy 122.373281 -236.220896) (xy 122.396152 -236.264473) (xy 122.411736 -236.311154)
			(xy 122.419631 -236.359731) (xy 122.420126 -236.384338) (xy 122.748814 -236.384338) (xy 122.752774 -236.335284)
			(xy 122.764551 -236.2875) (xy 122.783842 -236.242224) (xy 122.810145 -236.200628) (xy 122.84278 -236.163791)
			(xy 122.880901 -236.132666) (xy 122.923522 -236.108059) (xy 122.969538 -236.090607) (xy 123.017757 -236.080763)
			(xy 123.066932 -236.078782) (xy 123.115787 -236.084714) (xy 123.163058 -236.098406) (xy 123.20752 -236.119504)
			(xy 123.248023 -236.14746) (xy 123.283516 -236.181552) (xy 123.313081 -236.220896) (xy 123.335952 -236.264473)
			(xy 123.351536 -236.311154) (xy 123.359431 -236.359731) (xy 123.359926 -236.384338) (xy 123.688868 -236.384338)
			(xy 123.692828 -236.335284) (xy 123.704605 -236.2875) (xy 123.723896 -236.242224) (xy 123.750199 -236.200628)
			(xy 123.782834 -236.163791) (xy 123.820955 -236.132666) (xy 123.863576 -236.108059) (xy 123.909592 -236.090607)
			(xy 123.957811 -236.080763) (xy 124.006986 -236.078782) (xy 124.055841 -236.084714) (xy 124.103112 -236.098406)
			(xy 124.147574 -236.119504) (xy 124.188077 -236.14746) (xy 124.22357 -236.181552) (xy 124.253135 -236.220896)
			(xy 124.276006 -236.264473) (xy 124.29159 -236.311154) (xy 124.299485 -236.359731) (xy 124.29998 -236.384338)
			(xy 124.628922 -236.384338) (xy 124.632882 -236.335284) (xy 124.644659 -236.2875) (xy 124.66395 -236.242224)
			(xy 124.690253 -236.200628) (xy 124.722888 -236.163791) (xy 124.761009 -236.132666) (xy 124.80363 -236.108059)
			(xy 124.849646 -236.090607) (xy 124.897865 -236.080763) (xy 124.94704 -236.078782) (xy 124.995895 -236.084714)
			(xy 125.043166 -236.098406) (xy 125.087628 -236.119504) (xy 125.128131 -236.14746) (xy 125.163624 -236.181552)
			(xy 125.193189 -236.220896) (xy 125.21606 -236.264473) (xy 125.231644 -236.311154) (xy 125.239539 -236.359731)
			(xy 125.240034 -236.384338) (xy 125.568976 -236.384338) (xy 125.572936 -236.335284) (xy 125.584713 -236.2875)
			(xy 125.604004 -236.242224) (xy 125.630307 -236.200628) (xy 125.662942 -236.163791) (xy 125.701063 -236.132666)
			(xy 125.743684 -236.108059) (xy 125.7897 -236.090607) (xy 125.837919 -236.080763) (xy 125.887094 -236.078782)
			(xy 125.935949 -236.084714) (xy 125.98322 -236.098406) (xy 126.027682 -236.119504) (xy 126.068185 -236.14746)
			(xy 126.103678 -236.181552) (xy 126.133243 -236.220896) (xy 126.156114 -236.264473) (xy 126.171698 -236.311154)
			(xy 126.179593 -236.359731) (xy 126.180088 -236.384338) (xy 126.50903 -236.384338) (xy 126.51299 -236.335284)
			(xy 126.524767 -236.2875) (xy 126.544058 -236.242224) (xy 126.570361 -236.200628) (xy 126.602996 -236.163791)
			(xy 126.641117 -236.132666) (xy 126.683738 -236.108059) (xy 126.729754 -236.090607) (xy 126.777973 -236.080763)
			(xy 126.827148 -236.078782) (xy 126.876003 -236.084714) (xy 126.923274 -236.098406) (xy 126.967736 -236.119504)
			(xy 127.008239 -236.14746) (xy 127.043732 -236.181552) (xy 127.073297 -236.220896) (xy 127.096168 -236.264473)
			(xy 127.111752 -236.311154) (xy 127.119647 -236.359731) (xy 127.120142 -236.384338) (xy 127.438399 -236.384338)
			(xy 127.442494 -236.33361) (xy 127.454673 -236.284196) (xy 127.474621 -236.237376) (xy 127.501822 -236.194362)
			(xy 127.53557 -236.156268) (xy 127.574992 -236.124081) (xy 127.619066 -236.098635) (xy 127.666652 -236.080588)
			(xy 127.716516 -236.070408) (xy 127.767368 -236.068359) (xy 127.817889 -236.074493) (xy 127.866773 -236.088653)
			(xy 127.912752 -236.11047) (xy 127.954636 -236.13938) (xy 127.99134 -236.174635) (xy 128.021913 -236.215321)
			(xy 128.045564 -236.260384) (xy 128.06168 -236.308658) (xy 128.069844 -236.358892) (xy 128.070356 -236.384338)
			(xy 128.388884 -236.384338) (xy 128.392844 -236.335284) (xy 128.404621 -236.2875) (xy 128.423912 -236.242224)
			(xy 128.450215 -236.200628) (xy 128.48285 -236.163791) (xy 128.520971 -236.132666) (xy 128.563592 -236.108059)
			(xy 128.609608 -236.090607) (xy 128.657827 -236.080763) (xy 128.707002 -236.078782) (xy 128.755857 -236.084714)
			(xy 128.803128 -236.098406) (xy 128.84759 -236.119504) (xy 128.888093 -236.14746) (xy 128.923586 -236.181552)
			(xy 128.953151 -236.220896) (xy 128.976022 -236.264473) (xy 128.991606 -236.311154) (xy 128.999501 -236.359731)
			(xy 128.999996 -236.384338) (xy 129.318507 -236.384338) (xy 129.322602 -236.33361) (xy 129.334781 -236.284196)
			(xy 129.354729 -236.237376) (xy 129.38193 -236.194362) (xy 129.415678 -236.156268) (xy 129.4551 -236.124081)
			(xy 129.499174 -236.098635) (xy 129.54676 -236.080588) (xy 129.596624 -236.070408) (xy 129.647476 -236.068359)
			(xy 129.697997 -236.074493) (xy 129.746881 -236.088653) (xy 129.79286 -236.11047) (xy 129.834744 -236.13938)
			(xy 129.871448 -236.174635) (xy 129.902021 -236.215321) (xy 129.925672 -236.260384) (xy 129.941788 -236.308658)
			(xy 129.949952 -236.358892) (xy 129.950464 -236.384338) (xy 129.949952 -236.409784) (xy 129.941788 -236.460018)
			(xy 129.925672 -236.508292) (xy 129.902021 -236.553355) (xy 129.871448 -236.594041) (xy 129.834744 -236.629296)
			(xy 129.79286 -236.658206) (xy 129.746881 -236.680023) (xy 129.697997 -236.694183) (xy 129.647476 -236.700317)
			(xy 129.596624 -236.698268) (xy 129.54676 -236.688088) (xy 129.499174 -236.670041) (xy 129.4551 -236.644595)
			(xy 129.415678 -236.612408) (xy 129.38193 -236.574314) (xy 129.354729 -236.5313) (xy 129.334781 -236.48448)
			(xy 129.322602 -236.435066) (xy 129.318507 -236.384338) (xy 128.999996 -236.384338) (xy 128.999501 -236.408945)
			(xy 128.991606 -236.457522) (xy 128.976022 -236.504203) (xy 128.953151 -236.54778) (xy 128.923586 -236.587124)
			(xy 128.888093 -236.621216) (xy 128.84759 -236.649172) (xy 128.803128 -236.67027) (xy 128.755857 -236.683962)
			(xy 128.707002 -236.689894) (xy 128.657827 -236.687913) (xy 128.609608 -236.678069) (xy 128.563592 -236.660617)
			(xy 128.520971 -236.63601) (xy 128.48285 -236.604885) (xy 128.450215 -236.568048) (xy 128.423912 -236.526452)
			(xy 128.404621 -236.481176) (xy 128.392844 -236.433392) (xy 128.388884 -236.384338) (xy 128.070356 -236.384338)
			(xy 128.069844 -236.409784) (xy 128.06168 -236.460018) (xy 128.045564 -236.508292) (xy 128.021913 -236.553355)
			(xy 127.99134 -236.594041) (xy 127.954636 -236.629296) (xy 127.912752 -236.658206) (xy 127.866773 -236.680023)
			(xy 127.817889 -236.694183) (xy 127.767368 -236.700317) (xy 127.716516 -236.698268) (xy 127.666652 -236.688088)
			(xy 127.619066 -236.670041) (xy 127.574992 -236.644595) (xy 127.53557 -236.612408) (xy 127.501822 -236.574314)
			(xy 127.474621 -236.5313) (xy 127.454673 -236.48448) (xy 127.442494 -236.435066) (xy 127.438399 -236.384338)
			(xy 127.120142 -236.384338) (xy 127.119647 -236.408945) (xy 127.111752 -236.457522) (xy 127.096168 -236.504203)
			(xy 127.073297 -236.54778) (xy 127.043732 -236.587124) (xy 127.008239 -236.621216) (xy 126.967736 -236.649172)
			(xy 126.923274 -236.67027) (xy 126.876003 -236.683962) (xy 126.827148 -236.689894) (xy 126.777973 -236.687913)
			(xy 126.729754 -236.678069) (xy 126.683738 -236.660617) (xy 126.641117 -236.63601) (xy 126.602996 -236.604885)
			(xy 126.570361 -236.568048) (xy 126.544058 -236.526452) (xy 126.524767 -236.481176) (xy 126.51299 -236.433392)
			(xy 126.50903 -236.384338) (xy 126.180088 -236.384338) (xy 126.179593 -236.408945) (xy 126.171698 -236.457522)
			(xy 126.156114 -236.504203) (xy 126.133243 -236.54778) (xy 126.103678 -236.587124) (xy 126.068185 -236.621216)
			(xy 126.027682 -236.649172) (xy 125.98322 -236.67027) (xy 125.935949 -236.683962) (xy 125.887094 -236.689894)
			(xy 125.837919 -236.687913) (xy 125.7897 -236.678069) (xy 125.743684 -236.660617) (xy 125.701063 -236.63601)
			(xy 125.662942 -236.604885) (xy 125.630307 -236.568048) (xy 125.604004 -236.526452) (xy 125.584713 -236.481176)
			(xy 125.572936 -236.433392) (xy 125.568976 -236.384338) (xy 125.240034 -236.384338) (xy 125.239539 -236.408945)
			(xy 125.231644 -236.457522) (xy 125.21606 -236.504203) (xy 125.193189 -236.54778) (xy 125.163624 -236.587124)
			(xy 125.128131 -236.621216) (xy 125.087628 -236.649172) (xy 125.043166 -236.67027) (xy 124.995895 -236.683962)
			(xy 124.94704 -236.689894) (xy 124.897865 -236.687913) (xy 124.849646 -236.678069) (xy 124.80363 -236.660617)
			(xy 124.761009 -236.63601) (xy 124.722888 -236.604885) (xy 124.690253 -236.568048) (xy 124.66395 -236.526452)
			(xy 124.644659 -236.481176) (xy 124.632882 -236.433392) (xy 124.628922 -236.384338) (xy 124.29998 -236.384338)
			(xy 124.299485 -236.408945) (xy 124.29159 -236.457522) (xy 124.276006 -236.504203) (xy 124.253135 -236.54778)
			(xy 124.22357 -236.587124) (xy 124.188077 -236.621216) (xy 124.147574 -236.649172) (xy 124.103112 -236.67027)
			(xy 124.055841 -236.683962) (xy 124.006986 -236.689894) (xy 123.957811 -236.687913) (xy 123.909592 -236.678069)
			(xy 123.863576 -236.660617) (xy 123.820955 -236.63601) (xy 123.782834 -236.604885) (xy 123.750199 -236.568048)
			(xy 123.723896 -236.526452) (xy 123.704605 -236.481176) (xy 123.692828 -236.433392) (xy 123.688868 -236.384338)
			(xy 123.359926 -236.384338) (xy 123.359431 -236.408945) (xy 123.351536 -236.457522) (xy 123.335952 -236.504203)
			(xy 123.313081 -236.54778) (xy 123.283516 -236.587124) (xy 123.248023 -236.621216) (xy 123.20752 -236.649172)
			(xy 123.163058 -236.67027) (xy 123.115787 -236.683962) (xy 123.066932 -236.689894) (xy 123.017757 -236.687913)
			(xy 122.969538 -236.678069) (xy 122.923522 -236.660617) (xy 122.880901 -236.63601) (xy 122.84278 -236.604885)
			(xy 122.810145 -236.568048) (xy 122.783842 -236.526452) (xy 122.764551 -236.481176) (xy 122.752774 -236.433392)
			(xy 122.748814 -236.384338) (xy 122.420126 -236.384338) (xy 122.419631 -236.408945) (xy 122.411736 -236.457522)
			(xy 122.396152 -236.504203) (xy 122.373281 -236.54778) (xy 122.343716 -236.587124) (xy 122.308223 -236.621216)
			(xy 122.26772 -236.649172) (xy 122.223258 -236.67027) (xy 122.175987 -236.683962) (xy 122.127132 -236.689894)
			(xy 122.077957 -236.687913) (xy 122.029738 -236.678069) (xy 121.983722 -236.660617) (xy 121.941101 -236.63601)
			(xy 121.90298 -236.604885) (xy 121.870345 -236.568048) (xy 121.844042 -236.526452) (xy 121.824751 -236.481176)
			(xy 121.812974 -236.433392) (xy 121.809014 -236.384338) (xy 121.480072 -236.384338) (xy 121.479577 -236.408945)
			(xy 121.471682 -236.457522) (xy 121.456098 -236.504203) (xy 121.433227 -236.54778) (xy 121.403662 -236.587124)
			(xy 121.368169 -236.621216) (xy 121.327666 -236.649172) (xy 121.283204 -236.67027) (xy 121.235933 -236.683962)
			(xy 121.187078 -236.689894) (xy 121.137903 -236.687913) (xy 121.089684 -236.678069) (xy 121.043668 -236.660617)
			(xy 121.001047 -236.63601) (xy 120.962926 -236.604885) (xy 120.930291 -236.568048) (xy 120.903988 -236.526452)
			(xy 120.884697 -236.481176) (xy 120.87292 -236.433392) (xy 120.86896 -236.384338) (xy 118.660164 -236.384338)
			(xy 118.659669 -236.408945) (xy 118.651774 -236.457522) (xy 118.63619 -236.504203) (xy 118.613319 -236.54778)
			(xy 118.583754 -236.587124) (xy 118.548261 -236.621216) (xy 118.507758 -236.649172) (xy 118.463296 -236.67027)
			(xy 118.416025 -236.683962) (xy 118.36717 -236.689894) (xy 118.317995 -236.687913) (xy 118.269776 -236.678069)
			(xy 118.22376 -236.660617) (xy 118.181139 -236.63601) (xy 118.143018 -236.604885) (xy 118.110383 -236.568048)
			(xy 118.08408 -236.526452) (xy 118.064789 -236.481176) (xy 118.053012 -236.433392) (xy 118.049052 -236.384338)
			(xy 115.840002 -236.384338) (xy 115.839507 -236.408945) (xy 115.831612 -236.457522) (xy 115.816028 -236.504203)
			(xy 115.793157 -236.54778) (xy 115.763592 -236.587124) (xy 115.728099 -236.621216) (xy 115.687596 -236.649172)
			(xy 115.643134 -236.67027) (xy 115.595863 -236.683962) (xy 115.547008 -236.689894) (xy 115.497833 -236.687913)
			(xy 115.449614 -236.678069) (xy 115.403598 -236.660617) (xy 115.360977 -236.63601) (xy 115.322856 -236.604885)
			(xy 115.290221 -236.568048) (xy 115.263918 -236.526452) (xy 115.244627 -236.481176) (xy 115.23285 -236.433392)
			(xy 115.22889 -236.384338) (xy 114.899948 -236.384338) (xy 114.899453 -236.408945) (xy 114.891558 -236.457522)
			(xy 114.875974 -236.504203) (xy 114.853103 -236.54778) (xy 114.823538 -236.587124) (xy 114.788045 -236.621216)
			(xy 114.747542 -236.649172) (xy 114.70308 -236.67027) (xy 114.655809 -236.683962) (xy 114.606954 -236.689894)
			(xy 114.557779 -236.687913) (xy 114.50956 -236.678069) (xy 114.463544 -236.660617) (xy 114.420923 -236.63601)
			(xy 114.382802 -236.604885) (xy 114.350167 -236.568048) (xy 114.323864 -236.526452) (xy 114.304573 -236.481176)
			(xy 114.292796 -236.433392) (xy 114.288836 -236.384338) (xy 113.960148 -236.384338) (xy 113.959653 -236.408945)
			(xy 113.951758 -236.457522) (xy 113.936174 -236.504203) (xy 113.913303 -236.54778) (xy 113.883738 -236.587124)
			(xy 113.848245 -236.621216) (xy 113.807742 -236.649172) (xy 113.76328 -236.67027) (xy 113.716009 -236.683962)
			(xy 113.667154 -236.689894) (xy 113.617979 -236.687913) (xy 113.56976 -236.678069) (xy 113.523744 -236.660617)
			(xy 113.481123 -236.63601) (xy 113.443002 -236.604885) (xy 113.410367 -236.568048) (xy 113.384064 -236.526452)
			(xy 113.364773 -236.481176) (xy 113.352996 -236.433392) (xy 113.349036 -236.384338) (xy 110.206282 -236.384338)
			(xy 110.205838 -236.407964) (xy 110.198556 -236.454653) (xy 110.184172 -236.499663) (xy 110.163028 -236.541922)
			(xy 110.135629 -236.580421) (xy 110.102629 -236.614241) (xy 110.064815 -236.642577) (xy 110.023089 -236.664753)
			(xy 109.978445 -236.680238) (xy 109.931949 -236.688665) (xy 109.90834 -236.689646) (xy 109.902244 -236.689646)
			(xy 109.900974 -236.689646) (xy 109.876008 -236.689146) (xy 109.826743 -236.681015) (xy 109.779458 -236.664975)
			(xy 109.735414 -236.641452) (xy 109.7153 -236.626654) (xy 109.708696 -236.621574) (xy 109.68228 -236.61243)
			(xy 109.668818 -236.611668) (xy 109.661706 -236.613192) (xy 109.623922 -236.621196) (xy 109.547494 -236.632371)
			(xy 109.470457 -236.637982) (xy 109.431836 -236.638338) (xy 109.15142 -236.638338) (xy 109.137958 -236.640116)
			(xy 109.119924 -236.645196) (xy 109.114336 -236.648498) (xy 109.090904 -236.661431) (xy 109.040632 -236.679783)
			(xy 108.987932 -236.689101) (xy 108.934416 -236.689101) (xy 108.881716 -236.679783) (xy 108.831444 -236.661431)
			(xy 108.808012 -236.648498) (xy 108.802424 -236.645196) (xy 108.78439 -236.640116) (xy 108.770928 -236.638338)
			(xy 108.490258 -236.638338) (xy 108.451637 -236.637993) (xy 108.374599 -236.632387) (xy 108.298171 -236.621202)
			(xy 108.260388 -236.613192) (xy 108.253276 -236.611668) (xy 108.239814 -236.61243) (xy 108.213398 -236.621574)
			(xy 108.206794 -236.626654) (xy 108.18668 -236.641453) (xy 108.14264 -236.664982) (xy 108.095354 -236.681023)
			(xy 108.046086 -236.689145) (xy 108.02112 -236.689646) (xy 108.013754 -236.689646) (xy 107.990145 -236.688635)
			(xy 107.943645 -236.680231) (xy 107.898995 -236.664762) (xy 107.857263 -236.642596) (xy 107.819445 -236.614264)
			(xy 107.786445 -236.580443) (xy 107.759052 -236.541939) (xy 107.737919 -236.499674) (xy 107.723553 -236.454658)
			(xy 107.716295 -236.407965) (xy 107.715812 -236.384338) (xy 107.715911 -236.373633) (xy 107.717438 -236.352277)
			(xy 107.71886 -236.341666) (xy 107.720638 -236.328458) (xy 107.707176 -236.29366) (xy 107.700826 -236.286802)
			(xy 107.67031 -236.252222) (xy 107.614707 -236.178633) (xy 107.565684 -236.100506) (xy 107.52361 -236.018428)
			(xy 107.505754 -235.975906) (xy 107.50296 -235.96854) (xy 107.493816 -235.957364) (xy 107.466638 -235.938822)
			(xy 107.460185 -235.934716) (xy 107.445581 -235.93019) (xy 107.437936 -235.929932) (xy 103.223568 -235.929932)
			(xy 103.213728 -235.930462) (xy 103.19556 -235.938043) (xy 103.188262 -235.944664) (xy 102.748588 -236.384338)
			(xy 104.895154 -236.384338) (xy 104.899114 -236.335284) (xy 104.910891 -236.2875) (xy 104.930182 -236.242224)
			(xy 104.956485 -236.200628) (xy 104.98912 -236.163791) (xy 105.027241 -236.132666) (xy 105.069862 -236.108059)
			(xy 105.115878 -236.090607) (xy 105.164097 -236.080763) (xy 105.213272 -236.078782) (xy 105.262127 -236.084714)
			(xy 105.309398 -236.098406) (xy 105.35386 -236.119504) (xy 105.394363 -236.14746) (xy 105.429856 -236.181552)
			(xy 105.459421 -236.220896) (xy 105.482292 -236.264473) (xy 105.497876 -236.311154) (xy 105.505771 -236.359731)
			(xy 105.506266 -236.384338) (xy 105.505771 -236.408945) (xy 105.497876 -236.457522) (xy 105.482292 -236.504203)
			(xy 105.459421 -236.54778) (xy 105.429856 -236.587124) (xy 105.394363 -236.621216) (xy 105.35386 -236.649172)
			(xy 105.309398 -236.67027) (xy 105.262127 -236.683962) (xy 105.213272 -236.689894) (xy 105.164097 -236.687913)
			(xy 105.115878 -236.678069) (xy 105.069862 -236.660617) (xy 105.027241 -236.63601) (xy 104.98912 -236.604885)
			(xy 104.956485 -236.568048) (xy 104.930182 -236.526452) (xy 104.910891 -236.481176) (xy 104.899114 -236.433392)
			(xy 104.895154 -236.384338) (xy 102.748588 -236.384338) (xy 102.68331 -236.449616) (xy 102.676706 -236.460792)
			(xy 102.674928 -236.467142) (xy 102.668243 -236.489276) (xy 102.649132 -236.531378) (xy 102.623901 -236.570124)
			(xy 102.593125 -236.60463) (xy 102.557506 -236.634109) (xy 102.517855 -236.657891) (xy 102.49662 -236.66704)
			(xy 102.48646 -236.671104) (xy 102.456234 -236.702854) (xy 102.452678 -236.713776) (xy 102.438443 -236.755984)
			(xy 102.403872 -236.838087) (xy 102.36256 -236.917012) (xy 102.314794 -236.992208) (xy 102.26091 -237.063148)
			(xy 102.231444 -237.096554) (xy 102.225094 -237.103412) (xy 102.211632 -237.13821) (xy 102.213156 -237.149894)
			(xy 102.214687 -237.160943) (xy 102.216338 -237.18319) (xy 102.216458 -237.194344) (xy 102.545146 -237.194344)
			(xy 102.549106 -237.14529) (xy 102.560883 -237.097506) (xy 102.580174 -237.05223) (xy 102.606477 -237.010634)
			(xy 102.639112 -236.973797) (xy 102.677233 -236.942672) (xy 102.719854 -236.918065) (xy 102.76587 -236.900613)
			(xy 102.814089 -236.890769) (xy 102.863264 -236.888788) (xy 102.912119 -236.89472) (xy 102.95939 -236.908412)
			(xy 103.003852 -236.92951) (xy 103.044355 -236.957466) (xy 103.079848 -236.991558) (xy 103.109413 -237.030902)
			(xy 103.132284 -237.074479) (xy 103.147868 -237.12116) (xy 103.155763 -237.169737) (xy 103.156258 -237.194344)
			(xy 103.4852 -237.194344) (xy 103.48916 -237.14529) (xy 103.500937 -237.097506) (xy 103.520228 -237.05223)
			(xy 103.546531 -237.010634) (xy 103.579166 -236.973797) (xy 103.617287 -236.942672) (xy 103.659908 -236.918065)
			(xy 103.705924 -236.900613) (xy 103.754143 -236.890769) (xy 103.803318 -236.888788) (xy 103.852173 -236.89472)
			(xy 103.899444 -236.908412) (xy 103.943906 -236.92951) (xy 103.984409 -236.957466) (xy 104.019902 -236.991558)
			(xy 104.049467 -237.030902) (xy 104.072338 -237.074479) (xy 104.087922 -237.12116) (xy 104.095817 -237.169737)
			(xy 104.096312 -237.194344) (xy 104.425254 -237.194344) (xy 104.429214 -237.14529) (xy 104.440991 -237.097506)
			(xy 104.460282 -237.05223) (xy 104.486585 -237.010634) (xy 104.51922 -236.973797) (xy 104.557341 -236.942672)
			(xy 104.599962 -236.918065) (xy 104.645978 -236.900613) (xy 104.694197 -236.890769) (xy 104.743372 -236.888788)
			(xy 104.792227 -236.89472) (xy 104.839498 -236.908412) (xy 104.88396 -236.92951) (xy 104.924463 -236.957466)
			(xy 104.959956 -236.991558) (xy 104.989521 -237.030902) (xy 105.012392 -237.074479) (xy 105.027976 -237.12116)
			(xy 105.035871 -237.169737) (xy 105.036366 -237.194344) (xy 105.365308 -237.194344) (xy 105.369268 -237.14529)
			(xy 105.381045 -237.097506) (xy 105.400336 -237.05223) (xy 105.426639 -237.010634) (xy 105.459274 -236.973797)
			(xy 105.497395 -236.942672) (xy 105.540016 -236.918065) (xy 105.586032 -236.900613) (xy 105.634251 -236.890769)
			(xy 105.683426 -236.888788) (xy 105.732281 -236.89472) (xy 105.779552 -236.908412) (xy 105.824014 -236.92951)
			(xy 105.864517 -236.957466) (xy 105.90001 -236.991558) (xy 105.929575 -237.030902) (xy 105.952446 -237.074479)
			(xy 105.96803 -237.12116) (xy 105.975925 -237.169737) (xy 105.97642 -237.194344) (xy 106.305362 -237.194344)
			(xy 106.309322 -237.14529) (xy 106.321099 -237.097506) (xy 106.34039 -237.05223) (xy 106.366693 -237.010634)
			(xy 106.399328 -236.973797) (xy 106.437449 -236.942672) (xy 106.48007 -236.918065) (xy 106.526086 -236.900613)
			(xy 106.574305 -236.890769) (xy 106.62348 -236.888788) (xy 106.672335 -236.89472) (xy 106.719606 -236.908412)
			(xy 106.764068 -236.92951) (xy 106.804571 -236.957466) (xy 106.840064 -236.991558) (xy 106.869629 -237.030902)
			(xy 106.8925 -237.074479) (xy 106.908084 -237.12116) (xy 106.915979 -237.169737) (xy 106.916474 -237.194344)
			(xy 107.245162 -237.194344) (xy 107.249122 -237.14529) (xy 107.260899 -237.097506) (xy 107.28019 -237.05223)
			(xy 107.306493 -237.010634) (xy 107.339128 -236.973797) (xy 107.377249 -236.942672) (xy 107.41987 -236.918065)
			(xy 107.465886 -236.900613) (xy 107.514105 -236.890769) (xy 107.56328 -236.888788) (xy 107.612135 -236.89472)
			(xy 107.659406 -236.908412) (xy 107.703868 -236.92951) (xy 107.744371 -236.957466) (xy 107.779864 -236.991558)
			(xy 107.809429 -237.030902) (xy 107.8323 -237.074479) (xy 107.847884 -237.12116) (xy 107.855779 -237.169737)
			(xy 107.856274 -237.194344) (xy 110.065324 -237.194344) (xy 110.069284 -237.14529) (xy 110.081061 -237.097506)
			(xy 110.100352 -237.05223) (xy 110.126655 -237.010634) (xy 110.15929 -236.973797) (xy 110.197411 -236.942672)
			(xy 110.240032 -236.918065) (xy 110.286048 -236.900613) (xy 110.334267 -236.890769) (xy 110.383442 -236.888788)
			(xy 110.432297 -236.89472) (xy 110.479568 -236.908412) (xy 110.52403 -236.92951) (xy 110.564533 -236.957466)
			(xy 110.600026 -236.991558) (xy 110.629591 -237.030902) (xy 110.652462 -237.074479) (xy 110.668046 -237.12116)
			(xy 110.675941 -237.169737) (xy 110.676436 -237.194344) (xy 112.878882 -237.194344) (xy 112.882842 -237.14529)
			(xy 112.894619 -237.097506) (xy 112.91391 -237.05223) (xy 112.940213 -237.010634) (xy 112.972848 -236.973797)
			(xy 113.010969 -236.942672) (xy 113.05359 -236.918065) (xy 113.099606 -236.900613) (xy 113.147825 -236.890769)
			(xy 113.197 -236.888788) (xy 113.245855 -236.89472) (xy 113.293126 -236.908412) (xy 113.337588 -236.92951)
			(xy 113.378091 -236.957466) (xy 113.413584 -236.991558) (xy 113.443149 -237.030902) (xy 113.46602 -237.074479)
			(xy 113.481604 -237.12116) (xy 113.489499 -237.169737) (xy 113.489994 -237.194344) (xy 115.699044 -237.194344)
			(xy 115.703004 -237.14529) (xy 115.714781 -237.097506) (xy 115.734072 -237.05223) (xy 115.760375 -237.010634)
			(xy 115.79301 -236.973797) (xy 115.831131 -236.942672) (xy 115.873752 -236.918065) (xy 115.919768 -236.900613)
			(xy 115.967987 -236.890769) (xy 116.017162 -236.888788) (xy 116.066017 -236.89472) (xy 116.113288 -236.908412)
			(xy 116.15775 -236.92951) (xy 116.198253 -236.957466) (xy 116.233746 -236.991558) (xy 116.263311 -237.030902)
			(xy 116.286182 -237.074479) (xy 116.301766 -237.12116) (xy 116.309661 -237.169737) (xy 116.310156 -237.194344)
			(xy 116.638844 -237.194344) (xy 116.642804 -237.14529) (xy 116.654581 -237.097506) (xy 116.673872 -237.05223)
			(xy 116.700175 -237.010634) (xy 116.73281 -236.973797) (xy 116.770931 -236.942672) (xy 116.813552 -236.918065)
			(xy 116.859568 -236.900613) (xy 116.907787 -236.890769) (xy 116.956962 -236.888788) (xy 117.005817 -236.89472)
			(xy 117.053088 -236.908412) (xy 117.09755 -236.92951) (xy 117.138053 -236.957466) (xy 117.173546 -236.991558)
			(xy 117.203111 -237.030902) (xy 117.225982 -237.074479) (xy 117.241566 -237.12116) (xy 117.249461 -237.169737)
			(xy 117.249956 -237.194344) (xy 117.578898 -237.194344) (xy 117.582858 -237.14529) (xy 117.594635 -237.097506)
			(xy 117.613926 -237.05223) (xy 117.640229 -237.010634) (xy 117.672864 -236.973797) (xy 117.710985 -236.942672)
			(xy 117.753606 -236.918065) (xy 117.799622 -236.900613) (xy 117.847841 -236.890769) (xy 117.897016 -236.888788)
			(xy 117.945871 -236.89472) (xy 117.993142 -236.908412) (xy 118.037604 -236.92951) (xy 118.078107 -236.957466)
			(xy 118.1136 -236.991558) (xy 118.143165 -237.030902) (xy 118.166036 -237.074479) (xy 118.18162 -237.12116)
			(xy 118.189515 -237.169737) (xy 118.19001 -237.194344) (xy 118.518952 -237.194344) (xy 118.522912 -237.14529)
			(xy 118.534689 -237.097506) (xy 118.55398 -237.05223) (xy 118.580283 -237.010634) (xy 118.612918 -236.973797)
			(xy 118.651039 -236.942672) (xy 118.69366 -236.918065) (xy 118.739676 -236.900613) (xy 118.787895 -236.890769)
			(xy 118.83707 -236.888788) (xy 118.885925 -236.89472) (xy 118.933196 -236.908412) (xy 118.977658 -236.92951)
			(xy 119.018161 -236.957466) (xy 119.053654 -236.991558) (xy 119.083219 -237.030902) (xy 119.10609 -237.074479)
			(xy 119.121674 -237.12116) (xy 119.129569 -237.169737) (xy 119.130064 -237.194344) (xy 119.459006 -237.194344)
			(xy 119.462966 -237.14529) (xy 119.474743 -237.097506) (xy 119.494034 -237.05223) (xy 119.520337 -237.010634)
			(xy 119.552972 -236.973797) (xy 119.591093 -236.942672) (xy 119.633714 -236.918065) (xy 119.67973 -236.900613)
			(xy 119.727949 -236.890769) (xy 119.777124 -236.888788) (xy 119.825979 -236.89472) (xy 119.87325 -236.908412)
			(xy 119.917712 -236.92951) (xy 119.958215 -236.957466) (xy 119.993708 -236.991558) (xy 120.023273 -237.030902)
			(xy 120.046144 -237.074479) (xy 120.061728 -237.12116) (xy 120.069623 -237.169737) (xy 120.070118 -237.194344)
			(xy 120.398806 -237.194344) (xy 120.402766 -237.14529) (xy 120.414543 -237.097506) (xy 120.433834 -237.05223)
			(xy 120.460137 -237.010634) (xy 120.492772 -236.973797) (xy 120.530893 -236.942672) (xy 120.573514 -236.918065)
			(xy 120.61953 -236.900613) (xy 120.667749 -236.890769) (xy 120.716924 -236.888788) (xy 120.765779 -236.89472)
			(xy 120.81305 -236.908412) (xy 120.857512 -236.92951) (xy 120.898015 -236.957466) (xy 120.933508 -236.991558)
			(xy 120.963073 -237.030902) (xy 120.985944 -237.074479) (xy 121.001528 -237.12116) (xy 121.009423 -237.169737)
			(xy 121.009918 -237.194344) (xy 121.33886 -237.194344) (xy 121.34282 -237.14529) (xy 121.354597 -237.097506)
			(xy 121.373888 -237.05223) (xy 121.400191 -237.010634) (xy 121.432826 -236.973797) (xy 121.470947 -236.942672)
			(xy 121.513568 -236.918065) (xy 121.559584 -236.900613) (xy 121.607803 -236.890769) (xy 121.656978 -236.888788)
			(xy 121.705833 -236.89472) (xy 121.753104 -236.908412) (xy 121.797566 -236.92951) (xy 121.838069 -236.957466)
			(xy 121.873562 -236.991558) (xy 121.903127 -237.030902) (xy 121.925998 -237.074479) (xy 121.941582 -237.12116)
			(xy 121.949477 -237.169737) (xy 121.949972 -237.194344) (xy 122.278914 -237.194344) (xy 122.282874 -237.14529)
			(xy 122.294651 -237.097506) (xy 122.313942 -237.05223) (xy 122.340245 -237.010634) (xy 122.37288 -236.973797)
			(xy 122.411001 -236.942672) (xy 122.453622 -236.918065) (xy 122.499638 -236.900613) (xy 122.547857 -236.890769)
			(xy 122.597032 -236.888788) (xy 122.645887 -236.89472) (xy 122.693158 -236.908412) (xy 122.73762 -236.92951)
			(xy 122.778123 -236.957466) (xy 122.813616 -236.991558) (xy 122.843181 -237.030902) (xy 122.866052 -237.074479)
			(xy 122.881636 -237.12116) (xy 122.889531 -237.169737) (xy 122.890026 -237.194344) (xy 123.218968 -237.194344)
			(xy 123.222928 -237.14529) (xy 123.234705 -237.097506) (xy 123.253996 -237.05223) (xy 123.280299 -237.010634)
			(xy 123.312934 -236.973797) (xy 123.351055 -236.942672) (xy 123.393676 -236.918065) (xy 123.439692 -236.900613)
			(xy 123.487911 -236.890769) (xy 123.537086 -236.888788) (xy 123.585941 -236.89472) (xy 123.633212 -236.908412)
			(xy 123.677674 -236.92951) (xy 123.718177 -236.957466) (xy 123.75367 -236.991558) (xy 123.783235 -237.030902)
			(xy 123.806106 -237.074479) (xy 123.82169 -237.12116) (xy 123.829585 -237.169737) (xy 123.83008 -237.194344)
			(xy 124.159022 -237.194344) (xy 124.162982 -237.14529) (xy 124.174759 -237.097506) (xy 124.19405 -237.05223)
			(xy 124.220353 -237.010634) (xy 124.252988 -236.973797) (xy 124.291109 -236.942672) (xy 124.33373 -236.918065)
			(xy 124.379746 -236.900613) (xy 124.427965 -236.890769) (xy 124.47714 -236.888788) (xy 124.525995 -236.89472)
			(xy 124.573266 -236.908412) (xy 124.617728 -236.92951) (xy 124.658231 -236.957466) (xy 124.693724 -236.991558)
			(xy 124.723289 -237.030902) (xy 124.74616 -237.074479) (xy 124.761744 -237.12116) (xy 124.769639 -237.169737)
			(xy 124.770134 -237.194344) (xy 125.098822 -237.194344) (xy 125.102782 -237.14529) (xy 125.114559 -237.097506)
			(xy 125.13385 -237.05223) (xy 125.160153 -237.010634) (xy 125.192788 -236.973797) (xy 125.230909 -236.942672)
			(xy 125.27353 -236.918065) (xy 125.319546 -236.900613) (xy 125.367765 -236.890769) (xy 125.41694 -236.888788)
			(xy 125.465795 -236.89472) (xy 125.513066 -236.908412) (xy 125.557528 -236.92951) (xy 125.598031 -236.957466)
			(xy 125.633524 -236.991558) (xy 125.663089 -237.030902) (xy 125.68596 -237.074479) (xy 125.701544 -237.12116)
			(xy 125.709439 -237.169737) (xy 125.709934 -237.194344) (xy 126.038876 -237.194344) (xy 126.042836 -237.14529)
			(xy 126.054613 -237.097506) (xy 126.073904 -237.05223) (xy 126.100207 -237.010634) (xy 126.132842 -236.973797)
			(xy 126.170963 -236.942672) (xy 126.213584 -236.918065) (xy 126.2596 -236.900613) (xy 126.307819 -236.890769)
			(xy 126.356994 -236.888788) (xy 126.405849 -236.89472) (xy 126.45312 -236.908412) (xy 126.497582 -236.92951)
			(xy 126.538085 -236.957466) (xy 126.573578 -236.991558) (xy 126.603143 -237.030902) (xy 126.626014 -237.074479)
			(xy 126.641598 -237.12116) (xy 126.649493 -237.169737) (xy 126.649988 -237.194344) (xy 126.97893 -237.194344)
			(xy 126.98289 -237.14529) (xy 126.994667 -237.097506) (xy 127.013958 -237.05223) (xy 127.040261 -237.010634)
			(xy 127.072896 -236.973797) (xy 127.111017 -236.942672) (xy 127.153638 -236.918065) (xy 127.199654 -236.900613)
			(xy 127.247873 -236.890769) (xy 127.297048 -236.888788) (xy 127.345903 -236.89472) (xy 127.393174 -236.908412)
			(xy 127.437636 -236.92951) (xy 127.478139 -236.957466) (xy 127.513632 -236.991558) (xy 127.543197 -237.030902)
			(xy 127.566068 -237.074479) (xy 127.581652 -237.12116) (xy 127.589547 -237.169737) (xy 127.590042 -237.194344)
			(xy 127.908553 -237.194344) (xy 127.912648 -237.143616) (xy 127.924827 -237.094202) (xy 127.944775 -237.047382)
			(xy 127.971976 -237.004368) (xy 128.005724 -236.966274) (xy 128.045146 -236.934087) (xy 128.08922 -236.908641)
			(xy 128.136806 -236.890594) (xy 128.18667 -236.880414) (xy 128.237522 -236.878365) (xy 128.288043 -236.884499)
			(xy 128.336927 -236.898659) (xy 128.382906 -236.920476) (xy 128.42479 -236.949386) (xy 128.461494 -236.984641)
			(xy 128.492067 -237.025327) (xy 128.515718 -237.07039) (xy 128.531834 -237.118664) (xy 128.539998 -237.168898)
			(xy 128.54051 -237.194344) (xy 128.848607 -237.194344) (xy 128.852702 -237.143616) (xy 128.864881 -237.094202)
			(xy 128.884829 -237.047382) (xy 128.91203 -237.004368) (xy 128.945778 -236.966274) (xy 128.9852 -236.934087)
			(xy 129.029274 -236.908641) (xy 129.07686 -236.890594) (xy 129.126724 -236.880414) (xy 129.177576 -236.878365)
			(xy 129.228097 -236.884499) (xy 129.276981 -236.898659) (xy 129.32296 -236.920476) (xy 129.364844 -236.949386)
			(xy 129.401548 -236.984641) (xy 129.432121 -237.025327) (xy 129.455772 -237.07039) (xy 129.471888 -237.118664)
			(xy 129.480052 -237.168898) (xy 129.480564 -237.194344) (xy 129.480052 -237.21979) (xy 129.471888 -237.270024)
			(xy 129.455772 -237.318298) (xy 129.432121 -237.363361) (xy 129.401548 -237.404047) (xy 129.364844 -237.439302)
			(xy 129.32296 -237.468212) (xy 129.276981 -237.490029) (xy 129.228097 -237.504189) (xy 129.177576 -237.510323)
			(xy 129.126724 -237.508274) (xy 129.07686 -237.498094) (xy 129.029274 -237.480047) (xy 128.9852 -237.454601)
			(xy 128.945778 -237.422414) (xy 128.91203 -237.38432) (xy 128.884829 -237.341306) (xy 128.864881 -237.294486)
			(xy 128.852702 -237.245072) (xy 128.848607 -237.194344) (xy 128.54051 -237.194344) (xy 128.539998 -237.21979)
			(xy 128.531834 -237.270024) (xy 128.515718 -237.318298) (xy 128.492067 -237.363361) (xy 128.461494 -237.404047)
			(xy 128.42479 -237.439302) (xy 128.382906 -237.468212) (xy 128.336927 -237.490029) (xy 128.288043 -237.504189)
			(xy 128.237522 -237.510323) (xy 128.18667 -237.508274) (xy 128.136806 -237.498094) (xy 128.08922 -237.480047)
			(xy 128.045146 -237.454601) (xy 128.005724 -237.422414) (xy 127.971976 -237.38432) (xy 127.944775 -237.341306)
			(xy 127.924827 -237.294486) (xy 127.912648 -237.245072) (xy 127.908553 -237.194344) (xy 127.590042 -237.194344)
			(xy 127.589547 -237.218951) (xy 127.581652 -237.267528) (xy 127.566068 -237.314209) (xy 127.543197 -237.357786)
			(xy 127.513632 -237.39713) (xy 127.478139 -237.431222) (xy 127.437636 -237.459178) (xy 127.393174 -237.480276)
			(xy 127.345903 -237.493968) (xy 127.297048 -237.4999) (xy 127.247873 -237.497919) (xy 127.199654 -237.488075)
			(xy 127.153638 -237.470623) (xy 127.111017 -237.446016) (xy 127.072896 -237.414891) (xy 127.040261 -237.378054)
			(xy 127.013958 -237.336458) (xy 126.994667 -237.291182) (xy 126.98289 -237.243398) (xy 126.97893 -237.194344)
			(xy 126.649988 -237.194344) (xy 126.649493 -237.218951) (xy 126.641598 -237.267528) (xy 126.626014 -237.314209)
			(xy 126.603143 -237.357786) (xy 126.573578 -237.39713) (xy 126.538085 -237.431222) (xy 126.497582 -237.459178)
			(xy 126.45312 -237.480276) (xy 126.405849 -237.493968) (xy 126.356994 -237.4999) (xy 126.307819 -237.497919)
			(xy 126.2596 -237.488075) (xy 126.213584 -237.470623) (xy 126.170963 -237.446016) (xy 126.132842 -237.414891)
			(xy 126.100207 -237.378054) (xy 126.073904 -237.336458) (xy 126.054613 -237.291182) (xy 126.042836 -237.243398)
			(xy 126.038876 -237.194344) (xy 125.709934 -237.194344) (xy 125.709439 -237.218951) (xy 125.701544 -237.267528)
			(xy 125.68596 -237.314209) (xy 125.663089 -237.357786) (xy 125.633524 -237.39713) (xy 125.598031 -237.431222)
			(xy 125.557528 -237.459178) (xy 125.513066 -237.480276) (xy 125.465795 -237.493968) (xy 125.41694 -237.4999)
			(xy 125.367765 -237.497919) (xy 125.319546 -237.488075) (xy 125.27353 -237.470623) (xy 125.230909 -237.446016)
			(xy 125.192788 -237.414891) (xy 125.160153 -237.378054) (xy 125.13385 -237.336458) (xy 125.114559 -237.291182)
			(xy 125.102782 -237.243398) (xy 125.098822 -237.194344) (xy 124.770134 -237.194344) (xy 124.769639 -237.218951)
			(xy 124.761744 -237.267528) (xy 124.74616 -237.314209) (xy 124.723289 -237.357786) (xy 124.693724 -237.39713)
			(xy 124.658231 -237.431222) (xy 124.617728 -237.459178) (xy 124.573266 -237.480276) (xy 124.525995 -237.493968)
			(xy 124.47714 -237.4999) (xy 124.427965 -237.497919) (xy 124.379746 -237.488075) (xy 124.33373 -237.470623)
			(xy 124.291109 -237.446016) (xy 124.252988 -237.414891) (xy 124.220353 -237.378054) (xy 124.19405 -237.336458)
			(xy 124.174759 -237.291182) (xy 124.162982 -237.243398) (xy 124.159022 -237.194344) (xy 123.83008 -237.194344)
			(xy 123.829585 -237.218951) (xy 123.82169 -237.267528) (xy 123.806106 -237.314209) (xy 123.783235 -237.357786)
			(xy 123.75367 -237.39713) (xy 123.718177 -237.431222) (xy 123.677674 -237.459178) (xy 123.633212 -237.480276)
			(xy 123.585941 -237.493968) (xy 123.537086 -237.4999) (xy 123.487911 -237.497919) (xy 123.439692 -237.488075)
			(xy 123.393676 -237.470623) (xy 123.351055 -237.446016) (xy 123.312934 -237.414891) (xy 123.280299 -237.378054)
			(xy 123.253996 -237.336458) (xy 123.234705 -237.291182) (xy 123.222928 -237.243398) (xy 123.218968 -237.194344)
			(xy 122.890026 -237.194344) (xy 122.889531 -237.218951) (xy 122.881636 -237.267528) (xy 122.866052 -237.314209)
			(xy 122.843181 -237.357786) (xy 122.813616 -237.39713) (xy 122.778123 -237.431222) (xy 122.73762 -237.459178)
			(xy 122.693158 -237.480276) (xy 122.645887 -237.493968) (xy 122.597032 -237.4999) (xy 122.547857 -237.497919)
			(xy 122.499638 -237.488075) (xy 122.453622 -237.470623) (xy 122.411001 -237.446016) (xy 122.37288 -237.414891)
			(xy 122.340245 -237.378054) (xy 122.313942 -237.336458) (xy 122.294651 -237.291182) (xy 122.282874 -237.243398)
			(xy 122.278914 -237.194344) (xy 121.949972 -237.194344) (xy 121.949477 -237.218951) (xy 121.941582 -237.267528)
			(xy 121.925998 -237.314209) (xy 121.903127 -237.357786) (xy 121.873562 -237.39713) (xy 121.838069 -237.431222)
			(xy 121.797566 -237.459178) (xy 121.753104 -237.480276) (xy 121.705833 -237.493968) (xy 121.656978 -237.4999)
			(xy 121.607803 -237.497919) (xy 121.559584 -237.488075) (xy 121.513568 -237.470623) (xy 121.470947 -237.446016)
			(xy 121.432826 -237.414891) (xy 121.400191 -237.378054) (xy 121.373888 -237.336458) (xy 121.354597 -237.291182)
			(xy 121.34282 -237.243398) (xy 121.33886 -237.194344) (xy 121.009918 -237.194344) (xy 121.009423 -237.218951)
			(xy 121.001528 -237.267528) (xy 120.985944 -237.314209) (xy 120.963073 -237.357786) (xy 120.933508 -237.39713)
			(xy 120.898015 -237.431222) (xy 120.857512 -237.459178) (xy 120.81305 -237.480276) (xy 120.765779 -237.493968)
			(xy 120.716924 -237.4999) (xy 120.667749 -237.497919) (xy 120.61953 -237.488075) (xy 120.573514 -237.470623)
			(xy 120.530893 -237.446016) (xy 120.492772 -237.414891) (xy 120.460137 -237.378054) (xy 120.433834 -237.336458)
			(xy 120.414543 -237.291182) (xy 120.402766 -237.243398) (xy 120.398806 -237.194344) (xy 120.070118 -237.194344)
			(xy 120.069623 -237.218951) (xy 120.061728 -237.267528) (xy 120.046144 -237.314209) (xy 120.023273 -237.357786)
			(xy 119.993708 -237.39713) (xy 119.958215 -237.431222) (xy 119.917712 -237.459178) (xy 119.87325 -237.480276)
			(xy 119.825979 -237.493968) (xy 119.777124 -237.4999) (xy 119.727949 -237.497919) (xy 119.67973 -237.488075)
			(xy 119.633714 -237.470623) (xy 119.591093 -237.446016) (xy 119.552972 -237.414891) (xy 119.520337 -237.378054)
			(xy 119.494034 -237.336458) (xy 119.474743 -237.291182) (xy 119.462966 -237.243398) (xy 119.459006 -237.194344)
			(xy 119.130064 -237.194344) (xy 119.129569 -237.218951) (xy 119.121674 -237.267528) (xy 119.10609 -237.314209)
			(xy 119.083219 -237.357786) (xy 119.053654 -237.39713) (xy 119.018161 -237.431222) (xy 118.977658 -237.459178)
			(xy 118.933196 -237.480276) (xy 118.885925 -237.493968) (xy 118.83707 -237.4999) (xy 118.787895 -237.497919)
			(xy 118.739676 -237.488075) (xy 118.69366 -237.470623) (xy 118.651039 -237.446016) (xy 118.612918 -237.414891)
			(xy 118.580283 -237.378054) (xy 118.55398 -237.336458) (xy 118.534689 -237.291182) (xy 118.522912 -237.243398)
			(xy 118.518952 -237.194344) (xy 118.19001 -237.194344) (xy 118.189515 -237.218951) (xy 118.18162 -237.267528)
			(xy 118.166036 -237.314209) (xy 118.143165 -237.357786) (xy 118.1136 -237.39713) (xy 118.078107 -237.431222)
			(xy 118.037604 -237.459178) (xy 117.993142 -237.480276) (xy 117.945871 -237.493968) (xy 117.897016 -237.4999)
			(xy 117.847841 -237.497919) (xy 117.799622 -237.488075) (xy 117.753606 -237.470623) (xy 117.710985 -237.446016)
			(xy 117.672864 -237.414891) (xy 117.640229 -237.378054) (xy 117.613926 -237.336458) (xy 117.594635 -237.291182)
			(xy 117.582858 -237.243398) (xy 117.578898 -237.194344) (xy 117.249956 -237.194344) (xy 117.249461 -237.218951)
			(xy 117.241566 -237.267528) (xy 117.225982 -237.314209) (xy 117.203111 -237.357786) (xy 117.173546 -237.39713)
			(xy 117.138053 -237.431222) (xy 117.09755 -237.459178) (xy 117.053088 -237.480276) (xy 117.005817 -237.493968)
			(xy 116.956962 -237.4999) (xy 116.907787 -237.497919) (xy 116.859568 -237.488075) (xy 116.813552 -237.470623)
			(xy 116.770931 -237.446016) (xy 116.73281 -237.414891) (xy 116.700175 -237.378054) (xy 116.673872 -237.336458)
			(xy 116.654581 -237.291182) (xy 116.642804 -237.243398) (xy 116.638844 -237.194344) (xy 116.310156 -237.194344)
			(xy 116.309661 -237.218951) (xy 116.301766 -237.267528) (xy 116.286182 -237.314209) (xy 116.263311 -237.357786)
			(xy 116.233746 -237.39713) (xy 116.198253 -237.431222) (xy 116.15775 -237.459178) (xy 116.113288 -237.480276)
			(xy 116.066017 -237.493968) (xy 116.017162 -237.4999) (xy 115.967987 -237.497919) (xy 115.919768 -237.488075)
			(xy 115.873752 -237.470623) (xy 115.831131 -237.446016) (xy 115.79301 -237.414891) (xy 115.760375 -237.378054)
			(xy 115.734072 -237.336458) (xy 115.714781 -237.291182) (xy 115.703004 -237.243398) (xy 115.699044 -237.194344)
			(xy 113.489994 -237.194344) (xy 113.489499 -237.218951) (xy 113.481604 -237.267528) (xy 113.46602 -237.314209)
			(xy 113.443149 -237.357786) (xy 113.413584 -237.39713) (xy 113.378091 -237.431222) (xy 113.337588 -237.459178)
			(xy 113.293126 -237.480276) (xy 113.245855 -237.493968) (xy 113.197 -237.4999) (xy 113.147825 -237.497919)
			(xy 113.099606 -237.488075) (xy 113.05359 -237.470623) (xy 113.010969 -237.446016) (xy 112.972848 -237.414891)
			(xy 112.940213 -237.378054) (xy 112.91391 -237.336458) (xy 112.894619 -237.291182) (xy 112.882842 -237.243398)
			(xy 112.878882 -237.194344) (xy 110.676436 -237.194344) (xy 110.675941 -237.218951) (xy 110.668046 -237.267528)
			(xy 110.652462 -237.314209) (xy 110.629591 -237.357786) (xy 110.600026 -237.39713) (xy 110.564533 -237.431222)
			(xy 110.52403 -237.459178) (xy 110.479568 -237.480276) (xy 110.432297 -237.493968) (xy 110.383442 -237.4999)
			(xy 110.334267 -237.497919) (xy 110.286048 -237.488075) (xy 110.240032 -237.470623) (xy 110.197411 -237.446016)
			(xy 110.15929 -237.414891) (xy 110.126655 -237.378054) (xy 110.100352 -237.336458) (xy 110.081061 -237.291182)
			(xy 110.069284 -237.243398) (xy 110.065324 -237.194344) (xy 107.856274 -237.194344) (xy 107.855779 -237.218951)
			(xy 107.847884 -237.267528) (xy 107.8323 -237.314209) (xy 107.809429 -237.357786) (xy 107.779864 -237.39713)
			(xy 107.744371 -237.431222) (xy 107.703868 -237.459178) (xy 107.659406 -237.480276) (xy 107.612135 -237.493968)
			(xy 107.56328 -237.4999) (xy 107.514105 -237.497919) (xy 107.465886 -237.488075) (xy 107.41987 -237.470623)
			(xy 107.377249 -237.446016) (xy 107.339128 -237.414891) (xy 107.306493 -237.378054) (xy 107.28019 -237.336458)
			(xy 107.260899 -237.291182) (xy 107.249122 -237.243398) (xy 107.245162 -237.194344) (xy 106.916474 -237.194344)
			(xy 106.915979 -237.218951) (xy 106.908084 -237.267528) (xy 106.8925 -237.314209) (xy 106.869629 -237.357786)
			(xy 106.840064 -237.39713) (xy 106.804571 -237.431222) (xy 106.764068 -237.459178) (xy 106.719606 -237.480276)
			(xy 106.672335 -237.493968) (xy 106.62348 -237.4999) (xy 106.574305 -237.497919) (xy 106.526086 -237.488075)
			(xy 106.48007 -237.470623) (xy 106.437449 -237.446016) (xy 106.399328 -237.414891) (xy 106.366693 -237.378054)
			(xy 106.34039 -237.336458) (xy 106.321099 -237.291182) (xy 106.309322 -237.243398) (xy 106.305362 -237.194344)
			(xy 105.97642 -237.194344) (xy 105.975925 -237.218951) (xy 105.96803 -237.267528) (xy 105.952446 -237.314209)
			(xy 105.929575 -237.357786) (xy 105.90001 -237.39713) (xy 105.864517 -237.431222) (xy 105.824014 -237.459178)
			(xy 105.779552 -237.480276) (xy 105.732281 -237.493968) (xy 105.683426 -237.4999) (xy 105.634251 -237.497919)
			(xy 105.586032 -237.488075) (xy 105.540016 -237.470623) (xy 105.497395 -237.446016) (xy 105.459274 -237.414891)
			(xy 105.426639 -237.378054) (xy 105.400336 -237.336458) (xy 105.381045 -237.291182) (xy 105.369268 -237.243398)
			(xy 105.365308 -237.194344) (xy 105.036366 -237.194344) (xy 105.035871 -237.218951) (xy 105.027976 -237.267528)
			(xy 105.012392 -237.314209) (xy 104.989521 -237.357786) (xy 104.959956 -237.39713) (xy 104.924463 -237.431222)
			(xy 104.88396 -237.459178) (xy 104.839498 -237.480276) (xy 104.792227 -237.493968) (xy 104.743372 -237.4999)
			(xy 104.694197 -237.497919) (xy 104.645978 -237.488075) (xy 104.599962 -237.470623) (xy 104.557341 -237.446016)
			(xy 104.51922 -237.414891) (xy 104.486585 -237.378054) (xy 104.460282 -237.336458) (xy 104.440991 -237.291182)
			(xy 104.429214 -237.243398) (xy 104.425254 -237.194344) (xy 104.096312 -237.194344) (xy 104.095817 -237.218951)
			(xy 104.087922 -237.267528) (xy 104.072338 -237.314209) (xy 104.049467 -237.357786) (xy 104.019902 -237.39713)
			(xy 103.984409 -237.431222) (xy 103.943906 -237.459178) (xy 103.899444 -237.480276) (xy 103.852173 -237.493968)
			(xy 103.803318 -237.4999) (xy 103.754143 -237.497919) (xy 103.705924 -237.488075) (xy 103.659908 -237.470623)
			(xy 103.617287 -237.446016) (xy 103.579166 -237.414891) (xy 103.546531 -237.378054) (xy 103.520228 -237.336458)
			(xy 103.500937 -237.291182) (xy 103.48916 -237.243398) (xy 103.4852 -237.194344) (xy 103.156258 -237.194344)
			(xy 103.155763 -237.218951) (xy 103.147868 -237.267528) (xy 103.132284 -237.314209) (xy 103.109413 -237.357786)
			(xy 103.079848 -237.39713) (xy 103.044355 -237.431222) (xy 103.003852 -237.459178) (xy 102.95939 -237.480276)
			(xy 102.912119 -237.493968) (xy 102.863264 -237.4999) (xy 102.814089 -237.497919) (xy 102.76587 -237.488075)
			(xy 102.719854 -237.470623) (xy 102.677233 -237.446016) (xy 102.639112 -237.414891) (xy 102.606477 -237.378054)
			(xy 102.580174 -237.336458) (xy 102.560883 -237.291182) (xy 102.549106 -237.243398) (xy 102.545146 -237.194344)
			(xy 102.216458 -237.194344) (xy 102.215984 -237.218334) (xy 102.208473 -237.265724) (xy 102.193642 -237.311355)
			(xy 102.171857 -237.354105) (xy 102.143654 -237.392922) (xy 102.109727 -237.42685) (xy 102.07091 -237.455054)
			(xy 102.028161 -237.47684) (xy 101.98253 -237.491671) (xy 101.93514 -237.499184) (xy 101.91115 -237.499652)
			(xy 101.898451 -237.499507) (xy 101.873143 -237.497349) (xy 101.860604 -237.495334) (xy 101.839593 -237.491477)
			(xy 101.798841 -237.478668) (xy 101.760268 -237.460312) (xy 101.74224 -237.448852) (xy 101.741986 -237.448598)
			(xy 101.731945 -237.442574) (xy 101.708758 -237.439508) (xy 101.686617 -237.447047) (xy 101.677978 -237.454948)
			(xy 101.558598 -237.574328) (xy 101.550658 -237.583233) (xy 101.543253 -237.605882) (xy 101.544374 -237.617762)
			(xy 101.556566 -237.696756) (xy 101.557613 -237.702626) (xy 101.562101 -237.713671) (xy 101.565456 -237.7186)
			(xy 101.569012 -237.72368) (xy 101.577902 -237.7313) (xy 101.583236 -237.734094) (xy 101.603994 -237.745548)
			(xy 101.642009 -237.773875) (xy 101.675196 -237.80773) (xy 101.702759 -237.846303) (xy 101.724037 -237.888668)
			(xy 101.73852 -237.93381) (xy 101.745861 -237.980646) (xy 101.746304 -238.00435) (xy 102.075246 -238.00435)
			(xy 102.079206 -237.955296) (xy 102.090983 -237.907512) (xy 102.110274 -237.862236) (xy 102.136577 -237.82064)
			(xy 102.169212 -237.783803) (xy 102.207333 -237.752678) (xy 102.249954 -237.728071) (xy 102.29597 -237.710619)
			(xy 102.344189 -237.700775) (xy 102.393364 -237.698794) (xy 102.442219 -237.704726) (xy 102.48949 -237.718418)
			(xy 102.533952 -237.739516) (xy 102.574455 -237.767472) (xy 102.609948 -237.801564) (xy 102.639513 -237.840908)
			(xy 102.662384 -237.884485) (xy 102.677968 -237.931166) (xy 102.685863 -237.979743) (xy 102.686358 -238.00435)
			(xy 103.0153 -238.00435) (xy 103.01926 -237.955296) (xy 103.031037 -237.907512) (xy 103.050328 -237.862236)
			(xy 103.076631 -237.82064) (xy 103.109266 -237.783803) (xy 103.147387 -237.752678) (xy 103.190008 -237.728071)
			(xy 103.236024 -237.710619) (xy 103.284243 -237.700775) (xy 103.333418 -237.698794) (xy 103.382273 -237.704726)
			(xy 103.429544 -237.718418) (xy 103.474006 -237.739516) (xy 103.514509 -237.767472) (xy 103.550002 -237.801564)
			(xy 103.579567 -237.840908) (xy 103.602438 -237.884485) (xy 103.618022 -237.931166) (xy 103.625917 -237.979743)
			(xy 103.626412 -238.00435) (xy 103.955354 -238.00435) (xy 103.959314 -237.955296) (xy 103.971091 -237.907512)
			(xy 103.990382 -237.862236) (xy 104.016685 -237.82064) (xy 104.04932 -237.783803) (xy 104.087441 -237.752678)
			(xy 104.130062 -237.728071) (xy 104.176078 -237.710619) (xy 104.224297 -237.700775) (xy 104.273472 -237.698794)
			(xy 104.322327 -237.704726) (xy 104.369598 -237.718418) (xy 104.41406 -237.739516) (xy 104.454563 -237.767472)
			(xy 104.490056 -237.801564) (xy 104.519621 -237.840908) (xy 104.542492 -237.884485) (xy 104.558076 -237.931166)
			(xy 104.565971 -237.979743) (xy 104.566466 -238.00435) (xy 104.895154 -238.00435) (xy 104.899114 -237.955296)
			(xy 104.910891 -237.907512) (xy 104.930182 -237.862236) (xy 104.956485 -237.82064) (xy 104.98912 -237.783803)
			(xy 105.027241 -237.752678) (xy 105.069862 -237.728071) (xy 105.115878 -237.710619) (xy 105.164097 -237.700775)
			(xy 105.213272 -237.698794) (xy 105.262127 -237.704726) (xy 105.309398 -237.718418) (xy 105.35386 -237.739516)
			(xy 105.394363 -237.767472) (xy 105.429856 -237.801564) (xy 105.459421 -237.840908) (xy 105.482292 -237.884485)
			(xy 105.497876 -237.931166) (xy 105.505771 -237.979743) (xy 105.506266 -238.00435) (xy 105.835208 -238.00435)
			(xy 105.839168 -237.955296) (xy 105.850945 -237.907512) (xy 105.870236 -237.862236) (xy 105.896539 -237.82064)
			(xy 105.929174 -237.783803) (xy 105.967295 -237.752678) (xy 106.009916 -237.728071) (xy 106.055932 -237.710619)
			(xy 106.104151 -237.700775) (xy 106.153326 -237.698794) (xy 106.202181 -237.704726) (xy 106.249452 -237.718418)
			(xy 106.293914 -237.739516) (xy 106.334417 -237.767472) (xy 106.36991 -237.801564) (xy 106.399475 -237.840908)
			(xy 106.422346 -237.884485) (xy 106.43793 -237.931166) (xy 106.445825 -237.979743) (xy 106.44632 -238.00435)
			(xy 106.775262 -238.00435) (xy 106.779222 -237.955296) (xy 106.790999 -237.907512) (xy 106.81029 -237.862236)
			(xy 106.836593 -237.82064) (xy 106.869228 -237.783803) (xy 106.907349 -237.752678) (xy 106.94997 -237.728071)
			(xy 106.995986 -237.710619) (xy 107.044205 -237.700775) (xy 107.09338 -237.698794) (xy 107.142235 -237.704726)
			(xy 107.189506 -237.718418) (xy 107.233968 -237.739516) (xy 107.274471 -237.767472) (xy 107.309964 -237.801564)
			(xy 107.339529 -237.840908) (xy 107.3624 -237.884485) (xy 107.377984 -237.931166) (xy 107.385879 -237.979743)
			(xy 107.386374 -238.00435) (xy 107.715316 -238.00435) (xy 107.719276 -237.955296) (xy 107.731053 -237.907512)
			(xy 107.750344 -237.862236) (xy 107.776647 -237.82064) (xy 107.809282 -237.783803) (xy 107.847403 -237.752678)
			(xy 107.890024 -237.728071) (xy 107.93604 -237.710619) (xy 107.984259 -237.700775) (xy 108.033434 -237.698794)
			(xy 108.082289 -237.704726) (xy 108.12956 -237.718418) (xy 108.174022 -237.739516) (xy 108.214525 -237.767472)
			(xy 108.250018 -237.801564) (xy 108.279583 -237.840908) (xy 108.302454 -237.884485) (xy 108.318038 -237.931166)
			(xy 108.325933 -237.979743) (xy 108.326428 -238.00435) (xy 108.65537 -238.00435) (xy 108.65933 -237.955296)
			(xy 108.671107 -237.907512) (xy 108.690398 -237.862236) (xy 108.716701 -237.82064) (xy 108.749336 -237.783803)
			(xy 108.787457 -237.752678) (xy 108.830078 -237.728071) (xy 108.876094 -237.710619) (xy 108.924313 -237.700775)
			(xy 108.973488 -237.698794) (xy 109.022343 -237.704726) (xy 109.069614 -237.718418) (xy 109.114076 -237.739516)
			(xy 109.154579 -237.767472) (xy 109.190072 -237.801564) (xy 109.219637 -237.840908) (xy 109.242508 -237.884485)
			(xy 109.258092 -237.931166) (xy 109.265987 -237.979743) (xy 109.266482 -238.00435) (xy 109.59517 -238.00435)
			(xy 109.59913 -237.955296) (xy 109.610907 -237.907512) (xy 109.630198 -237.862236) (xy 109.656501 -237.82064)
			(xy 109.689136 -237.783803) (xy 109.727257 -237.752678) (xy 109.769878 -237.728071) (xy 109.815894 -237.710619)
			(xy 109.864113 -237.700775) (xy 109.913288 -237.698794) (xy 109.962143 -237.704726) (xy 110.009414 -237.718418)
			(xy 110.053876 -237.739516) (xy 110.094379 -237.767472) (xy 110.129872 -237.801564) (xy 110.159437 -237.840908)
			(xy 110.182308 -237.884485) (xy 110.197892 -237.931166) (xy 110.205787 -237.979743) (xy 110.206282 -238.00435)
			(xy 113.349036 -238.00435) (xy 113.352996 -237.955296) (xy 113.364773 -237.907512) (xy 113.384064 -237.862236)
			(xy 113.410367 -237.82064) (xy 113.443002 -237.783803) (xy 113.481123 -237.752678) (xy 113.523744 -237.728071)
			(xy 113.56976 -237.710619) (xy 113.617979 -237.700775) (xy 113.667154 -237.698794) (xy 113.716009 -237.704726)
			(xy 113.76328 -237.718418) (xy 113.807742 -237.739516) (xy 113.848245 -237.767472) (xy 113.883738 -237.801564)
			(xy 113.913303 -237.840908) (xy 113.936174 -237.884485) (xy 113.951758 -237.931166) (xy 113.959653 -237.979743)
			(xy 113.960148 -238.00435) (xy 114.288836 -238.00435) (xy 114.292796 -237.955296) (xy 114.304573 -237.907512)
			(xy 114.323864 -237.862236) (xy 114.350167 -237.82064) (xy 114.382802 -237.783803) (xy 114.420923 -237.752678)
			(xy 114.463544 -237.728071) (xy 114.50956 -237.710619) (xy 114.557779 -237.700775) (xy 114.606954 -237.698794)
			(xy 114.655809 -237.704726) (xy 114.70308 -237.718418) (xy 114.747542 -237.739516) (xy 114.788045 -237.767472)
			(xy 114.823538 -237.801564) (xy 114.853103 -237.840908) (xy 114.875974 -237.884485) (xy 114.891558 -237.931166)
			(xy 114.899453 -237.979743) (xy 114.899948 -238.00435) (xy 115.22889 -238.00435) (xy 115.23285 -237.955296)
			(xy 115.244627 -237.907512) (xy 115.263918 -237.862236) (xy 115.290221 -237.82064) (xy 115.322856 -237.783803)
			(xy 115.360977 -237.752678) (xy 115.403598 -237.728071) (xy 115.449614 -237.710619) (xy 115.497833 -237.700775)
			(xy 115.547008 -237.698794) (xy 115.595863 -237.704726) (xy 115.643134 -237.718418) (xy 115.687596 -237.739516)
			(xy 115.728099 -237.767472) (xy 115.763592 -237.801564) (xy 115.793157 -237.840908) (xy 115.816028 -237.884485)
			(xy 115.831612 -237.931166) (xy 115.839507 -237.979743) (xy 115.840002 -238.00435) (xy 116.168944 -238.00435)
			(xy 116.172904 -237.955296) (xy 116.184681 -237.907512) (xy 116.203972 -237.862236) (xy 116.230275 -237.82064)
			(xy 116.26291 -237.783803) (xy 116.301031 -237.752678) (xy 116.343652 -237.728071) (xy 116.389668 -237.710619)
			(xy 116.437887 -237.700775) (xy 116.487062 -237.698794) (xy 116.535917 -237.704726) (xy 116.583188 -237.718418)
			(xy 116.62765 -237.739516) (xy 116.668153 -237.767472) (xy 116.703646 -237.801564) (xy 116.733211 -237.840908)
			(xy 116.756082 -237.884485) (xy 116.771666 -237.931166) (xy 116.779561 -237.979743) (xy 116.780056 -238.00435)
			(xy 117.108998 -238.00435) (xy 117.112958 -237.955296) (xy 117.124735 -237.907512) (xy 117.144026 -237.862236)
			(xy 117.170329 -237.82064) (xy 117.202964 -237.783803) (xy 117.241085 -237.752678) (xy 117.283706 -237.728071)
			(xy 117.329722 -237.710619) (xy 117.377941 -237.700775) (xy 117.427116 -237.698794) (xy 117.475971 -237.704726)
			(xy 117.523242 -237.718418) (xy 117.567704 -237.739516) (xy 117.608207 -237.767472) (xy 117.6437 -237.801564)
			(xy 117.673265 -237.840908) (xy 117.696136 -237.884485) (xy 117.71172 -237.931166) (xy 117.719615 -237.979743)
			(xy 117.72011 -238.00435) (xy 118.049052 -238.00435) (xy 118.053012 -237.955296) (xy 118.064789 -237.907512)
			(xy 118.08408 -237.862236) (xy 118.110383 -237.82064) (xy 118.143018 -237.783803) (xy 118.181139 -237.752678)
			(xy 118.22376 -237.728071) (xy 118.269776 -237.710619) (xy 118.317995 -237.700775) (xy 118.36717 -237.698794)
			(xy 118.416025 -237.704726) (xy 118.463296 -237.718418) (xy 118.507758 -237.739516) (xy 118.548261 -237.767472)
			(xy 118.583754 -237.801564) (xy 118.613319 -237.840908) (xy 118.63619 -237.884485) (xy 118.651774 -237.931166)
			(xy 118.659669 -237.979743) (xy 118.660164 -238.00435) (xy 118.988852 -238.00435) (xy 118.992812 -237.955296)
			(xy 119.004589 -237.907512) (xy 119.02388 -237.862236) (xy 119.050183 -237.82064) (xy 119.082818 -237.783803)
			(xy 119.120939 -237.752678) (xy 119.16356 -237.728071) (xy 119.209576 -237.710619) (xy 119.257795 -237.700775)
			(xy 119.30697 -237.698794) (xy 119.355825 -237.704726) (xy 119.403096 -237.718418) (xy 119.447558 -237.739516)
			(xy 119.488061 -237.767472) (xy 119.523554 -237.801564) (xy 119.553119 -237.840908) (xy 119.57599 -237.884485)
			(xy 119.591574 -237.931166) (xy 119.599469 -237.979743) (xy 119.599964 -238.00435) (xy 119.928906 -238.00435)
			(xy 119.932866 -237.955296) (xy 119.944643 -237.907512) (xy 119.963934 -237.862236) (xy 119.990237 -237.82064)
			(xy 120.022872 -237.783803) (xy 120.060993 -237.752678) (xy 120.103614 -237.728071) (xy 120.14963 -237.710619)
			(xy 120.197849 -237.700775) (xy 120.247024 -237.698794) (xy 120.295879 -237.704726) (xy 120.34315 -237.718418)
			(xy 120.387612 -237.739516) (xy 120.428115 -237.767472) (xy 120.463608 -237.801564) (xy 120.493173 -237.840908)
			(xy 120.516044 -237.884485) (xy 120.531628 -237.931166) (xy 120.539523 -237.979743) (xy 120.540018 -238.00435)
			(xy 120.86896 -238.00435) (xy 120.87292 -237.955296) (xy 120.884697 -237.907512) (xy 120.903988 -237.862236)
			(xy 120.930291 -237.82064) (xy 120.962926 -237.783803) (xy 121.001047 -237.752678) (xy 121.043668 -237.728071)
			(xy 121.089684 -237.710619) (xy 121.137903 -237.700775) (xy 121.187078 -237.698794) (xy 121.235933 -237.704726)
			(xy 121.283204 -237.718418) (xy 121.327666 -237.739516) (xy 121.368169 -237.767472) (xy 121.403662 -237.801564)
			(xy 121.433227 -237.840908) (xy 121.456098 -237.884485) (xy 121.471682 -237.931166) (xy 121.479577 -237.979743)
			(xy 121.480072 -238.00435) (xy 121.809014 -238.00435) (xy 121.812974 -237.955296) (xy 121.824751 -237.907512)
			(xy 121.844042 -237.862236) (xy 121.870345 -237.82064) (xy 121.90298 -237.783803) (xy 121.941101 -237.752678)
			(xy 121.983722 -237.728071) (xy 122.029738 -237.710619) (xy 122.077957 -237.700775) (xy 122.127132 -237.698794)
			(xy 122.175987 -237.704726) (xy 122.223258 -237.718418) (xy 122.26772 -237.739516) (xy 122.308223 -237.767472)
			(xy 122.343716 -237.801564) (xy 122.373281 -237.840908) (xy 122.396152 -237.884485) (xy 122.411736 -237.931166)
			(xy 122.419631 -237.979743) (xy 122.420126 -238.00435) (xy 122.748814 -238.00435) (xy 122.752774 -237.955296)
			(xy 122.764551 -237.907512) (xy 122.783842 -237.862236) (xy 122.810145 -237.82064) (xy 122.84278 -237.783803)
			(xy 122.880901 -237.752678) (xy 122.923522 -237.728071) (xy 122.969538 -237.710619) (xy 123.017757 -237.700775)
			(xy 123.066932 -237.698794) (xy 123.115787 -237.704726) (xy 123.163058 -237.718418) (xy 123.20752 -237.739516)
			(xy 123.248023 -237.767472) (xy 123.283516 -237.801564) (xy 123.313081 -237.840908) (xy 123.335952 -237.884485)
			(xy 123.351536 -237.931166) (xy 123.359431 -237.979743) (xy 123.359926 -238.00435) (xy 123.688868 -238.00435)
			(xy 123.692828 -237.955296) (xy 123.704605 -237.907512) (xy 123.723896 -237.862236) (xy 123.750199 -237.82064)
			(xy 123.782834 -237.783803) (xy 123.820955 -237.752678) (xy 123.863576 -237.728071) (xy 123.909592 -237.710619)
			(xy 123.957811 -237.700775) (xy 124.006986 -237.698794) (xy 124.055841 -237.704726) (xy 124.103112 -237.718418)
			(xy 124.147574 -237.739516) (xy 124.188077 -237.767472) (xy 124.22357 -237.801564) (xy 124.253135 -237.840908)
			(xy 124.276006 -237.884485) (xy 124.29159 -237.931166) (xy 124.299485 -237.979743) (xy 124.29998 -238.00435)
			(xy 124.628922 -238.00435) (xy 124.632882 -237.955296) (xy 124.644659 -237.907512) (xy 124.66395 -237.862236)
			(xy 124.690253 -237.82064) (xy 124.722888 -237.783803) (xy 124.761009 -237.752678) (xy 124.80363 -237.728071)
			(xy 124.849646 -237.710619) (xy 124.897865 -237.700775) (xy 124.94704 -237.698794) (xy 124.995895 -237.704726)
			(xy 125.043166 -237.718418) (xy 125.087628 -237.739516) (xy 125.128131 -237.767472) (xy 125.163624 -237.801564)
			(xy 125.193189 -237.840908) (xy 125.21606 -237.884485) (xy 125.231644 -237.931166) (xy 125.239539 -237.979743)
			(xy 125.240034 -238.00435) (xy 125.568976 -238.00435) (xy 125.572936 -237.955296) (xy 125.584713 -237.907512)
			(xy 125.604004 -237.862236) (xy 125.630307 -237.82064) (xy 125.662942 -237.783803) (xy 125.701063 -237.752678)
			(xy 125.743684 -237.728071) (xy 125.7897 -237.710619) (xy 125.837919 -237.700775) (xy 125.887094 -237.698794)
			(xy 125.935949 -237.704726) (xy 125.98322 -237.718418) (xy 126.027682 -237.739516) (xy 126.068185 -237.767472)
			(xy 126.103678 -237.801564) (xy 126.133243 -237.840908) (xy 126.156114 -237.884485) (xy 126.171698 -237.931166)
			(xy 126.179593 -237.979743) (xy 126.180088 -238.00435) (xy 126.50903 -238.00435) (xy 126.51299 -237.955296)
			(xy 126.524767 -237.907512) (xy 126.544058 -237.862236) (xy 126.570361 -237.82064) (xy 126.602996 -237.783803)
			(xy 126.641117 -237.752678) (xy 126.683738 -237.728071) (xy 126.729754 -237.710619) (xy 126.777973 -237.700775)
			(xy 126.827148 -237.698794) (xy 126.876003 -237.704726) (xy 126.923274 -237.718418) (xy 126.967736 -237.739516)
			(xy 127.008239 -237.767472) (xy 127.043732 -237.801564) (xy 127.073297 -237.840908) (xy 127.096168 -237.884485)
			(xy 127.111752 -237.931166) (xy 127.119647 -237.979743) (xy 127.120142 -238.00435) (xy 127.438399 -238.00435)
			(xy 127.442494 -237.953622) (xy 127.454673 -237.904208) (xy 127.474621 -237.857388) (xy 127.501822 -237.814374)
			(xy 127.53557 -237.77628) (xy 127.574992 -237.744093) (xy 127.619066 -237.718647) (xy 127.666652 -237.7006)
			(xy 127.716516 -237.69042) (xy 127.767368 -237.688371) (xy 127.817889 -237.694505) (xy 127.866773 -237.708665)
			(xy 127.912752 -237.730482) (xy 127.954636 -237.759392) (xy 127.99134 -237.794647) (xy 128.021913 -237.835333)
			(xy 128.045564 -237.880396) (xy 128.06168 -237.92867) (xy 128.069844 -237.978904) (xy 128.070356 -238.00435)
			(xy 128.388884 -238.00435) (xy 128.392844 -237.955296) (xy 128.404621 -237.907512) (xy 128.423912 -237.862236)
			(xy 128.450215 -237.82064) (xy 128.48285 -237.783803) (xy 128.520971 -237.752678) (xy 128.563592 -237.728071)
			(xy 128.609608 -237.710619) (xy 128.657827 -237.700775) (xy 128.707002 -237.698794) (xy 128.755857 -237.704726)
			(xy 128.803128 -237.718418) (xy 128.84759 -237.739516) (xy 128.888093 -237.767472) (xy 128.923586 -237.801564)
			(xy 128.953151 -237.840908) (xy 128.976022 -237.884485) (xy 128.991606 -237.931166) (xy 128.999501 -237.979743)
			(xy 128.999996 -238.00435) (xy 129.318507 -238.00435) (xy 129.322602 -237.953622) (xy 129.334781 -237.904208)
			(xy 129.354729 -237.857388) (xy 129.38193 -237.814374) (xy 129.415678 -237.77628) (xy 129.4551 -237.744093)
			(xy 129.499174 -237.718647) (xy 129.54676 -237.7006) (xy 129.596624 -237.69042) (xy 129.647476 -237.688371)
			(xy 129.697997 -237.694505) (xy 129.746881 -237.708665) (xy 129.79286 -237.730482) (xy 129.834744 -237.759392)
			(xy 129.871448 -237.794647) (xy 129.902021 -237.835333) (xy 129.925672 -237.880396) (xy 129.941788 -237.92867)
			(xy 129.949952 -237.978904) (xy 129.950464 -238.00435) (xy 129.949952 -238.029796) (xy 129.941788 -238.08003)
			(xy 129.925672 -238.128304) (xy 129.902021 -238.173367) (xy 129.871448 -238.214053) (xy 129.834744 -238.249308)
			(xy 129.79286 -238.278218) (xy 129.746881 -238.300035) (xy 129.697997 -238.314195) (xy 129.647476 -238.320329)
			(xy 129.596624 -238.31828) (xy 129.54676 -238.3081) (xy 129.499174 -238.290053) (xy 129.4551 -238.264607)
			(xy 129.415678 -238.23242) (xy 129.38193 -238.194326) (xy 129.354729 -238.151312) (xy 129.334781 -238.104492)
			(xy 129.322602 -238.055078) (xy 129.318507 -238.00435) (xy 128.999996 -238.00435) (xy 128.999501 -238.028957)
			(xy 128.991606 -238.077534) (xy 128.976022 -238.124215) (xy 128.953151 -238.167792) (xy 128.923586 -238.207136)
			(xy 128.888093 -238.241228) (xy 128.84759 -238.269184) (xy 128.803128 -238.290282) (xy 128.755857 -238.303974)
			(xy 128.707002 -238.309906) (xy 128.657827 -238.307925) (xy 128.609608 -238.298081) (xy 128.563592 -238.280629)
			(xy 128.520971 -238.256022) (xy 128.48285 -238.224897) (xy 128.450215 -238.18806) (xy 128.423912 -238.146464)
			(xy 128.404621 -238.101188) (xy 128.392844 -238.053404) (xy 128.388884 -238.00435) (xy 128.070356 -238.00435)
			(xy 128.069844 -238.029796) (xy 128.06168 -238.08003) (xy 128.045564 -238.128304) (xy 128.021913 -238.173367)
			(xy 127.99134 -238.214053) (xy 127.954636 -238.249308) (xy 127.912752 -238.278218) (xy 127.866773 -238.300035)
			(xy 127.817889 -238.314195) (xy 127.767368 -238.320329) (xy 127.716516 -238.31828) (xy 127.666652 -238.3081)
			(xy 127.619066 -238.290053) (xy 127.574992 -238.264607) (xy 127.53557 -238.23242) (xy 127.501822 -238.194326)
			(xy 127.474621 -238.151312) (xy 127.454673 -238.104492) (xy 127.442494 -238.055078) (xy 127.438399 -238.00435)
			(xy 127.120142 -238.00435) (xy 127.119647 -238.028957) (xy 127.111752 -238.077534) (xy 127.096168 -238.124215)
			(xy 127.073297 -238.167792) (xy 127.043732 -238.207136) (xy 127.008239 -238.241228) (xy 126.967736 -238.269184)
			(xy 126.923274 -238.290282) (xy 126.876003 -238.303974) (xy 126.827148 -238.309906) (xy 126.777973 -238.307925)
			(xy 126.729754 -238.298081) (xy 126.683738 -238.280629) (xy 126.641117 -238.256022) (xy 126.602996 -238.224897)
			(xy 126.570361 -238.18806) (xy 126.544058 -238.146464) (xy 126.524767 -238.101188) (xy 126.51299 -238.053404)
			(xy 126.50903 -238.00435) (xy 126.180088 -238.00435) (xy 126.179593 -238.028957) (xy 126.171698 -238.077534)
			(xy 126.156114 -238.124215) (xy 126.133243 -238.167792) (xy 126.103678 -238.207136) (xy 126.068185 -238.241228)
			(xy 126.027682 -238.269184) (xy 125.98322 -238.290282) (xy 125.935949 -238.303974) (xy 125.887094 -238.309906)
			(xy 125.837919 -238.307925) (xy 125.7897 -238.298081) (xy 125.743684 -238.280629) (xy 125.701063 -238.256022)
			(xy 125.662942 -238.224897) (xy 125.630307 -238.18806) (xy 125.604004 -238.146464) (xy 125.584713 -238.101188)
			(xy 125.572936 -238.053404) (xy 125.568976 -238.00435) (xy 125.240034 -238.00435) (xy 125.239539 -238.028957)
			(xy 125.231644 -238.077534) (xy 125.21606 -238.124215) (xy 125.193189 -238.167792) (xy 125.163624 -238.207136)
			(xy 125.128131 -238.241228) (xy 125.087628 -238.269184) (xy 125.043166 -238.290282) (xy 124.995895 -238.303974)
			(xy 124.94704 -238.309906) (xy 124.897865 -238.307925) (xy 124.849646 -238.298081) (xy 124.80363 -238.280629)
			(xy 124.761009 -238.256022) (xy 124.722888 -238.224897) (xy 124.690253 -238.18806) (xy 124.66395 -238.146464)
			(xy 124.644659 -238.101188) (xy 124.632882 -238.053404) (xy 124.628922 -238.00435) (xy 124.29998 -238.00435)
			(xy 124.299485 -238.028957) (xy 124.29159 -238.077534) (xy 124.276006 -238.124215) (xy 124.253135 -238.167792)
			(xy 124.22357 -238.207136) (xy 124.188077 -238.241228) (xy 124.147574 -238.269184) (xy 124.103112 -238.290282)
			(xy 124.055841 -238.303974) (xy 124.006986 -238.309906) (xy 123.957811 -238.307925) (xy 123.909592 -238.298081)
			(xy 123.863576 -238.280629) (xy 123.820955 -238.256022) (xy 123.782834 -238.224897) (xy 123.750199 -238.18806)
			(xy 123.723896 -238.146464) (xy 123.704605 -238.101188) (xy 123.692828 -238.053404) (xy 123.688868 -238.00435)
			(xy 123.359926 -238.00435) (xy 123.359431 -238.028957) (xy 123.351536 -238.077534) (xy 123.335952 -238.124215)
			(xy 123.313081 -238.167792) (xy 123.283516 -238.207136) (xy 123.248023 -238.241228) (xy 123.20752 -238.269184)
			(xy 123.163058 -238.290282) (xy 123.115787 -238.303974) (xy 123.066932 -238.309906) (xy 123.017757 -238.307925)
			(xy 122.969538 -238.298081) (xy 122.923522 -238.280629) (xy 122.880901 -238.256022) (xy 122.84278 -238.224897)
			(xy 122.810145 -238.18806) (xy 122.783842 -238.146464) (xy 122.764551 -238.101188) (xy 122.752774 -238.053404)
			(xy 122.748814 -238.00435) (xy 122.420126 -238.00435) (xy 122.419631 -238.028957) (xy 122.411736 -238.077534)
			(xy 122.396152 -238.124215) (xy 122.373281 -238.167792) (xy 122.343716 -238.207136) (xy 122.308223 -238.241228)
			(xy 122.26772 -238.269184) (xy 122.223258 -238.290282) (xy 122.175987 -238.303974) (xy 122.127132 -238.309906)
			(xy 122.077957 -238.307925) (xy 122.029738 -238.298081) (xy 121.983722 -238.280629) (xy 121.941101 -238.256022)
			(xy 121.90298 -238.224897) (xy 121.870345 -238.18806) (xy 121.844042 -238.146464) (xy 121.824751 -238.101188)
			(xy 121.812974 -238.053404) (xy 121.809014 -238.00435) (xy 121.480072 -238.00435) (xy 121.479577 -238.028957)
			(xy 121.471682 -238.077534) (xy 121.456098 -238.124215) (xy 121.433227 -238.167792) (xy 121.403662 -238.207136)
			(xy 121.368169 -238.241228) (xy 121.327666 -238.269184) (xy 121.283204 -238.290282) (xy 121.235933 -238.303974)
			(xy 121.187078 -238.309906) (xy 121.137903 -238.307925) (xy 121.089684 -238.298081) (xy 121.043668 -238.280629)
			(xy 121.001047 -238.256022) (xy 120.962926 -238.224897) (xy 120.930291 -238.18806) (xy 120.903988 -238.146464)
			(xy 120.884697 -238.101188) (xy 120.87292 -238.053404) (xy 120.86896 -238.00435) (xy 120.540018 -238.00435)
			(xy 120.539523 -238.028957) (xy 120.531628 -238.077534) (xy 120.516044 -238.124215) (xy 120.493173 -238.167792)
			(xy 120.463608 -238.207136) (xy 120.428115 -238.241228) (xy 120.387612 -238.269184) (xy 120.34315 -238.290282)
			(xy 120.295879 -238.303974) (xy 120.247024 -238.309906) (xy 120.197849 -238.307925) (xy 120.14963 -238.298081)
			(xy 120.103614 -238.280629) (xy 120.060993 -238.256022) (xy 120.022872 -238.224897) (xy 119.990237 -238.18806)
			(xy 119.963934 -238.146464) (xy 119.944643 -238.101188) (xy 119.932866 -238.053404) (xy 119.928906 -238.00435)
			(xy 119.599964 -238.00435) (xy 119.599469 -238.028957) (xy 119.591574 -238.077534) (xy 119.57599 -238.124215)
			(xy 119.553119 -238.167792) (xy 119.523554 -238.207136) (xy 119.488061 -238.241228) (xy 119.447558 -238.269184)
			(xy 119.403096 -238.290282) (xy 119.355825 -238.303974) (xy 119.30697 -238.309906) (xy 119.257795 -238.307925)
			(xy 119.209576 -238.298081) (xy 119.16356 -238.280629) (xy 119.120939 -238.256022) (xy 119.082818 -238.224897)
			(xy 119.050183 -238.18806) (xy 119.02388 -238.146464) (xy 119.004589 -238.101188) (xy 118.992812 -238.053404)
			(xy 118.988852 -238.00435) (xy 118.660164 -238.00435) (xy 118.659669 -238.028957) (xy 118.651774 -238.077534)
			(xy 118.63619 -238.124215) (xy 118.613319 -238.167792) (xy 118.583754 -238.207136) (xy 118.548261 -238.241228)
			(xy 118.507758 -238.269184) (xy 118.463296 -238.290282) (xy 118.416025 -238.303974) (xy 118.36717 -238.309906)
			(xy 118.317995 -238.307925) (xy 118.269776 -238.298081) (xy 118.22376 -238.280629) (xy 118.181139 -238.256022)
			(xy 118.143018 -238.224897) (xy 118.110383 -238.18806) (xy 118.08408 -238.146464) (xy 118.064789 -238.101188)
			(xy 118.053012 -238.053404) (xy 118.049052 -238.00435) (xy 117.72011 -238.00435) (xy 117.719615 -238.028957)
			(xy 117.71172 -238.077534) (xy 117.696136 -238.124215) (xy 117.673265 -238.167792) (xy 117.6437 -238.207136)
			(xy 117.608207 -238.241228) (xy 117.567704 -238.269184) (xy 117.523242 -238.290282) (xy 117.475971 -238.303974)
			(xy 117.427116 -238.309906) (xy 117.377941 -238.307925) (xy 117.329722 -238.298081) (xy 117.283706 -238.280629)
			(xy 117.241085 -238.256022) (xy 117.202964 -238.224897) (xy 117.170329 -238.18806) (xy 117.144026 -238.146464)
			(xy 117.124735 -238.101188) (xy 117.112958 -238.053404) (xy 117.108998 -238.00435) (xy 116.780056 -238.00435)
			(xy 116.779561 -238.028957) (xy 116.771666 -238.077534) (xy 116.756082 -238.124215) (xy 116.733211 -238.167792)
			(xy 116.703646 -238.207136) (xy 116.668153 -238.241228) (xy 116.62765 -238.269184) (xy 116.583188 -238.290282)
			(xy 116.535917 -238.303974) (xy 116.487062 -238.309906) (xy 116.437887 -238.307925) (xy 116.389668 -238.298081)
			(xy 116.343652 -238.280629) (xy 116.301031 -238.256022) (xy 116.26291 -238.224897) (xy 116.230275 -238.18806)
			(xy 116.203972 -238.146464) (xy 116.184681 -238.101188) (xy 116.172904 -238.053404) (xy 116.168944 -238.00435)
			(xy 115.840002 -238.00435) (xy 115.839507 -238.028957) (xy 115.831612 -238.077534) (xy 115.816028 -238.124215)
			(xy 115.793157 -238.167792) (xy 115.763592 -238.207136) (xy 115.728099 -238.241228) (xy 115.687596 -238.269184)
			(xy 115.643134 -238.290282) (xy 115.595863 -238.303974) (xy 115.547008 -238.309906) (xy 115.497833 -238.307925)
			(xy 115.449614 -238.298081) (xy 115.403598 -238.280629) (xy 115.360977 -238.256022) (xy 115.322856 -238.224897)
			(xy 115.290221 -238.18806) (xy 115.263918 -238.146464) (xy 115.244627 -238.101188) (xy 115.23285 -238.053404)
			(xy 115.22889 -238.00435) (xy 114.899948 -238.00435) (xy 114.899453 -238.028957) (xy 114.891558 -238.077534)
			(xy 114.875974 -238.124215) (xy 114.853103 -238.167792) (xy 114.823538 -238.207136) (xy 114.788045 -238.241228)
			(xy 114.747542 -238.269184) (xy 114.70308 -238.290282) (xy 114.655809 -238.303974) (xy 114.606954 -238.309906)
			(xy 114.557779 -238.307925) (xy 114.50956 -238.298081) (xy 114.463544 -238.280629) (xy 114.420923 -238.256022)
			(xy 114.382802 -238.224897) (xy 114.350167 -238.18806) (xy 114.323864 -238.146464) (xy 114.304573 -238.101188)
			(xy 114.292796 -238.053404) (xy 114.288836 -238.00435) (xy 113.960148 -238.00435) (xy 113.959653 -238.028957)
			(xy 113.951758 -238.077534) (xy 113.936174 -238.124215) (xy 113.913303 -238.167792) (xy 113.883738 -238.207136)
			(xy 113.848245 -238.241228) (xy 113.807742 -238.269184) (xy 113.76328 -238.290282) (xy 113.716009 -238.303974)
			(xy 113.667154 -238.309906) (xy 113.617979 -238.307925) (xy 113.56976 -238.298081) (xy 113.523744 -238.280629)
			(xy 113.481123 -238.256022) (xy 113.443002 -238.224897) (xy 113.410367 -238.18806) (xy 113.384064 -238.146464)
			(xy 113.364773 -238.101188) (xy 113.352996 -238.053404) (xy 113.349036 -238.00435) (xy 110.206282 -238.00435)
			(xy 110.205787 -238.028957) (xy 110.197892 -238.077534) (xy 110.182308 -238.124215) (xy 110.159437 -238.167792)
			(xy 110.129872 -238.207136) (xy 110.094379 -238.241228) (xy 110.053876 -238.269184) (xy 110.009414 -238.290282)
			(xy 109.962143 -238.303974) (xy 109.913288 -238.309906) (xy 109.864113 -238.307925) (xy 109.815894 -238.298081)
			(xy 109.769878 -238.280629) (xy 109.727257 -238.256022) (xy 109.689136 -238.224897) (xy 109.656501 -238.18806)
			(xy 109.630198 -238.146464) (xy 109.610907 -238.101188) (xy 109.59913 -238.053404) (xy 109.59517 -238.00435)
			(xy 109.266482 -238.00435) (xy 109.265987 -238.028957) (xy 109.258092 -238.077534) (xy 109.242508 -238.124215)
			(xy 109.219637 -238.167792) (xy 109.190072 -238.207136) (xy 109.154579 -238.241228) (xy 109.114076 -238.269184)
			(xy 109.069614 -238.290282) (xy 109.022343 -238.303974) (xy 108.973488 -238.309906) (xy 108.924313 -238.307925)
			(xy 108.876094 -238.298081) (xy 108.830078 -238.280629) (xy 108.787457 -238.256022) (xy 108.749336 -238.224897)
			(xy 108.716701 -238.18806) (xy 108.690398 -238.146464) (xy 108.671107 -238.101188) (xy 108.65933 -238.053404)
			(xy 108.65537 -238.00435) (xy 108.326428 -238.00435) (xy 108.325933 -238.028957) (xy 108.318038 -238.077534)
			(xy 108.302454 -238.124215) (xy 108.279583 -238.167792) (xy 108.250018 -238.207136) (xy 108.214525 -238.241228)
			(xy 108.174022 -238.269184) (xy 108.12956 -238.290282) (xy 108.082289 -238.303974) (xy 108.033434 -238.309906)
			(xy 107.984259 -238.307925) (xy 107.93604 -238.298081) (xy 107.890024 -238.280629) (xy 107.847403 -238.256022)
			(xy 107.809282 -238.224897) (xy 107.776647 -238.18806) (xy 107.750344 -238.146464) (xy 107.731053 -238.101188)
			(xy 107.719276 -238.053404) (xy 107.715316 -238.00435) (xy 107.386374 -238.00435) (xy 107.385879 -238.028957)
			(xy 107.377984 -238.077534) (xy 107.3624 -238.124215) (xy 107.339529 -238.167792) (xy 107.309964 -238.207136)
			(xy 107.274471 -238.241228) (xy 107.233968 -238.269184) (xy 107.189506 -238.290282) (xy 107.142235 -238.303974)
			(xy 107.09338 -238.309906) (xy 107.044205 -238.307925) (xy 106.995986 -238.298081) (xy 106.94997 -238.280629)
			(xy 106.907349 -238.256022) (xy 106.869228 -238.224897) (xy 106.836593 -238.18806) (xy 106.81029 -238.146464)
			(xy 106.790999 -238.101188) (xy 106.779222 -238.053404) (xy 106.775262 -238.00435) (xy 106.44632 -238.00435)
			(xy 106.445825 -238.028957) (xy 106.43793 -238.077534) (xy 106.422346 -238.124215) (xy 106.399475 -238.167792)
			(xy 106.36991 -238.207136) (xy 106.334417 -238.241228) (xy 106.293914 -238.269184) (xy 106.249452 -238.290282)
			(xy 106.202181 -238.303974) (xy 106.153326 -238.309906) (xy 106.104151 -238.307925) (xy 106.055932 -238.298081)
			(xy 106.009916 -238.280629) (xy 105.967295 -238.256022) (xy 105.929174 -238.224897) (xy 105.896539 -238.18806)
			(xy 105.870236 -238.146464) (xy 105.850945 -238.101188) (xy 105.839168 -238.053404) (xy 105.835208 -238.00435)
			(xy 105.506266 -238.00435) (xy 105.505771 -238.028957) (xy 105.497876 -238.077534) (xy 105.482292 -238.124215)
			(xy 105.459421 -238.167792) (xy 105.429856 -238.207136) (xy 105.394363 -238.241228) (xy 105.35386 -238.269184)
			(xy 105.309398 -238.290282) (xy 105.262127 -238.303974) (xy 105.213272 -238.309906) (xy 105.164097 -238.307925)
			(xy 105.115878 -238.298081) (xy 105.069862 -238.280629) (xy 105.027241 -238.256022) (xy 104.98912 -238.224897)
			(xy 104.956485 -238.18806) (xy 104.930182 -238.146464) (xy 104.910891 -238.101188) (xy 104.899114 -238.053404)
			(xy 104.895154 -238.00435) (xy 104.566466 -238.00435) (xy 104.565971 -238.028957) (xy 104.558076 -238.077534)
			(xy 104.542492 -238.124215) (xy 104.519621 -238.167792) (xy 104.490056 -238.207136) (xy 104.454563 -238.241228)
			(xy 104.41406 -238.269184) (xy 104.369598 -238.290282) (xy 104.322327 -238.303974) (xy 104.273472 -238.309906)
			(xy 104.224297 -238.307925) (xy 104.176078 -238.298081) (xy 104.130062 -238.280629) (xy 104.087441 -238.256022)
			(xy 104.04932 -238.224897) (xy 104.016685 -238.18806) (xy 103.990382 -238.146464) (xy 103.971091 -238.101188)
			(xy 103.959314 -238.053404) (xy 103.955354 -238.00435) (xy 103.626412 -238.00435) (xy 103.625917 -238.028957)
			(xy 103.618022 -238.077534) (xy 103.602438 -238.124215) (xy 103.579567 -238.167792) (xy 103.550002 -238.207136)
			(xy 103.514509 -238.241228) (xy 103.474006 -238.269184) (xy 103.429544 -238.290282) (xy 103.382273 -238.303974)
			(xy 103.333418 -238.309906) (xy 103.284243 -238.307925) (xy 103.236024 -238.298081) (xy 103.190008 -238.280629)
			(xy 103.147387 -238.256022) (xy 103.109266 -238.224897) (xy 103.076631 -238.18806) (xy 103.050328 -238.146464)
			(xy 103.031037 -238.101188) (xy 103.01926 -238.053404) (xy 103.0153 -238.00435) (xy 102.686358 -238.00435)
			(xy 102.685863 -238.028957) (xy 102.677968 -238.077534) (xy 102.662384 -238.124215) (xy 102.639513 -238.167792)
			(xy 102.609948 -238.207136) (xy 102.574455 -238.241228) (xy 102.533952 -238.269184) (xy 102.48949 -238.290282)
			(xy 102.442219 -238.303974) (xy 102.393364 -238.309906) (xy 102.344189 -238.307925) (xy 102.29597 -238.298081)
			(xy 102.249954 -238.280629) (xy 102.207333 -238.256022) (xy 102.169212 -238.224897) (xy 102.136577 -238.18806)
			(xy 102.110274 -238.146464) (xy 102.090983 -238.101188) (xy 102.079206 -238.053404) (xy 102.075246 -238.00435)
			(xy 101.746304 -238.00435) (xy 101.74583 -238.028339) (xy 101.738317 -238.075724) (xy 101.723485 -238.121351)
			(xy 101.701699 -238.164096) (xy 101.673495 -238.202908) (xy 101.639567 -238.23683) (xy 101.60075 -238.265027)
			(xy 101.558001 -238.286806) (xy 101.512371 -238.30163) (xy 101.464985 -238.309134) (xy 101.440996 -238.309658)
			(xy 101.429456 -238.309531) (xy 101.406444 -238.307752) (xy 101.395022 -238.306102) (xy 101.391212 -238.305594)
			(xy 101.390196 -238.305594) (xy 101.367148 -238.301275) (xy 101.322645 -238.286506) (xy 101.28092 -238.265111)
			(xy 101.242954 -238.237593) (xy 101.209637 -238.204598) (xy 101.181753 -238.166901) (xy 101.170486 -238.146336)
			(xy 101.164898 -238.135668) (xy 101.14534 -238.121698) (xy 101.054408 -238.107728) (xy 101.042529 -238.106573)
			(xy 101.019882 -238.114006) (xy 101.010974 -238.121952) (xy 100.870766 -238.26216) (xy 100.863524 -238.268864)
			(xy 100.84532 -238.276443) (xy 100.83546 -238.276892) (xy 100.639118 -238.276892) (xy 100.628958 -238.281464)
			(xy 100.608796 -238.290344) (xy 100.566562 -238.302878) (xy 100.522969 -238.309235) (xy 100.500942 -238.309658)
			(xy 100.478911 -238.309277) (xy 100.435308 -238.30294) (xy 100.393076 -238.290378) (xy 100.372926 -238.281464)
			(xy 100.362766 -238.276892) (xy 99.699318 -238.276892) (xy 99.689158 -238.281464) (xy 99.668996 -238.290344)
			(xy 99.626762 -238.302878) (xy 99.583169 -238.309235) (xy 99.561142 -238.309658) (xy 99.539111 -238.309277)
			(xy 99.495508 -238.30294) (xy 99.453276 -238.290378) (xy 99.433126 -238.281464) (xy 99.422966 -238.276892)
			(xy 98.759264 -238.276892) (xy 98.749104 -238.281464) (xy 98.728943 -238.290347) (xy 98.686709 -238.302888)
			(xy 98.643115 -238.309251) (xy 98.621088 -238.309658) (xy 98.599058 -238.309274) (xy 98.555458 -238.302929)
			(xy 98.51323 -238.29036) (xy 98.493072 -238.281464) (xy 98.482912 -238.276892) (xy 97.81921 -238.276892)
			(xy 97.80905 -238.281464) (xy 97.788888 -238.290343) (xy 97.746654 -238.302877) (xy 97.703061 -238.309233)
			(xy 97.681034 -238.309658) (xy 97.659003 -238.309277) (xy 97.615401 -238.302939) (xy 97.573169 -238.290375)
			(xy 97.553018 -238.281464) (xy 97.542858 -238.276892) (xy 97.244408 -238.276892) (xy 97.234572 -238.277431)
			(xy 97.216416 -238.285023) (xy 97.209102 -238.291624) (xy 96.882966 -238.61776) (xy 96.876247 -238.624996)
			(xy 96.868638 -238.643201) (xy 96.868234 -238.653066) (xy 96.868234 -238.814356) (xy 98.785184 -238.814356)
			(xy 98.789144 -238.765302) (xy 98.800921 -238.717518) (xy 98.820212 -238.672242) (xy 98.846515 -238.630646)
			(xy 98.87915 -238.593809) (xy 98.917271 -238.562684) (xy 98.959892 -238.538077) (xy 99.005908 -238.520625)
			(xy 99.054127 -238.510781) (xy 99.103302 -238.5088) (xy 99.152157 -238.514732) (xy 99.199428 -238.528424)
			(xy 99.24389 -238.549522) (xy 99.284393 -238.577478) (xy 99.319886 -238.61157) (xy 99.349451 -238.650914)
			(xy 99.372322 -238.694491) (xy 99.387906 -238.741172) (xy 99.395801 -238.789749) (xy 99.396296 -238.814356)
			(xy 101.605346 -238.814356) (xy 101.609306 -238.765302) (xy 101.621083 -238.717518) (xy 101.640374 -238.672242)
			(xy 101.666677 -238.630646) (xy 101.699312 -238.593809) (xy 101.737433 -238.562684) (xy 101.780054 -238.538077)
			(xy 101.82607 -238.520625) (xy 101.874289 -238.510781) (xy 101.923464 -238.5088) (xy 101.972319 -238.514732)
			(xy 102.01959 -238.528424) (xy 102.064052 -238.549522) (xy 102.104555 -238.577478) (xy 102.140048 -238.61157)
			(xy 102.169613 -238.650914) (xy 102.192484 -238.694491) (xy 102.208068 -238.741172) (xy 102.215963 -238.789749)
			(xy 102.216458 -238.814356) (xy 104.425254 -238.814356) (xy 104.429214 -238.765302) (xy 104.440991 -238.717518)
			(xy 104.460282 -238.672242) (xy 104.486585 -238.630646) (xy 104.51922 -238.593809) (xy 104.557341 -238.562684)
			(xy 104.599962 -238.538077) (xy 104.645978 -238.520625) (xy 104.694197 -238.510781) (xy 104.743372 -238.5088)
			(xy 104.792227 -238.514732) (xy 104.839498 -238.528424) (xy 104.88396 -238.549522) (xy 104.924463 -238.577478)
			(xy 104.959956 -238.61157) (xy 104.989521 -238.650914) (xy 105.012392 -238.694491) (xy 105.027976 -238.741172)
			(xy 105.035871 -238.789749) (xy 105.036366 -238.814356) (xy 107.245162 -238.814356) (xy 107.249122 -238.765302)
			(xy 107.260899 -238.717518) (xy 107.28019 -238.672242) (xy 107.306493 -238.630646) (xy 107.339128 -238.593809)
			(xy 107.377249 -238.562684) (xy 107.41987 -238.538077) (xy 107.465886 -238.520625) (xy 107.514105 -238.510781)
			(xy 107.56328 -238.5088) (xy 107.612135 -238.514732) (xy 107.659406 -238.528424) (xy 107.703868 -238.549522)
			(xy 107.744371 -238.577478) (xy 107.779864 -238.61157) (xy 107.809429 -238.650914) (xy 107.8323 -238.694491)
			(xy 107.847884 -238.741172) (xy 107.855779 -238.789749) (xy 107.856274 -238.814356) (xy 108.185216 -238.814356)
			(xy 108.189176 -238.765302) (xy 108.200953 -238.717518) (xy 108.220244 -238.672242) (xy 108.246547 -238.630646)
			(xy 108.279182 -238.593809) (xy 108.317303 -238.562684) (xy 108.359924 -238.538077) (xy 108.40594 -238.520625)
			(xy 108.454159 -238.510781) (xy 108.503334 -238.5088) (xy 108.552189 -238.514732) (xy 108.59946 -238.528424)
			(xy 108.643922 -238.549522) (xy 108.684425 -238.577478) (xy 108.719918 -238.61157) (xy 108.749483 -238.650914)
			(xy 108.772354 -238.694491) (xy 108.787938 -238.741172) (xy 108.795833 -238.789749) (xy 108.796328 -238.814356)
			(xy 109.12527 -238.814356) (xy 109.12923 -238.765302) (xy 109.141007 -238.717518) (xy 109.160298 -238.672242)
			(xy 109.186601 -238.630646) (xy 109.219236 -238.593809) (xy 109.257357 -238.562684) (xy 109.299978 -238.538077)
			(xy 109.345994 -238.520625) (xy 109.394213 -238.510781) (xy 109.443388 -238.5088) (xy 109.492243 -238.514732)
			(xy 109.539514 -238.528424) (xy 109.583976 -238.549522) (xy 109.624479 -238.577478) (xy 109.659972 -238.61157)
			(xy 109.689537 -238.650914) (xy 109.712408 -238.694491) (xy 109.727992 -238.741172) (xy 109.735887 -238.789749)
			(xy 109.736382 -238.814356) (xy 110.065324 -238.814356) (xy 110.069284 -238.765302) (xy 110.081061 -238.717518)
			(xy 110.100352 -238.672242) (xy 110.126655 -238.630646) (xy 110.15929 -238.593809) (xy 110.197411 -238.562684)
			(xy 110.240032 -238.538077) (xy 110.286048 -238.520625) (xy 110.334267 -238.510781) (xy 110.383442 -238.5088)
			(xy 110.432297 -238.514732) (xy 110.479568 -238.528424) (xy 110.52403 -238.549522) (xy 110.564533 -238.577478)
			(xy 110.600026 -238.61157) (xy 110.629591 -238.650914) (xy 110.652462 -238.694491) (xy 110.668046 -238.741172)
			(xy 110.675941 -238.789749) (xy 110.676436 -238.814356) (xy 112.878882 -238.814356) (xy 112.882842 -238.765302)
			(xy 112.894619 -238.717518) (xy 112.91391 -238.672242) (xy 112.940213 -238.630646) (xy 112.972848 -238.593809)
			(xy 113.010969 -238.562684) (xy 113.05359 -238.538077) (xy 113.099606 -238.520625) (xy 113.147825 -238.510781)
			(xy 113.197 -238.5088) (xy 113.245855 -238.514732) (xy 113.293126 -238.528424) (xy 113.337588 -238.549522)
			(xy 113.378091 -238.577478) (xy 113.413584 -238.61157) (xy 113.443149 -238.650914) (xy 113.46602 -238.694491)
			(xy 113.481604 -238.741172) (xy 113.489499 -238.789749) (xy 113.489994 -238.814356) (xy 113.818936 -238.814356)
			(xy 113.822896 -238.765302) (xy 113.834673 -238.717518) (xy 113.853964 -238.672242) (xy 113.880267 -238.630646)
			(xy 113.912902 -238.593809) (xy 113.951023 -238.562684) (xy 113.993644 -238.538077) (xy 114.03966 -238.520625)
			(xy 114.087879 -238.510781) (xy 114.137054 -238.5088) (xy 114.185909 -238.514732) (xy 114.23318 -238.528424)
			(xy 114.277642 -238.549522) (xy 114.318145 -238.577478) (xy 114.353638 -238.61157) (xy 114.383203 -238.650914)
			(xy 114.406074 -238.694491) (xy 114.421658 -238.741172) (xy 114.429553 -238.789749) (xy 114.430048 -238.814356)
			(xy 114.75899 -238.814356) (xy 114.76295 -238.765302) (xy 114.774727 -238.717518) (xy 114.794018 -238.672242)
			(xy 114.820321 -238.630646) (xy 114.852956 -238.593809) (xy 114.891077 -238.562684) (xy 114.933698 -238.538077)
			(xy 114.979714 -238.520625) (xy 115.027933 -238.510781) (xy 115.077108 -238.5088) (xy 115.125963 -238.514732)
			(xy 115.173234 -238.528424) (xy 115.217696 -238.549522) (xy 115.258199 -238.577478) (xy 115.293692 -238.61157)
			(xy 115.323257 -238.650914) (xy 115.346128 -238.694491) (xy 115.361712 -238.741172) (xy 115.369607 -238.789749)
			(xy 115.370102 -238.814356) (xy 115.699044 -238.814356) (xy 115.703004 -238.765302) (xy 115.714781 -238.717518)
			(xy 115.734072 -238.672242) (xy 115.760375 -238.630646) (xy 115.79301 -238.593809) (xy 115.831131 -238.562684)
			(xy 115.873752 -238.538077) (xy 115.919768 -238.520625) (xy 115.967987 -238.510781) (xy 116.017162 -238.5088)
			(xy 116.066017 -238.514732) (xy 116.113288 -238.528424) (xy 116.15775 -238.549522) (xy 116.198253 -238.577478)
			(xy 116.233746 -238.61157) (xy 116.263311 -238.650914) (xy 116.286182 -238.694491) (xy 116.301766 -238.741172)
			(xy 116.309661 -238.789749) (xy 116.310156 -238.814356) (xy 118.518952 -238.814356) (xy 118.522912 -238.765302)
			(xy 118.534689 -238.717518) (xy 118.55398 -238.672242) (xy 118.580283 -238.630646) (xy 118.612918 -238.593809)
			(xy 118.651039 -238.562684) (xy 118.69366 -238.538077) (xy 118.739676 -238.520625) (xy 118.787895 -238.510781)
			(xy 118.83707 -238.5088) (xy 118.885925 -238.514732) (xy 118.933196 -238.528424) (xy 118.977658 -238.549522)
			(xy 119.018161 -238.577478) (xy 119.053654 -238.61157) (xy 119.083219 -238.650914) (xy 119.10609 -238.694491)
			(xy 119.121674 -238.741172) (xy 119.129569 -238.789749) (xy 119.130064 -238.814356) (xy 121.33886 -238.814356)
			(xy 121.34282 -238.765302) (xy 121.354597 -238.717518) (xy 121.373888 -238.672242) (xy 121.400191 -238.630646)
			(xy 121.432826 -238.593809) (xy 121.470947 -238.562684) (xy 121.513568 -238.538077) (xy 121.559584 -238.520625)
			(xy 121.607803 -238.510781) (xy 121.656978 -238.5088) (xy 121.705833 -238.514732) (xy 121.753104 -238.528424)
			(xy 121.797566 -238.549522) (xy 121.838069 -238.577478) (xy 121.873562 -238.61157) (xy 121.903127 -238.650914)
			(xy 121.925998 -238.694491) (xy 121.941582 -238.741172) (xy 121.949477 -238.789749) (xy 121.949972 -238.814356)
			(xy 124.159022 -238.814356) (xy 124.162982 -238.765302) (xy 124.174759 -238.717518) (xy 124.19405 -238.672242)
			(xy 124.220353 -238.630646) (xy 124.252988 -238.593809) (xy 124.291109 -238.562684) (xy 124.33373 -238.538077)
			(xy 124.379746 -238.520625) (xy 124.427965 -238.510781) (xy 124.47714 -238.5088) (xy 124.525995 -238.514732)
			(xy 124.573266 -238.528424) (xy 124.617728 -238.549522) (xy 124.658231 -238.577478) (xy 124.693724 -238.61157)
			(xy 124.723289 -238.650914) (xy 124.74616 -238.694491) (xy 124.761744 -238.741172) (xy 124.769639 -238.789749)
			(xy 124.770134 -238.814356) (xy 126.97893 -238.814356) (xy 126.98289 -238.765302) (xy 126.994667 -238.717518)
			(xy 127.013958 -238.672242) (xy 127.040261 -238.630646) (xy 127.072896 -238.593809) (xy 127.111017 -238.562684)
			(xy 127.153638 -238.538077) (xy 127.199654 -238.520625) (xy 127.247873 -238.510781) (xy 127.297048 -238.5088)
			(xy 127.345903 -238.514732) (xy 127.393174 -238.528424) (xy 127.437636 -238.549522) (xy 127.478139 -238.577478)
			(xy 127.513632 -238.61157) (xy 127.543197 -238.650914) (xy 127.566068 -238.694491) (xy 127.581652 -238.741172)
			(xy 127.589547 -238.789749) (xy 127.590042 -238.814356) (xy 127.908553 -238.814356) (xy 127.912648 -238.763628)
			(xy 127.924827 -238.714214) (xy 127.944775 -238.667394) (xy 127.971976 -238.62438) (xy 128.005724 -238.586286)
			(xy 128.045146 -238.554099) (xy 128.08922 -238.528653) (xy 128.136806 -238.510606) (xy 128.18667 -238.500426)
			(xy 128.237522 -238.498377) (xy 128.288043 -238.504511) (xy 128.336927 -238.518671) (xy 128.382906 -238.540488)
			(xy 128.42479 -238.569398) (xy 128.461494 -238.604653) (xy 128.492067 -238.645339) (xy 128.515718 -238.690402)
			(xy 128.531834 -238.738676) (xy 128.539998 -238.78891) (xy 128.54051 -238.814356) (xy 128.848607 -238.814356)
			(xy 128.852702 -238.763628) (xy 128.864881 -238.714214) (xy 128.884829 -238.667394) (xy 128.91203 -238.62438)
			(xy 128.945778 -238.586286) (xy 128.9852 -238.554099) (xy 129.029274 -238.528653) (xy 129.07686 -238.510606)
			(xy 129.126724 -238.500426) (xy 129.177576 -238.498377) (xy 129.228097 -238.504511) (xy 129.276981 -238.518671)
			(xy 129.32296 -238.540488) (xy 129.364844 -238.569398) (xy 129.401548 -238.604653) (xy 129.432121 -238.645339)
			(xy 129.455772 -238.690402) (xy 129.471888 -238.738676) (xy 129.480052 -238.78891) (xy 129.480564 -238.814356)
			(xy 129.480052 -238.839802) (xy 129.471888 -238.890036) (xy 129.455772 -238.93831) (xy 129.432121 -238.983373)
			(xy 129.401548 -239.024059) (xy 129.364844 -239.059314) (xy 129.32296 -239.088224) (xy 129.276981 -239.110041)
			(xy 129.228097 -239.124201) (xy 129.177576 -239.130335) (xy 129.126724 -239.128286) (xy 129.07686 -239.118106)
			(xy 129.029274 -239.100059) (xy 128.9852 -239.074613) (xy 128.945778 -239.042426) (xy 128.91203 -239.004332)
			(xy 128.884829 -238.961318) (xy 128.864881 -238.914498) (xy 128.852702 -238.865084) (xy 128.848607 -238.814356)
			(xy 128.54051 -238.814356) (xy 128.539998 -238.839802) (xy 128.531834 -238.890036) (xy 128.515718 -238.93831)
			(xy 128.492067 -238.983373) (xy 128.461494 -239.024059) (xy 128.42479 -239.059314) (xy 128.382906 -239.088224)
			(xy 128.336927 -239.110041) (xy 128.288043 -239.124201) (xy 128.237522 -239.130335) (xy 128.18667 -239.128286)
			(xy 128.136806 -239.118106) (xy 128.08922 -239.100059) (xy 128.045146 -239.074613) (xy 128.005724 -239.042426)
			(xy 127.971976 -239.004332) (xy 127.944775 -238.961318) (xy 127.924827 -238.914498) (xy 127.912648 -238.865084)
			(xy 127.908553 -238.814356) (xy 127.590042 -238.814356) (xy 127.589547 -238.838963) (xy 127.581652 -238.88754)
			(xy 127.566068 -238.934221) (xy 127.543197 -238.977798) (xy 127.513632 -239.017142) (xy 127.478139 -239.051234)
			(xy 127.437636 -239.07919) (xy 127.393174 -239.100288) (xy 127.345903 -239.11398) (xy 127.297048 -239.119912)
			(xy 127.247873 -239.117931) (xy 127.199654 -239.108087) (xy 127.153638 -239.090635) (xy 127.111017 -239.066028)
			(xy 127.072896 -239.034903) (xy 127.040261 -238.998066) (xy 127.013958 -238.95647) (xy 126.994667 -238.911194)
			(xy 126.98289 -238.86341) (xy 126.97893 -238.814356) (xy 124.770134 -238.814356) (xy 124.769639 -238.838963)
			(xy 124.761744 -238.88754) (xy 124.74616 -238.934221) (xy 124.723289 -238.977798) (xy 124.693724 -239.017142)
			(xy 124.658231 -239.051234) (xy 124.617728 -239.07919) (xy 124.573266 -239.100288) (xy 124.525995 -239.11398)
			(xy 124.47714 -239.119912) (xy 124.427965 -239.117931) (xy 124.379746 -239.108087) (xy 124.33373 -239.090635)
			(xy 124.291109 -239.066028) (xy 124.252988 -239.034903) (xy 124.220353 -238.998066) (xy 124.19405 -238.95647)
			(xy 124.174759 -238.911194) (xy 124.162982 -238.86341) (xy 124.159022 -238.814356) (xy 121.949972 -238.814356)
			(xy 121.949477 -238.838963) (xy 121.941582 -238.88754) (xy 121.925998 -238.934221) (xy 121.903127 -238.977798)
			(xy 121.873562 -239.017142) (xy 121.838069 -239.051234) (xy 121.797566 -239.07919) (xy 121.753104 -239.100288)
			(xy 121.705833 -239.11398) (xy 121.656978 -239.119912) (xy 121.607803 -239.117931) (xy 121.559584 -239.108087)
			(xy 121.513568 -239.090635) (xy 121.470947 -239.066028) (xy 121.432826 -239.034903) (xy 121.400191 -238.998066)
			(xy 121.373888 -238.95647) (xy 121.354597 -238.911194) (xy 121.34282 -238.86341) (xy 121.33886 -238.814356)
			(xy 119.130064 -238.814356) (xy 119.129569 -238.838963) (xy 119.121674 -238.88754) (xy 119.10609 -238.934221)
			(xy 119.083219 -238.977798) (xy 119.053654 -239.017142) (xy 119.018161 -239.051234) (xy 118.977658 -239.07919)
			(xy 118.933196 -239.100288) (xy 118.885925 -239.11398) (xy 118.83707 -239.119912) (xy 118.787895 -239.117931)
			(xy 118.739676 -239.108087) (xy 118.69366 -239.090635) (xy 118.651039 -239.066028) (xy 118.612918 -239.034903)
			(xy 118.580283 -238.998066) (xy 118.55398 -238.95647) (xy 118.534689 -238.911194) (xy 118.522912 -238.86341)
			(xy 118.518952 -238.814356) (xy 116.310156 -238.814356) (xy 116.309661 -238.838963) (xy 116.301766 -238.88754)
			(xy 116.286182 -238.934221) (xy 116.263311 -238.977798) (xy 116.233746 -239.017142) (xy 116.198253 -239.051234)
			(xy 116.15775 -239.07919) (xy 116.113288 -239.100288) (xy 116.066017 -239.11398) (xy 116.017162 -239.119912)
			(xy 115.967987 -239.117931) (xy 115.919768 -239.108087) (xy 115.873752 -239.090635) (xy 115.831131 -239.066028)
			(xy 115.79301 -239.034903) (xy 115.760375 -238.998066) (xy 115.734072 -238.95647) (xy 115.714781 -238.911194)
			(xy 115.703004 -238.86341) (xy 115.699044 -238.814356) (xy 115.370102 -238.814356) (xy 115.369607 -238.838963)
			(xy 115.361712 -238.88754) (xy 115.346128 -238.934221) (xy 115.323257 -238.977798) (xy 115.293692 -239.017142)
			(xy 115.258199 -239.051234) (xy 115.217696 -239.07919) (xy 115.173234 -239.100288) (xy 115.125963 -239.11398)
			(xy 115.077108 -239.119912) (xy 115.027933 -239.117931) (xy 114.979714 -239.108087) (xy 114.933698 -239.090635)
			(xy 114.891077 -239.066028) (xy 114.852956 -239.034903) (xy 114.820321 -238.998066) (xy 114.794018 -238.95647)
			(xy 114.774727 -238.911194) (xy 114.76295 -238.86341) (xy 114.75899 -238.814356) (xy 114.430048 -238.814356)
			(xy 114.429553 -238.838963) (xy 114.421658 -238.88754) (xy 114.406074 -238.934221) (xy 114.383203 -238.977798)
			(xy 114.353638 -239.017142) (xy 114.318145 -239.051234) (xy 114.277642 -239.07919) (xy 114.23318 -239.100288)
			(xy 114.185909 -239.11398) (xy 114.137054 -239.119912) (xy 114.087879 -239.117931) (xy 114.03966 -239.108087)
			(xy 113.993644 -239.090635) (xy 113.951023 -239.066028) (xy 113.912902 -239.034903) (xy 113.880267 -238.998066)
			(xy 113.853964 -238.95647) (xy 113.834673 -238.911194) (xy 113.822896 -238.86341) (xy 113.818936 -238.814356)
			(xy 113.489994 -238.814356) (xy 113.489499 -238.838963) (xy 113.481604 -238.88754) (xy 113.46602 -238.934221)
			(xy 113.443149 -238.977798) (xy 113.413584 -239.017142) (xy 113.378091 -239.051234) (xy 113.337588 -239.07919)
			(xy 113.293126 -239.100288) (xy 113.245855 -239.11398) (xy 113.197 -239.119912) (xy 113.147825 -239.117931)
			(xy 113.099606 -239.108087) (xy 113.05359 -239.090635) (xy 113.010969 -239.066028) (xy 112.972848 -239.034903)
			(xy 112.940213 -238.998066) (xy 112.91391 -238.95647) (xy 112.894619 -238.911194) (xy 112.882842 -238.86341)
			(xy 112.878882 -238.814356) (xy 110.676436 -238.814356) (xy 110.675941 -238.838963) (xy 110.668046 -238.88754)
			(xy 110.652462 -238.934221) (xy 110.629591 -238.977798) (xy 110.600026 -239.017142) (xy 110.564533 -239.051234)
			(xy 110.52403 -239.07919) (xy 110.479568 -239.100288) (xy 110.432297 -239.11398) (xy 110.383442 -239.119912)
			(xy 110.334267 -239.117931) (xy 110.286048 -239.108087) (xy 110.240032 -239.090635) (xy 110.197411 -239.066028)
			(xy 110.15929 -239.034903) (xy 110.126655 -238.998066) (xy 110.100352 -238.95647) (xy 110.081061 -238.911194)
			(xy 110.069284 -238.86341) (xy 110.065324 -238.814356) (xy 109.736382 -238.814356) (xy 109.735887 -238.838963)
			(xy 109.727992 -238.88754) (xy 109.712408 -238.934221) (xy 109.689537 -238.977798) (xy 109.659972 -239.017142)
			(xy 109.624479 -239.051234) (xy 109.583976 -239.07919) (xy 109.539514 -239.100288) (xy 109.492243 -239.11398)
			(xy 109.443388 -239.119912) (xy 109.394213 -239.117931) (xy 109.345994 -239.108087) (xy 109.299978 -239.090635)
			(xy 109.257357 -239.066028) (xy 109.219236 -239.034903) (xy 109.186601 -238.998066) (xy 109.160298 -238.95647)
			(xy 109.141007 -238.911194) (xy 109.12923 -238.86341) (xy 109.12527 -238.814356) (xy 108.796328 -238.814356)
			(xy 108.795833 -238.838963) (xy 108.787938 -238.88754) (xy 108.772354 -238.934221) (xy 108.749483 -238.977798)
			(xy 108.719918 -239.017142) (xy 108.684425 -239.051234) (xy 108.643922 -239.07919) (xy 108.59946 -239.100288)
			(xy 108.552189 -239.11398) (xy 108.503334 -239.119912) (xy 108.454159 -239.117931) (xy 108.40594 -239.108087)
			(xy 108.359924 -239.090635) (xy 108.317303 -239.066028) (xy 108.279182 -239.034903) (xy 108.246547 -238.998066)
			(xy 108.220244 -238.95647) (xy 108.200953 -238.911194) (xy 108.189176 -238.86341) (xy 108.185216 -238.814356)
			(xy 107.856274 -238.814356) (xy 107.855779 -238.838963) (xy 107.847884 -238.88754) (xy 107.8323 -238.934221)
			(xy 107.809429 -238.977798) (xy 107.779864 -239.017142) (xy 107.744371 -239.051234) (xy 107.703868 -239.07919)
			(xy 107.659406 -239.100288) (xy 107.612135 -239.11398) (xy 107.56328 -239.119912) (xy 107.514105 -239.117931)
			(xy 107.465886 -239.108087) (xy 107.41987 -239.090635) (xy 107.377249 -239.066028) (xy 107.339128 -239.034903)
			(xy 107.306493 -238.998066) (xy 107.28019 -238.95647) (xy 107.260899 -238.911194) (xy 107.249122 -238.86341)
			(xy 107.245162 -238.814356) (xy 105.036366 -238.814356) (xy 105.035871 -238.838963) (xy 105.027976 -238.88754)
			(xy 105.012392 -238.934221) (xy 104.989521 -238.977798) (xy 104.959956 -239.017142) (xy 104.924463 -239.051234)
			(xy 104.88396 -239.07919) (xy 104.839498 -239.100288) (xy 104.792227 -239.11398) (xy 104.743372 -239.119912)
			(xy 104.694197 -239.117931) (xy 104.645978 -239.108087) (xy 104.599962 -239.090635) (xy 104.557341 -239.066028)
			(xy 104.51922 -239.034903) (xy 104.486585 -238.998066) (xy 104.460282 -238.95647) (xy 104.440991 -238.911194)
			(xy 104.429214 -238.86341) (xy 104.425254 -238.814356) (xy 102.216458 -238.814356) (xy 102.215963 -238.838963)
			(xy 102.208068 -238.88754) (xy 102.192484 -238.934221) (xy 102.169613 -238.977798) (xy 102.140048 -239.017142)
			(xy 102.104555 -239.051234) (xy 102.064052 -239.07919) (xy 102.01959 -239.100288) (xy 101.972319 -239.11398)
			(xy 101.923464 -239.119912) (xy 101.874289 -239.117931) (xy 101.82607 -239.108087) (xy 101.780054 -239.090635)
			(xy 101.737433 -239.066028) (xy 101.699312 -239.034903) (xy 101.666677 -238.998066) (xy 101.640374 -238.95647)
			(xy 101.621083 -238.911194) (xy 101.609306 -238.86341) (xy 101.605346 -238.814356) (xy 99.396296 -238.814356)
			(xy 99.395801 -238.838963) (xy 99.387906 -238.88754) (xy 99.372322 -238.934221) (xy 99.349451 -238.977798)
			(xy 99.319886 -239.017142) (xy 99.284393 -239.051234) (xy 99.24389 -239.07919) (xy 99.199428 -239.100288)
			(xy 99.152157 -239.11398) (xy 99.103302 -239.119912) (xy 99.054127 -239.117931) (xy 99.005908 -239.108087)
			(xy 98.959892 -239.090635) (xy 98.917271 -239.066028) (xy 98.87915 -239.034903) (xy 98.846515 -238.998066)
			(xy 98.820212 -238.95647) (xy 98.800921 -238.911194) (xy 98.789144 -238.86341) (xy 98.785184 -238.814356)
			(xy 96.868234 -238.814356) (xy 96.868234 -239.329468) (xy 96.881696 -239.352836) (xy 96.893634 -239.359694)
			(xy 96.914746 -239.37241) (xy 96.952934 -239.40356) (xy 96.985629 -239.440435) (xy 97.011982 -239.482078)
			(xy 97.03131 -239.527412) (xy 97.043112 -239.575259) (xy 97.047081 -239.624362) (xy 97.37523 -239.624362)
			(xy 97.37919 -239.575308) (xy 97.390967 -239.527524) (xy 97.410258 -239.482248) (xy 97.436561 -239.440652)
			(xy 97.469196 -239.403815) (xy 97.507317 -239.37269) (xy 97.549938 -239.348083) (xy 97.595954 -239.330631)
			(xy 97.644173 -239.320787) (xy 97.693348 -239.318806) (xy 97.742203 -239.324738) (xy 97.789474 -239.33843)
			(xy 97.833936 -239.359528) (xy 97.874439 -239.387484) (xy 97.909932 -239.421576) (xy 97.939497 -239.46092)
			(xy 97.962368 -239.504497) (xy 97.977952 -239.551178) (xy 97.985847 -239.599755) (xy 97.986342 -239.624362)
			(xy 98.315284 -239.624362) (xy 98.319244 -239.575308) (xy 98.331021 -239.527524) (xy 98.350312 -239.482248)
			(xy 98.376615 -239.440652) (xy 98.40925 -239.403815) (xy 98.447371 -239.37269) (xy 98.489992 -239.348083)
			(xy 98.536008 -239.330631) (xy 98.584227 -239.320787) (xy 98.633402 -239.318806) (xy 98.682257 -239.324738)
			(xy 98.729528 -239.33843) (xy 98.77399 -239.359528) (xy 98.814493 -239.387484) (xy 98.849986 -239.421576)
			(xy 98.879551 -239.46092) (xy 98.902422 -239.504497) (xy 98.918006 -239.551178) (xy 98.925901 -239.599755)
			(xy 98.926396 -239.624362) (xy 99.255338 -239.624362) (xy 99.259298 -239.575308) (xy 99.271075 -239.527524)
			(xy 99.290366 -239.482248) (xy 99.316669 -239.440652) (xy 99.349304 -239.403815) (xy 99.387425 -239.37269)
			(xy 99.430046 -239.348083) (xy 99.476062 -239.330631) (xy 99.524281 -239.320787) (xy 99.573456 -239.318806)
			(xy 99.622311 -239.324738) (xy 99.669582 -239.33843) (xy 99.714044 -239.359528) (xy 99.754547 -239.387484)
			(xy 99.79004 -239.421576) (xy 99.819605 -239.46092) (xy 99.842476 -239.504497) (xy 99.85806 -239.551178)
			(xy 99.865955 -239.599755) (xy 99.86645 -239.624362) (xy 100.195138 -239.624362) (xy 100.199098 -239.575308)
			(xy 100.210875 -239.527524) (xy 100.230166 -239.482248) (xy 100.256469 -239.440652) (xy 100.289104 -239.403815)
			(xy 100.327225 -239.37269) (xy 100.369846 -239.348083) (xy 100.415862 -239.330631) (xy 100.464081 -239.320787)
			(xy 100.513256 -239.318806) (xy 100.562111 -239.324738) (xy 100.609382 -239.33843) (xy 100.653844 -239.359528)
			(xy 100.694347 -239.387484) (xy 100.72984 -239.421576) (xy 100.759405 -239.46092) (xy 100.782276 -239.504497)
			(xy 100.79786 -239.551178) (xy 100.805755 -239.599755) (xy 100.80625 -239.624362) (xy 101.135192 -239.624362)
			(xy 101.139152 -239.575308) (xy 101.150929 -239.527524) (xy 101.17022 -239.482248) (xy 101.196523 -239.440652)
			(xy 101.229158 -239.403815) (xy 101.267279 -239.37269) (xy 101.3099 -239.348083) (xy 101.355916 -239.330631)
			(xy 101.404135 -239.320787) (xy 101.45331 -239.318806) (xy 101.502165 -239.324738) (xy 101.549436 -239.33843)
			(xy 101.593898 -239.359528) (xy 101.634401 -239.387484) (xy 101.669894 -239.421576) (xy 101.699459 -239.46092)
			(xy 101.72233 -239.504497) (xy 101.737914 -239.551178) (xy 101.745809 -239.599755) (xy 101.746304 -239.624362)
			(xy 102.075246 -239.624362) (xy 102.079206 -239.575308) (xy 102.090983 -239.527524) (xy 102.110274 -239.482248)
			(xy 102.136577 -239.440652) (xy 102.169212 -239.403815) (xy 102.207333 -239.37269) (xy 102.249954 -239.348083)
			(xy 102.29597 -239.330631) (xy 102.344189 -239.320787) (xy 102.393364 -239.318806) (xy 102.442219 -239.324738)
			(xy 102.48949 -239.33843) (xy 102.533952 -239.359528) (xy 102.574455 -239.387484) (xy 102.609948 -239.421576)
			(xy 102.639513 -239.46092) (xy 102.662384 -239.504497) (xy 102.677968 -239.551178) (xy 102.685863 -239.599755)
			(xy 102.686358 -239.624362) (xy 103.0153 -239.624362) (xy 103.01926 -239.575308) (xy 103.031037 -239.527524)
			(xy 103.050328 -239.482248) (xy 103.076631 -239.440652) (xy 103.109266 -239.403815) (xy 103.147387 -239.37269)
			(xy 103.190008 -239.348083) (xy 103.236024 -239.330631) (xy 103.284243 -239.320787) (xy 103.333418 -239.318806)
			(xy 103.382273 -239.324738) (xy 103.429544 -239.33843) (xy 103.474006 -239.359528) (xy 103.514509 -239.387484)
			(xy 103.550002 -239.421576) (xy 103.579567 -239.46092) (xy 103.602438 -239.504497) (xy 103.618022 -239.551178)
			(xy 103.625917 -239.599755) (xy 103.626412 -239.624362) (xy 103.955354 -239.624362) (xy 103.959314 -239.575308)
			(xy 103.971091 -239.527524) (xy 103.990382 -239.482248) (xy 104.016685 -239.440652) (xy 104.04932 -239.403815)
			(xy 104.087441 -239.37269) (xy 104.130062 -239.348083) (xy 104.176078 -239.330631) (xy 104.224297 -239.320787)
			(xy 104.273472 -239.318806) (xy 104.322327 -239.324738) (xy 104.369598 -239.33843) (xy 104.41406 -239.359528)
			(xy 104.454563 -239.387484) (xy 104.490056 -239.421576) (xy 104.519621 -239.46092) (xy 104.542492 -239.504497)
			(xy 104.558076 -239.551178) (xy 104.565971 -239.599755) (xy 104.566466 -239.624362) (xy 104.895154 -239.624362)
			(xy 104.899114 -239.575308) (xy 104.910891 -239.527524) (xy 104.930182 -239.482248) (xy 104.956485 -239.440652)
			(xy 104.98912 -239.403815) (xy 105.027241 -239.37269) (xy 105.069862 -239.348083) (xy 105.115878 -239.330631)
			(xy 105.164097 -239.320787) (xy 105.213272 -239.318806) (xy 105.262127 -239.324738) (xy 105.309398 -239.33843)
			(xy 105.35386 -239.359528) (xy 105.394363 -239.387484) (xy 105.429856 -239.421576) (xy 105.459421 -239.46092)
			(xy 105.482292 -239.504497) (xy 105.497876 -239.551178) (xy 105.505771 -239.599755) (xy 105.506266 -239.624362)
			(xy 105.835208 -239.624362) (xy 105.839168 -239.575308) (xy 105.850945 -239.527524) (xy 105.870236 -239.482248)
			(xy 105.896539 -239.440652) (xy 105.929174 -239.403815) (xy 105.967295 -239.37269) (xy 106.009916 -239.348083)
			(xy 106.055932 -239.330631) (xy 106.104151 -239.320787) (xy 106.153326 -239.318806) (xy 106.202181 -239.324738)
			(xy 106.249452 -239.33843) (xy 106.293914 -239.359528) (xy 106.334417 -239.387484) (xy 106.36991 -239.421576)
			(xy 106.399475 -239.46092) (xy 106.422346 -239.504497) (xy 106.43793 -239.551178) (xy 106.445825 -239.599755)
			(xy 106.44632 -239.624362) (xy 106.775262 -239.624362) (xy 106.779222 -239.575308) (xy 106.790999 -239.527524)
			(xy 106.81029 -239.482248) (xy 106.836593 -239.440652) (xy 106.869228 -239.403815) (xy 106.907349 -239.37269)
			(xy 106.94997 -239.348083) (xy 106.995986 -239.330631) (xy 107.044205 -239.320787) (xy 107.09338 -239.318806)
			(xy 107.142235 -239.324738) (xy 107.189506 -239.33843) (xy 107.233968 -239.359528) (xy 107.274471 -239.387484)
			(xy 107.309964 -239.421576) (xy 107.339529 -239.46092) (xy 107.3624 -239.504497) (xy 107.377984 -239.551178)
			(xy 107.385879 -239.599755) (xy 107.386374 -239.624362) (xy 107.715316 -239.624362) (xy 107.719276 -239.575308)
			(xy 107.731053 -239.527524) (xy 107.750344 -239.482248) (xy 107.776647 -239.440652) (xy 107.809282 -239.403815)
			(xy 107.847403 -239.37269) (xy 107.890024 -239.348083) (xy 107.93604 -239.330631) (xy 107.984259 -239.320787)
			(xy 108.033434 -239.318806) (xy 108.082289 -239.324738) (xy 108.12956 -239.33843) (xy 108.174022 -239.359528)
			(xy 108.214525 -239.387484) (xy 108.250018 -239.421576) (xy 108.279583 -239.46092) (xy 108.302454 -239.504497)
			(xy 108.318038 -239.551178) (xy 108.325933 -239.599755) (xy 108.326428 -239.624362) (xy 115.22889 -239.624362)
			(xy 115.23285 -239.575308) (xy 115.244627 -239.527524) (xy 115.263918 -239.482248) (xy 115.290221 -239.440652)
			(xy 115.322856 -239.403815) (xy 115.360977 -239.37269) (xy 115.403598 -239.348083) (xy 115.449614 -239.330631)
			(xy 115.497833 -239.320787) (xy 115.547008 -239.318806) (xy 115.595863 -239.324738) (xy 115.643134 -239.33843)
			(xy 115.687596 -239.359528) (xy 115.728099 -239.387484) (xy 115.763592 -239.421576) (xy 115.793157 -239.46092)
			(xy 115.816028 -239.504497) (xy 115.831612 -239.551178) (xy 115.839507 -239.599755) (xy 115.840002 -239.624362)
			(xy 116.168944 -239.624362) (xy 116.172904 -239.575308) (xy 116.184681 -239.527524) (xy 116.203972 -239.482248)
			(xy 116.230275 -239.440652) (xy 116.26291 -239.403815) (xy 116.301031 -239.37269) (xy 116.343652 -239.348083)
			(xy 116.389668 -239.330631) (xy 116.437887 -239.320787) (xy 116.487062 -239.318806) (xy 116.535917 -239.324738)
			(xy 116.583188 -239.33843) (xy 116.62765 -239.359528) (xy 116.668153 -239.387484) (xy 116.703646 -239.421576)
			(xy 116.733211 -239.46092) (xy 116.756082 -239.504497) (xy 116.771666 -239.551178) (xy 116.779561 -239.599755)
			(xy 116.780056 -239.624362) (xy 117.108998 -239.624362) (xy 117.112958 -239.575308) (xy 117.124735 -239.527524)
			(xy 117.144026 -239.482248) (xy 117.170329 -239.440652) (xy 117.202964 -239.403815) (xy 117.241085 -239.37269)
			(xy 117.283706 -239.348083) (xy 117.329722 -239.330631) (xy 117.377941 -239.320787) (xy 117.427116 -239.318806)
			(xy 117.475971 -239.324738) (xy 117.523242 -239.33843) (xy 117.567704 -239.359528) (xy 117.608207 -239.387484)
			(xy 117.6437 -239.421576) (xy 117.673265 -239.46092) (xy 117.696136 -239.504497) (xy 117.71172 -239.551178)
			(xy 117.719615 -239.599755) (xy 117.72011 -239.624362) (xy 118.049052 -239.624362) (xy 118.053012 -239.575308)
			(xy 118.064789 -239.527524) (xy 118.08408 -239.482248) (xy 118.110383 -239.440652) (xy 118.143018 -239.403815)
			(xy 118.181139 -239.37269) (xy 118.22376 -239.348083) (xy 118.269776 -239.330631) (xy 118.317995 -239.320787)
			(xy 118.36717 -239.318806) (xy 118.416025 -239.324738) (xy 118.463296 -239.33843) (xy 118.507758 -239.359528)
			(xy 118.548261 -239.387484) (xy 118.583754 -239.421576) (xy 118.613319 -239.46092) (xy 118.63619 -239.504497)
			(xy 118.651774 -239.551178) (xy 118.659669 -239.599755) (xy 118.660164 -239.624362) (xy 118.988852 -239.624362)
			(xy 118.992812 -239.575308) (xy 119.004589 -239.527524) (xy 119.02388 -239.482248) (xy 119.050183 -239.440652)
			(xy 119.082818 -239.403815) (xy 119.120939 -239.37269) (xy 119.16356 -239.348083) (xy 119.209576 -239.330631)
			(xy 119.257795 -239.320787) (xy 119.30697 -239.318806) (xy 119.355825 -239.324738) (xy 119.403096 -239.33843)
			(xy 119.447558 -239.359528) (xy 119.488061 -239.387484) (xy 119.523554 -239.421576) (xy 119.553119 -239.46092)
			(xy 119.57599 -239.504497) (xy 119.591574 -239.551178) (xy 119.599469 -239.599755) (xy 119.599964 -239.624362)
			(xy 119.928906 -239.624362) (xy 119.932866 -239.575308) (xy 119.944643 -239.527524) (xy 119.963934 -239.482248)
			(xy 119.990237 -239.440652) (xy 120.022872 -239.403815) (xy 120.060993 -239.37269) (xy 120.103614 -239.348083)
			(xy 120.14963 -239.330631) (xy 120.197849 -239.320787) (xy 120.247024 -239.318806) (xy 120.295879 -239.324738)
			(xy 120.34315 -239.33843) (xy 120.387612 -239.359528) (xy 120.428115 -239.387484) (xy 120.463608 -239.421576)
			(xy 120.493173 -239.46092) (xy 120.516044 -239.504497) (xy 120.531628 -239.551178) (xy 120.539523 -239.599755)
			(xy 120.540018 -239.624362) (xy 120.86896 -239.624362) (xy 120.87292 -239.575308) (xy 120.884697 -239.527524)
			(xy 120.903988 -239.482248) (xy 120.930291 -239.440652) (xy 120.962926 -239.403815) (xy 121.001047 -239.37269)
			(xy 121.043668 -239.348083) (xy 121.089684 -239.330631) (xy 121.137903 -239.320787) (xy 121.187078 -239.318806)
			(xy 121.235933 -239.324738) (xy 121.283204 -239.33843) (xy 121.327666 -239.359528) (xy 121.368169 -239.387484)
			(xy 121.403662 -239.421576) (xy 121.433227 -239.46092) (xy 121.456098 -239.504497) (xy 121.471682 -239.551178)
			(xy 121.479577 -239.599755) (xy 121.480072 -239.624362) (xy 121.809014 -239.624362) (xy 121.812974 -239.575308)
			(xy 121.824751 -239.527524) (xy 121.844042 -239.482248) (xy 121.870345 -239.440652) (xy 121.90298 -239.403815)
			(xy 121.941101 -239.37269) (xy 121.983722 -239.348083) (xy 122.029738 -239.330631) (xy 122.077957 -239.320787)
			(xy 122.127132 -239.318806) (xy 122.175987 -239.324738) (xy 122.223258 -239.33843) (xy 122.26772 -239.359528)
			(xy 122.308223 -239.387484) (xy 122.343716 -239.421576) (xy 122.373281 -239.46092) (xy 122.396152 -239.504497)
			(xy 122.411736 -239.551178) (xy 122.419631 -239.599755) (xy 122.420126 -239.624362) (xy 122.748814 -239.624362)
			(xy 122.752774 -239.575308) (xy 122.764551 -239.527524) (xy 122.783842 -239.482248) (xy 122.810145 -239.440652)
			(xy 122.84278 -239.403815) (xy 122.880901 -239.37269) (xy 122.923522 -239.348083) (xy 122.969538 -239.330631)
			(xy 123.017757 -239.320787) (xy 123.066932 -239.318806) (xy 123.115787 -239.324738) (xy 123.163058 -239.33843)
			(xy 123.20752 -239.359528) (xy 123.248023 -239.387484) (xy 123.283516 -239.421576) (xy 123.313081 -239.46092)
			(xy 123.335952 -239.504497) (xy 123.351536 -239.551178) (xy 123.359431 -239.599755) (xy 123.359926 -239.624362)
			(xy 123.688868 -239.624362) (xy 123.692828 -239.575308) (xy 123.704605 -239.527524) (xy 123.723896 -239.482248)
			(xy 123.750199 -239.440652) (xy 123.782834 -239.403815) (xy 123.820955 -239.37269) (xy 123.863576 -239.348083)
			(xy 123.909592 -239.330631) (xy 123.957811 -239.320787) (xy 124.006986 -239.318806) (xy 124.055841 -239.324738)
			(xy 124.103112 -239.33843) (xy 124.147574 -239.359528) (xy 124.188077 -239.387484) (xy 124.22357 -239.421576)
			(xy 124.253135 -239.46092) (xy 124.276006 -239.504497) (xy 124.29159 -239.551178) (xy 124.299485 -239.599755)
			(xy 124.29998 -239.624362) (xy 124.628922 -239.624362) (xy 124.632882 -239.575308) (xy 124.644659 -239.527524)
			(xy 124.66395 -239.482248) (xy 124.690253 -239.440652) (xy 124.722888 -239.403815) (xy 124.761009 -239.37269)
			(xy 124.80363 -239.348083) (xy 124.849646 -239.330631) (xy 124.897865 -239.320787) (xy 124.94704 -239.318806)
			(xy 124.995895 -239.324738) (xy 125.043166 -239.33843) (xy 125.087628 -239.359528) (xy 125.128131 -239.387484)
			(xy 125.163624 -239.421576) (xy 125.193189 -239.46092) (xy 125.21606 -239.504497) (xy 125.231644 -239.551178)
			(xy 125.239539 -239.599755) (xy 125.240034 -239.624362) (xy 125.568976 -239.624362) (xy 125.572936 -239.575308)
			(xy 125.584713 -239.527524) (xy 125.604004 -239.482248) (xy 125.630307 -239.440652) (xy 125.662942 -239.403815)
			(xy 125.701063 -239.37269) (xy 125.743684 -239.348083) (xy 125.7897 -239.330631) (xy 125.837919 -239.320787)
			(xy 125.887094 -239.318806) (xy 125.935949 -239.324738) (xy 125.98322 -239.33843) (xy 126.027682 -239.359528)
			(xy 126.068185 -239.387484) (xy 126.103678 -239.421576) (xy 126.133243 -239.46092) (xy 126.156114 -239.504497)
			(xy 126.171698 -239.551178) (xy 126.179593 -239.599755) (xy 126.180088 -239.624362) (xy 126.50903 -239.624362)
			(xy 126.51299 -239.575308) (xy 126.524767 -239.527524) (xy 126.544058 -239.482248) (xy 126.570361 -239.440652)
			(xy 126.602996 -239.403815) (xy 126.641117 -239.37269) (xy 126.683738 -239.348083) (xy 126.729754 -239.330631)
			(xy 126.777973 -239.320787) (xy 126.827148 -239.318806) (xy 126.876003 -239.324738) (xy 126.923274 -239.33843)
			(xy 126.967736 -239.359528) (xy 127.008239 -239.387484) (xy 127.043732 -239.421576) (xy 127.073297 -239.46092)
			(xy 127.096168 -239.504497) (xy 127.111752 -239.551178) (xy 127.119647 -239.599755) (xy 127.120142 -239.624362)
			(xy 127.438399 -239.624362) (xy 127.442494 -239.573634) (xy 127.454673 -239.52422) (xy 127.474621 -239.4774)
			(xy 127.501822 -239.434386) (xy 127.53557 -239.396292) (xy 127.574992 -239.364105) (xy 127.619066 -239.338659)
			(xy 127.666652 -239.320612) (xy 127.716516 -239.310432) (xy 127.767368 -239.308383) (xy 127.817889 -239.314517)
			(xy 127.866773 -239.328677) (xy 127.912752 -239.350494) (xy 127.954636 -239.379404) (xy 127.99134 -239.414659)
			(xy 128.021913 -239.455345) (xy 128.045564 -239.500408) (xy 128.06168 -239.548682) (xy 128.069844 -239.598916)
			(xy 128.070356 -239.624362) (xy 128.388884 -239.624362) (xy 128.392844 -239.575308) (xy 128.404621 -239.527524)
			(xy 128.423912 -239.482248) (xy 128.450215 -239.440652) (xy 128.48285 -239.403815) (xy 128.520971 -239.37269)
			(xy 128.563592 -239.348083) (xy 128.609608 -239.330631) (xy 128.657827 -239.320787) (xy 128.707002 -239.318806)
			(xy 128.755857 -239.324738) (xy 128.803128 -239.33843) (xy 128.84759 -239.359528) (xy 128.888093 -239.387484)
			(xy 128.923586 -239.421576) (xy 128.953151 -239.46092) (xy 128.976022 -239.504497) (xy 128.991606 -239.551178)
			(xy 128.999501 -239.599755) (xy 128.999996 -239.624362) (xy 129.318507 -239.624362) (xy 129.322602 -239.573634)
			(xy 129.334781 -239.52422) (xy 129.354729 -239.4774) (xy 129.38193 -239.434386) (xy 129.415678 -239.396292)
			(xy 129.4551 -239.364105) (xy 129.499174 -239.338659) (xy 129.54676 -239.320612) (xy 129.596624 -239.310432)
			(xy 129.647476 -239.308383) (xy 129.697997 -239.314517) (xy 129.746881 -239.328677) (xy 129.79286 -239.350494)
			(xy 129.834744 -239.379404) (xy 129.871448 -239.414659) (xy 129.902021 -239.455345) (xy 129.925672 -239.500408)
			(xy 129.941788 -239.548682) (xy 129.949952 -239.598916) (xy 129.950464 -239.624362) (xy 129.949952 -239.649808)
			(xy 129.941788 -239.700042) (xy 129.925672 -239.748316) (xy 129.902021 -239.793379) (xy 129.871448 -239.834065)
			(xy 129.834744 -239.86932) (xy 129.79286 -239.89823) (xy 129.746881 -239.920047) (xy 129.697997 -239.934207)
			(xy 129.647476 -239.940341) (xy 129.596624 -239.938292) (xy 129.54676 -239.928112) (xy 129.499174 -239.910065)
			(xy 129.4551 -239.884619) (xy 129.415678 -239.852432) (xy 129.38193 -239.814338) (xy 129.354729 -239.771324)
			(xy 129.334781 -239.724504) (xy 129.322602 -239.67509) (xy 129.318507 -239.624362) (xy 128.999996 -239.624362)
			(xy 128.999501 -239.648969) (xy 128.991606 -239.697546) (xy 128.976022 -239.744227) (xy 128.953151 -239.787804)
			(xy 128.923586 -239.827148) (xy 128.888093 -239.86124) (xy 128.84759 -239.889196) (xy 128.803128 -239.910294)
			(xy 128.755857 -239.923986) (xy 128.707002 -239.929918) (xy 128.657827 -239.927937) (xy 128.609608 -239.918093)
			(xy 128.563592 -239.900641) (xy 128.520971 -239.876034) (xy 128.48285 -239.844909) (xy 128.450215 -239.808072)
			(xy 128.423912 -239.766476) (xy 128.404621 -239.7212) (xy 128.392844 -239.673416) (xy 128.388884 -239.624362)
			(xy 128.070356 -239.624362) (xy 128.069844 -239.649808) (xy 128.06168 -239.700042) (xy 128.045564 -239.748316)
			(xy 128.021913 -239.793379) (xy 127.99134 -239.834065) (xy 127.954636 -239.86932) (xy 127.912752 -239.89823)
			(xy 127.866773 -239.920047) (xy 127.817889 -239.934207) (xy 127.767368 -239.940341) (xy 127.716516 -239.938292)
			(xy 127.666652 -239.928112) (xy 127.619066 -239.910065) (xy 127.574992 -239.884619) (xy 127.53557 -239.852432)
			(xy 127.501822 -239.814338) (xy 127.474621 -239.771324) (xy 127.454673 -239.724504) (xy 127.442494 -239.67509)
			(xy 127.438399 -239.624362) (xy 127.120142 -239.624362) (xy 127.119647 -239.648969) (xy 127.111752 -239.697546)
			(xy 127.096168 -239.744227) (xy 127.073297 -239.787804) (xy 127.043732 -239.827148) (xy 127.008239 -239.86124)
			(xy 126.967736 -239.889196) (xy 126.923274 -239.910294) (xy 126.876003 -239.923986) (xy 126.827148 -239.929918)
			(xy 126.777973 -239.927937) (xy 126.729754 -239.918093) (xy 126.683738 -239.900641) (xy 126.641117 -239.876034)
			(xy 126.602996 -239.844909) (xy 126.570361 -239.808072) (xy 126.544058 -239.766476) (xy 126.524767 -239.7212)
			(xy 126.51299 -239.673416) (xy 126.50903 -239.624362) (xy 126.180088 -239.624362) (xy 126.179593 -239.648969)
			(xy 126.171698 -239.697546) (xy 126.156114 -239.744227) (xy 126.133243 -239.787804) (xy 126.103678 -239.827148)
			(xy 126.068185 -239.86124) (xy 126.027682 -239.889196) (xy 125.98322 -239.910294) (xy 125.935949 -239.923986)
			(xy 125.887094 -239.929918) (xy 125.837919 -239.927937) (xy 125.7897 -239.918093) (xy 125.743684 -239.900641)
			(xy 125.701063 -239.876034) (xy 125.662942 -239.844909) (xy 125.630307 -239.808072) (xy 125.604004 -239.766476)
			(xy 125.584713 -239.7212) (xy 125.572936 -239.673416) (xy 125.568976 -239.624362) (xy 125.240034 -239.624362)
			(xy 125.239539 -239.648969) (xy 125.231644 -239.697546) (xy 125.21606 -239.744227) (xy 125.193189 -239.787804)
			(xy 125.163624 -239.827148) (xy 125.128131 -239.86124) (xy 125.087628 -239.889196) (xy 125.043166 -239.910294)
			(xy 124.995895 -239.923986) (xy 124.94704 -239.929918) (xy 124.897865 -239.927937) (xy 124.849646 -239.918093)
			(xy 124.80363 -239.900641) (xy 124.761009 -239.876034) (xy 124.722888 -239.844909) (xy 124.690253 -239.808072)
			(xy 124.66395 -239.766476) (xy 124.644659 -239.7212) (xy 124.632882 -239.673416) (xy 124.628922 -239.624362)
			(xy 124.29998 -239.624362) (xy 124.299485 -239.648969) (xy 124.29159 -239.697546) (xy 124.276006 -239.744227)
			(xy 124.253135 -239.787804) (xy 124.22357 -239.827148) (xy 124.188077 -239.86124) (xy 124.147574 -239.889196)
			(xy 124.103112 -239.910294) (xy 124.055841 -239.923986) (xy 124.006986 -239.929918) (xy 123.957811 -239.927937)
			(xy 123.909592 -239.918093) (xy 123.863576 -239.900641) (xy 123.820955 -239.876034) (xy 123.782834 -239.844909)
			(xy 123.750199 -239.808072) (xy 123.723896 -239.766476) (xy 123.704605 -239.7212) (xy 123.692828 -239.673416)
			(xy 123.688868 -239.624362) (xy 123.359926 -239.624362) (xy 123.359431 -239.648969) (xy 123.351536 -239.697546)
			(xy 123.335952 -239.744227) (xy 123.313081 -239.787804) (xy 123.283516 -239.827148) (xy 123.248023 -239.86124)
			(xy 123.20752 -239.889196) (xy 123.163058 -239.910294) (xy 123.115787 -239.923986) (xy 123.066932 -239.929918)
			(xy 123.017757 -239.927937) (xy 122.969538 -239.918093) (xy 122.923522 -239.900641) (xy 122.880901 -239.876034)
			(xy 122.84278 -239.844909) (xy 122.810145 -239.808072) (xy 122.783842 -239.766476) (xy 122.764551 -239.7212)
			(xy 122.752774 -239.673416) (xy 122.748814 -239.624362) (xy 122.420126 -239.624362) (xy 122.419631 -239.648969)
			(xy 122.411736 -239.697546) (xy 122.396152 -239.744227) (xy 122.373281 -239.787804) (xy 122.343716 -239.827148)
			(xy 122.308223 -239.86124) (xy 122.26772 -239.889196) (xy 122.223258 -239.910294) (xy 122.175987 -239.923986)
			(xy 122.127132 -239.929918) (xy 122.077957 -239.927937) (xy 122.029738 -239.918093) (xy 121.983722 -239.900641)
			(xy 121.941101 -239.876034) (xy 121.90298 -239.844909) (xy 121.870345 -239.808072) (xy 121.844042 -239.766476)
			(xy 121.824751 -239.7212) (xy 121.812974 -239.673416) (xy 121.809014 -239.624362) (xy 121.480072 -239.624362)
			(xy 121.479577 -239.648969) (xy 121.471682 -239.697546) (xy 121.456098 -239.744227) (xy 121.433227 -239.787804)
			(xy 121.403662 -239.827148) (xy 121.368169 -239.86124) (xy 121.327666 -239.889196) (xy 121.283204 -239.910294)
			(xy 121.235933 -239.923986) (xy 121.187078 -239.929918) (xy 121.137903 -239.927937) (xy 121.089684 -239.918093)
			(xy 121.043668 -239.900641) (xy 121.001047 -239.876034) (xy 120.962926 -239.844909) (xy 120.930291 -239.808072)
			(xy 120.903988 -239.766476) (xy 120.884697 -239.7212) (xy 120.87292 -239.673416) (xy 120.86896 -239.624362)
			(xy 120.540018 -239.624362) (xy 120.539523 -239.648969) (xy 120.531628 -239.697546) (xy 120.516044 -239.744227)
			(xy 120.493173 -239.787804) (xy 120.463608 -239.827148) (xy 120.428115 -239.86124) (xy 120.387612 -239.889196)
			(xy 120.34315 -239.910294) (xy 120.295879 -239.923986) (xy 120.247024 -239.929918) (xy 120.197849 -239.927937)
			(xy 120.14963 -239.918093) (xy 120.103614 -239.900641) (xy 120.060993 -239.876034) (xy 120.022872 -239.844909)
			(xy 119.990237 -239.808072) (xy 119.963934 -239.766476) (xy 119.944643 -239.7212) (xy 119.932866 -239.673416)
			(xy 119.928906 -239.624362) (xy 119.599964 -239.624362) (xy 119.599469 -239.648969) (xy 119.591574 -239.697546)
			(xy 119.57599 -239.744227) (xy 119.553119 -239.787804) (xy 119.523554 -239.827148) (xy 119.488061 -239.86124)
			(xy 119.447558 -239.889196) (xy 119.403096 -239.910294) (xy 119.355825 -239.923986) (xy 119.30697 -239.929918)
			(xy 119.257795 -239.927937) (xy 119.209576 -239.918093) (xy 119.16356 -239.900641) (xy 119.120939 -239.876034)
			(xy 119.082818 -239.844909) (xy 119.050183 -239.808072) (xy 119.02388 -239.766476) (xy 119.004589 -239.7212)
			(xy 118.992812 -239.673416) (xy 118.988852 -239.624362) (xy 118.660164 -239.624362) (xy 118.659669 -239.648969)
			(xy 118.651774 -239.697546) (xy 118.63619 -239.744227) (xy 118.613319 -239.787804) (xy 118.583754 -239.827148)
			(xy 118.548261 -239.86124) (xy 118.507758 -239.889196) (xy 118.463296 -239.910294) (xy 118.416025 -239.923986)
			(xy 118.36717 -239.929918) (xy 118.317995 -239.927937) (xy 118.269776 -239.918093) (xy 118.22376 -239.900641)
			(xy 118.181139 -239.876034) (xy 118.143018 -239.844909) (xy 118.110383 -239.808072) (xy 118.08408 -239.766476)
			(xy 118.064789 -239.7212) (xy 118.053012 -239.673416) (xy 118.049052 -239.624362) (xy 117.72011 -239.624362)
			(xy 117.719615 -239.648969) (xy 117.71172 -239.697546) (xy 117.696136 -239.744227) (xy 117.673265 -239.787804)
			(xy 117.6437 -239.827148) (xy 117.608207 -239.86124) (xy 117.567704 -239.889196) (xy 117.523242 -239.910294)
			(xy 117.475971 -239.923986) (xy 117.427116 -239.929918) (xy 117.377941 -239.927937) (xy 117.329722 -239.918093)
			(xy 117.283706 -239.900641) (xy 117.241085 -239.876034) (xy 117.202964 -239.844909) (xy 117.170329 -239.808072)
			(xy 117.144026 -239.766476) (xy 117.124735 -239.7212) (xy 117.112958 -239.673416) (xy 117.108998 -239.624362)
			(xy 116.780056 -239.624362) (xy 116.779561 -239.648969) (xy 116.771666 -239.697546) (xy 116.756082 -239.744227)
			(xy 116.733211 -239.787804) (xy 116.703646 -239.827148) (xy 116.668153 -239.86124) (xy 116.62765 -239.889196)
			(xy 116.583188 -239.910294) (xy 116.535917 -239.923986) (xy 116.487062 -239.929918) (xy 116.437887 -239.927937)
			(xy 116.389668 -239.918093) (xy 116.343652 -239.900641) (xy 116.301031 -239.876034) (xy 116.26291 -239.844909)
			(xy 116.230275 -239.808072) (xy 116.203972 -239.766476) (xy 116.184681 -239.7212) (xy 116.172904 -239.673416)
			(xy 116.168944 -239.624362) (xy 115.840002 -239.624362) (xy 115.839507 -239.648969) (xy 115.831612 -239.697546)
			(xy 115.816028 -239.744227) (xy 115.793157 -239.787804) (xy 115.763592 -239.827148) (xy 115.728099 -239.86124)
			(xy 115.687596 -239.889196) (xy 115.643134 -239.910294) (xy 115.595863 -239.923986) (xy 115.547008 -239.929918)
			(xy 115.497833 -239.927937) (xy 115.449614 -239.918093) (xy 115.403598 -239.900641) (xy 115.360977 -239.876034)
			(xy 115.322856 -239.844909) (xy 115.290221 -239.808072) (xy 115.263918 -239.766476) (xy 115.244627 -239.7212)
			(xy 115.23285 -239.673416) (xy 115.22889 -239.624362) (xy 108.326428 -239.624362) (xy 108.325933 -239.648969)
			(xy 108.318038 -239.697546) (xy 108.302454 -239.744227) (xy 108.279583 -239.787804) (xy 108.250018 -239.827148)
			(xy 108.214525 -239.86124) (xy 108.174022 -239.889196) (xy 108.12956 -239.910294) (xy 108.082289 -239.923986)
			(xy 108.033434 -239.929918) (xy 107.984259 -239.927937) (xy 107.93604 -239.918093) (xy 107.890024 -239.900641)
			(xy 107.847403 -239.876034) (xy 107.809282 -239.844909) (xy 107.776647 -239.808072) (xy 107.750344 -239.766476)
			(xy 107.731053 -239.7212) (xy 107.719276 -239.673416) (xy 107.715316 -239.624362) (xy 107.386374 -239.624362)
			(xy 107.385879 -239.648969) (xy 107.377984 -239.697546) (xy 107.3624 -239.744227) (xy 107.339529 -239.787804)
			(xy 107.309964 -239.827148) (xy 107.274471 -239.86124) (xy 107.233968 -239.889196) (xy 107.189506 -239.910294)
			(xy 107.142235 -239.923986) (xy 107.09338 -239.929918) (xy 107.044205 -239.927937) (xy 106.995986 -239.918093)
			(xy 106.94997 -239.900641) (xy 106.907349 -239.876034) (xy 106.869228 -239.844909) (xy 106.836593 -239.808072)
			(xy 106.81029 -239.766476) (xy 106.790999 -239.7212) (xy 106.779222 -239.673416) (xy 106.775262 -239.624362)
			(xy 106.44632 -239.624362) (xy 106.445825 -239.648969) (xy 106.43793 -239.697546) (xy 106.422346 -239.744227)
			(xy 106.399475 -239.787804) (xy 106.36991 -239.827148) (xy 106.334417 -239.86124) (xy 106.293914 -239.889196)
			(xy 106.249452 -239.910294) (xy 106.202181 -239.923986) (xy 106.153326 -239.929918) (xy 106.104151 -239.927937)
			(xy 106.055932 -239.918093) (xy 106.009916 -239.900641) (xy 105.967295 -239.876034) (xy 105.929174 -239.844909)
			(xy 105.896539 -239.808072) (xy 105.870236 -239.766476) (xy 105.850945 -239.7212) (xy 105.839168 -239.673416)
			(xy 105.835208 -239.624362) (xy 105.506266 -239.624362) (xy 105.505771 -239.648969) (xy 105.497876 -239.697546)
			(xy 105.482292 -239.744227) (xy 105.459421 -239.787804) (xy 105.429856 -239.827148) (xy 105.394363 -239.86124)
			(xy 105.35386 -239.889196) (xy 105.309398 -239.910294) (xy 105.262127 -239.923986) (xy 105.213272 -239.929918)
			(xy 105.164097 -239.927937) (xy 105.115878 -239.918093) (xy 105.069862 -239.900641) (xy 105.027241 -239.876034)
			(xy 104.98912 -239.844909) (xy 104.956485 -239.808072) (xy 104.930182 -239.766476) (xy 104.910891 -239.7212)
			(xy 104.899114 -239.673416) (xy 104.895154 -239.624362) (xy 104.566466 -239.624362) (xy 104.565971 -239.648969)
			(xy 104.558076 -239.697546) (xy 104.542492 -239.744227) (xy 104.519621 -239.787804) (xy 104.490056 -239.827148)
			(xy 104.454563 -239.86124) (xy 104.41406 -239.889196) (xy 104.369598 -239.910294) (xy 104.322327 -239.923986)
			(xy 104.273472 -239.929918) (xy 104.224297 -239.927937) (xy 104.176078 -239.918093) (xy 104.130062 -239.900641)
			(xy 104.087441 -239.876034) (xy 104.04932 -239.844909) (xy 104.016685 -239.808072) (xy 103.990382 -239.766476)
			(xy 103.971091 -239.7212) (xy 103.959314 -239.673416) (xy 103.955354 -239.624362) (xy 103.626412 -239.624362)
			(xy 103.625917 -239.648969) (xy 103.618022 -239.697546) (xy 103.602438 -239.744227) (xy 103.579567 -239.787804)
			(xy 103.550002 -239.827148) (xy 103.514509 -239.86124) (xy 103.474006 -239.889196) (xy 103.429544 -239.910294)
			(xy 103.382273 -239.923986) (xy 103.333418 -239.929918) (xy 103.284243 -239.927937) (xy 103.236024 -239.918093)
			(xy 103.190008 -239.900641) (xy 103.147387 -239.876034) (xy 103.109266 -239.844909) (xy 103.076631 -239.808072)
			(xy 103.050328 -239.766476) (xy 103.031037 -239.7212) (xy 103.01926 -239.673416) (xy 103.0153 -239.624362)
			(xy 102.686358 -239.624362) (xy 102.685863 -239.648969) (xy 102.677968 -239.697546) (xy 102.662384 -239.744227)
			(xy 102.639513 -239.787804) (xy 102.609948 -239.827148) (xy 102.574455 -239.86124) (xy 102.533952 -239.889196)
			(xy 102.48949 -239.910294) (xy 102.442219 -239.923986) (xy 102.393364 -239.929918) (xy 102.344189 -239.927937)
			(xy 102.29597 -239.918093) (xy 102.249954 -239.900641) (xy 102.207333 -239.876034) (xy 102.169212 -239.844909)
			(xy 102.136577 -239.808072) (xy 102.110274 -239.766476) (xy 102.090983 -239.7212) (xy 102.079206 -239.673416)
			(xy 102.075246 -239.624362) (xy 101.746304 -239.624362) (xy 101.745809 -239.648969) (xy 101.737914 -239.697546)
			(xy 101.72233 -239.744227) (xy 101.699459 -239.787804) (xy 101.669894 -239.827148) (xy 101.634401 -239.86124)
			(xy 101.593898 -239.889196) (xy 101.549436 -239.910294) (xy 101.502165 -239.923986) (xy 101.45331 -239.929918)
			(xy 101.404135 -239.927937) (xy 101.355916 -239.918093) (xy 101.3099 -239.900641) (xy 101.267279 -239.876034)
			(xy 101.229158 -239.844909) (xy 101.196523 -239.808072) (xy 101.17022 -239.766476) (xy 101.150929 -239.7212)
			(xy 101.139152 -239.673416) (xy 101.135192 -239.624362) (xy 100.80625 -239.624362) (xy 100.805755 -239.648969)
			(xy 100.79786 -239.697546) (xy 100.782276 -239.744227) (xy 100.759405 -239.787804) (xy 100.72984 -239.827148)
			(xy 100.694347 -239.86124) (xy 100.653844 -239.889196) (xy 100.609382 -239.910294) (xy 100.562111 -239.923986)
			(xy 100.513256 -239.929918) (xy 100.464081 -239.927937) (xy 100.415862 -239.918093) (xy 100.369846 -239.900641)
			(xy 100.327225 -239.876034) (xy 100.289104 -239.844909) (xy 100.256469 -239.808072) (xy 100.230166 -239.766476)
			(xy 100.210875 -239.7212) (xy 100.199098 -239.673416) (xy 100.195138 -239.624362) (xy 99.86645 -239.624362)
			(xy 99.865955 -239.648969) (xy 99.85806 -239.697546) (xy 99.842476 -239.744227) (xy 99.819605 -239.787804)
			(xy 99.79004 -239.827148) (xy 99.754547 -239.86124) (xy 99.714044 -239.889196) (xy 99.669582 -239.910294)
			(xy 99.622311 -239.923986) (xy 99.573456 -239.929918) (xy 99.524281 -239.927937) (xy 99.476062 -239.918093)
			(xy 99.430046 -239.900641) (xy 99.387425 -239.876034) (xy 99.349304 -239.844909) (xy 99.316669 -239.808072)
			(xy 99.290366 -239.766476) (xy 99.271075 -239.7212) (xy 99.259298 -239.673416) (xy 99.255338 -239.624362)
			(xy 98.926396 -239.624362) (xy 98.925901 -239.648969) (xy 98.918006 -239.697546) (xy 98.902422 -239.744227)
			(xy 98.879551 -239.787804) (xy 98.849986 -239.827148) (xy 98.814493 -239.86124) (xy 98.77399 -239.889196)
			(xy 98.729528 -239.910294) (xy 98.682257 -239.923986) (xy 98.633402 -239.929918) (xy 98.584227 -239.927937)
			(xy 98.536008 -239.918093) (xy 98.489992 -239.900641) (xy 98.447371 -239.876034) (xy 98.40925 -239.844909)
			(xy 98.376615 -239.808072) (xy 98.350312 -239.766476) (xy 98.331021 -239.7212) (xy 98.319244 -239.673416)
			(xy 98.315284 -239.624362) (xy 97.986342 -239.624362) (xy 97.985847 -239.648969) (xy 97.977952 -239.697546)
			(xy 97.962368 -239.744227) (xy 97.939497 -239.787804) (xy 97.909932 -239.827148) (xy 97.874439 -239.86124)
			(xy 97.833936 -239.889196) (xy 97.789474 -239.910294) (xy 97.742203 -239.923986) (xy 97.693348 -239.929918)
			(xy 97.644173 -239.927937) (xy 97.595954 -239.918093) (xy 97.549938 -239.900641) (xy 97.507317 -239.876034)
			(xy 97.469196 -239.844909) (xy 97.436561 -239.808072) (xy 97.410258 -239.766476) (xy 97.390967 -239.7212)
			(xy 97.37919 -239.673416) (xy 97.37523 -239.624362) (xy 97.047081 -239.624362) (xy 97.047083 -239.624381)
			(xy 97.043118 -239.673503) (xy 97.031322 -239.721352) (xy 97.012 -239.766688) (xy 96.985652 -239.808335)
			(xy 96.952962 -239.845214) (xy 96.914777 -239.876369) (xy 96.893634 -239.88903) (xy 96.881696 -239.895888)
			(xy 96.868234 -239.919256) (xy 96.868234 -240.109248) (xy 96.868234 -240.112042) (xy 96.869499 -240.124323)
			(xy 96.882151 -240.145491) (xy 96.892364 -240.152428) (xy 96.896174 -240.154714) (xy 96.988376 -240.200942)
			(xy 97.016824 -240.198402) (xy 97.028508 -240.189766) (xy 97.048415 -240.175498) (xy 97.091825 -240.152826)
			(xy 97.138301 -240.137381) (xy 97.186647 -240.129561) (xy 97.211134 -240.12906) (xy 97.23639 -240.129584)
			(xy 97.286213 -240.137903) (xy 97.333987 -240.154309) (xy 97.378409 -240.178354) (xy 97.418269 -240.209381)
			(xy 97.452478 -240.246546) (xy 97.480104 -240.288835) (xy 97.500393 -240.335093) (xy 97.512792 -240.38406)
			(xy 97.51696 -240.434368) (xy 97.84513 -240.434368) (xy 97.84909 -240.385314) (xy 97.860867 -240.33753)
			(xy 97.880158 -240.292254) (xy 97.906461 -240.250658) (xy 97.939096 -240.213821) (xy 97.977217 -240.182696)
			(xy 98.019838 -240.158089) (xy 98.065854 -240.140637) (xy 98.114073 -240.130793) (xy 98.163248 -240.128812)
			(xy 98.212103 -240.134744) (xy 98.259374 -240.148436) (xy 98.303836 -240.169534) (xy 98.344339 -240.19749)
			(xy 98.379832 -240.231582) (xy 98.409397 -240.270926) (xy 98.432268 -240.314503) (xy 98.447852 -240.361184)
			(xy 98.455747 -240.409761) (xy 98.456242 -240.434368) (xy 98.785184 -240.434368) (xy 98.789144 -240.385314)
			(xy 98.800921 -240.33753) (xy 98.820212 -240.292254) (xy 98.846515 -240.250658) (xy 98.87915 -240.213821)
			(xy 98.917271 -240.182696) (xy 98.959892 -240.158089) (xy 99.005908 -240.140637) (xy 99.054127 -240.130793)
			(xy 99.103302 -240.128812) (xy 99.152157 -240.134744) (xy 99.199428 -240.148436) (xy 99.24389 -240.169534)
			(xy 99.284393 -240.19749) (xy 99.319886 -240.231582) (xy 99.349451 -240.270926) (xy 99.372322 -240.314503)
			(xy 99.387906 -240.361184) (xy 99.395801 -240.409761) (xy 99.396296 -240.434368) (xy 99.725238 -240.434368)
			(xy 99.729198 -240.385314) (xy 99.740975 -240.33753) (xy 99.760266 -240.292254) (xy 99.786569 -240.250658)
			(xy 99.819204 -240.213821) (xy 99.857325 -240.182696) (xy 99.899946 -240.158089) (xy 99.945962 -240.140637)
			(xy 99.994181 -240.130793) (xy 100.043356 -240.128812) (xy 100.092211 -240.134744) (xy 100.139482 -240.148436)
			(xy 100.183944 -240.169534) (xy 100.224447 -240.19749) (xy 100.25994 -240.231582) (xy 100.289505 -240.270926)
			(xy 100.312376 -240.314503) (xy 100.32796 -240.361184) (xy 100.335855 -240.409761) (xy 100.33635 -240.434368)
			(xy 100.665292 -240.434368) (xy 100.669252 -240.385314) (xy 100.681029 -240.33753) (xy 100.70032 -240.292254)
			(xy 100.726623 -240.250658) (xy 100.759258 -240.213821) (xy 100.797379 -240.182696) (xy 100.84 -240.158089)
			(xy 100.886016 -240.140637) (xy 100.934235 -240.130793) (xy 100.98341 -240.128812) (xy 101.032265 -240.134744)
			(xy 101.079536 -240.148436) (xy 101.123998 -240.169534) (xy 101.164501 -240.19749) (xy 101.199994 -240.231582)
			(xy 101.229559 -240.270926) (xy 101.25243 -240.314503) (xy 101.268014 -240.361184) (xy 101.275909 -240.409761)
			(xy 101.276404 -240.434368) (xy 101.605346 -240.434368) (xy 101.609306 -240.385314) (xy 101.621083 -240.33753)
			(xy 101.640374 -240.292254) (xy 101.666677 -240.250658) (xy 101.699312 -240.213821) (xy 101.737433 -240.182696)
			(xy 101.780054 -240.158089) (xy 101.82607 -240.140637) (xy 101.874289 -240.130793) (xy 101.923464 -240.128812)
			(xy 101.972319 -240.134744) (xy 102.01959 -240.148436) (xy 102.064052 -240.169534) (xy 102.104555 -240.19749)
			(xy 102.140048 -240.231582) (xy 102.169613 -240.270926) (xy 102.192484 -240.314503) (xy 102.208068 -240.361184)
			(xy 102.215963 -240.409761) (xy 102.216458 -240.434368) (xy 102.545146 -240.434368) (xy 102.549106 -240.385314)
			(xy 102.560883 -240.33753) (xy 102.580174 -240.292254) (xy 102.606477 -240.250658) (xy 102.639112 -240.213821)
			(xy 102.677233 -240.182696) (xy 102.719854 -240.158089) (xy 102.76587 -240.140637) (xy 102.814089 -240.130793)
			(xy 102.863264 -240.128812) (xy 102.912119 -240.134744) (xy 102.95939 -240.148436) (xy 103.003852 -240.169534)
			(xy 103.044355 -240.19749) (xy 103.079848 -240.231582) (xy 103.109413 -240.270926) (xy 103.132284 -240.314503)
			(xy 103.147868 -240.361184) (xy 103.155763 -240.409761) (xy 103.156258 -240.434368) (xy 103.4852 -240.434368)
			(xy 103.48916 -240.385314) (xy 103.500937 -240.33753) (xy 103.520228 -240.292254) (xy 103.546531 -240.250658)
			(xy 103.579166 -240.213821) (xy 103.617287 -240.182696) (xy 103.659908 -240.158089) (xy 103.705924 -240.140637)
			(xy 103.754143 -240.130793) (xy 103.803318 -240.128812) (xy 103.852173 -240.134744) (xy 103.899444 -240.148436)
			(xy 103.943906 -240.169534) (xy 103.984409 -240.19749) (xy 104.019902 -240.231582) (xy 104.049467 -240.270926)
			(xy 104.072338 -240.314503) (xy 104.087922 -240.361184) (xy 104.095817 -240.409761) (xy 104.096312 -240.434368)
			(xy 104.425254 -240.434368) (xy 104.429214 -240.385314) (xy 104.440991 -240.33753) (xy 104.460282 -240.292254)
			(xy 104.486585 -240.250658) (xy 104.51922 -240.213821) (xy 104.557341 -240.182696) (xy 104.599962 -240.158089)
			(xy 104.645978 -240.140637) (xy 104.694197 -240.130793) (xy 104.743372 -240.128812) (xy 104.792227 -240.134744)
			(xy 104.839498 -240.148436) (xy 104.88396 -240.169534) (xy 104.924463 -240.19749) (xy 104.959956 -240.231582)
			(xy 104.989521 -240.270926) (xy 105.012392 -240.314503) (xy 105.027976 -240.361184) (xy 105.035871 -240.409761)
			(xy 105.036366 -240.434368) (xy 105.365308 -240.434368) (xy 105.369268 -240.385314) (xy 105.381045 -240.33753)
			(xy 105.400336 -240.292254) (xy 105.426639 -240.250658) (xy 105.459274 -240.213821) (xy 105.497395 -240.182696)
			(xy 105.540016 -240.158089) (xy 105.586032 -240.140637) (xy 105.634251 -240.130793) (xy 105.683426 -240.128812)
			(xy 105.732281 -240.134744) (xy 105.779552 -240.148436) (xy 105.824014 -240.169534) (xy 105.864517 -240.19749)
			(xy 105.90001 -240.231582) (xy 105.929575 -240.270926) (xy 105.952446 -240.314503) (xy 105.96803 -240.361184)
			(xy 105.975925 -240.409761) (xy 105.97642 -240.434368) (xy 106.305362 -240.434368) (xy 106.309322 -240.385314)
			(xy 106.321099 -240.33753) (xy 106.34039 -240.292254) (xy 106.366693 -240.250658) (xy 106.399328 -240.213821)
			(xy 106.437449 -240.182696) (xy 106.48007 -240.158089) (xy 106.526086 -240.140637) (xy 106.574305 -240.130793)
			(xy 106.62348 -240.128812) (xy 106.672335 -240.134744) (xy 106.719606 -240.148436) (xy 106.764068 -240.169534)
			(xy 106.804571 -240.19749) (xy 106.840064 -240.231582) (xy 106.869629 -240.270926) (xy 106.8925 -240.314503)
			(xy 106.908084 -240.361184) (xy 106.915979 -240.409761) (xy 106.916474 -240.434368) (xy 107.245162 -240.434368)
			(xy 107.249122 -240.385314) (xy 107.260899 -240.33753) (xy 107.28019 -240.292254) (xy 107.306493 -240.250658)
			(xy 107.339128 -240.213821) (xy 107.377249 -240.182696) (xy 107.41987 -240.158089) (xy 107.465886 -240.140637)
			(xy 107.514105 -240.130793) (xy 107.56328 -240.128812) (xy 107.612135 -240.134744) (xy 107.659406 -240.148436)
			(xy 107.703868 -240.169534) (xy 107.744371 -240.19749) (xy 107.779864 -240.231582) (xy 107.809429 -240.270926)
			(xy 107.8323 -240.314503) (xy 107.847884 -240.361184) (xy 107.855779 -240.409761) (xy 107.856274 -240.434368)
			(xy 108.185216 -240.434368) (xy 108.189176 -240.385314) (xy 108.200953 -240.33753) (xy 108.220244 -240.292254)
			(xy 108.246547 -240.250658) (xy 108.279182 -240.213821) (xy 108.317303 -240.182696) (xy 108.359924 -240.158089)
			(xy 108.40594 -240.140637) (xy 108.454159 -240.130793) (xy 108.503334 -240.128812) (xy 108.552189 -240.134744)
			(xy 108.59946 -240.148436) (xy 108.643922 -240.169534) (xy 108.684425 -240.19749) (xy 108.719918 -240.231582)
			(xy 108.749483 -240.270926) (xy 108.772354 -240.314503) (xy 108.787938 -240.361184) (xy 108.795833 -240.409761)
			(xy 108.796328 -240.434368) (xy 109.12527 -240.434368) (xy 109.12923 -240.385314) (xy 109.141007 -240.33753)
			(xy 109.160298 -240.292254) (xy 109.186601 -240.250658) (xy 109.219236 -240.213821) (xy 109.257357 -240.182696)
			(xy 109.299978 -240.158089) (xy 109.345994 -240.140637) (xy 109.394213 -240.130793) (xy 109.443388 -240.128812)
			(xy 109.492243 -240.134744) (xy 109.539514 -240.148436) (xy 109.583976 -240.169534) (xy 109.624479 -240.19749)
			(xy 109.659972 -240.231582) (xy 109.689537 -240.270926) (xy 109.712408 -240.314503) (xy 109.727992 -240.361184)
			(xy 109.735887 -240.409761) (xy 109.736382 -240.434368) (xy 110.065324 -240.434368) (xy 110.069284 -240.385314)
			(xy 110.081061 -240.33753) (xy 110.100352 -240.292254) (xy 110.126655 -240.250658) (xy 110.15929 -240.213821)
			(xy 110.197411 -240.182696) (xy 110.240032 -240.158089) (xy 110.286048 -240.140637) (xy 110.334267 -240.130793)
			(xy 110.383442 -240.128812) (xy 110.432297 -240.134744) (xy 110.479568 -240.148436) (xy 110.52403 -240.169534)
			(xy 110.564533 -240.19749) (xy 110.600026 -240.231582) (xy 110.629591 -240.270926) (xy 110.652462 -240.314503)
			(xy 110.668046 -240.361184) (xy 110.675941 -240.409761) (xy 110.676436 -240.434368) (xy 112.878882 -240.434368)
			(xy 112.882842 -240.385314) (xy 112.894619 -240.33753) (xy 112.91391 -240.292254) (xy 112.940213 -240.250658)
			(xy 112.972848 -240.213821) (xy 113.010969 -240.182696) (xy 113.05359 -240.158089) (xy 113.099606 -240.140637)
			(xy 113.147825 -240.130793) (xy 113.197 -240.128812) (xy 113.245855 -240.134744) (xy 113.293126 -240.148436)
			(xy 113.337588 -240.169534) (xy 113.378091 -240.19749) (xy 113.413584 -240.231582) (xy 113.443149 -240.270926)
			(xy 113.46602 -240.314503) (xy 113.481604 -240.361184) (xy 113.489499 -240.409761) (xy 113.489994 -240.434368)
			(xy 113.818936 -240.434368) (xy 113.822896 -240.385314) (xy 113.834673 -240.33753) (xy 113.853964 -240.292254)
			(xy 113.880267 -240.250658) (xy 113.912902 -240.213821) (xy 113.951023 -240.182696) (xy 113.993644 -240.158089)
			(xy 114.03966 -240.140637) (xy 114.087879 -240.130793) (xy 114.137054 -240.128812) (xy 114.185909 -240.134744)
			(xy 114.23318 -240.148436) (xy 114.277642 -240.169534) (xy 114.318145 -240.19749) (xy 114.353638 -240.231582)
			(xy 114.383203 -240.270926) (xy 114.406074 -240.314503) (xy 114.421658 -240.361184) (xy 114.429553 -240.409761)
			(xy 114.430048 -240.434368) (xy 114.75899 -240.434368) (xy 114.76295 -240.385314) (xy 114.774727 -240.33753)
			(xy 114.794018 -240.292254) (xy 114.820321 -240.250658) (xy 114.852956 -240.213821) (xy 114.891077 -240.182696)
			(xy 114.933698 -240.158089) (xy 114.979714 -240.140637) (xy 115.027933 -240.130793) (xy 115.077108 -240.128812)
			(xy 115.125963 -240.134744) (xy 115.173234 -240.148436) (xy 115.217696 -240.169534) (xy 115.258199 -240.19749)
			(xy 115.293692 -240.231582) (xy 115.323257 -240.270926) (xy 115.346128 -240.314503) (xy 115.361712 -240.361184)
			(xy 115.369607 -240.409761) (xy 115.370102 -240.434368) (xy 115.699044 -240.434368) (xy 115.703004 -240.385314)
			(xy 115.714781 -240.33753) (xy 115.734072 -240.292254) (xy 115.760375 -240.250658) (xy 115.79301 -240.213821)
			(xy 115.831131 -240.182696) (xy 115.873752 -240.158089) (xy 115.919768 -240.140637) (xy 115.967987 -240.130793)
			(xy 116.017162 -240.128812) (xy 116.066017 -240.134744) (xy 116.113288 -240.148436) (xy 116.15775 -240.169534)
			(xy 116.198253 -240.19749) (xy 116.233746 -240.231582) (xy 116.263311 -240.270926) (xy 116.286182 -240.314503)
			(xy 116.301766 -240.361184) (xy 116.309661 -240.409761) (xy 116.310156 -240.434368) (xy 116.638844 -240.434368)
			(xy 116.642804 -240.385314) (xy 116.654581 -240.33753) (xy 116.673872 -240.292254) (xy 116.700175 -240.250658)
			(xy 116.73281 -240.213821) (xy 116.770931 -240.182696) (xy 116.813552 -240.158089) (xy 116.859568 -240.140637)
			(xy 116.907787 -240.130793) (xy 116.956962 -240.128812) (xy 117.005817 -240.134744) (xy 117.053088 -240.148436)
			(xy 117.09755 -240.169534) (xy 117.138053 -240.19749) (xy 117.173546 -240.231582) (xy 117.203111 -240.270926)
			(xy 117.225982 -240.314503) (xy 117.241566 -240.361184) (xy 117.249461 -240.409761) (xy 117.249956 -240.434368)
			(xy 117.578898 -240.434368) (xy 117.582858 -240.385314) (xy 117.594635 -240.33753) (xy 117.613926 -240.292254)
			(xy 117.640229 -240.250658) (xy 117.672864 -240.213821) (xy 117.710985 -240.182696) (xy 117.753606 -240.158089)
			(xy 117.799622 -240.140637) (xy 117.847841 -240.130793) (xy 117.897016 -240.128812) (xy 117.945871 -240.134744)
			(xy 117.993142 -240.148436) (xy 118.037604 -240.169534) (xy 118.078107 -240.19749) (xy 118.1136 -240.231582)
			(xy 118.143165 -240.270926) (xy 118.166036 -240.314503) (xy 118.18162 -240.361184) (xy 118.189515 -240.409761)
			(xy 118.19001 -240.434368) (xy 118.518952 -240.434368) (xy 118.522912 -240.385314) (xy 118.534689 -240.33753)
			(xy 118.55398 -240.292254) (xy 118.580283 -240.250658) (xy 118.612918 -240.213821) (xy 118.651039 -240.182696)
			(xy 118.69366 -240.158089) (xy 118.739676 -240.140637) (xy 118.787895 -240.130793) (xy 118.83707 -240.128812)
			(xy 118.885925 -240.134744) (xy 118.933196 -240.148436) (xy 118.977658 -240.169534) (xy 119.018161 -240.19749)
			(xy 119.053654 -240.231582) (xy 119.083219 -240.270926) (xy 119.10609 -240.314503) (xy 119.121674 -240.361184)
			(xy 119.129569 -240.409761) (xy 119.130064 -240.434368) (xy 119.459006 -240.434368) (xy 119.462966 -240.385314)
			(xy 119.474743 -240.33753) (xy 119.494034 -240.292254) (xy 119.520337 -240.250658) (xy 119.552972 -240.213821)
			(xy 119.591093 -240.182696) (xy 119.633714 -240.158089) (xy 119.67973 -240.140637) (xy 119.727949 -240.130793)
			(xy 119.777124 -240.128812) (xy 119.825979 -240.134744) (xy 119.87325 -240.148436) (xy 119.917712 -240.169534)
			(xy 119.958215 -240.19749) (xy 119.993708 -240.231582) (xy 120.023273 -240.270926) (xy 120.046144 -240.314503)
			(xy 120.061728 -240.361184) (xy 120.069623 -240.409761) (xy 120.070118 -240.434368) (xy 120.398806 -240.434368)
			(xy 120.402766 -240.385314) (xy 120.414543 -240.33753) (xy 120.433834 -240.292254) (xy 120.460137 -240.250658)
			(xy 120.492772 -240.213821) (xy 120.530893 -240.182696) (xy 120.573514 -240.158089) (xy 120.61953 -240.140637)
			(xy 120.667749 -240.130793) (xy 120.716924 -240.128812) (xy 120.765779 -240.134744) (xy 120.81305 -240.148436)
			(xy 120.857512 -240.169534) (xy 120.898015 -240.19749) (xy 120.933508 -240.231582) (xy 120.963073 -240.270926)
			(xy 120.985944 -240.314503) (xy 121.001528 -240.361184) (xy 121.009423 -240.409761) (xy 121.009918 -240.434368)
			(xy 121.33886 -240.434368) (xy 121.34282 -240.385314) (xy 121.354597 -240.33753) (xy 121.373888 -240.292254)
			(xy 121.400191 -240.250658) (xy 121.432826 -240.213821) (xy 121.470947 -240.182696) (xy 121.513568 -240.158089)
			(xy 121.559584 -240.140637) (xy 121.607803 -240.130793) (xy 121.656978 -240.128812) (xy 121.705833 -240.134744)
			(xy 121.753104 -240.148436) (xy 121.797566 -240.169534) (xy 121.838069 -240.19749) (xy 121.873562 -240.231582)
			(xy 121.903127 -240.270926) (xy 121.925998 -240.314503) (xy 121.941582 -240.361184) (xy 121.949477 -240.409761)
			(xy 121.949972 -240.434368) (xy 122.278914 -240.434368) (xy 122.282874 -240.385314) (xy 122.294651 -240.33753)
			(xy 122.313942 -240.292254) (xy 122.340245 -240.250658) (xy 122.37288 -240.213821) (xy 122.411001 -240.182696)
			(xy 122.453622 -240.158089) (xy 122.499638 -240.140637) (xy 122.547857 -240.130793) (xy 122.597032 -240.128812)
			(xy 122.645887 -240.134744) (xy 122.693158 -240.148436) (xy 122.73762 -240.169534) (xy 122.778123 -240.19749)
			(xy 122.813616 -240.231582) (xy 122.843181 -240.270926) (xy 122.866052 -240.314503) (xy 122.881636 -240.361184)
			(xy 122.889531 -240.409761) (xy 122.890026 -240.434368) (xy 123.218968 -240.434368) (xy 123.222928 -240.385314)
			(xy 123.234705 -240.33753) (xy 123.253996 -240.292254) (xy 123.280299 -240.250658) (xy 123.312934 -240.213821)
			(xy 123.351055 -240.182696) (xy 123.393676 -240.158089) (xy 123.439692 -240.140637) (xy 123.487911 -240.130793)
			(xy 123.537086 -240.128812) (xy 123.585941 -240.134744) (xy 123.633212 -240.148436) (xy 123.677674 -240.169534)
			(xy 123.718177 -240.19749) (xy 123.75367 -240.231582) (xy 123.783235 -240.270926) (xy 123.806106 -240.314503)
			(xy 123.82169 -240.361184) (xy 123.829585 -240.409761) (xy 123.83008 -240.434368) (xy 124.159022 -240.434368)
			(xy 124.162982 -240.385314) (xy 124.174759 -240.33753) (xy 124.19405 -240.292254) (xy 124.220353 -240.250658)
			(xy 124.252988 -240.213821) (xy 124.291109 -240.182696) (xy 124.33373 -240.158089) (xy 124.379746 -240.140637)
			(xy 124.427965 -240.130793) (xy 124.47714 -240.128812) (xy 124.525995 -240.134744) (xy 124.573266 -240.148436)
			(xy 124.617728 -240.169534) (xy 124.658231 -240.19749) (xy 124.693724 -240.231582) (xy 124.723289 -240.270926)
			(xy 124.74616 -240.314503) (xy 124.761744 -240.361184) (xy 124.769639 -240.409761) (xy 124.770134 -240.434368)
			(xy 125.098822 -240.434368) (xy 125.102782 -240.385314) (xy 125.114559 -240.33753) (xy 125.13385 -240.292254)
			(xy 125.160153 -240.250658) (xy 125.192788 -240.213821) (xy 125.230909 -240.182696) (xy 125.27353 -240.158089)
			(xy 125.319546 -240.140637) (xy 125.367765 -240.130793) (xy 125.41694 -240.128812) (xy 125.465795 -240.134744)
			(xy 125.513066 -240.148436) (xy 125.557528 -240.169534) (xy 125.598031 -240.19749) (xy 125.633524 -240.231582)
			(xy 125.663089 -240.270926) (xy 125.68596 -240.314503) (xy 125.701544 -240.361184) (xy 125.709439 -240.409761)
			(xy 125.709934 -240.434368) (xy 126.038876 -240.434368) (xy 126.042836 -240.385314) (xy 126.054613 -240.33753)
			(xy 126.073904 -240.292254) (xy 126.100207 -240.250658) (xy 126.132842 -240.213821) (xy 126.170963 -240.182696)
			(xy 126.213584 -240.158089) (xy 126.2596 -240.140637) (xy 126.307819 -240.130793) (xy 126.356994 -240.128812)
			(xy 126.405849 -240.134744) (xy 126.45312 -240.148436) (xy 126.497582 -240.169534) (xy 126.538085 -240.19749)
			(xy 126.573578 -240.231582) (xy 126.603143 -240.270926) (xy 126.626014 -240.314503) (xy 126.641598 -240.361184)
			(xy 126.649493 -240.409761) (xy 126.649988 -240.434368) (xy 126.97893 -240.434368) (xy 126.98289 -240.385314)
			(xy 126.994667 -240.33753) (xy 127.013958 -240.292254) (xy 127.040261 -240.250658) (xy 127.072896 -240.213821)
			(xy 127.111017 -240.182696) (xy 127.153638 -240.158089) (xy 127.199654 -240.140637) (xy 127.247873 -240.130793)
			(xy 127.297048 -240.128812) (xy 127.345903 -240.134744) (xy 127.393174 -240.148436) (xy 127.437636 -240.169534)
			(xy 127.478139 -240.19749) (xy 127.513632 -240.231582) (xy 127.543197 -240.270926) (xy 127.566068 -240.314503)
			(xy 127.581652 -240.361184) (xy 127.589547 -240.409761) (xy 127.590042 -240.434368) (xy 127.908553 -240.434368)
			(xy 127.912648 -240.38364) (xy 127.924827 -240.334226) (xy 127.944775 -240.287406) (xy 127.971976 -240.244392)
			(xy 128.005724 -240.206298) (xy 128.045146 -240.174111) (xy 128.08922 -240.148665) (xy 128.136806 -240.130618)
			(xy 128.18667 -240.120438) (xy 128.237522 -240.118389) (xy 128.288043 -240.124523) (xy 128.336927 -240.138683)
			(xy 128.382906 -240.1605) (xy 128.42479 -240.18941) (xy 128.461494 -240.224665) (xy 128.492067 -240.265351)
			(xy 128.515718 -240.310414) (xy 128.531834 -240.358688) (xy 128.539998 -240.408922) (xy 128.54051 -240.434368)
			(xy 128.848607 -240.434368) (xy 128.852702 -240.38364) (xy 128.864881 -240.334226) (xy 128.884829 -240.287406)
			(xy 128.91203 -240.244392) (xy 128.945778 -240.206298) (xy 128.9852 -240.174111) (xy 129.029274 -240.148665)
			(xy 129.07686 -240.130618) (xy 129.126724 -240.120438) (xy 129.177576 -240.118389) (xy 129.228097 -240.124523)
			(xy 129.276981 -240.138683) (xy 129.32296 -240.1605) (xy 129.364844 -240.18941) (xy 129.401548 -240.224665)
			(xy 129.432121 -240.265351) (xy 129.455772 -240.310414) (xy 129.471888 -240.358688) (xy 129.480052 -240.408922)
			(xy 129.480564 -240.434368) (xy 129.480052 -240.459814) (xy 129.471888 -240.510048) (xy 129.455772 -240.558322)
			(xy 129.432121 -240.603385) (xy 129.401548 -240.644071) (xy 129.364844 -240.679326) (xy 129.32296 -240.708236)
			(xy 129.276981 -240.730053) (xy 129.228097 -240.744213) (xy 129.177576 -240.750347) (xy 129.126724 -240.748298)
			(xy 129.07686 -240.738118) (xy 129.029274 -240.720071) (xy 128.9852 -240.694625) (xy 128.945778 -240.662438)
			(xy 128.91203 -240.624344) (xy 128.884829 -240.58133) (xy 128.864881 -240.53451) (xy 128.852702 -240.485096)
			(xy 128.848607 -240.434368) (xy 128.54051 -240.434368) (xy 128.539998 -240.459814) (xy 128.531834 -240.510048)
			(xy 128.515718 -240.558322) (xy 128.492067 -240.603385) (xy 128.461494 -240.644071) (xy 128.42479 -240.679326)
			(xy 128.382906 -240.708236) (xy 128.336927 -240.730053) (xy 128.288043 -240.744213) (xy 128.237522 -240.750347)
			(xy 128.18667 -240.748298) (xy 128.136806 -240.738118) (xy 128.08922 -240.720071) (xy 128.045146 -240.694625)
			(xy 128.005724 -240.662438) (xy 127.971976 -240.624344) (xy 127.944775 -240.58133) (xy 127.924827 -240.53451)
			(xy 127.912648 -240.485096) (xy 127.908553 -240.434368) (xy 127.590042 -240.434368) (xy 127.589547 -240.458975)
			(xy 127.581652 -240.507552) (xy 127.566068 -240.554233) (xy 127.543197 -240.59781) (xy 127.513632 -240.637154)
			(xy 127.478139 -240.671246) (xy 127.437636 -240.699202) (xy 127.393174 -240.7203) (xy 127.345903 -240.733992)
			(xy 127.297048 -240.739924) (xy 127.247873 -240.737943) (xy 127.199654 -240.728099) (xy 127.153638 -240.710647)
			(xy 127.111017 -240.68604) (xy 127.072896 -240.654915) (xy 127.040261 -240.618078) (xy 127.013958 -240.576482)
			(xy 126.994667 -240.531206) (xy 126.98289 -240.483422) (xy 126.97893 -240.434368) (xy 126.649988 -240.434368)
			(xy 126.649493 -240.458975) (xy 126.641598 -240.507552) (xy 126.626014 -240.554233) (xy 126.603143 -240.59781)
			(xy 126.573578 -240.637154) (xy 126.538085 -240.671246) (xy 126.497582 -240.699202) (xy 126.45312 -240.7203)
			(xy 126.405849 -240.733992) (xy 126.356994 -240.739924) (xy 126.307819 -240.737943) (xy 126.2596 -240.728099)
			(xy 126.213584 -240.710647) (xy 126.170963 -240.68604) (xy 126.132842 -240.654915) (xy 126.100207 -240.618078)
			(xy 126.073904 -240.576482) (xy 126.054613 -240.531206) (xy 126.042836 -240.483422) (xy 126.038876 -240.434368)
			(xy 125.709934 -240.434368) (xy 125.709439 -240.458975) (xy 125.701544 -240.507552) (xy 125.68596 -240.554233)
			(xy 125.663089 -240.59781) (xy 125.633524 -240.637154) (xy 125.598031 -240.671246) (xy 125.557528 -240.699202)
			(xy 125.513066 -240.7203) (xy 125.465795 -240.733992) (xy 125.41694 -240.739924) (xy 125.367765 -240.737943)
			(xy 125.319546 -240.728099) (xy 125.27353 -240.710647) (xy 125.230909 -240.68604) (xy 125.192788 -240.654915)
			(xy 125.160153 -240.618078) (xy 125.13385 -240.576482) (xy 125.114559 -240.531206) (xy 125.102782 -240.483422)
			(xy 125.098822 -240.434368) (xy 124.770134 -240.434368) (xy 124.769639 -240.458975) (xy 124.761744 -240.507552)
			(xy 124.74616 -240.554233) (xy 124.723289 -240.59781) (xy 124.693724 -240.637154) (xy 124.658231 -240.671246)
			(xy 124.617728 -240.699202) (xy 124.573266 -240.7203) (xy 124.525995 -240.733992) (xy 124.47714 -240.739924)
			(xy 124.427965 -240.737943) (xy 124.379746 -240.728099) (xy 124.33373 -240.710647) (xy 124.291109 -240.68604)
			(xy 124.252988 -240.654915) (xy 124.220353 -240.618078) (xy 124.19405 -240.576482) (xy 124.174759 -240.531206)
			(xy 124.162982 -240.483422) (xy 124.159022 -240.434368) (xy 123.83008 -240.434368) (xy 123.829585 -240.458975)
			(xy 123.82169 -240.507552) (xy 123.806106 -240.554233) (xy 123.783235 -240.59781) (xy 123.75367 -240.637154)
			(xy 123.718177 -240.671246) (xy 123.677674 -240.699202) (xy 123.633212 -240.7203) (xy 123.585941 -240.733992)
			(xy 123.537086 -240.739924) (xy 123.487911 -240.737943) (xy 123.439692 -240.728099) (xy 123.393676 -240.710647)
			(xy 123.351055 -240.68604) (xy 123.312934 -240.654915) (xy 123.280299 -240.618078) (xy 123.253996 -240.576482)
			(xy 123.234705 -240.531206) (xy 123.222928 -240.483422) (xy 123.218968 -240.434368) (xy 122.890026 -240.434368)
			(xy 122.889531 -240.458975) (xy 122.881636 -240.507552) (xy 122.866052 -240.554233) (xy 122.843181 -240.59781)
			(xy 122.813616 -240.637154) (xy 122.778123 -240.671246) (xy 122.73762 -240.699202) (xy 122.693158 -240.7203)
			(xy 122.645887 -240.733992) (xy 122.597032 -240.739924) (xy 122.547857 -240.737943) (xy 122.499638 -240.728099)
			(xy 122.453622 -240.710647) (xy 122.411001 -240.68604) (xy 122.37288 -240.654915) (xy 122.340245 -240.618078)
			(xy 122.313942 -240.576482) (xy 122.294651 -240.531206) (xy 122.282874 -240.483422) (xy 122.278914 -240.434368)
			(xy 121.949972 -240.434368) (xy 121.949477 -240.458975) (xy 121.941582 -240.507552) (xy 121.925998 -240.554233)
			(xy 121.903127 -240.59781) (xy 121.873562 -240.637154) (xy 121.838069 -240.671246) (xy 121.797566 -240.699202)
			(xy 121.753104 -240.7203) (xy 121.705833 -240.733992) (xy 121.656978 -240.739924) (xy 121.607803 -240.737943)
			(xy 121.559584 -240.728099) (xy 121.513568 -240.710647) (xy 121.470947 -240.68604) (xy 121.432826 -240.654915)
			(xy 121.400191 -240.618078) (xy 121.373888 -240.576482) (xy 121.354597 -240.531206) (xy 121.34282 -240.483422)
			(xy 121.33886 -240.434368) (xy 121.009918 -240.434368) (xy 121.009423 -240.458975) (xy 121.001528 -240.507552)
			(xy 120.985944 -240.554233) (xy 120.963073 -240.59781) (xy 120.933508 -240.637154) (xy 120.898015 -240.671246)
			(xy 120.857512 -240.699202) (xy 120.81305 -240.7203) (xy 120.765779 -240.733992) (xy 120.716924 -240.739924)
			(xy 120.667749 -240.737943) (xy 120.61953 -240.728099) (xy 120.573514 -240.710647) (xy 120.530893 -240.68604)
			(xy 120.492772 -240.654915) (xy 120.460137 -240.618078) (xy 120.433834 -240.576482) (xy 120.414543 -240.531206)
			(xy 120.402766 -240.483422) (xy 120.398806 -240.434368) (xy 120.070118 -240.434368) (xy 120.069623 -240.458975)
			(xy 120.061728 -240.507552) (xy 120.046144 -240.554233) (xy 120.023273 -240.59781) (xy 119.993708 -240.637154)
			(xy 119.958215 -240.671246) (xy 119.917712 -240.699202) (xy 119.87325 -240.7203) (xy 119.825979 -240.733992)
			(xy 119.777124 -240.739924) (xy 119.727949 -240.737943) (xy 119.67973 -240.728099) (xy 119.633714 -240.710647)
			(xy 119.591093 -240.68604) (xy 119.552972 -240.654915) (xy 119.520337 -240.618078) (xy 119.494034 -240.576482)
			(xy 119.474743 -240.531206) (xy 119.462966 -240.483422) (xy 119.459006 -240.434368) (xy 119.130064 -240.434368)
			(xy 119.129569 -240.458975) (xy 119.121674 -240.507552) (xy 119.10609 -240.554233) (xy 119.083219 -240.59781)
			(xy 119.053654 -240.637154) (xy 119.018161 -240.671246) (xy 118.977658 -240.699202) (xy 118.933196 -240.7203)
			(xy 118.885925 -240.733992) (xy 118.83707 -240.739924) (xy 118.787895 -240.737943) (xy 118.739676 -240.728099)
			(xy 118.69366 -240.710647) (xy 118.651039 -240.68604) (xy 118.612918 -240.654915) (xy 118.580283 -240.618078)
			(xy 118.55398 -240.576482) (xy 118.534689 -240.531206) (xy 118.522912 -240.483422) (xy 118.518952 -240.434368)
			(xy 118.19001 -240.434368) (xy 118.189515 -240.458975) (xy 118.18162 -240.507552) (xy 118.166036 -240.554233)
			(xy 118.143165 -240.59781) (xy 118.1136 -240.637154) (xy 118.078107 -240.671246) (xy 118.037604 -240.699202)
			(xy 117.993142 -240.7203) (xy 117.945871 -240.733992) (xy 117.897016 -240.739924) (xy 117.847841 -240.737943)
			(xy 117.799622 -240.728099) (xy 117.753606 -240.710647) (xy 117.710985 -240.68604) (xy 117.672864 -240.654915)
			(xy 117.640229 -240.618078) (xy 117.613926 -240.576482) (xy 117.594635 -240.531206) (xy 117.582858 -240.483422)
			(xy 117.578898 -240.434368) (xy 117.249956 -240.434368) (xy 117.249461 -240.458975) (xy 117.241566 -240.507552)
			(xy 117.225982 -240.554233) (xy 117.203111 -240.59781) (xy 117.173546 -240.637154) (xy 117.138053 -240.671246)
			(xy 117.09755 -240.699202) (xy 117.053088 -240.7203) (xy 117.005817 -240.733992) (xy 116.956962 -240.739924)
			(xy 116.907787 -240.737943) (xy 116.859568 -240.728099) (xy 116.813552 -240.710647) (xy 116.770931 -240.68604)
			(xy 116.73281 -240.654915) (xy 116.700175 -240.618078) (xy 116.673872 -240.576482) (xy 116.654581 -240.531206)
			(xy 116.642804 -240.483422) (xy 116.638844 -240.434368) (xy 116.310156 -240.434368) (xy 116.309661 -240.458975)
			(xy 116.301766 -240.507552) (xy 116.286182 -240.554233) (xy 116.263311 -240.59781) (xy 116.233746 -240.637154)
			(xy 116.198253 -240.671246) (xy 116.15775 -240.699202) (xy 116.113288 -240.7203) (xy 116.066017 -240.733992)
			(xy 116.017162 -240.739924) (xy 115.967987 -240.737943) (xy 115.919768 -240.728099) (xy 115.873752 -240.710647)
			(xy 115.831131 -240.68604) (xy 115.79301 -240.654915) (xy 115.760375 -240.618078) (xy 115.734072 -240.576482)
			(xy 115.714781 -240.531206) (xy 115.703004 -240.483422) (xy 115.699044 -240.434368) (xy 115.370102 -240.434368)
			(xy 115.369607 -240.458975) (xy 115.361712 -240.507552) (xy 115.346128 -240.554233) (xy 115.323257 -240.59781)
			(xy 115.293692 -240.637154) (xy 115.258199 -240.671246) (xy 115.217696 -240.699202) (xy 115.173234 -240.7203)
			(xy 115.125963 -240.733992) (xy 115.077108 -240.739924) (xy 115.027933 -240.737943) (xy 114.979714 -240.728099)
			(xy 114.933698 -240.710647) (xy 114.891077 -240.68604) (xy 114.852956 -240.654915) (xy 114.820321 -240.618078)
			(xy 114.794018 -240.576482) (xy 114.774727 -240.531206) (xy 114.76295 -240.483422) (xy 114.75899 -240.434368)
			(xy 114.430048 -240.434368) (xy 114.429553 -240.458975) (xy 114.421658 -240.507552) (xy 114.406074 -240.554233)
			(xy 114.383203 -240.59781) (xy 114.353638 -240.637154) (xy 114.318145 -240.671246) (xy 114.277642 -240.699202)
			(xy 114.23318 -240.7203) (xy 114.185909 -240.733992) (xy 114.137054 -240.739924) (xy 114.087879 -240.737943)
			(xy 114.03966 -240.728099) (xy 113.993644 -240.710647) (xy 113.951023 -240.68604) (xy 113.912902 -240.654915)
			(xy 113.880267 -240.618078) (xy 113.853964 -240.576482) (xy 113.834673 -240.531206) (xy 113.822896 -240.483422)
			(xy 113.818936 -240.434368) (xy 113.489994 -240.434368) (xy 113.489499 -240.458975) (xy 113.481604 -240.507552)
			(xy 113.46602 -240.554233) (xy 113.443149 -240.59781) (xy 113.413584 -240.637154) (xy 113.378091 -240.671246)
			(xy 113.337588 -240.699202) (xy 113.293126 -240.7203) (xy 113.245855 -240.733992) (xy 113.197 -240.739924)
			(xy 113.147825 -240.737943) (xy 113.099606 -240.728099) (xy 113.05359 -240.710647) (xy 113.010969 -240.68604)
			(xy 112.972848 -240.654915) (xy 112.940213 -240.618078) (xy 112.91391 -240.576482) (xy 112.894619 -240.531206)
			(xy 112.882842 -240.483422) (xy 112.878882 -240.434368) (xy 110.676436 -240.434368) (xy 110.675941 -240.458975)
			(xy 110.668046 -240.507552) (xy 110.652462 -240.554233) (xy 110.629591 -240.59781) (xy 110.600026 -240.637154)
			(xy 110.564533 -240.671246) (xy 110.52403 -240.699202) (xy 110.479568 -240.7203) (xy 110.432297 -240.733992)
			(xy 110.383442 -240.739924) (xy 110.334267 -240.737943) (xy 110.286048 -240.728099) (xy 110.240032 -240.710647)
			(xy 110.197411 -240.68604) (xy 110.15929 -240.654915) (xy 110.126655 -240.618078) (xy 110.100352 -240.576482)
			(xy 110.081061 -240.531206) (xy 110.069284 -240.483422) (xy 110.065324 -240.434368) (xy 109.736382 -240.434368)
			(xy 109.735887 -240.458975) (xy 109.727992 -240.507552) (xy 109.712408 -240.554233) (xy 109.689537 -240.59781)
			(xy 109.659972 -240.637154) (xy 109.624479 -240.671246) (xy 109.583976 -240.699202) (xy 109.539514 -240.7203)
			(xy 109.492243 -240.733992) (xy 109.443388 -240.739924) (xy 109.394213 -240.737943) (xy 109.345994 -240.728099)
			(xy 109.299978 -240.710647) (xy 109.257357 -240.68604) (xy 109.219236 -240.654915) (xy 109.186601 -240.618078)
			(xy 109.160298 -240.576482) (xy 109.141007 -240.531206) (xy 109.12923 -240.483422) (xy 109.12527 -240.434368)
			(xy 108.796328 -240.434368) (xy 108.795833 -240.458975) (xy 108.787938 -240.507552) (xy 108.772354 -240.554233)
			(xy 108.749483 -240.59781) (xy 108.719918 -240.637154) (xy 108.684425 -240.671246) (xy 108.643922 -240.699202)
			(xy 108.59946 -240.7203) (xy 108.552189 -240.733992) (xy 108.503334 -240.739924) (xy 108.454159 -240.737943)
			(xy 108.40594 -240.728099) (xy 108.359924 -240.710647) (xy 108.317303 -240.68604) (xy 108.279182 -240.654915)
			(xy 108.246547 -240.618078) (xy 108.220244 -240.576482) (xy 108.200953 -240.531206) (xy 108.189176 -240.483422)
			(xy 108.185216 -240.434368) (xy 107.856274 -240.434368) (xy 107.855779 -240.458975) (xy 107.847884 -240.507552)
			(xy 107.8323 -240.554233) (xy 107.809429 -240.59781) (xy 107.779864 -240.637154) (xy 107.744371 -240.671246)
			(xy 107.703868 -240.699202) (xy 107.659406 -240.7203) (xy 107.612135 -240.733992) (xy 107.56328 -240.739924)
			(xy 107.514105 -240.737943) (xy 107.465886 -240.728099) (xy 107.41987 -240.710647) (xy 107.377249 -240.68604)
			(xy 107.339128 -240.654915) (xy 107.306493 -240.618078) (xy 107.28019 -240.576482) (xy 107.260899 -240.531206)
			(xy 107.249122 -240.483422) (xy 107.245162 -240.434368) (xy 106.916474 -240.434368) (xy 106.915979 -240.458975)
			(xy 106.908084 -240.507552) (xy 106.8925 -240.554233) (xy 106.869629 -240.59781) (xy 106.840064 -240.637154)
			(xy 106.804571 -240.671246) (xy 106.764068 -240.699202) (xy 106.719606 -240.7203) (xy 106.672335 -240.733992)
			(xy 106.62348 -240.739924) (xy 106.574305 -240.737943) (xy 106.526086 -240.728099) (xy 106.48007 -240.710647)
			(xy 106.437449 -240.68604) (xy 106.399328 -240.654915) (xy 106.366693 -240.618078) (xy 106.34039 -240.576482)
			(xy 106.321099 -240.531206) (xy 106.309322 -240.483422) (xy 106.305362 -240.434368) (xy 105.97642 -240.434368)
			(xy 105.975925 -240.458975) (xy 105.96803 -240.507552) (xy 105.952446 -240.554233) (xy 105.929575 -240.59781)
			(xy 105.90001 -240.637154) (xy 105.864517 -240.671246) (xy 105.824014 -240.699202) (xy 105.779552 -240.7203)
			(xy 105.732281 -240.733992) (xy 105.683426 -240.739924) (xy 105.634251 -240.737943) (xy 105.586032 -240.728099)
			(xy 105.540016 -240.710647) (xy 105.497395 -240.68604) (xy 105.459274 -240.654915) (xy 105.426639 -240.618078)
			(xy 105.400336 -240.576482) (xy 105.381045 -240.531206) (xy 105.369268 -240.483422) (xy 105.365308 -240.434368)
			(xy 105.036366 -240.434368) (xy 105.035871 -240.458975) (xy 105.027976 -240.507552) (xy 105.012392 -240.554233)
			(xy 104.989521 -240.59781) (xy 104.959956 -240.637154) (xy 104.924463 -240.671246) (xy 104.88396 -240.699202)
			(xy 104.839498 -240.7203) (xy 104.792227 -240.733992) (xy 104.743372 -240.739924) (xy 104.694197 -240.737943)
			(xy 104.645978 -240.728099) (xy 104.599962 -240.710647) (xy 104.557341 -240.68604) (xy 104.51922 -240.654915)
			(xy 104.486585 -240.618078) (xy 104.460282 -240.576482) (xy 104.440991 -240.531206) (xy 104.429214 -240.483422)
			(xy 104.425254 -240.434368) (xy 104.096312 -240.434368) (xy 104.095817 -240.458975) (xy 104.087922 -240.507552)
			(xy 104.072338 -240.554233) (xy 104.049467 -240.59781) (xy 104.019902 -240.637154) (xy 103.984409 -240.671246)
			(xy 103.943906 -240.699202) (xy 103.899444 -240.7203) (xy 103.852173 -240.733992) (xy 103.803318 -240.739924)
			(xy 103.754143 -240.737943) (xy 103.705924 -240.728099) (xy 103.659908 -240.710647) (xy 103.617287 -240.68604)
			(xy 103.579166 -240.654915) (xy 103.546531 -240.618078) (xy 103.520228 -240.576482) (xy 103.500937 -240.531206)
			(xy 103.48916 -240.483422) (xy 103.4852 -240.434368) (xy 103.156258 -240.434368) (xy 103.155763 -240.458975)
			(xy 103.147868 -240.507552) (xy 103.132284 -240.554233) (xy 103.109413 -240.59781) (xy 103.079848 -240.637154)
			(xy 103.044355 -240.671246) (xy 103.003852 -240.699202) (xy 102.95939 -240.7203) (xy 102.912119 -240.733992)
			(xy 102.863264 -240.739924) (xy 102.814089 -240.737943) (xy 102.76587 -240.728099) (xy 102.719854 -240.710647)
			(xy 102.677233 -240.68604) (xy 102.639112 -240.654915) (xy 102.606477 -240.618078) (xy 102.580174 -240.576482)
			(xy 102.560883 -240.531206) (xy 102.549106 -240.483422) (xy 102.545146 -240.434368) (xy 102.216458 -240.434368)
			(xy 102.215963 -240.458975) (xy 102.208068 -240.507552) (xy 102.192484 -240.554233) (xy 102.169613 -240.59781)
			(xy 102.140048 -240.637154) (xy 102.104555 -240.671246) (xy 102.064052 -240.699202) (xy 102.01959 -240.7203)
			(xy 101.972319 -240.733992) (xy 101.923464 -240.739924) (xy 101.874289 -240.737943) (xy 101.82607 -240.728099)
			(xy 101.780054 -240.710647) (xy 101.737433 -240.68604) (xy 101.699312 -240.654915) (xy 101.666677 -240.618078)
			(xy 101.640374 -240.576482) (xy 101.621083 -240.531206) (xy 101.609306 -240.483422) (xy 101.605346 -240.434368)
			(xy 101.276404 -240.434368) (xy 101.275909 -240.458975) (xy 101.268014 -240.507552) (xy 101.25243 -240.554233)
			(xy 101.229559 -240.59781) (xy 101.199994 -240.637154) (xy 101.164501 -240.671246) (xy 101.123998 -240.699202)
			(xy 101.079536 -240.7203) (xy 101.032265 -240.733992) (xy 100.98341 -240.739924) (xy 100.934235 -240.737943)
			(xy 100.886016 -240.728099) (xy 100.84 -240.710647) (xy 100.797379 -240.68604) (xy 100.759258 -240.654915)
			(xy 100.726623 -240.618078) (xy 100.70032 -240.576482) (xy 100.681029 -240.531206) (xy 100.669252 -240.483422)
			(xy 100.665292 -240.434368) (xy 100.33635 -240.434368) (xy 100.335855 -240.458975) (xy 100.32796 -240.507552)
			(xy 100.312376 -240.554233) (xy 100.289505 -240.59781) (xy 100.25994 -240.637154) (xy 100.224447 -240.671246)
			(xy 100.183944 -240.699202) (xy 100.139482 -240.7203) (xy 100.092211 -240.733992) (xy 100.043356 -240.739924)
			(xy 99.994181 -240.737943) (xy 99.945962 -240.728099) (xy 99.899946 -240.710647) (xy 99.857325 -240.68604)
			(xy 99.819204 -240.654915) (xy 99.786569 -240.618078) (xy 99.760266 -240.576482) (xy 99.740975 -240.531206)
			(xy 99.729198 -240.483422) (xy 99.725238 -240.434368) (xy 99.396296 -240.434368) (xy 99.395801 -240.458975)
			(xy 99.387906 -240.507552) (xy 99.372322 -240.554233) (xy 99.349451 -240.59781) (xy 99.319886 -240.637154)
			(xy 99.284393 -240.671246) (xy 99.24389 -240.699202) (xy 99.199428 -240.7203) (xy 99.152157 -240.733992)
			(xy 99.103302 -240.739924) (xy 99.054127 -240.737943) (xy 99.005908 -240.728099) (xy 98.959892 -240.710647)
			(xy 98.917271 -240.68604) (xy 98.87915 -240.654915) (xy 98.846515 -240.618078) (xy 98.820212 -240.576482)
			(xy 98.800921 -240.531206) (xy 98.789144 -240.483422) (xy 98.785184 -240.434368) (xy 98.456242 -240.434368)
			(xy 98.455747 -240.458975) (xy 98.447852 -240.507552) (xy 98.432268 -240.554233) (xy 98.409397 -240.59781)
			(xy 98.379832 -240.637154) (xy 98.344339 -240.671246) (xy 98.303836 -240.699202) (xy 98.259374 -240.7203)
			(xy 98.212103 -240.733992) (xy 98.163248 -240.739924) (xy 98.114073 -240.737943) (xy 98.065854 -240.728099)
			(xy 98.019838 -240.710647) (xy 97.977217 -240.68604) (xy 97.939096 -240.654915) (xy 97.906461 -240.618078)
			(xy 97.880158 -240.576482) (xy 97.860867 -240.531206) (xy 97.84909 -240.483422) (xy 97.84513 -240.434368)
			(xy 97.51696 -240.434368) (xy 97.516963 -240.4344) (xy 97.512792 -240.48474) (xy 97.500393 -240.533707)
			(xy 97.480104 -240.579965) (xy 97.452478 -240.622254) (xy 97.418269 -240.659419) (xy 97.378409 -240.690446)
			(xy 97.333987 -240.714491) (xy 97.286213 -240.730897) (xy 97.23639 -240.739216) (xy 97.211134 -240.739676)
			(xy 97.186645 -240.739192) (xy 97.138296 -240.731372) (xy 97.091817 -240.715929) (xy 97.048402 -240.693257)
			(xy 97.028508 -240.67897) (xy 97.016824 -240.670334) (xy 96.988376 -240.667794) (xy 96.896174 -240.714022)
			(xy 96.892364 -240.716308) (xy 96.882292 -240.723382) (xy 96.869676 -240.744472) (xy 96.868234 -240.756694)
			(xy 96.868234 -240.94948) (xy 96.881696 -240.972848) (xy 96.893634 -240.979706) (xy 96.914745 -240.992422)
			(xy 96.952931 -241.023571) (xy 96.985624 -241.060446) (xy 97.011975 -241.102089) (xy 97.031302 -241.147421)
			(xy 97.043103 -241.195267) (xy 97.047071 -241.244374) (xy 97.37523 -241.244374) (xy 97.37919 -241.19532)
			(xy 97.390967 -241.147536) (xy 97.410258 -241.10226) (xy 97.436561 -241.060664) (xy 97.469196 -241.023827)
			(xy 97.507317 -240.992702) (xy 97.549938 -240.968095) (xy 97.595954 -240.950643) (xy 97.644173 -240.940799)
			(xy 97.693348 -240.938818) (xy 97.742203 -240.94475) (xy 97.789474 -240.958442) (xy 97.833936 -240.97954)
			(xy 97.874439 -241.007496) (xy 97.909932 -241.041588) (xy 97.939497 -241.080932) (xy 97.962368 -241.124509)
			(xy 97.977952 -241.17119) (xy 97.985847 -241.219767) (xy 97.986342 -241.244374) (xy 98.315284 -241.244374)
			(xy 98.319244 -241.19532) (xy 98.331021 -241.147536) (xy 98.350312 -241.10226) (xy 98.376615 -241.060664)
			(xy 98.40925 -241.023827) (xy 98.447371 -240.992702) (xy 98.489992 -240.968095) (xy 98.536008 -240.950643)
			(xy 98.584227 -240.940799) (xy 98.633402 -240.938818) (xy 98.682257 -240.94475) (xy 98.729528 -240.958442)
			(xy 98.77399 -240.97954) (xy 98.814493 -241.007496) (xy 98.849986 -241.041588) (xy 98.879551 -241.080932)
			(xy 98.902422 -241.124509) (xy 98.918006 -241.17119) (xy 98.925901 -241.219767) (xy 98.926396 -241.244374)
			(xy 99.255338 -241.244374) (xy 99.259298 -241.19532) (xy 99.271075 -241.147536) (xy 99.290366 -241.10226)
			(xy 99.316669 -241.060664) (xy 99.349304 -241.023827) (xy 99.387425 -240.992702) (xy 99.430046 -240.968095)
			(xy 99.476062 -240.950643) (xy 99.524281 -240.940799) (xy 99.573456 -240.938818) (xy 99.622311 -240.94475)
			(xy 99.669582 -240.958442) (xy 99.714044 -240.97954) (xy 99.754547 -241.007496) (xy 99.79004 -241.041588)
			(xy 99.819605 -241.080932) (xy 99.842476 -241.124509) (xy 99.85806 -241.17119) (xy 99.865955 -241.219767)
			(xy 99.86645 -241.244374) (xy 100.195138 -241.244374) (xy 100.199098 -241.19532) (xy 100.210875 -241.147536)
			(xy 100.230166 -241.10226) (xy 100.256469 -241.060664) (xy 100.289104 -241.023827) (xy 100.327225 -240.992702)
			(xy 100.369846 -240.968095) (xy 100.415862 -240.950643) (xy 100.464081 -240.940799) (xy 100.513256 -240.938818)
			(xy 100.562111 -240.94475) (xy 100.609382 -240.958442) (xy 100.653844 -240.97954) (xy 100.694347 -241.007496)
			(xy 100.72984 -241.041588) (xy 100.759405 -241.080932) (xy 100.782276 -241.124509) (xy 100.79786 -241.17119)
			(xy 100.805755 -241.219767) (xy 100.80625 -241.244374) (xy 101.135192 -241.244374) (xy 101.139152 -241.19532)
			(xy 101.150929 -241.147536) (xy 101.17022 -241.10226) (xy 101.196523 -241.060664) (xy 101.229158 -241.023827)
			(xy 101.267279 -240.992702) (xy 101.3099 -240.968095) (xy 101.355916 -240.950643) (xy 101.404135 -240.940799)
			(xy 101.45331 -240.938818) (xy 101.502165 -240.94475) (xy 101.549436 -240.958442) (xy 101.593898 -240.97954)
			(xy 101.634401 -241.007496) (xy 101.669894 -241.041588) (xy 101.699459 -241.080932) (xy 101.72233 -241.124509)
			(xy 101.737914 -241.17119) (xy 101.745809 -241.219767) (xy 101.746304 -241.244374) (xy 102.075246 -241.244374)
			(xy 102.079206 -241.19532) (xy 102.090983 -241.147536) (xy 102.110274 -241.10226) (xy 102.136577 -241.060664)
			(xy 102.169212 -241.023827) (xy 102.207333 -240.992702) (xy 102.249954 -240.968095) (xy 102.29597 -240.950643)
			(xy 102.344189 -240.940799) (xy 102.393364 -240.938818) (xy 102.442219 -240.94475) (xy 102.48949 -240.958442)
			(xy 102.533952 -240.97954) (xy 102.574455 -241.007496) (xy 102.609948 -241.041588) (xy 102.639513 -241.080932)
			(xy 102.662384 -241.124509) (xy 102.677968 -241.17119) (xy 102.685863 -241.219767) (xy 102.686358 -241.244374)
			(xy 103.0153 -241.244374) (xy 103.01926 -241.19532) (xy 103.031037 -241.147536) (xy 103.050328 -241.10226)
			(xy 103.076631 -241.060664) (xy 103.109266 -241.023827) (xy 103.147387 -240.992702) (xy 103.190008 -240.968095)
			(xy 103.236024 -240.950643) (xy 103.284243 -240.940799) (xy 103.333418 -240.938818) (xy 103.382273 -240.94475)
			(xy 103.429544 -240.958442) (xy 103.474006 -240.97954) (xy 103.514509 -241.007496) (xy 103.550002 -241.041588)
			(xy 103.579567 -241.080932) (xy 103.602438 -241.124509) (xy 103.618022 -241.17119) (xy 103.625917 -241.219767)
			(xy 103.626412 -241.244374) (xy 103.955354 -241.244374) (xy 103.959314 -241.19532) (xy 103.971091 -241.147536)
			(xy 103.990382 -241.10226) (xy 104.016685 -241.060664) (xy 104.04932 -241.023827) (xy 104.087441 -240.992702)
			(xy 104.130062 -240.968095) (xy 104.176078 -240.950643) (xy 104.224297 -240.940799) (xy 104.273472 -240.938818)
			(xy 104.322327 -240.94475) (xy 104.369598 -240.958442) (xy 104.41406 -240.97954) (xy 104.454563 -241.007496)
			(xy 104.490056 -241.041588) (xy 104.519621 -241.080932) (xy 104.542492 -241.124509) (xy 104.558076 -241.17119)
			(xy 104.565971 -241.219767) (xy 104.566466 -241.244374) (xy 104.895154 -241.244374) (xy 104.899114 -241.19532)
			(xy 104.910891 -241.147536) (xy 104.930182 -241.10226) (xy 104.956485 -241.060664) (xy 104.98912 -241.023827)
			(xy 105.027241 -240.992702) (xy 105.069862 -240.968095) (xy 105.115878 -240.950643) (xy 105.164097 -240.940799)
			(xy 105.213272 -240.938818) (xy 105.262127 -240.94475) (xy 105.309398 -240.958442) (xy 105.35386 -240.97954)
			(xy 105.394363 -241.007496) (xy 105.429856 -241.041588) (xy 105.459421 -241.080932) (xy 105.482292 -241.124509)
			(xy 105.497876 -241.17119) (xy 105.505771 -241.219767) (xy 105.506266 -241.244374) (xy 105.835208 -241.244374)
			(xy 105.839168 -241.19532) (xy 105.850945 -241.147536) (xy 105.870236 -241.10226) (xy 105.896539 -241.060664)
			(xy 105.929174 -241.023827) (xy 105.967295 -240.992702) (xy 106.009916 -240.968095) (xy 106.055932 -240.950643)
			(xy 106.104151 -240.940799) (xy 106.153326 -240.938818) (xy 106.202181 -240.94475) (xy 106.249452 -240.958442)
			(xy 106.293914 -240.97954) (xy 106.334417 -241.007496) (xy 106.36991 -241.041588) (xy 106.399475 -241.080932)
			(xy 106.422346 -241.124509) (xy 106.43793 -241.17119) (xy 106.445825 -241.219767) (xy 106.44632 -241.244374)
			(xy 106.775262 -241.244374) (xy 106.779222 -241.19532) (xy 106.790999 -241.147536) (xy 106.81029 -241.10226)
			(xy 106.836593 -241.060664) (xy 106.869228 -241.023827) (xy 106.907349 -240.992702) (xy 106.94997 -240.968095)
			(xy 106.995986 -240.950643) (xy 107.044205 -240.940799) (xy 107.09338 -240.938818) (xy 107.142235 -240.94475)
			(xy 107.189506 -240.958442) (xy 107.233968 -240.97954) (xy 107.274471 -241.007496) (xy 107.309964 -241.041588)
			(xy 107.339529 -241.080932) (xy 107.3624 -241.124509) (xy 107.377984 -241.17119) (xy 107.385879 -241.219767)
			(xy 107.386374 -241.244374) (xy 107.715316 -241.244374) (xy 107.719276 -241.19532) (xy 107.731053 -241.147536)
			(xy 107.750344 -241.10226) (xy 107.776647 -241.060664) (xy 107.809282 -241.023827) (xy 107.847403 -240.992702)
			(xy 107.890024 -240.968095) (xy 107.93604 -240.950643) (xy 107.984259 -240.940799) (xy 108.033434 -240.938818)
			(xy 108.082289 -240.94475) (xy 108.12956 -240.958442) (xy 108.174022 -240.97954) (xy 108.214525 -241.007496)
			(xy 108.250018 -241.041588) (xy 108.279583 -241.080932) (xy 108.302454 -241.124509) (xy 108.318038 -241.17119)
			(xy 108.325933 -241.219767) (xy 108.326428 -241.244374) (xy 108.65537 -241.244374) (xy 108.65933 -241.19532)
			(xy 108.671107 -241.147536) (xy 108.690398 -241.10226) (xy 108.716701 -241.060664) (xy 108.749336 -241.023827)
			(xy 108.787457 -240.992702) (xy 108.830078 -240.968095) (xy 108.876094 -240.950643) (xy 108.924313 -240.940799)
			(xy 108.973488 -240.938818) (xy 109.022343 -240.94475) (xy 109.069614 -240.958442) (xy 109.114076 -240.97954)
			(xy 109.154579 -241.007496) (xy 109.190072 -241.041588) (xy 109.219637 -241.080932) (xy 109.242508 -241.124509)
			(xy 109.258092 -241.17119) (xy 109.265987 -241.219767) (xy 109.266482 -241.244374) (xy 109.59517 -241.244374)
			(xy 109.59913 -241.19532) (xy 109.610907 -241.147536) (xy 109.630198 -241.10226) (xy 109.656501 -241.060664)
			(xy 109.689136 -241.023827) (xy 109.727257 -240.992702) (xy 109.769878 -240.968095) (xy 109.815894 -240.950643)
			(xy 109.864113 -240.940799) (xy 109.913288 -240.938818) (xy 109.962143 -240.94475) (xy 110.009414 -240.958442)
			(xy 110.053876 -240.97954) (xy 110.094379 -241.007496) (xy 110.129872 -241.041588) (xy 110.159437 -241.080932)
			(xy 110.182308 -241.124509) (xy 110.197892 -241.17119) (xy 110.205787 -241.219767) (xy 110.206282 -241.244374)
			(xy 113.349036 -241.244374) (xy 113.352996 -241.19532) (xy 113.364773 -241.147536) (xy 113.384064 -241.10226)
			(xy 113.410367 -241.060664) (xy 113.443002 -241.023827) (xy 113.481123 -240.992702) (xy 113.523744 -240.968095)
			(xy 113.56976 -240.950643) (xy 113.617979 -240.940799) (xy 113.667154 -240.938818) (xy 113.716009 -240.94475)
			(xy 113.76328 -240.958442) (xy 113.807742 -240.97954) (xy 113.848245 -241.007496) (xy 113.883738 -241.041588)
			(xy 113.913303 -241.080932) (xy 113.936174 -241.124509) (xy 113.951758 -241.17119) (xy 113.959653 -241.219767)
			(xy 113.960148 -241.244374) (xy 114.288836 -241.244374) (xy 114.292796 -241.19532) (xy 114.304573 -241.147536)
			(xy 114.323864 -241.10226) (xy 114.350167 -241.060664) (xy 114.382802 -241.023827) (xy 114.420923 -240.992702)
			(xy 114.463544 -240.968095) (xy 114.50956 -240.950643) (xy 114.557779 -240.940799) (xy 114.606954 -240.938818)
			(xy 114.655809 -240.94475) (xy 114.70308 -240.958442) (xy 114.747542 -240.97954) (xy 114.788045 -241.007496)
			(xy 114.823538 -241.041588) (xy 114.853103 -241.080932) (xy 114.875974 -241.124509) (xy 114.891558 -241.17119)
			(xy 114.899453 -241.219767) (xy 114.899948 -241.244374) (xy 115.22889 -241.244374) (xy 115.23285 -241.19532)
			(xy 115.244627 -241.147536) (xy 115.263918 -241.10226) (xy 115.290221 -241.060664) (xy 115.322856 -241.023827)
			(xy 115.360977 -240.992702) (xy 115.403598 -240.968095) (xy 115.449614 -240.950643) (xy 115.497833 -240.940799)
			(xy 115.547008 -240.938818) (xy 115.595863 -240.94475) (xy 115.643134 -240.958442) (xy 115.687596 -240.97954)
			(xy 115.728099 -241.007496) (xy 115.763592 -241.041588) (xy 115.793157 -241.080932) (xy 115.816028 -241.124509)
			(xy 115.831612 -241.17119) (xy 115.839507 -241.219767) (xy 115.840002 -241.244374) (xy 116.168944 -241.244374)
			(xy 116.172904 -241.19532) (xy 116.184681 -241.147536) (xy 116.203972 -241.10226) (xy 116.230275 -241.060664)
			(xy 116.26291 -241.023827) (xy 116.301031 -240.992702) (xy 116.343652 -240.968095) (xy 116.389668 -240.950643)
			(xy 116.437887 -240.940799) (xy 116.487062 -240.938818) (xy 116.535917 -240.94475) (xy 116.583188 -240.958442)
			(xy 116.62765 -240.97954) (xy 116.668153 -241.007496) (xy 116.703646 -241.041588) (xy 116.733211 -241.080932)
			(xy 116.756082 -241.124509) (xy 116.771666 -241.17119) (xy 116.779561 -241.219767) (xy 116.780056 -241.244374)
			(xy 117.108998 -241.244374) (xy 117.112958 -241.19532) (xy 117.124735 -241.147536) (xy 117.144026 -241.10226)
			(xy 117.170329 -241.060664) (xy 117.202964 -241.023827) (xy 117.241085 -240.992702) (xy 117.283706 -240.968095)
			(xy 117.329722 -240.950643) (xy 117.377941 -240.940799) (xy 117.427116 -240.938818) (xy 117.475971 -240.94475)
			(xy 117.523242 -240.958442) (xy 117.567704 -240.97954) (xy 117.608207 -241.007496) (xy 117.6437 -241.041588)
			(xy 117.673265 -241.080932) (xy 117.696136 -241.124509) (xy 117.71172 -241.17119) (xy 117.719615 -241.219767)
			(xy 117.72011 -241.244374) (xy 118.049052 -241.244374) (xy 118.053012 -241.19532) (xy 118.064789 -241.147536)
			(xy 118.08408 -241.10226) (xy 118.110383 -241.060664) (xy 118.143018 -241.023827) (xy 118.181139 -240.992702)
			(xy 118.22376 -240.968095) (xy 118.269776 -240.950643) (xy 118.317995 -240.940799) (xy 118.36717 -240.938818)
			(xy 118.416025 -240.94475) (xy 118.463296 -240.958442) (xy 118.507758 -240.97954) (xy 118.548261 -241.007496)
			(xy 118.583754 -241.041588) (xy 118.613319 -241.080932) (xy 118.63619 -241.124509) (xy 118.651774 -241.17119)
			(xy 118.659669 -241.219767) (xy 118.660164 -241.244374) (xy 118.988852 -241.244374) (xy 118.992812 -241.19532)
			(xy 119.004589 -241.147536) (xy 119.02388 -241.10226) (xy 119.050183 -241.060664) (xy 119.082818 -241.023827)
			(xy 119.120939 -240.992702) (xy 119.16356 -240.968095) (xy 119.209576 -240.950643) (xy 119.257795 -240.940799)
			(xy 119.30697 -240.938818) (xy 119.355825 -240.94475) (xy 119.403096 -240.958442) (xy 119.447558 -240.97954)
			(xy 119.488061 -241.007496) (xy 119.523554 -241.041588) (xy 119.553119 -241.080932) (xy 119.57599 -241.124509)
			(xy 119.591574 -241.17119) (xy 119.599469 -241.219767) (xy 119.599964 -241.244374) (xy 119.928906 -241.244374)
			(xy 119.932866 -241.19532) (xy 119.944643 -241.147536) (xy 119.963934 -241.10226) (xy 119.990237 -241.060664)
			(xy 120.022872 -241.023827) (xy 120.060993 -240.992702) (xy 120.103614 -240.968095) (xy 120.14963 -240.950643)
			(xy 120.197849 -240.940799) (xy 120.247024 -240.938818) (xy 120.295879 -240.94475) (xy 120.34315 -240.958442)
			(xy 120.387612 -240.97954) (xy 120.428115 -241.007496) (xy 120.463608 -241.041588) (xy 120.493173 -241.080932)
			(xy 120.516044 -241.124509) (xy 120.531628 -241.17119) (xy 120.539523 -241.219767) (xy 120.540018 -241.244374)
			(xy 120.86896 -241.244374) (xy 120.87292 -241.19532) (xy 120.884697 -241.147536) (xy 120.903988 -241.10226)
			(xy 120.930291 -241.060664) (xy 120.962926 -241.023827) (xy 121.001047 -240.992702) (xy 121.043668 -240.968095)
			(xy 121.089684 -240.950643) (xy 121.137903 -240.940799) (xy 121.187078 -240.938818) (xy 121.235933 -240.94475)
			(xy 121.283204 -240.958442) (xy 121.327666 -240.97954) (xy 121.368169 -241.007496) (xy 121.403662 -241.041588)
			(xy 121.433227 -241.080932) (xy 121.456098 -241.124509) (xy 121.471682 -241.17119) (xy 121.479577 -241.219767)
			(xy 121.480072 -241.244374) (xy 121.809014 -241.244374) (xy 121.812974 -241.19532) (xy 121.824751 -241.147536)
			(xy 121.844042 -241.10226) (xy 121.870345 -241.060664) (xy 121.90298 -241.023827) (xy 121.941101 -240.992702)
			(xy 121.983722 -240.968095) (xy 122.029738 -240.950643) (xy 122.077957 -240.940799) (xy 122.127132 -240.938818)
			(xy 122.175987 -240.94475) (xy 122.223258 -240.958442) (xy 122.26772 -240.97954) (xy 122.308223 -241.007496)
			(xy 122.343716 -241.041588) (xy 122.373281 -241.080932) (xy 122.396152 -241.124509) (xy 122.411736 -241.17119)
			(xy 122.419631 -241.219767) (xy 122.420126 -241.244374) (xy 122.748814 -241.244374) (xy 122.752774 -241.19532)
			(xy 122.764551 -241.147536) (xy 122.783842 -241.10226) (xy 122.810145 -241.060664) (xy 122.84278 -241.023827)
			(xy 122.880901 -240.992702) (xy 122.923522 -240.968095) (xy 122.969538 -240.950643) (xy 123.017757 -240.940799)
			(xy 123.066932 -240.938818) (xy 123.115787 -240.94475) (xy 123.163058 -240.958442) (xy 123.20752 -240.97954)
			(xy 123.248023 -241.007496) (xy 123.283516 -241.041588) (xy 123.313081 -241.080932) (xy 123.335952 -241.124509)
			(xy 123.351536 -241.17119) (xy 123.359431 -241.219767) (xy 123.359926 -241.244374) (xy 123.688868 -241.244374)
			(xy 123.692828 -241.19532) (xy 123.704605 -241.147536) (xy 123.723896 -241.10226) (xy 123.750199 -241.060664)
			(xy 123.782834 -241.023827) (xy 123.820955 -240.992702) (xy 123.863576 -240.968095) (xy 123.909592 -240.950643)
			(xy 123.957811 -240.940799) (xy 124.006986 -240.938818) (xy 124.055841 -240.94475) (xy 124.103112 -240.958442)
			(xy 124.147574 -240.97954) (xy 124.188077 -241.007496) (xy 124.22357 -241.041588) (xy 124.253135 -241.080932)
			(xy 124.276006 -241.124509) (xy 124.29159 -241.17119) (xy 124.299485 -241.219767) (xy 124.29998 -241.244374)
			(xy 124.628922 -241.244374) (xy 124.632882 -241.19532) (xy 124.644659 -241.147536) (xy 124.66395 -241.10226)
			(xy 124.690253 -241.060664) (xy 124.722888 -241.023827) (xy 124.761009 -240.992702) (xy 124.80363 -240.968095)
			(xy 124.849646 -240.950643) (xy 124.897865 -240.940799) (xy 124.94704 -240.938818) (xy 124.995895 -240.94475)
			(xy 125.043166 -240.958442) (xy 125.087628 -240.97954) (xy 125.128131 -241.007496) (xy 125.163624 -241.041588)
			(xy 125.193189 -241.080932) (xy 125.21606 -241.124509) (xy 125.231644 -241.17119) (xy 125.239539 -241.219767)
			(xy 125.240034 -241.244374) (xy 125.568976 -241.244374) (xy 125.572936 -241.19532) (xy 125.584713 -241.147536)
			(xy 125.604004 -241.10226) (xy 125.630307 -241.060664) (xy 125.662942 -241.023827) (xy 125.701063 -240.992702)
			(xy 125.743684 -240.968095) (xy 125.7897 -240.950643) (xy 125.837919 -240.940799) (xy 125.887094 -240.938818)
			(xy 125.935949 -240.94475) (xy 125.98322 -240.958442) (xy 126.027682 -240.97954) (xy 126.068185 -241.007496)
			(xy 126.103678 -241.041588) (xy 126.133243 -241.080932) (xy 126.156114 -241.124509) (xy 126.171698 -241.17119)
			(xy 126.179593 -241.219767) (xy 126.180088 -241.244374) (xy 126.50903 -241.244374) (xy 126.51299 -241.19532)
			(xy 126.524767 -241.147536) (xy 126.544058 -241.10226) (xy 126.570361 -241.060664) (xy 126.602996 -241.023827)
			(xy 126.641117 -240.992702) (xy 126.683738 -240.968095) (xy 126.729754 -240.950643) (xy 126.777973 -240.940799)
			(xy 126.827148 -240.938818) (xy 126.876003 -240.94475) (xy 126.923274 -240.958442) (xy 126.967736 -240.97954)
			(xy 127.008239 -241.007496) (xy 127.043732 -241.041588) (xy 127.073297 -241.080932) (xy 127.096168 -241.124509)
			(xy 127.111752 -241.17119) (xy 127.119647 -241.219767) (xy 127.120142 -241.244374) (xy 127.438399 -241.244374)
			(xy 127.442494 -241.193646) (xy 127.454673 -241.144232) (xy 127.474621 -241.097412) (xy 127.501822 -241.054398)
			(xy 127.53557 -241.016304) (xy 127.574992 -240.984117) (xy 127.619066 -240.958671) (xy 127.666652 -240.940624)
			(xy 127.716516 -240.930444) (xy 127.767368 -240.928395) (xy 127.817889 -240.934529) (xy 127.866773 -240.948689)
			(xy 127.912752 -240.970506) (xy 127.954636 -240.999416) (xy 127.99134 -241.034671) (xy 128.021913 -241.075357)
			(xy 128.045564 -241.12042) (xy 128.06168 -241.168694) (xy 128.069844 -241.218928) (xy 128.070356 -241.244374)
			(xy 128.388884 -241.244374) (xy 128.392844 -241.19532) (xy 128.404621 -241.147536) (xy 128.423912 -241.10226)
			(xy 128.450215 -241.060664) (xy 128.48285 -241.023827) (xy 128.520971 -240.992702) (xy 128.563592 -240.968095)
			(xy 128.609608 -240.950643) (xy 128.657827 -240.940799) (xy 128.707002 -240.938818) (xy 128.755857 -240.94475)
			(xy 128.803128 -240.958442) (xy 128.84759 -240.97954) (xy 128.888093 -241.007496) (xy 128.923586 -241.041588)
			(xy 128.953151 -241.080932) (xy 128.976022 -241.124509) (xy 128.991606 -241.17119) (xy 128.999501 -241.219767)
			(xy 128.999996 -241.244374) (xy 129.318507 -241.244374) (xy 129.322602 -241.193646) (xy 129.334781 -241.144232)
			(xy 129.354729 -241.097412) (xy 129.38193 -241.054398) (xy 129.415678 -241.016304) (xy 129.4551 -240.984117)
			(xy 129.499174 -240.958671) (xy 129.54676 -240.940624) (xy 129.596624 -240.930444) (xy 129.647476 -240.928395)
			(xy 129.697997 -240.934529) (xy 129.746881 -240.948689) (xy 129.79286 -240.970506) (xy 129.834744 -240.999416)
			(xy 129.871448 -241.034671) (xy 129.902021 -241.075357) (xy 129.925672 -241.12042) (xy 129.941788 -241.168694)
			(xy 129.949952 -241.218928) (xy 129.950464 -241.244374) (xy 129.949952 -241.26982) (xy 129.941788 -241.320054)
			(xy 129.925672 -241.368328) (xy 129.902021 -241.413391) (xy 129.871448 -241.454077) (xy 129.834744 -241.489332)
			(xy 129.79286 -241.518242) (xy 129.746881 -241.540059) (xy 129.697997 -241.554219) (xy 129.647476 -241.560353)
			(xy 129.596624 -241.558304) (xy 129.54676 -241.548124) (xy 129.499174 -241.530077) (xy 129.4551 -241.504631)
			(xy 129.415678 -241.472444) (xy 129.38193 -241.43435) (xy 129.354729 -241.391336) (xy 129.334781 -241.344516)
			(xy 129.322602 -241.295102) (xy 129.318507 -241.244374) (xy 128.999996 -241.244374) (xy 128.999501 -241.268981)
			(xy 128.991606 -241.317558) (xy 128.976022 -241.364239) (xy 128.953151 -241.407816) (xy 128.923586 -241.44716)
			(xy 128.888093 -241.481252) (xy 128.84759 -241.509208) (xy 128.803128 -241.530306) (xy 128.755857 -241.543998)
			(xy 128.707002 -241.54993) (xy 128.657827 -241.547949) (xy 128.609608 -241.538105) (xy 128.563592 -241.520653)
			(xy 128.520971 -241.496046) (xy 128.48285 -241.464921) (xy 128.450215 -241.428084) (xy 128.423912 -241.386488)
			(xy 128.404621 -241.341212) (xy 128.392844 -241.293428) (xy 128.388884 -241.244374) (xy 128.070356 -241.244374)
			(xy 128.069844 -241.26982) (xy 128.06168 -241.320054) (xy 128.045564 -241.368328) (xy 128.021913 -241.413391)
			(xy 127.99134 -241.454077) (xy 127.954636 -241.489332) (xy 127.912752 -241.518242) (xy 127.866773 -241.540059)
			(xy 127.817889 -241.554219) (xy 127.767368 -241.560353) (xy 127.716516 -241.558304) (xy 127.666652 -241.548124)
			(xy 127.619066 -241.530077) (xy 127.574992 -241.504631) (xy 127.53557 -241.472444) (xy 127.501822 -241.43435)
			(xy 127.474621 -241.391336) (xy 127.454673 -241.344516) (xy 127.442494 -241.295102) (xy 127.438399 -241.244374)
			(xy 127.120142 -241.244374) (xy 127.119647 -241.268981) (xy 127.111752 -241.317558) (xy 127.096168 -241.364239)
			(xy 127.073297 -241.407816) (xy 127.043732 -241.44716) (xy 127.008239 -241.481252) (xy 126.967736 -241.509208)
			(xy 126.923274 -241.530306) (xy 126.876003 -241.543998) (xy 126.827148 -241.54993) (xy 126.777973 -241.547949)
			(xy 126.729754 -241.538105) (xy 126.683738 -241.520653) (xy 126.641117 -241.496046) (xy 126.602996 -241.464921)
			(xy 126.570361 -241.428084) (xy 126.544058 -241.386488) (xy 126.524767 -241.341212) (xy 126.51299 -241.293428)
			(xy 126.50903 -241.244374) (xy 126.180088 -241.244374) (xy 126.179593 -241.268981) (xy 126.171698 -241.317558)
			(xy 126.156114 -241.364239) (xy 126.133243 -241.407816) (xy 126.103678 -241.44716) (xy 126.068185 -241.481252)
			(xy 126.027682 -241.509208) (xy 125.98322 -241.530306) (xy 125.935949 -241.543998) (xy 125.887094 -241.54993)
			(xy 125.837919 -241.547949) (xy 125.7897 -241.538105) (xy 125.743684 -241.520653) (xy 125.701063 -241.496046)
			(xy 125.662942 -241.464921) (xy 125.630307 -241.428084) (xy 125.604004 -241.386488) (xy 125.584713 -241.341212)
			(xy 125.572936 -241.293428) (xy 125.568976 -241.244374) (xy 125.240034 -241.244374) (xy 125.239539 -241.268981)
			(xy 125.231644 -241.317558) (xy 125.21606 -241.364239) (xy 125.193189 -241.407816) (xy 125.163624 -241.44716)
			(xy 125.128131 -241.481252) (xy 125.087628 -241.509208) (xy 125.043166 -241.530306) (xy 124.995895 -241.543998)
			(xy 124.94704 -241.54993) (xy 124.897865 -241.547949) (xy 124.849646 -241.538105) (xy 124.80363 -241.520653)
			(xy 124.761009 -241.496046) (xy 124.722888 -241.464921) (xy 124.690253 -241.428084) (xy 124.66395 -241.386488)
			(xy 124.644659 -241.341212) (xy 124.632882 -241.293428) (xy 124.628922 -241.244374) (xy 124.29998 -241.244374)
			(xy 124.299485 -241.268981) (xy 124.29159 -241.317558) (xy 124.276006 -241.364239) (xy 124.253135 -241.407816)
			(xy 124.22357 -241.44716) (xy 124.188077 -241.481252) (xy 124.147574 -241.509208) (xy 124.103112 -241.530306)
			(xy 124.055841 -241.543998) (xy 124.006986 -241.54993) (xy 123.957811 -241.547949) (xy 123.909592 -241.538105)
			(xy 123.863576 -241.520653) (xy 123.820955 -241.496046) (xy 123.782834 -241.464921) (xy 123.750199 -241.428084)
			(xy 123.723896 -241.386488) (xy 123.704605 -241.341212) (xy 123.692828 -241.293428) (xy 123.688868 -241.244374)
			(xy 123.359926 -241.244374) (xy 123.359431 -241.268981) (xy 123.351536 -241.317558) (xy 123.335952 -241.364239)
			(xy 123.313081 -241.407816) (xy 123.283516 -241.44716) (xy 123.248023 -241.481252) (xy 123.20752 -241.509208)
			(xy 123.163058 -241.530306) (xy 123.115787 -241.543998) (xy 123.066932 -241.54993) (xy 123.017757 -241.547949)
			(xy 122.969538 -241.538105) (xy 122.923522 -241.520653) (xy 122.880901 -241.496046) (xy 122.84278 -241.464921)
			(xy 122.810145 -241.428084) (xy 122.783842 -241.386488) (xy 122.764551 -241.341212) (xy 122.752774 -241.293428)
			(xy 122.748814 -241.244374) (xy 122.420126 -241.244374) (xy 122.419631 -241.268981) (xy 122.411736 -241.317558)
			(xy 122.396152 -241.364239) (xy 122.373281 -241.407816) (xy 122.343716 -241.44716) (xy 122.308223 -241.481252)
			(xy 122.26772 -241.509208) (xy 122.223258 -241.530306) (xy 122.175987 -241.543998) (xy 122.127132 -241.54993)
			(xy 122.077957 -241.547949) (xy 122.029738 -241.538105) (xy 121.983722 -241.520653) (xy 121.941101 -241.496046)
			(xy 121.90298 -241.464921) (xy 121.870345 -241.428084) (xy 121.844042 -241.386488) (xy 121.824751 -241.341212)
			(xy 121.812974 -241.293428) (xy 121.809014 -241.244374) (xy 121.480072 -241.244374) (xy 121.479577 -241.268981)
			(xy 121.471682 -241.317558) (xy 121.456098 -241.364239) (xy 121.433227 -241.407816) (xy 121.403662 -241.44716)
			(xy 121.368169 -241.481252) (xy 121.327666 -241.509208) (xy 121.283204 -241.530306) (xy 121.235933 -241.543998)
			(xy 121.187078 -241.54993) (xy 121.137903 -241.547949) (xy 121.089684 -241.538105) (xy 121.043668 -241.520653)
			(xy 121.001047 -241.496046) (xy 120.962926 -241.464921) (xy 120.930291 -241.428084) (xy 120.903988 -241.386488)
			(xy 120.884697 -241.341212) (xy 120.87292 -241.293428) (xy 120.86896 -241.244374) (xy 120.540018 -241.244374)
			(xy 120.539523 -241.268981) (xy 120.531628 -241.317558) (xy 120.516044 -241.364239) (xy 120.493173 -241.407816)
			(xy 120.463608 -241.44716) (xy 120.428115 -241.481252) (xy 120.387612 -241.509208) (xy 120.34315 -241.530306)
			(xy 120.295879 -241.543998) (xy 120.247024 -241.54993) (xy 120.197849 -241.547949) (xy 120.14963 -241.538105)
			(xy 120.103614 -241.520653) (xy 120.060993 -241.496046) (xy 120.022872 -241.464921) (xy 119.990237 -241.428084)
			(xy 119.963934 -241.386488) (xy 119.944643 -241.341212) (xy 119.932866 -241.293428) (xy 119.928906 -241.244374)
			(xy 119.599964 -241.244374) (xy 119.599469 -241.268981) (xy 119.591574 -241.317558) (xy 119.57599 -241.364239)
			(xy 119.553119 -241.407816) (xy 119.523554 -241.44716) (xy 119.488061 -241.481252) (xy 119.447558 -241.509208)
			(xy 119.403096 -241.530306) (xy 119.355825 -241.543998) (xy 119.30697 -241.54993) (xy 119.257795 -241.547949)
			(xy 119.209576 -241.538105) (xy 119.16356 -241.520653) (xy 119.120939 -241.496046) (xy 119.082818 -241.464921)
			(xy 119.050183 -241.428084) (xy 119.02388 -241.386488) (xy 119.004589 -241.341212) (xy 118.992812 -241.293428)
			(xy 118.988852 -241.244374) (xy 118.660164 -241.244374) (xy 118.659669 -241.268981) (xy 118.651774 -241.317558)
			(xy 118.63619 -241.364239) (xy 118.613319 -241.407816) (xy 118.583754 -241.44716) (xy 118.548261 -241.481252)
			(xy 118.507758 -241.509208) (xy 118.463296 -241.530306) (xy 118.416025 -241.543998) (xy 118.36717 -241.54993)
			(xy 118.317995 -241.547949) (xy 118.269776 -241.538105) (xy 118.22376 -241.520653) (xy 118.181139 -241.496046)
			(xy 118.143018 -241.464921) (xy 118.110383 -241.428084) (xy 118.08408 -241.386488) (xy 118.064789 -241.341212)
			(xy 118.053012 -241.293428) (xy 118.049052 -241.244374) (xy 117.72011 -241.244374) (xy 117.719615 -241.268981)
			(xy 117.71172 -241.317558) (xy 117.696136 -241.364239) (xy 117.673265 -241.407816) (xy 117.6437 -241.44716)
			(xy 117.608207 -241.481252) (xy 117.567704 -241.509208) (xy 117.523242 -241.530306) (xy 117.475971 -241.543998)
			(xy 117.427116 -241.54993) (xy 117.377941 -241.547949) (xy 117.329722 -241.538105) (xy 117.283706 -241.520653)
			(xy 117.241085 -241.496046) (xy 117.202964 -241.464921) (xy 117.170329 -241.428084) (xy 117.144026 -241.386488)
			(xy 117.124735 -241.341212) (xy 117.112958 -241.293428) (xy 117.108998 -241.244374) (xy 116.780056 -241.244374)
			(xy 116.779561 -241.268981) (xy 116.771666 -241.317558) (xy 116.756082 -241.364239) (xy 116.733211 -241.407816)
			(xy 116.703646 -241.44716) (xy 116.668153 -241.481252) (xy 116.62765 -241.509208) (xy 116.583188 -241.530306)
			(xy 116.535917 -241.543998) (xy 116.487062 -241.54993) (xy 116.437887 -241.547949) (xy 116.389668 -241.538105)
			(xy 116.343652 -241.520653) (xy 116.301031 -241.496046) (xy 116.26291 -241.464921) (xy 116.230275 -241.428084)
			(xy 116.203972 -241.386488) (xy 116.184681 -241.341212) (xy 116.172904 -241.293428) (xy 116.168944 -241.244374)
			(xy 115.840002 -241.244374) (xy 115.839507 -241.268981) (xy 115.831612 -241.317558) (xy 115.816028 -241.364239)
			(xy 115.793157 -241.407816) (xy 115.763592 -241.44716) (xy 115.728099 -241.481252) (xy 115.687596 -241.509208)
			(xy 115.643134 -241.530306) (xy 115.595863 -241.543998) (xy 115.547008 -241.54993) (xy 115.497833 -241.547949)
			(xy 115.449614 -241.538105) (xy 115.403598 -241.520653) (xy 115.360977 -241.496046) (xy 115.322856 -241.464921)
			(xy 115.290221 -241.428084) (xy 115.263918 -241.386488) (xy 115.244627 -241.341212) (xy 115.23285 -241.293428)
			(xy 115.22889 -241.244374) (xy 114.899948 -241.244374) (xy 114.899453 -241.268981) (xy 114.891558 -241.317558)
			(xy 114.875974 -241.364239) (xy 114.853103 -241.407816) (xy 114.823538 -241.44716) (xy 114.788045 -241.481252)
			(xy 114.747542 -241.509208) (xy 114.70308 -241.530306) (xy 114.655809 -241.543998) (xy 114.606954 -241.54993)
			(xy 114.557779 -241.547949) (xy 114.50956 -241.538105) (xy 114.463544 -241.520653) (xy 114.420923 -241.496046)
			(xy 114.382802 -241.464921) (xy 114.350167 -241.428084) (xy 114.323864 -241.386488) (xy 114.304573 -241.341212)
			(xy 114.292796 -241.293428) (xy 114.288836 -241.244374) (xy 113.960148 -241.244374) (xy 113.959653 -241.268981)
			(xy 113.951758 -241.317558) (xy 113.936174 -241.364239) (xy 113.913303 -241.407816) (xy 113.883738 -241.44716)
			(xy 113.848245 -241.481252) (xy 113.807742 -241.509208) (xy 113.76328 -241.530306) (xy 113.716009 -241.543998)
			(xy 113.667154 -241.54993) (xy 113.617979 -241.547949) (xy 113.56976 -241.538105) (xy 113.523744 -241.520653)
			(xy 113.481123 -241.496046) (xy 113.443002 -241.464921) (xy 113.410367 -241.428084) (xy 113.384064 -241.386488)
			(xy 113.364773 -241.341212) (xy 113.352996 -241.293428) (xy 113.349036 -241.244374) (xy 110.206282 -241.244374)
			(xy 110.205787 -241.268981) (xy 110.197892 -241.317558) (xy 110.182308 -241.364239) (xy 110.159437 -241.407816)
			(xy 110.129872 -241.44716) (xy 110.094379 -241.481252) (xy 110.053876 -241.509208) (xy 110.009414 -241.530306)
			(xy 109.962143 -241.543998) (xy 109.913288 -241.54993) (xy 109.864113 -241.547949) (xy 109.815894 -241.538105)
			(xy 109.769878 -241.520653) (xy 109.727257 -241.496046) (xy 109.689136 -241.464921) (xy 109.656501 -241.428084)
			(xy 109.630198 -241.386488) (xy 109.610907 -241.341212) (xy 109.59913 -241.293428) (xy 109.59517 -241.244374)
			(xy 109.266482 -241.244374) (xy 109.265987 -241.268981) (xy 109.258092 -241.317558) (xy 109.242508 -241.364239)
			(xy 109.219637 -241.407816) (xy 109.190072 -241.44716) (xy 109.154579 -241.481252) (xy 109.114076 -241.509208)
			(xy 109.069614 -241.530306) (xy 109.022343 -241.543998) (xy 108.973488 -241.54993) (xy 108.924313 -241.547949)
			(xy 108.876094 -241.538105) (xy 108.830078 -241.520653) (xy 108.787457 -241.496046) (xy 108.749336 -241.464921)
			(xy 108.716701 -241.428084) (xy 108.690398 -241.386488) (xy 108.671107 -241.341212) (xy 108.65933 -241.293428)
			(xy 108.65537 -241.244374) (xy 108.326428 -241.244374) (xy 108.325933 -241.268981) (xy 108.318038 -241.317558)
			(xy 108.302454 -241.364239) (xy 108.279583 -241.407816) (xy 108.250018 -241.44716) (xy 108.214525 -241.481252)
			(xy 108.174022 -241.509208) (xy 108.12956 -241.530306) (xy 108.082289 -241.543998) (xy 108.033434 -241.54993)
			(xy 107.984259 -241.547949) (xy 107.93604 -241.538105) (xy 107.890024 -241.520653) (xy 107.847403 -241.496046)
			(xy 107.809282 -241.464921) (xy 107.776647 -241.428084) (xy 107.750344 -241.386488) (xy 107.731053 -241.341212)
			(xy 107.719276 -241.293428) (xy 107.715316 -241.244374) (xy 107.386374 -241.244374) (xy 107.385879 -241.268981)
			(xy 107.377984 -241.317558) (xy 107.3624 -241.364239) (xy 107.339529 -241.407816) (xy 107.309964 -241.44716)
			(xy 107.274471 -241.481252) (xy 107.233968 -241.509208) (xy 107.189506 -241.530306) (xy 107.142235 -241.543998)
			(xy 107.09338 -241.54993) (xy 107.044205 -241.547949) (xy 106.995986 -241.538105) (xy 106.94997 -241.520653)
			(xy 106.907349 -241.496046) (xy 106.869228 -241.464921) (xy 106.836593 -241.428084) (xy 106.81029 -241.386488)
			(xy 106.790999 -241.341212) (xy 106.779222 -241.293428) (xy 106.775262 -241.244374) (xy 106.44632 -241.244374)
			(xy 106.445825 -241.268981) (xy 106.43793 -241.317558) (xy 106.422346 -241.364239) (xy 106.399475 -241.407816)
			(xy 106.36991 -241.44716) (xy 106.334417 -241.481252) (xy 106.293914 -241.509208) (xy 106.249452 -241.530306)
			(xy 106.202181 -241.543998) (xy 106.153326 -241.54993) (xy 106.104151 -241.547949) (xy 106.055932 -241.538105)
			(xy 106.009916 -241.520653) (xy 105.967295 -241.496046) (xy 105.929174 -241.464921) (xy 105.896539 -241.428084)
			(xy 105.870236 -241.386488) (xy 105.850945 -241.341212) (xy 105.839168 -241.293428) (xy 105.835208 -241.244374)
			(xy 105.506266 -241.244374) (xy 105.505771 -241.268981) (xy 105.497876 -241.317558) (xy 105.482292 -241.364239)
			(xy 105.459421 -241.407816) (xy 105.429856 -241.44716) (xy 105.394363 -241.481252) (xy 105.35386 -241.509208)
			(xy 105.309398 -241.530306) (xy 105.262127 -241.543998) (xy 105.213272 -241.54993) (xy 105.164097 -241.547949)
			(xy 105.115878 -241.538105) (xy 105.069862 -241.520653) (xy 105.027241 -241.496046) (xy 104.98912 -241.464921)
			(xy 104.956485 -241.428084) (xy 104.930182 -241.386488) (xy 104.910891 -241.341212) (xy 104.899114 -241.293428)
			(xy 104.895154 -241.244374) (xy 104.566466 -241.244374) (xy 104.565971 -241.268981) (xy 104.558076 -241.317558)
			(xy 104.542492 -241.364239) (xy 104.519621 -241.407816) (xy 104.490056 -241.44716) (xy 104.454563 -241.481252)
			(xy 104.41406 -241.509208) (xy 104.369598 -241.530306) (xy 104.322327 -241.543998) (xy 104.273472 -241.54993)
			(xy 104.224297 -241.547949) (xy 104.176078 -241.538105) (xy 104.130062 -241.520653) (xy 104.087441 -241.496046)
			(xy 104.04932 -241.464921) (xy 104.016685 -241.428084) (xy 103.990382 -241.386488) (xy 103.971091 -241.341212)
			(xy 103.959314 -241.293428) (xy 103.955354 -241.244374) (xy 103.626412 -241.244374) (xy 103.625917 -241.268981)
			(xy 103.618022 -241.317558) (xy 103.602438 -241.364239) (xy 103.579567 -241.407816) (xy 103.550002 -241.44716)
			(xy 103.514509 -241.481252) (xy 103.474006 -241.509208) (xy 103.429544 -241.530306) (xy 103.382273 -241.543998)
			(xy 103.333418 -241.54993) (xy 103.284243 -241.547949) (xy 103.236024 -241.538105) (xy 103.190008 -241.520653)
			(xy 103.147387 -241.496046) (xy 103.109266 -241.464921) (xy 103.076631 -241.428084) (xy 103.050328 -241.386488)
			(xy 103.031037 -241.341212) (xy 103.01926 -241.293428) (xy 103.0153 -241.244374) (xy 102.686358 -241.244374)
			(xy 102.685863 -241.268981) (xy 102.677968 -241.317558) (xy 102.662384 -241.364239) (xy 102.639513 -241.407816)
			(xy 102.609948 -241.44716) (xy 102.574455 -241.481252) (xy 102.533952 -241.509208) (xy 102.48949 -241.530306)
			(xy 102.442219 -241.543998) (xy 102.393364 -241.54993) (xy 102.344189 -241.547949) (xy 102.29597 -241.538105)
			(xy 102.249954 -241.520653) (xy 102.207333 -241.496046) (xy 102.169212 -241.464921) (xy 102.136577 -241.428084)
			(xy 102.110274 -241.386488) (xy 102.090983 -241.341212) (xy 102.079206 -241.293428) (xy 102.075246 -241.244374)
			(xy 101.746304 -241.244374) (xy 101.745809 -241.268981) (xy 101.737914 -241.317558) (xy 101.72233 -241.364239)
			(xy 101.699459 -241.407816) (xy 101.669894 -241.44716) (xy 101.634401 -241.481252) (xy 101.593898 -241.509208)
			(xy 101.549436 -241.530306) (xy 101.502165 -241.543998) (xy 101.45331 -241.54993) (xy 101.404135 -241.547949)
			(xy 101.355916 -241.538105) (xy 101.3099 -241.520653) (xy 101.267279 -241.496046) (xy 101.229158 -241.464921)
			(xy 101.196523 -241.428084) (xy 101.17022 -241.386488) (xy 101.150929 -241.341212) (xy 101.139152 -241.293428)
			(xy 101.135192 -241.244374) (xy 100.80625 -241.244374) (xy 100.805755 -241.268981) (xy 100.79786 -241.317558)
			(xy 100.782276 -241.364239) (xy 100.759405 -241.407816) (xy 100.72984 -241.44716) (xy 100.694347 -241.481252)
			(xy 100.653844 -241.509208) (xy 100.609382 -241.530306) (xy 100.562111 -241.543998) (xy 100.513256 -241.54993)
			(xy 100.464081 -241.547949) (xy 100.415862 -241.538105) (xy 100.369846 -241.520653) (xy 100.327225 -241.496046)
			(xy 100.289104 -241.464921) (xy 100.256469 -241.428084) (xy 100.230166 -241.386488) (xy 100.210875 -241.341212)
			(xy 100.199098 -241.293428) (xy 100.195138 -241.244374) (xy 99.86645 -241.244374) (xy 99.865955 -241.268981)
			(xy 99.85806 -241.317558) (xy 99.842476 -241.364239) (xy 99.819605 -241.407816) (xy 99.79004 -241.44716)
			(xy 99.754547 -241.481252) (xy 99.714044 -241.509208) (xy 99.669582 -241.530306) (xy 99.622311 -241.543998)
			(xy 99.573456 -241.54993) (xy 99.524281 -241.547949) (xy 99.476062 -241.538105) (xy 99.430046 -241.520653)
			(xy 99.387425 -241.496046) (xy 99.349304 -241.464921) (xy 99.316669 -241.428084) (xy 99.290366 -241.386488)
			(xy 99.271075 -241.341212) (xy 99.259298 -241.293428) (xy 99.255338 -241.244374) (xy 98.926396 -241.244374)
			(xy 98.925901 -241.268981) (xy 98.918006 -241.317558) (xy 98.902422 -241.364239) (xy 98.879551 -241.407816)
			(xy 98.849986 -241.44716) (xy 98.814493 -241.481252) (xy 98.77399 -241.509208) (xy 98.729528 -241.530306)
			(xy 98.682257 -241.543998) (xy 98.633402 -241.54993) (xy 98.584227 -241.547949) (xy 98.536008 -241.538105)
			(xy 98.489992 -241.520653) (xy 98.447371 -241.496046) (xy 98.40925 -241.464921) (xy 98.376615 -241.428084)
			(xy 98.350312 -241.386488) (xy 98.331021 -241.341212) (xy 98.319244 -241.293428) (xy 98.315284 -241.244374)
			(xy 97.986342 -241.244374) (xy 97.985847 -241.268981) (xy 97.977952 -241.317558) (xy 97.962368 -241.364239)
			(xy 97.939497 -241.407816) (xy 97.909932 -241.44716) (xy 97.874439 -241.481252) (xy 97.833936 -241.509208)
			(xy 97.789474 -241.530306) (xy 97.742203 -241.543998) (xy 97.693348 -241.54993) (xy 97.644173 -241.547949)
			(xy 97.595954 -241.538105) (xy 97.549938 -241.520653) (xy 97.507317 -241.496046) (xy 97.469196 -241.464921)
			(xy 97.436561 -241.428084) (xy 97.410258 -241.386488) (xy 97.390967 -241.341212) (xy 97.37919 -241.293428)
			(xy 97.37523 -241.244374) (xy 97.047071 -241.244374) (xy 97.047072 -241.244387) (xy 97.043107 -241.293507)
			(xy 97.03131 -241.341355) (xy 97.011988 -241.386688) (xy 96.98564 -241.428334) (xy 96.95295 -241.465211)
			(xy 96.914766 -241.496363) (xy 96.893634 -241.509042) (xy 96.881696 -241.5159) (xy 96.868234 -241.539268)
			(xy 96.868234 -242.05438) (xy 98.785184 -242.05438) (xy 98.789144 -242.005326) (xy 98.800921 -241.957542)
			(xy 98.820212 -241.912266) (xy 98.846515 -241.87067) (xy 98.87915 -241.833833) (xy 98.917271 -241.802708)
			(xy 98.959892 -241.778101) (xy 99.005908 -241.760649) (xy 99.054127 -241.750805) (xy 99.103302 -241.748824)
			(xy 99.152157 -241.754756) (xy 99.199428 -241.768448) (xy 99.24389 -241.789546) (xy 99.284393 -241.817502)
			(xy 99.319886 -241.851594) (xy 99.349451 -241.890938) (xy 99.372322 -241.934515) (xy 99.387906 -241.981196)
			(xy 99.395801 -242.029773) (xy 99.396296 -242.05438) (xy 101.605346 -242.05438) (xy 101.609306 -242.005326)
			(xy 101.621083 -241.957542) (xy 101.640374 -241.912266) (xy 101.666677 -241.87067) (xy 101.699312 -241.833833)
			(xy 101.737433 -241.802708) (xy 101.780054 -241.778101) (xy 101.82607 -241.760649) (xy 101.874289 -241.750805)
			(xy 101.923464 -241.748824) (xy 101.972319 -241.754756) (xy 102.01959 -241.768448) (xy 102.064052 -241.789546)
			(xy 102.104555 -241.817502) (xy 102.140048 -241.851594) (xy 102.169613 -241.890938) (xy 102.192484 -241.934515)
			(xy 102.208068 -241.981196) (xy 102.215963 -242.029773) (xy 102.216458 -242.05438) (xy 104.425254 -242.05438)
			(xy 104.429214 -242.005326) (xy 104.440991 -241.957542) (xy 104.460282 -241.912266) (xy 104.486585 -241.87067)
			(xy 104.51922 -241.833833) (xy 104.557341 -241.802708) (xy 104.599962 -241.778101) (xy 104.645978 -241.760649)
			(xy 104.694197 -241.750805) (xy 104.743372 -241.748824) (xy 104.792227 -241.754756) (xy 104.839498 -241.768448)
			(xy 104.88396 -241.789546) (xy 104.924463 -241.817502) (xy 104.959956 -241.851594) (xy 104.989521 -241.890938)
			(xy 105.012392 -241.934515) (xy 105.027976 -241.981196) (xy 105.035871 -242.029773) (xy 105.036366 -242.05438)
			(xy 107.245162 -242.05438) (xy 107.249122 -242.005326) (xy 107.260899 -241.957542) (xy 107.28019 -241.912266)
			(xy 107.306493 -241.87067) (xy 107.339128 -241.833833) (xy 107.377249 -241.802708) (xy 107.41987 -241.778101)
			(xy 107.465886 -241.760649) (xy 107.514105 -241.750805) (xy 107.56328 -241.748824) (xy 107.612135 -241.754756)
			(xy 107.659406 -241.768448) (xy 107.703868 -241.789546) (xy 107.744371 -241.817502) (xy 107.779864 -241.851594)
			(xy 107.809429 -241.890938) (xy 107.8323 -241.934515) (xy 107.847884 -241.981196) (xy 107.855779 -242.029773)
			(xy 107.856274 -242.05438) (xy 108.185216 -242.05438) (xy 108.189176 -242.005326) (xy 108.200953 -241.957542)
			(xy 108.220244 -241.912266) (xy 108.246547 -241.87067) (xy 108.279182 -241.833833) (xy 108.317303 -241.802708)
			(xy 108.359924 -241.778101) (xy 108.40594 -241.760649) (xy 108.454159 -241.750805) (xy 108.503334 -241.748824)
			(xy 108.552189 -241.754756) (xy 108.59946 -241.768448) (xy 108.643922 -241.789546) (xy 108.684425 -241.817502)
			(xy 108.719918 -241.851594) (xy 108.749483 -241.890938) (xy 108.772354 -241.934515) (xy 108.787938 -241.981196)
			(xy 108.795833 -242.029773) (xy 108.796328 -242.05438) (xy 109.12527 -242.05438) (xy 109.12923 -242.005326)
			(xy 109.141007 -241.957542) (xy 109.160298 -241.912266) (xy 109.186601 -241.87067) (xy 109.219236 -241.833833)
			(xy 109.257357 -241.802708) (xy 109.299978 -241.778101) (xy 109.345994 -241.760649) (xy 109.394213 -241.750805)
			(xy 109.443388 -241.748824) (xy 109.492243 -241.754756) (xy 109.539514 -241.768448) (xy 109.583976 -241.789546)
			(xy 109.624479 -241.817502) (xy 109.659972 -241.851594) (xy 109.689537 -241.890938) (xy 109.712408 -241.934515)
			(xy 109.727992 -241.981196) (xy 109.735887 -242.029773) (xy 109.736382 -242.05438) (xy 110.065324 -242.05438)
			(xy 110.069284 -242.005326) (xy 110.081061 -241.957542) (xy 110.100352 -241.912266) (xy 110.126655 -241.87067)
			(xy 110.15929 -241.833833) (xy 110.197411 -241.802708) (xy 110.240032 -241.778101) (xy 110.286048 -241.760649)
			(xy 110.334267 -241.750805) (xy 110.383442 -241.748824) (xy 110.432297 -241.754756) (xy 110.479568 -241.768448)
			(xy 110.52403 -241.789546) (xy 110.564533 -241.817502) (xy 110.600026 -241.851594) (xy 110.629591 -241.890938)
			(xy 110.652462 -241.934515) (xy 110.668046 -241.981196) (xy 110.675941 -242.029773) (xy 110.676436 -242.05438)
			(xy 112.878882 -242.05438) (xy 112.882842 -242.005326) (xy 112.894619 -241.957542) (xy 112.91391 -241.912266)
			(xy 112.940213 -241.87067) (xy 112.972848 -241.833833) (xy 113.010969 -241.802708) (xy 113.05359 -241.778101)
			(xy 113.099606 -241.760649) (xy 113.147825 -241.750805) (xy 113.197 -241.748824) (xy 113.245855 -241.754756)
			(xy 113.293126 -241.768448) (xy 113.337588 -241.789546) (xy 113.378091 -241.817502) (xy 113.413584 -241.851594)
			(xy 113.443149 -241.890938) (xy 113.46602 -241.934515) (xy 113.481604 -241.981196) (xy 113.489499 -242.029773)
			(xy 113.489994 -242.05438) (xy 113.818936 -242.05438) (xy 113.822896 -242.005326) (xy 113.834673 -241.957542)
			(xy 113.853964 -241.912266) (xy 113.880267 -241.87067) (xy 113.912902 -241.833833) (xy 113.951023 -241.802708)
			(xy 113.993644 -241.778101) (xy 114.03966 -241.760649) (xy 114.087879 -241.750805) (xy 114.137054 -241.748824)
			(xy 114.185909 -241.754756) (xy 114.23318 -241.768448) (xy 114.277642 -241.789546) (xy 114.318145 -241.817502)
			(xy 114.353638 -241.851594) (xy 114.383203 -241.890938) (xy 114.406074 -241.934515) (xy 114.421658 -241.981196)
			(xy 114.429553 -242.029773) (xy 114.430048 -242.05438) (xy 114.75899 -242.05438) (xy 114.76295 -242.005326)
			(xy 114.774727 -241.957542) (xy 114.794018 -241.912266) (xy 114.820321 -241.87067) (xy 114.852956 -241.833833)
			(xy 114.891077 -241.802708) (xy 114.933698 -241.778101) (xy 114.979714 -241.760649) (xy 115.027933 -241.750805)
			(xy 115.077108 -241.748824) (xy 115.125963 -241.754756) (xy 115.173234 -241.768448) (xy 115.217696 -241.789546)
			(xy 115.258199 -241.817502) (xy 115.293692 -241.851594) (xy 115.323257 -241.890938) (xy 115.346128 -241.934515)
			(xy 115.361712 -241.981196) (xy 115.369607 -242.029773) (xy 115.370102 -242.05438) (xy 115.699044 -242.05438)
			(xy 115.703004 -242.005326) (xy 115.714781 -241.957542) (xy 115.734072 -241.912266) (xy 115.760375 -241.87067)
			(xy 115.79301 -241.833833) (xy 115.831131 -241.802708) (xy 115.873752 -241.778101) (xy 115.919768 -241.760649)
			(xy 115.967987 -241.750805) (xy 116.017162 -241.748824) (xy 116.066017 -241.754756) (xy 116.113288 -241.768448)
			(xy 116.15775 -241.789546) (xy 116.198253 -241.817502) (xy 116.233746 -241.851594) (xy 116.263311 -241.890938)
			(xy 116.286182 -241.934515) (xy 116.301766 -241.981196) (xy 116.309661 -242.029773) (xy 116.310156 -242.05438)
			(xy 118.518952 -242.05438) (xy 118.522912 -242.005326) (xy 118.534689 -241.957542) (xy 118.55398 -241.912266)
			(xy 118.580283 -241.87067) (xy 118.612918 -241.833833) (xy 118.651039 -241.802708) (xy 118.69366 -241.778101)
			(xy 118.739676 -241.760649) (xy 118.787895 -241.750805) (xy 118.83707 -241.748824) (xy 118.885925 -241.754756)
			(xy 118.933196 -241.768448) (xy 118.977658 -241.789546) (xy 119.018161 -241.817502) (xy 119.053654 -241.851594)
			(xy 119.083219 -241.890938) (xy 119.10609 -241.934515) (xy 119.121674 -241.981196) (xy 119.129569 -242.029773)
			(xy 119.130064 -242.05438) (xy 121.33886 -242.05438) (xy 121.34282 -242.005326) (xy 121.354597 -241.957542)
			(xy 121.373888 -241.912266) (xy 121.400191 -241.87067) (xy 121.432826 -241.833833) (xy 121.470947 -241.802708)
			(xy 121.513568 -241.778101) (xy 121.559584 -241.760649) (xy 121.607803 -241.750805) (xy 121.656978 -241.748824)
			(xy 121.705833 -241.754756) (xy 121.753104 -241.768448) (xy 121.797566 -241.789546) (xy 121.838069 -241.817502)
			(xy 121.873562 -241.851594) (xy 121.903127 -241.890938) (xy 121.925998 -241.934515) (xy 121.941582 -241.981196)
			(xy 121.949477 -242.029773) (xy 121.949972 -242.05438) (xy 124.159022 -242.05438) (xy 124.162982 -242.005326)
			(xy 124.174759 -241.957542) (xy 124.19405 -241.912266) (xy 124.220353 -241.87067) (xy 124.252988 -241.833833)
			(xy 124.291109 -241.802708) (xy 124.33373 -241.778101) (xy 124.379746 -241.760649) (xy 124.427965 -241.750805)
			(xy 124.47714 -241.748824) (xy 124.525995 -241.754756) (xy 124.573266 -241.768448) (xy 124.617728 -241.789546)
			(xy 124.658231 -241.817502) (xy 124.693724 -241.851594) (xy 124.723289 -241.890938) (xy 124.74616 -241.934515)
			(xy 124.761744 -241.981196) (xy 124.769639 -242.029773) (xy 124.770134 -242.05438) (xy 126.97893 -242.05438)
			(xy 126.98289 -242.005326) (xy 126.994667 -241.957542) (xy 127.013958 -241.912266) (xy 127.040261 -241.87067)
			(xy 127.072896 -241.833833) (xy 127.111017 -241.802708) (xy 127.153638 -241.778101) (xy 127.199654 -241.760649)
			(xy 127.247873 -241.750805) (xy 127.297048 -241.748824) (xy 127.345903 -241.754756) (xy 127.393174 -241.768448)
			(xy 127.437636 -241.789546) (xy 127.478139 -241.817502) (xy 127.513632 -241.851594) (xy 127.543197 -241.890938)
			(xy 127.566068 -241.934515) (xy 127.581652 -241.981196) (xy 127.589547 -242.029773) (xy 127.590042 -242.05438)
			(xy 127.908553 -242.05438) (xy 127.912648 -242.003652) (xy 127.924827 -241.954238) (xy 127.944775 -241.907418)
			(xy 127.971976 -241.864404) (xy 128.005724 -241.82631) (xy 128.045146 -241.794123) (xy 128.08922 -241.768677)
			(xy 128.136806 -241.75063) (xy 128.18667 -241.74045) (xy 128.237522 -241.738401) (xy 128.288043 -241.744535)
			(xy 128.336927 -241.758695) (xy 128.382906 -241.780512) (xy 128.42479 -241.809422) (xy 128.461494 -241.844677)
			(xy 128.492067 -241.885363) (xy 128.515718 -241.930426) (xy 128.531834 -241.9787) (xy 128.539998 -242.028934)
			(xy 128.54051 -242.05438) (xy 128.848607 -242.05438) (xy 128.852702 -242.003652) (xy 128.864881 -241.954238)
			(xy 128.884829 -241.907418) (xy 128.91203 -241.864404) (xy 128.945778 -241.82631) (xy 128.9852 -241.794123)
			(xy 129.029274 -241.768677) (xy 129.07686 -241.75063) (xy 129.126724 -241.74045) (xy 129.177576 -241.738401)
			(xy 129.228097 -241.744535) (xy 129.276981 -241.758695) (xy 129.32296 -241.780512) (xy 129.364844 -241.809422)
			(xy 129.401548 -241.844677) (xy 129.432121 -241.885363) (xy 129.455772 -241.930426) (xy 129.471888 -241.9787)
			(xy 129.480052 -242.028934) (xy 129.480564 -242.05438) (xy 129.480052 -242.079826) (xy 129.471888 -242.13006)
			(xy 129.455772 -242.178334) (xy 129.432121 -242.223397) (xy 129.401548 -242.264083) (xy 129.364844 -242.299338)
			(xy 129.32296 -242.328248) (xy 129.276981 -242.350065) (xy 129.228097 -242.364225) (xy 129.177576 -242.370359)
			(xy 129.126724 -242.36831) (xy 129.07686 -242.35813) (xy 129.029274 -242.340083) (xy 128.9852 -242.314637)
			(xy 128.945778 -242.28245) (xy 128.91203 -242.244356) (xy 128.884829 -242.201342) (xy 128.864881 -242.154522)
			(xy 128.852702 -242.105108) (xy 128.848607 -242.05438) (xy 128.54051 -242.05438) (xy 128.539998 -242.079826)
			(xy 128.531834 -242.13006) (xy 128.515718 -242.178334) (xy 128.492067 -242.223397) (xy 128.461494 -242.264083)
			(xy 128.42479 -242.299338) (xy 128.382906 -242.328248) (xy 128.336927 -242.350065) (xy 128.288043 -242.364225)
			(xy 128.237522 -242.370359) (xy 128.18667 -242.36831) (xy 128.136806 -242.35813) (xy 128.08922 -242.340083)
			(xy 128.045146 -242.314637) (xy 128.005724 -242.28245) (xy 127.971976 -242.244356) (xy 127.944775 -242.201342)
			(xy 127.924827 -242.154522) (xy 127.912648 -242.105108) (xy 127.908553 -242.05438) (xy 127.590042 -242.05438)
			(xy 127.589547 -242.078987) (xy 127.581652 -242.127564) (xy 127.566068 -242.174245) (xy 127.543197 -242.217822)
			(xy 127.513632 -242.257166) (xy 127.478139 -242.291258) (xy 127.437636 -242.319214) (xy 127.393174 -242.340312)
			(xy 127.345903 -242.354004) (xy 127.297048 -242.359936) (xy 127.247873 -242.357955) (xy 127.199654 -242.348111)
			(xy 127.153638 -242.330659) (xy 127.111017 -242.306052) (xy 127.072896 -242.274927) (xy 127.040261 -242.23809)
			(xy 127.013958 -242.196494) (xy 126.994667 -242.151218) (xy 126.98289 -242.103434) (xy 126.97893 -242.05438)
			(xy 124.770134 -242.05438) (xy 124.769639 -242.078987) (xy 124.761744 -242.127564) (xy 124.74616 -242.174245)
			(xy 124.723289 -242.217822) (xy 124.693724 -242.257166) (xy 124.658231 -242.291258) (xy 124.617728 -242.319214)
			(xy 124.573266 -242.340312) (xy 124.525995 -242.354004) (xy 124.47714 -242.359936) (xy 124.427965 -242.357955)
			(xy 124.379746 -242.348111) (xy 124.33373 -242.330659) (xy 124.291109 -242.306052) (xy 124.252988 -242.274927)
			(xy 124.220353 -242.23809) (xy 124.19405 -242.196494) (xy 124.174759 -242.151218) (xy 124.162982 -242.103434)
			(xy 124.159022 -242.05438) (xy 121.949972 -242.05438) (xy 121.949477 -242.078987) (xy 121.941582 -242.127564)
			(xy 121.925998 -242.174245) (xy 121.903127 -242.217822) (xy 121.873562 -242.257166) (xy 121.838069 -242.291258)
			(xy 121.797566 -242.319214) (xy 121.753104 -242.340312) (xy 121.705833 -242.354004) (xy 121.656978 -242.359936)
			(xy 121.607803 -242.357955) (xy 121.559584 -242.348111) (xy 121.513568 -242.330659) (xy 121.470947 -242.306052)
			(xy 121.432826 -242.274927) (xy 121.400191 -242.23809) (xy 121.373888 -242.196494) (xy 121.354597 -242.151218)
			(xy 121.34282 -242.103434) (xy 121.33886 -242.05438) (xy 119.130064 -242.05438) (xy 119.129569 -242.078987)
			(xy 119.121674 -242.127564) (xy 119.10609 -242.174245) (xy 119.083219 -242.217822) (xy 119.053654 -242.257166)
			(xy 119.018161 -242.291258) (xy 118.977658 -242.319214) (xy 118.933196 -242.340312) (xy 118.885925 -242.354004)
			(xy 118.83707 -242.359936) (xy 118.787895 -242.357955) (xy 118.739676 -242.348111) (xy 118.69366 -242.330659)
			(xy 118.651039 -242.306052) (xy 118.612918 -242.274927) (xy 118.580283 -242.23809) (xy 118.55398 -242.196494)
			(xy 118.534689 -242.151218) (xy 118.522912 -242.103434) (xy 118.518952 -242.05438) (xy 116.310156 -242.05438)
			(xy 116.309661 -242.078987) (xy 116.301766 -242.127564) (xy 116.286182 -242.174245) (xy 116.263311 -242.217822)
			(xy 116.233746 -242.257166) (xy 116.198253 -242.291258) (xy 116.15775 -242.319214) (xy 116.113288 -242.340312)
			(xy 116.066017 -242.354004) (xy 116.017162 -242.359936) (xy 115.967987 -242.357955) (xy 115.919768 -242.348111)
			(xy 115.873752 -242.330659) (xy 115.831131 -242.306052) (xy 115.79301 -242.274927) (xy 115.760375 -242.23809)
			(xy 115.734072 -242.196494) (xy 115.714781 -242.151218) (xy 115.703004 -242.103434) (xy 115.699044 -242.05438)
			(xy 115.370102 -242.05438) (xy 115.369607 -242.078987) (xy 115.361712 -242.127564) (xy 115.346128 -242.174245)
			(xy 115.323257 -242.217822) (xy 115.293692 -242.257166) (xy 115.258199 -242.291258) (xy 115.217696 -242.319214)
			(xy 115.173234 -242.340312) (xy 115.125963 -242.354004) (xy 115.077108 -242.359936) (xy 115.027933 -242.357955)
			(xy 114.979714 -242.348111) (xy 114.933698 -242.330659) (xy 114.891077 -242.306052) (xy 114.852956 -242.274927)
			(xy 114.820321 -242.23809) (xy 114.794018 -242.196494) (xy 114.774727 -242.151218) (xy 114.76295 -242.103434)
			(xy 114.75899 -242.05438) (xy 114.430048 -242.05438) (xy 114.429553 -242.078987) (xy 114.421658 -242.127564)
			(xy 114.406074 -242.174245) (xy 114.383203 -242.217822) (xy 114.353638 -242.257166) (xy 114.318145 -242.291258)
			(xy 114.277642 -242.319214) (xy 114.23318 -242.340312) (xy 114.185909 -242.354004) (xy 114.137054 -242.359936)
			(xy 114.087879 -242.357955) (xy 114.03966 -242.348111) (xy 113.993644 -242.330659) (xy 113.951023 -242.306052)
			(xy 113.912902 -242.274927) (xy 113.880267 -242.23809) (xy 113.853964 -242.196494) (xy 113.834673 -242.151218)
			(xy 113.822896 -242.103434) (xy 113.818936 -242.05438) (xy 113.489994 -242.05438) (xy 113.489499 -242.078987)
			(xy 113.481604 -242.127564) (xy 113.46602 -242.174245) (xy 113.443149 -242.217822) (xy 113.413584 -242.257166)
			(xy 113.378091 -242.291258) (xy 113.337588 -242.319214) (xy 113.293126 -242.340312) (xy 113.245855 -242.354004)
			(xy 113.197 -242.359936) (xy 113.147825 -242.357955) (xy 113.099606 -242.348111) (xy 113.05359 -242.330659)
			(xy 113.010969 -242.306052) (xy 112.972848 -242.274927) (xy 112.940213 -242.23809) (xy 112.91391 -242.196494)
			(xy 112.894619 -242.151218) (xy 112.882842 -242.103434) (xy 112.878882 -242.05438) (xy 110.676436 -242.05438)
			(xy 110.675941 -242.078987) (xy 110.668046 -242.127564) (xy 110.652462 -242.174245) (xy 110.629591 -242.217822)
			(xy 110.600026 -242.257166) (xy 110.564533 -242.291258) (xy 110.52403 -242.319214) (xy 110.479568 -242.340312)
			(xy 110.432297 -242.354004) (xy 110.383442 -242.359936) (xy 110.334267 -242.357955) (xy 110.286048 -242.348111)
			(xy 110.240032 -242.330659) (xy 110.197411 -242.306052) (xy 110.15929 -242.274927) (xy 110.126655 -242.23809)
			(xy 110.100352 -242.196494) (xy 110.081061 -242.151218) (xy 110.069284 -242.103434) (xy 110.065324 -242.05438)
			(xy 109.736382 -242.05438) (xy 109.735887 -242.078987) (xy 109.727992 -242.127564) (xy 109.712408 -242.174245)
			(xy 109.689537 -242.217822) (xy 109.659972 -242.257166) (xy 109.624479 -242.291258) (xy 109.583976 -242.319214)
			(xy 109.539514 -242.340312) (xy 109.492243 -242.354004) (xy 109.443388 -242.359936) (xy 109.394213 -242.357955)
			(xy 109.345994 -242.348111) (xy 109.299978 -242.330659) (xy 109.257357 -242.306052) (xy 109.219236 -242.274927)
			(xy 109.186601 -242.23809) (xy 109.160298 -242.196494) (xy 109.141007 -242.151218) (xy 109.12923 -242.103434)
			(xy 109.12527 -242.05438) (xy 108.796328 -242.05438) (xy 108.795833 -242.078987) (xy 108.787938 -242.127564)
			(xy 108.772354 -242.174245) (xy 108.749483 -242.217822) (xy 108.719918 -242.257166) (xy 108.684425 -242.291258)
			(xy 108.643922 -242.319214) (xy 108.59946 -242.340312) (xy 108.552189 -242.354004) (xy 108.503334 -242.359936)
			(xy 108.454159 -242.357955) (xy 108.40594 -242.348111) (xy 108.359924 -242.330659) (xy 108.317303 -242.306052)
			(xy 108.279182 -242.274927) (xy 108.246547 -242.23809) (xy 108.220244 -242.196494) (xy 108.200953 -242.151218)
			(xy 108.189176 -242.103434) (xy 108.185216 -242.05438) (xy 107.856274 -242.05438) (xy 107.855779 -242.078987)
			(xy 107.847884 -242.127564) (xy 107.8323 -242.174245) (xy 107.809429 -242.217822) (xy 107.779864 -242.257166)
			(xy 107.744371 -242.291258) (xy 107.703868 -242.319214) (xy 107.659406 -242.340312) (xy 107.612135 -242.354004)
			(xy 107.56328 -242.359936) (xy 107.514105 -242.357955) (xy 107.465886 -242.348111) (xy 107.41987 -242.330659)
			(xy 107.377249 -242.306052) (xy 107.339128 -242.274927) (xy 107.306493 -242.23809) (xy 107.28019 -242.196494)
			(xy 107.260899 -242.151218) (xy 107.249122 -242.103434) (xy 107.245162 -242.05438) (xy 105.036366 -242.05438)
			(xy 105.035871 -242.078987) (xy 105.027976 -242.127564) (xy 105.012392 -242.174245) (xy 104.989521 -242.217822)
			(xy 104.959956 -242.257166) (xy 104.924463 -242.291258) (xy 104.88396 -242.319214) (xy 104.839498 -242.340312)
			(xy 104.792227 -242.354004) (xy 104.743372 -242.359936) (xy 104.694197 -242.357955) (xy 104.645978 -242.348111)
			(xy 104.599962 -242.330659) (xy 104.557341 -242.306052) (xy 104.51922 -242.274927) (xy 104.486585 -242.23809)
			(xy 104.460282 -242.196494) (xy 104.440991 -242.151218) (xy 104.429214 -242.103434) (xy 104.425254 -242.05438)
			(xy 102.216458 -242.05438) (xy 102.215963 -242.078987) (xy 102.208068 -242.127564) (xy 102.192484 -242.174245)
			(xy 102.169613 -242.217822) (xy 102.140048 -242.257166) (xy 102.104555 -242.291258) (xy 102.064052 -242.319214)
			(xy 102.01959 -242.340312) (xy 101.972319 -242.354004) (xy 101.923464 -242.359936) (xy 101.874289 -242.357955)
			(xy 101.82607 -242.348111) (xy 101.780054 -242.330659) (xy 101.737433 -242.306052) (xy 101.699312 -242.274927)
			(xy 101.666677 -242.23809) (xy 101.640374 -242.196494) (xy 101.621083 -242.151218) (xy 101.609306 -242.103434)
			(xy 101.605346 -242.05438) (xy 99.396296 -242.05438) (xy 99.395801 -242.078987) (xy 99.387906 -242.127564)
			(xy 99.372322 -242.174245) (xy 99.349451 -242.217822) (xy 99.319886 -242.257166) (xy 99.284393 -242.291258)
			(xy 99.24389 -242.319214) (xy 99.199428 -242.340312) (xy 99.152157 -242.354004) (xy 99.103302 -242.359936)
			(xy 99.054127 -242.357955) (xy 99.005908 -242.348111) (xy 98.959892 -242.330659) (xy 98.917271 -242.306052)
			(xy 98.87915 -242.274927) (xy 98.846515 -242.23809) (xy 98.820212 -242.196494) (xy 98.800921 -242.151218)
			(xy 98.789144 -242.103434) (xy 98.785184 -242.05438) (xy 96.868234 -242.05438) (xy 96.868234 -242.569492)
			(xy 96.881696 -242.59286) (xy 96.893634 -242.599718) (xy 96.914744 -242.612434) (xy 96.952929 -242.643583)
			(xy 96.98562 -242.680457) (xy 97.011969 -242.722099) (xy 97.031294 -242.76743) (xy 97.043094 -242.815275)
			(xy 97.047061 -242.864386) (xy 97.37523 -242.864386) (xy 97.37919 -242.815332) (xy 97.390967 -242.767548)
			(xy 97.410258 -242.722272) (xy 97.436561 -242.680676) (xy 97.469196 -242.643839) (xy 97.507317 -242.612714)
			(xy 97.549938 -242.588107) (xy 97.595954 -242.570655) (xy 97.644173 -242.560811) (xy 97.693348 -242.55883)
			(xy 97.742203 -242.564762) (xy 97.789474 -242.578454) (xy 97.833936 -242.599552) (xy 97.874439 -242.627508)
			(xy 97.909932 -242.6616) (xy 97.939497 -242.700944) (xy 97.962368 -242.744521) (xy 97.977952 -242.791202)
			(xy 97.985847 -242.839779) (xy 97.986342 -242.864386) (xy 98.315284 -242.864386) (xy 98.319244 -242.815332)
			(xy 98.331021 -242.767548) (xy 98.350312 -242.722272) (xy 98.376615 -242.680676) (xy 98.40925 -242.643839)
			(xy 98.447371 -242.612714) (xy 98.489992 -242.588107) (xy 98.536008 -242.570655) (xy 98.584227 -242.560811)
			(xy 98.633402 -242.55883) (xy 98.682257 -242.564762) (xy 98.729528 -242.578454) (xy 98.77399 -242.599552)
			(xy 98.814493 -242.627508) (xy 98.849986 -242.6616) (xy 98.879551 -242.700944) (xy 98.902422 -242.744521)
			(xy 98.918006 -242.791202) (xy 98.925901 -242.839779) (xy 98.926396 -242.864386) (xy 99.255338 -242.864386)
			(xy 99.259298 -242.815332) (xy 99.271075 -242.767548) (xy 99.290366 -242.722272) (xy 99.316669 -242.680676)
			(xy 99.349304 -242.643839) (xy 99.387425 -242.612714) (xy 99.430046 -242.588107) (xy 99.476062 -242.570655)
			(xy 99.524281 -242.560811) (xy 99.573456 -242.55883) (xy 99.622311 -242.564762) (xy 99.669582 -242.578454)
			(xy 99.714044 -242.599552) (xy 99.754547 -242.627508) (xy 99.79004 -242.6616) (xy 99.819605 -242.700944)
			(xy 99.842476 -242.744521) (xy 99.85806 -242.791202) (xy 99.865955 -242.839779) (xy 99.86645 -242.864386)
			(xy 100.195138 -242.864386) (xy 100.199098 -242.815332) (xy 100.210875 -242.767548) (xy 100.230166 -242.722272)
			(xy 100.256469 -242.680676) (xy 100.289104 -242.643839) (xy 100.327225 -242.612714) (xy 100.369846 -242.588107)
			(xy 100.415862 -242.570655) (xy 100.464081 -242.560811) (xy 100.513256 -242.55883) (xy 100.562111 -242.564762)
			(xy 100.609382 -242.578454) (xy 100.653844 -242.599552) (xy 100.694347 -242.627508) (xy 100.72984 -242.6616)
			(xy 100.759405 -242.700944) (xy 100.782276 -242.744521) (xy 100.79786 -242.791202) (xy 100.805755 -242.839779)
			(xy 100.80625 -242.864386) (xy 101.135192 -242.864386) (xy 101.139152 -242.815332) (xy 101.150929 -242.767548)
			(xy 101.17022 -242.722272) (xy 101.196523 -242.680676) (xy 101.229158 -242.643839) (xy 101.267279 -242.612714)
			(xy 101.3099 -242.588107) (xy 101.355916 -242.570655) (xy 101.404135 -242.560811) (xy 101.45331 -242.55883)
			(xy 101.502165 -242.564762) (xy 101.549436 -242.578454) (xy 101.593898 -242.599552) (xy 101.634401 -242.627508)
			(xy 101.669894 -242.6616) (xy 101.699459 -242.700944) (xy 101.72233 -242.744521) (xy 101.737914 -242.791202)
			(xy 101.745809 -242.839779) (xy 101.746304 -242.864386) (xy 102.075246 -242.864386) (xy 102.079206 -242.815332)
			(xy 102.090983 -242.767548) (xy 102.110274 -242.722272) (xy 102.136577 -242.680676) (xy 102.169212 -242.643839)
			(xy 102.207333 -242.612714) (xy 102.249954 -242.588107) (xy 102.29597 -242.570655) (xy 102.344189 -242.560811)
			(xy 102.393364 -242.55883) (xy 102.442219 -242.564762) (xy 102.48949 -242.578454) (xy 102.533952 -242.599552)
			(xy 102.574455 -242.627508) (xy 102.609948 -242.6616) (xy 102.639513 -242.700944) (xy 102.662384 -242.744521)
			(xy 102.677968 -242.791202) (xy 102.685863 -242.839779) (xy 102.686358 -242.864386) (xy 103.0153 -242.864386)
			(xy 103.01926 -242.815332) (xy 103.031037 -242.767548) (xy 103.050328 -242.722272) (xy 103.076631 -242.680676)
			(xy 103.109266 -242.643839) (xy 103.147387 -242.612714) (xy 103.190008 -242.588107) (xy 103.236024 -242.570655)
			(xy 103.284243 -242.560811) (xy 103.333418 -242.55883) (xy 103.382273 -242.564762) (xy 103.429544 -242.578454)
			(xy 103.474006 -242.599552) (xy 103.514509 -242.627508) (xy 103.550002 -242.6616) (xy 103.579567 -242.700944)
			(xy 103.602438 -242.744521) (xy 103.618022 -242.791202) (xy 103.625917 -242.839779) (xy 103.626412 -242.864386)
			(xy 103.955354 -242.864386) (xy 103.959314 -242.815332) (xy 103.971091 -242.767548) (xy 103.990382 -242.722272)
			(xy 104.016685 -242.680676) (xy 104.04932 -242.643839) (xy 104.087441 -242.612714) (xy 104.130062 -242.588107)
			(xy 104.176078 -242.570655) (xy 104.224297 -242.560811) (xy 104.273472 -242.55883) (xy 104.322327 -242.564762)
			(xy 104.369598 -242.578454) (xy 104.41406 -242.599552) (xy 104.454563 -242.627508) (xy 104.490056 -242.6616)
			(xy 104.519621 -242.700944) (xy 104.542492 -242.744521) (xy 104.558076 -242.791202) (xy 104.565971 -242.839779)
			(xy 104.566466 -242.864386) (xy 104.895154 -242.864386) (xy 104.899114 -242.815332) (xy 104.910891 -242.767548)
			(xy 104.930182 -242.722272) (xy 104.956485 -242.680676) (xy 104.98912 -242.643839) (xy 105.027241 -242.612714)
			(xy 105.069862 -242.588107) (xy 105.115878 -242.570655) (xy 105.164097 -242.560811) (xy 105.213272 -242.55883)
			(xy 105.262127 -242.564762) (xy 105.309398 -242.578454) (xy 105.35386 -242.599552) (xy 105.394363 -242.627508)
			(xy 105.429856 -242.6616) (xy 105.459421 -242.700944) (xy 105.482292 -242.744521) (xy 105.497876 -242.791202)
			(xy 105.505771 -242.839779) (xy 105.506266 -242.864386) (xy 105.835208 -242.864386) (xy 105.839168 -242.815332)
			(xy 105.850945 -242.767548) (xy 105.870236 -242.722272) (xy 105.896539 -242.680676) (xy 105.929174 -242.643839)
			(xy 105.967295 -242.612714) (xy 106.009916 -242.588107) (xy 106.055932 -242.570655) (xy 106.104151 -242.560811)
			(xy 106.153326 -242.55883) (xy 106.202181 -242.564762) (xy 106.249452 -242.578454) (xy 106.293914 -242.599552)
			(xy 106.334417 -242.627508) (xy 106.36991 -242.6616) (xy 106.399475 -242.700944) (xy 106.422346 -242.744521)
			(xy 106.43793 -242.791202) (xy 106.445825 -242.839779) (xy 106.44632 -242.864386) (xy 106.775262 -242.864386)
			(xy 106.779222 -242.815332) (xy 106.790999 -242.767548) (xy 106.81029 -242.722272) (xy 106.836593 -242.680676)
			(xy 106.869228 -242.643839) (xy 106.907349 -242.612714) (xy 106.94997 -242.588107) (xy 106.995986 -242.570655)
			(xy 107.044205 -242.560811) (xy 107.09338 -242.55883) (xy 107.142235 -242.564762) (xy 107.189506 -242.578454)
			(xy 107.233968 -242.599552) (xy 107.274471 -242.627508) (xy 107.309964 -242.6616) (xy 107.339529 -242.700944)
			(xy 107.3624 -242.744521) (xy 107.377984 -242.791202) (xy 107.385879 -242.839779) (xy 107.386374 -242.864386)
			(xy 107.715316 -242.864386) (xy 107.719276 -242.815332) (xy 107.731053 -242.767548) (xy 107.750344 -242.722272)
			(xy 107.776647 -242.680676) (xy 107.809282 -242.643839) (xy 107.847403 -242.612714) (xy 107.890024 -242.588107)
			(xy 107.93604 -242.570655) (xy 107.984259 -242.560811) (xy 108.033434 -242.55883) (xy 108.082289 -242.564762)
			(xy 108.12956 -242.578454) (xy 108.174022 -242.599552) (xy 108.214525 -242.627508) (xy 108.250018 -242.6616)
			(xy 108.279583 -242.700944) (xy 108.302454 -242.744521) (xy 108.318038 -242.791202) (xy 108.325933 -242.839779)
			(xy 108.326428 -242.864386) (xy 115.22889 -242.864386) (xy 115.23285 -242.815332) (xy 115.244627 -242.767548)
			(xy 115.263918 -242.722272) (xy 115.290221 -242.680676) (xy 115.322856 -242.643839) (xy 115.360977 -242.612714)
			(xy 115.403598 -242.588107) (xy 115.449614 -242.570655) (xy 115.497833 -242.560811) (xy 115.547008 -242.55883)
			(xy 115.595863 -242.564762) (xy 115.643134 -242.578454) (xy 115.687596 -242.599552) (xy 115.728099 -242.627508)
			(xy 115.763592 -242.6616) (xy 115.793157 -242.700944) (xy 115.816028 -242.744521) (xy 115.831612 -242.791202)
			(xy 115.839507 -242.839779) (xy 115.840002 -242.864386) (xy 116.168944 -242.864386) (xy 116.172904 -242.815332)
			(xy 116.184681 -242.767548) (xy 116.203972 -242.722272) (xy 116.230275 -242.680676) (xy 116.26291 -242.643839)
			(xy 116.301031 -242.612714) (xy 116.343652 -242.588107) (xy 116.389668 -242.570655) (xy 116.437887 -242.560811)
			(xy 116.487062 -242.55883) (xy 116.535917 -242.564762) (xy 116.583188 -242.578454) (xy 116.62765 -242.599552)
			(xy 116.668153 -242.627508) (xy 116.703646 -242.6616) (xy 116.733211 -242.700944) (xy 116.756082 -242.744521)
			(xy 116.771666 -242.791202) (xy 116.779561 -242.839779) (xy 116.780056 -242.864386) (xy 117.108998 -242.864386)
			(xy 117.112958 -242.815332) (xy 117.124735 -242.767548) (xy 117.144026 -242.722272) (xy 117.170329 -242.680676)
			(xy 117.202964 -242.643839) (xy 117.241085 -242.612714) (xy 117.283706 -242.588107) (xy 117.329722 -242.570655)
			(xy 117.377941 -242.560811) (xy 117.427116 -242.55883) (xy 117.475971 -242.564762) (xy 117.523242 -242.578454)
			(xy 117.567704 -242.599552) (xy 117.608207 -242.627508) (xy 117.6437 -242.6616) (xy 117.673265 -242.700944)
			(xy 117.696136 -242.744521) (xy 117.71172 -242.791202) (xy 117.719615 -242.839779) (xy 117.72011 -242.864386)
			(xy 118.049052 -242.864386) (xy 118.053012 -242.815332) (xy 118.064789 -242.767548) (xy 118.08408 -242.722272)
			(xy 118.110383 -242.680676) (xy 118.143018 -242.643839) (xy 118.181139 -242.612714) (xy 118.22376 -242.588107)
			(xy 118.269776 -242.570655) (xy 118.317995 -242.560811) (xy 118.36717 -242.55883) (xy 118.416025 -242.564762)
			(xy 118.463296 -242.578454) (xy 118.507758 -242.599552) (xy 118.548261 -242.627508) (xy 118.583754 -242.6616)
			(xy 118.613319 -242.700944) (xy 118.63619 -242.744521) (xy 118.651774 -242.791202) (xy 118.659669 -242.839779)
			(xy 118.660164 -242.864386) (xy 118.988852 -242.864386) (xy 118.992812 -242.815332) (xy 119.004589 -242.767548)
			(xy 119.02388 -242.722272) (xy 119.050183 -242.680676) (xy 119.082818 -242.643839) (xy 119.120939 -242.612714)
			(xy 119.16356 -242.588107) (xy 119.209576 -242.570655) (xy 119.257795 -242.560811) (xy 119.30697 -242.55883)
			(xy 119.355825 -242.564762) (xy 119.403096 -242.578454) (xy 119.447558 -242.599552) (xy 119.488061 -242.627508)
			(xy 119.523554 -242.6616) (xy 119.553119 -242.700944) (xy 119.57599 -242.744521) (xy 119.591574 -242.791202)
			(xy 119.599469 -242.839779) (xy 119.599964 -242.864386) (xy 119.928906 -242.864386) (xy 119.932866 -242.815332)
			(xy 119.944643 -242.767548) (xy 119.963934 -242.722272) (xy 119.990237 -242.680676) (xy 120.022872 -242.643839)
			(xy 120.060993 -242.612714) (xy 120.103614 -242.588107) (xy 120.14963 -242.570655) (xy 120.197849 -242.560811)
			(xy 120.247024 -242.55883) (xy 120.295879 -242.564762) (xy 120.34315 -242.578454) (xy 120.387612 -242.599552)
			(xy 120.428115 -242.627508) (xy 120.463608 -242.6616) (xy 120.493173 -242.700944) (xy 120.516044 -242.744521)
			(xy 120.531628 -242.791202) (xy 120.539523 -242.839779) (xy 120.540018 -242.864386) (xy 120.86896 -242.864386)
			(xy 120.87292 -242.815332) (xy 120.884697 -242.767548) (xy 120.903988 -242.722272) (xy 120.930291 -242.680676)
			(xy 120.962926 -242.643839) (xy 121.001047 -242.612714) (xy 121.043668 -242.588107) (xy 121.089684 -242.570655)
			(xy 121.137903 -242.560811) (xy 121.187078 -242.55883) (xy 121.235933 -242.564762) (xy 121.283204 -242.578454)
			(xy 121.327666 -242.599552) (xy 121.368169 -242.627508) (xy 121.403662 -242.6616) (xy 121.433227 -242.700944)
			(xy 121.456098 -242.744521) (xy 121.471682 -242.791202) (xy 121.479577 -242.839779) (xy 121.480072 -242.864386)
			(xy 121.809014 -242.864386) (xy 121.812974 -242.815332) (xy 121.824751 -242.767548) (xy 121.844042 -242.722272)
			(xy 121.870345 -242.680676) (xy 121.90298 -242.643839) (xy 121.941101 -242.612714) (xy 121.983722 -242.588107)
			(xy 122.029738 -242.570655) (xy 122.077957 -242.560811) (xy 122.127132 -242.55883) (xy 122.175987 -242.564762)
			(xy 122.223258 -242.578454) (xy 122.26772 -242.599552) (xy 122.308223 -242.627508) (xy 122.343716 -242.6616)
			(xy 122.373281 -242.700944) (xy 122.396152 -242.744521) (xy 122.411736 -242.791202) (xy 122.419631 -242.839779)
			(xy 122.420126 -242.864386) (xy 122.748814 -242.864386) (xy 122.752774 -242.815332) (xy 122.764551 -242.767548)
			(xy 122.783842 -242.722272) (xy 122.810145 -242.680676) (xy 122.84278 -242.643839) (xy 122.880901 -242.612714)
			(xy 122.923522 -242.588107) (xy 122.969538 -242.570655) (xy 123.017757 -242.560811) (xy 123.066932 -242.55883)
			(xy 123.115787 -242.564762) (xy 123.163058 -242.578454) (xy 123.20752 -242.599552) (xy 123.248023 -242.627508)
			(xy 123.283516 -242.6616) (xy 123.313081 -242.700944) (xy 123.335952 -242.744521) (xy 123.351536 -242.791202)
			(xy 123.359431 -242.839779) (xy 123.359926 -242.864386) (xy 123.688868 -242.864386) (xy 123.692828 -242.815332)
			(xy 123.704605 -242.767548) (xy 123.723896 -242.722272) (xy 123.750199 -242.680676) (xy 123.782834 -242.643839)
			(xy 123.820955 -242.612714) (xy 123.863576 -242.588107) (xy 123.909592 -242.570655) (xy 123.957811 -242.560811)
			(xy 124.006986 -242.55883) (xy 124.055841 -242.564762) (xy 124.103112 -242.578454) (xy 124.147574 -242.599552)
			(xy 124.188077 -242.627508) (xy 124.22357 -242.6616) (xy 124.253135 -242.700944) (xy 124.276006 -242.744521)
			(xy 124.29159 -242.791202) (xy 124.299485 -242.839779) (xy 124.29998 -242.864386) (xy 124.628922 -242.864386)
			(xy 124.632882 -242.815332) (xy 124.644659 -242.767548) (xy 124.66395 -242.722272) (xy 124.690253 -242.680676)
			(xy 124.722888 -242.643839) (xy 124.761009 -242.612714) (xy 124.80363 -242.588107) (xy 124.849646 -242.570655)
			(xy 124.897865 -242.560811) (xy 124.94704 -242.55883) (xy 124.995895 -242.564762) (xy 125.043166 -242.578454)
			(xy 125.087628 -242.599552) (xy 125.128131 -242.627508) (xy 125.163624 -242.6616) (xy 125.193189 -242.700944)
			(xy 125.21606 -242.744521) (xy 125.231644 -242.791202) (xy 125.239539 -242.839779) (xy 125.240034 -242.864386)
			(xy 125.568976 -242.864386) (xy 125.572936 -242.815332) (xy 125.584713 -242.767548) (xy 125.604004 -242.722272)
			(xy 125.630307 -242.680676) (xy 125.662942 -242.643839) (xy 125.701063 -242.612714) (xy 125.743684 -242.588107)
			(xy 125.7897 -242.570655) (xy 125.837919 -242.560811) (xy 125.887094 -242.55883) (xy 125.935949 -242.564762)
			(xy 125.98322 -242.578454) (xy 126.027682 -242.599552) (xy 126.068185 -242.627508) (xy 126.103678 -242.6616)
			(xy 126.133243 -242.700944) (xy 126.156114 -242.744521) (xy 126.171698 -242.791202) (xy 126.179593 -242.839779)
			(xy 126.180088 -242.864386) (xy 126.50903 -242.864386) (xy 126.51299 -242.815332) (xy 126.524767 -242.767548)
			(xy 126.544058 -242.722272) (xy 126.570361 -242.680676) (xy 126.602996 -242.643839) (xy 126.641117 -242.612714)
			(xy 126.683738 -242.588107) (xy 126.729754 -242.570655) (xy 126.777973 -242.560811) (xy 126.827148 -242.55883)
			(xy 126.876003 -242.564762) (xy 126.923274 -242.578454) (xy 126.967736 -242.599552) (xy 127.008239 -242.627508)
			(xy 127.043732 -242.6616) (xy 127.073297 -242.700944) (xy 127.096168 -242.744521) (xy 127.111752 -242.791202)
			(xy 127.119647 -242.839779) (xy 127.120142 -242.864386) (xy 127.438399 -242.864386) (xy 127.442494 -242.813658)
			(xy 127.454673 -242.764244) (xy 127.474621 -242.717424) (xy 127.501822 -242.67441) (xy 127.53557 -242.636316)
			(xy 127.574992 -242.604129) (xy 127.619066 -242.578683) (xy 127.666652 -242.560636) (xy 127.716516 -242.550456)
			(xy 127.767368 -242.548407) (xy 127.817889 -242.554541) (xy 127.866773 -242.568701) (xy 127.912752 -242.590518)
			(xy 127.954636 -242.619428) (xy 127.99134 -242.654683) (xy 128.021913 -242.695369) (xy 128.045564 -242.740432)
			(xy 128.06168 -242.788706) (xy 128.069844 -242.83894) (xy 128.070356 -242.864386) (xy 128.388884 -242.864386)
			(xy 128.392844 -242.815332) (xy 128.404621 -242.767548) (xy 128.423912 -242.722272) (xy 128.450215 -242.680676)
			(xy 128.48285 -242.643839) (xy 128.520971 -242.612714) (xy 128.563592 -242.588107) (xy 128.609608 -242.570655)
			(xy 128.657827 -242.560811) (xy 128.707002 -242.55883) (xy 128.755857 -242.564762) (xy 128.803128 -242.578454)
			(xy 128.84759 -242.599552) (xy 128.888093 -242.627508) (xy 128.923586 -242.6616) (xy 128.953151 -242.700944)
			(xy 128.976022 -242.744521) (xy 128.991606 -242.791202) (xy 128.999501 -242.839779) (xy 128.999996 -242.864386)
			(xy 129.318507 -242.864386) (xy 129.322602 -242.813658) (xy 129.334781 -242.764244) (xy 129.354729 -242.717424)
			(xy 129.38193 -242.67441) (xy 129.415678 -242.636316) (xy 129.4551 -242.604129) (xy 129.499174 -242.578683)
			(xy 129.54676 -242.560636) (xy 129.596624 -242.550456) (xy 129.647476 -242.548407) (xy 129.697997 -242.554541)
			(xy 129.746881 -242.568701) (xy 129.79286 -242.590518) (xy 129.834744 -242.619428) (xy 129.871448 -242.654683)
			(xy 129.902021 -242.695369) (xy 129.925672 -242.740432) (xy 129.941788 -242.788706) (xy 129.949952 -242.83894)
			(xy 129.950464 -242.864386) (xy 129.949952 -242.889832) (xy 129.941788 -242.940066) (xy 129.925672 -242.98834)
			(xy 129.902021 -243.033403) (xy 129.871448 -243.074089) (xy 129.834744 -243.109344) (xy 129.79286 -243.138254)
			(xy 129.746881 -243.160071) (xy 129.697997 -243.174231) (xy 129.647476 -243.180365) (xy 129.596624 -243.178316)
			(xy 129.54676 -243.168136) (xy 129.499174 -243.150089) (xy 129.4551 -243.124643) (xy 129.415678 -243.092456)
			(xy 129.38193 -243.054362) (xy 129.354729 -243.011348) (xy 129.334781 -242.964528) (xy 129.322602 -242.915114)
			(xy 129.318507 -242.864386) (xy 128.999996 -242.864386) (xy 128.999501 -242.888993) (xy 128.991606 -242.93757)
			(xy 128.976022 -242.984251) (xy 128.953151 -243.027828) (xy 128.923586 -243.067172) (xy 128.888093 -243.101264)
			(xy 128.84759 -243.12922) (xy 128.803128 -243.150318) (xy 128.755857 -243.16401) (xy 128.707002 -243.169942)
			(xy 128.657827 -243.167961) (xy 128.609608 -243.158117) (xy 128.563592 -243.140665) (xy 128.520971 -243.116058)
			(xy 128.48285 -243.084933) (xy 128.450215 -243.048096) (xy 128.423912 -243.0065) (xy 128.404621 -242.961224)
			(xy 128.392844 -242.91344) (xy 128.388884 -242.864386) (xy 128.070356 -242.864386) (xy 128.069844 -242.889832)
			(xy 128.06168 -242.940066) (xy 128.045564 -242.98834) (xy 128.021913 -243.033403) (xy 127.99134 -243.074089)
			(xy 127.954636 -243.109344) (xy 127.912752 -243.138254) (xy 127.866773 -243.160071) (xy 127.817889 -243.174231)
			(xy 127.767368 -243.180365) (xy 127.716516 -243.178316) (xy 127.666652 -243.168136) (xy 127.619066 -243.150089)
			(xy 127.574992 -243.124643) (xy 127.53557 -243.092456) (xy 127.501822 -243.054362) (xy 127.474621 -243.011348)
			(xy 127.454673 -242.964528) (xy 127.442494 -242.915114) (xy 127.438399 -242.864386) (xy 127.120142 -242.864386)
			(xy 127.119647 -242.888993) (xy 127.111752 -242.93757) (xy 127.096168 -242.984251) (xy 127.073297 -243.027828)
			(xy 127.043732 -243.067172) (xy 127.008239 -243.101264) (xy 126.967736 -243.12922) (xy 126.923274 -243.150318)
			(xy 126.876003 -243.16401) (xy 126.827148 -243.169942) (xy 126.777973 -243.167961) (xy 126.729754 -243.158117)
			(xy 126.683738 -243.140665) (xy 126.641117 -243.116058) (xy 126.602996 -243.084933) (xy 126.570361 -243.048096)
			(xy 126.544058 -243.0065) (xy 126.524767 -242.961224) (xy 126.51299 -242.91344) (xy 126.50903 -242.864386)
			(xy 126.180088 -242.864386) (xy 126.179593 -242.888993) (xy 126.171698 -242.93757) (xy 126.156114 -242.984251)
			(xy 126.133243 -243.027828) (xy 126.103678 -243.067172) (xy 126.068185 -243.101264) (xy 126.027682 -243.12922)
			(xy 125.98322 -243.150318) (xy 125.935949 -243.16401) (xy 125.887094 -243.169942) (xy 125.837919 -243.167961)
			(xy 125.7897 -243.158117) (xy 125.743684 -243.140665) (xy 125.701063 -243.116058) (xy 125.662942 -243.084933)
			(xy 125.630307 -243.048096) (xy 125.604004 -243.0065) (xy 125.584713 -242.961224) (xy 125.572936 -242.91344)
			(xy 125.568976 -242.864386) (xy 125.240034 -242.864386) (xy 125.239539 -242.888993) (xy 125.231644 -242.93757)
			(xy 125.21606 -242.984251) (xy 125.193189 -243.027828) (xy 125.163624 -243.067172) (xy 125.128131 -243.101264)
			(xy 125.087628 -243.12922) (xy 125.043166 -243.150318) (xy 124.995895 -243.16401) (xy 124.94704 -243.169942)
			(xy 124.897865 -243.167961) (xy 124.849646 -243.158117) (xy 124.80363 -243.140665) (xy 124.761009 -243.116058)
			(xy 124.722888 -243.084933) (xy 124.690253 -243.048096) (xy 124.66395 -243.0065) (xy 124.644659 -242.961224)
			(xy 124.632882 -242.91344) (xy 124.628922 -242.864386) (xy 124.29998 -242.864386) (xy 124.299485 -242.888993)
			(xy 124.29159 -242.93757) (xy 124.276006 -242.984251) (xy 124.253135 -243.027828) (xy 124.22357 -243.067172)
			(xy 124.188077 -243.101264) (xy 124.147574 -243.12922) (xy 124.103112 -243.150318) (xy 124.055841 -243.16401)
			(xy 124.006986 -243.169942) (xy 123.957811 -243.167961) (xy 123.909592 -243.158117) (xy 123.863576 -243.140665)
			(xy 123.820955 -243.116058) (xy 123.782834 -243.084933) (xy 123.750199 -243.048096) (xy 123.723896 -243.0065)
			(xy 123.704605 -242.961224) (xy 123.692828 -242.91344) (xy 123.688868 -242.864386) (xy 123.359926 -242.864386)
			(xy 123.359431 -242.888993) (xy 123.351536 -242.93757) (xy 123.335952 -242.984251) (xy 123.313081 -243.027828)
			(xy 123.283516 -243.067172) (xy 123.248023 -243.101264) (xy 123.20752 -243.12922) (xy 123.163058 -243.150318)
			(xy 123.115787 -243.16401) (xy 123.066932 -243.169942) (xy 123.017757 -243.167961) (xy 122.969538 -243.158117)
			(xy 122.923522 -243.140665) (xy 122.880901 -243.116058) (xy 122.84278 -243.084933) (xy 122.810145 -243.048096)
			(xy 122.783842 -243.0065) (xy 122.764551 -242.961224) (xy 122.752774 -242.91344) (xy 122.748814 -242.864386)
			(xy 122.420126 -242.864386) (xy 122.419631 -242.888993) (xy 122.411736 -242.93757) (xy 122.396152 -242.984251)
			(xy 122.373281 -243.027828) (xy 122.343716 -243.067172) (xy 122.308223 -243.101264) (xy 122.26772 -243.12922)
			(xy 122.223258 -243.150318) (xy 122.175987 -243.16401) (xy 122.127132 -243.169942) (xy 122.077957 -243.167961)
			(xy 122.029738 -243.158117) (xy 121.983722 -243.140665) (xy 121.941101 -243.116058) (xy 121.90298 -243.084933)
			(xy 121.870345 -243.048096) (xy 121.844042 -243.0065) (xy 121.824751 -242.961224) (xy 121.812974 -242.91344)
			(xy 121.809014 -242.864386) (xy 121.480072 -242.864386) (xy 121.479577 -242.888993) (xy 121.471682 -242.93757)
			(xy 121.456098 -242.984251) (xy 121.433227 -243.027828) (xy 121.403662 -243.067172) (xy 121.368169 -243.101264)
			(xy 121.327666 -243.12922) (xy 121.283204 -243.150318) (xy 121.235933 -243.16401) (xy 121.187078 -243.169942)
			(xy 121.137903 -243.167961) (xy 121.089684 -243.158117) (xy 121.043668 -243.140665) (xy 121.001047 -243.116058)
			(xy 120.962926 -243.084933) (xy 120.930291 -243.048096) (xy 120.903988 -243.0065) (xy 120.884697 -242.961224)
			(xy 120.87292 -242.91344) (xy 120.86896 -242.864386) (xy 120.540018 -242.864386) (xy 120.539523 -242.888993)
			(xy 120.531628 -242.93757) (xy 120.516044 -242.984251) (xy 120.493173 -243.027828) (xy 120.463608 -243.067172)
			(xy 120.428115 -243.101264) (xy 120.387612 -243.12922) (xy 120.34315 -243.150318) (xy 120.295879 -243.16401)
			(xy 120.247024 -243.169942) (xy 120.197849 -243.167961) (xy 120.14963 -243.158117) (xy 120.103614 -243.140665)
			(xy 120.060993 -243.116058) (xy 120.022872 -243.084933) (xy 119.990237 -243.048096) (xy 119.963934 -243.0065)
			(xy 119.944643 -242.961224) (xy 119.932866 -242.91344) (xy 119.928906 -242.864386) (xy 119.599964 -242.864386)
			(xy 119.599469 -242.888993) (xy 119.591574 -242.93757) (xy 119.57599 -242.984251) (xy 119.553119 -243.027828)
			(xy 119.523554 -243.067172) (xy 119.488061 -243.101264) (xy 119.447558 -243.12922) (xy 119.403096 -243.150318)
			(xy 119.355825 -243.16401) (xy 119.30697 -243.169942) (xy 119.257795 -243.167961) (xy 119.209576 -243.158117)
			(xy 119.16356 -243.140665) (xy 119.120939 -243.116058) (xy 119.082818 -243.084933) (xy 119.050183 -243.048096)
			(xy 119.02388 -243.0065) (xy 119.004589 -242.961224) (xy 118.992812 -242.91344) (xy 118.988852 -242.864386)
			(xy 118.660164 -242.864386) (xy 118.659669 -242.888993) (xy 118.651774 -242.93757) (xy 118.63619 -242.984251)
			(xy 118.613319 -243.027828) (xy 118.583754 -243.067172) (xy 118.548261 -243.101264) (xy 118.507758 -243.12922)
			(xy 118.463296 -243.150318) (xy 118.416025 -243.16401) (xy 118.36717 -243.169942) (xy 118.317995 -243.167961)
			(xy 118.269776 -243.158117) (xy 118.22376 -243.140665) (xy 118.181139 -243.116058) (xy 118.143018 -243.084933)
			(xy 118.110383 -243.048096) (xy 118.08408 -243.0065) (xy 118.064789 -242.961224) (xy 118.053012 -242.91344)
			(xy 118.049052 -242.864386) (xy 117.72011 -242.864386) (xy 117.719615 -242.888993) (xy 117.71172 -242.93757)
			(xy 117.696136 -242.984251) (xy 117.673265 -243.027828) (xy 117.6437 -243.067172) (xy 117.608207 -243.101264)
			(xy 117.567704 -243.12922) (xy 117.523242 -243.150318) (xy 117.475971 -243.16401) (xy 117.427116 -243.169942)
			(xy 117.377941 -243.167961) (xy 117.329722 -243.158117) (xy 117.283706 -243.140665) (xy 117.241085 -243.116058)
			(xy 117.202964 -243.084933) (xy 117.170329 -243.048096) (xy 117.144026 -243.0065) (xy 117.124735 -242.961224)
			(xy 117.112958 -242.91344) (xy 117.108998 -242.864386) (xy 116.780056 -242.864386) (xy 116.779561 -242.888993)
			(xy 116.771666 -242.93757) (xy 116.756082 -242.984251) (xy 116.733211 -243.027828) (xy 116.703646 -243.067172)
			(xy 116.668153 -243.101264) (xy 116.62765 -243.12922) (xy 116.583188 -243.150318) (xy 116.535917 -243.16401)
			(xy 116.487062 -243.169942) (xy 116.437887 -243.167961) (xy 116.389668 -243.158117) (xy 116.343652 -243.140665)
			(xy 116.301031 -243.116058) (xy 116.26291 -243.084933) (xy 116.230275 -243.048096) (xy 116.203972 -243.0065)
			(xy 116.184681 -242.961224) (xy 116.172904 -242.91344) (xy 116.168944 -242.864386) (xy 115.840002 -242.864386)
			(xy 115.839507 -242.888993) (xy 115.831612 -242.93757) (xy 115.816028 -242.984251) (xy 115.793157 -243.027828)
			(xy 115.763592 -243.067172) (xy 115.728099 -243.101264) (xy 115.687596 -243.12922) (xy 115.643134 -243.150318)
			(xy 115.595863 -243.16401) (xy 115.547008 -243.169942) (xy 115.497833 -243.167961) (xy 115.449614 -243.158117)
			(xy 115.403598 -243.140665) (xy 115.360977 -243.116058) (xy 115.322856 -243.084933) (xy 115.290221 -243.048096)
			(xy 115.263918 -243.0065) (xy 115.244627 -242.961224) (xy 115.23285 -242.91344) (xy 115.22889 -242.864386)
			(xy 108.326428 -242.864386) (xy 108.325933 -242.888993) (xy 108.318038 -242.93757) (xy 108.302454 -242.984251)
			(xy 108.279583 -243.027828) (xy 108.250018 -243.067172) (xy 108.214525 -243.101264) (xy 108.174022 -243.12922)
			(xy 108.12956 -243.150318) (xy 108.082289 -243.16401) (xy 108.033434 -243.169942) (xy 107.984259 -243.167961)
			(xy 107.93604 -243.158117) (xy 107.890024 -243.140665) (xy 107.847403 -243.116058) (xy 107.809282 -243.084933)
			(xy 107.776647 -243.048096) (xy 107.750344 -243.0065) (xy 107.731053 -242.961224) (xy 107.719276 -242.91344)
			(xy 107.715316 -242.864386) (xy 107.386374 -242.864386) (xy 107.385879 -242.888993) (xy 107.377984 -242.93757)
			(xy 107.3624 -242.984251) (xy 107.339529 -243.027828) (xy 107.309964 -243.067172) (xy 107.274471 -243.101264)
			(xy 107.233968 -243.12922) (xy 107.189506 -243.150318) (xy 107.142235 -243.16401) (xy 107.09338 -243.169942)
			(xy 107.044205 -243.167961) (xy 106.995986 -243.158117) (xy 106.94997 -243.140665) (xy 106.907349 -243.116058)
			(xy 106.869228 -243.084933) (xy 106.836593 -243.048096) (xy 106.81029 -243.0065) (xy 106.790999 -242.961224)
			(xy 106.779222 -242.91344) (xy 106.775262 -242.864386) (xy 106.44632 -242.864386) (xy 106.445825 -242.888993)
			(xy 106.43793 -242.93757) (xy 106.422346 -242.984251) (xy 106.399475 -243.027828) (xy 106.36991 -243.067172)
			(xy 106.334417 -243.101264) (xy 106.293914 -243.12922) (xy 106.249452 -243.150318) (xy 106.202181 -243.16401)
			(xy 106.153326 -243.169942) (xy 106.104151 -243.167961) (xy 106.055932 -243.158117) (xy 106.009916 -243.140665)
			(xy 105.967295 -243.116058) (xy 105.929174 -243.084933) (xy 105.896539 -243.048096) (xy 105.870236 -243.0065)
			(xy 105.850945 -242.961224) (xy 105.839168 -242.91344) (xy 105.835208 -242.864386) (xy 105.506266 -242.864386)
			(xy 105.505771 -242.888993) (xy 105.497876 -242.93757) (xy 105.482292 -242.984251) (xy 105.459421 -243.027828)
			(xy 105.429856 -243.067172) (xy 105.394363 -243.101264) (xy 105.35386 -243.12922) (xy 105.309398 -243.150318)
			(xy 105.262127 -243.16401) (xy 105.213272 -243.169942) (xy 105.164097 -243.167961) (xy 105.115878 -243.158117)
			(xy 105.069862 -243.140665) (xy 105.027241 -243.116058) (xy 104.98912 -243.084933) (xy 104.956485 -243.048096)
			(xy 104.930182 -243.0065) (xy 104.910891 -242.961224) (xy 104.899114 -242.91344) (xy 104.895154 -242.864386)
			(xy 104.566466 -242.864386) (xy 104.565971 -242.888993) (xy 104.558076 -242.93757) (xy 104.542492 -242.984251)
			(xy 104.519621 -243.027828) (xy 104.490056 -243.067172) (xy 104.454563 -243.101264) (xy 104.41406 -243.12922)
			(xy 104.369598 -243.150318) (xy 104.322327 -243.16401) (xy 104.273472 -243.169942) (xy 104.224297 -243.167961)
			(xy 104.176078 -243.158117) (xy 104.130062 -243.140665) (xy 104.087441 -243.116058) (xy 104.04932 -243.084933)
			(xy 104.016685 -243.048096) (xy 103.990382 -243.0065) (xy 103.971091 -242.961224) (xy 103.959314 -242.91344)
			(xy 103.955354 -242.864386) (xy 103.626412 -242.864386) (xy 103.625917 -242.888993) (xy 103.618022 -242.93757)
			(xy 103.602438 -242.984251) (xy 103.579567 -243.027828) (xy 103.550002 -243.067172) (xy 103.514509 -243.101264)
			(xy 103.474006 -243.12922) (xy 103.429544 -243.150318) (xy 103.382273 -243.16401) (xy 103.333418 -243.169942)
			(xy 103.284243 -243.167961) (xy 103.236024 -243.158117) (xy 103.190008 -243.140665) (xy 103.147387 -243.116058)
			(xy 103.109266 -243.084933) (xy 103.076631 -243.048096) (xy 103.050328 -243.0065) (xy 103.031037 -242.961224)
			(xy 103.01926 -242.91344) (xy 103.0153 -242.864386) (xy 102.686358 -242.864386) (xy 102.685863 -242.888993)
			(xy 102.677968 -242.93757) (xy 102.662384 -242.984251) (xy 102.639513 -243.027828) (xy 102.609948 -243.067172)
			(xy 102.574455 -243.101264) (xy 102.533952 -243.12922) (xy 102.48949 -243.150318) (xy 102.442219 -243.16401)
			(xy 102.393364 -243.169942) (xy 102.344189 -243.167961) (xy 102.29597 -243.158117) (xy 102.249954 -243.140665)
			(xy 102.207333 -243.116058) (xy 102.169212 -243.084933) (xy 102.136577 -243.048096) (xy 102.110274 -243.0065)
			(xy 102.090983 -242.961224) (xy 102.079206 -242.91344) (xy 102.075246 -242.864386) (xy 101.746304 -242.864386)
			(xy 101.745809 -242.888993) (xy 101.737914 -242.93757) (xy 101.72233 -242.984251) (xy 101.699459 -243.027828)
			(xy 101.669894 -243.067172) (xy 101.634401 -243.101264) (xy 101.593898 -243.12922) (xy 101.549436 -243.150318)
			(xy 101.502165 -243.16401) (xy 101.45331 -243.169942) (xy 101.404135 -243.167961) (xy 101.355916 -243.158117)
			(xy 101.3099 -243.140665) (xy 101.267279 -243.116058) (xy 101.229158 -243.084933) (xy 101.196523 -243.048096)
			(xy 101.17022 -243.0065) (xy 101.150929 -242.961224) (xy 101.139152 -242.91344) (xy 101.135192 -242.864386)
			(xy 100.80625 -242.864386) (xy 100.805755 -242.888993) (xy 100.79786 -242.93757) (xy 100.782276 -242.984251)
			(xy 100.759405 -243.027828) (xy 100.72984 -243.067172) (xy 100.694347 -243.101264) (xy 100.653844 -243.12922)
			(xy 100.609382 -243.150318) (xy 100.562111 -243.16401) (xy 100.513256 -243.169942) (xy 100.464081 -243.167961)
			(xy 100.415862 -243.158117) (xy 100.369846 -243.140665) (xy 100.327225 -243.116058) (xy 100.289104 -243.084933)
			(xy 100.256469 -243.048096) (xy 100.230166 -243.0065) (xy 100.210875 -242.961224) (xy 100.199098 -242.91344)
			(xy 100.195138 -242.864386) (xy 99.86645 -242.864386) (xy 99.865955 -242.888993) (xy 99.85806 -242.93757)
			(xy 99.842476 -242.984251) (xy 99.819605 -243.027828) (xy 99.79004 -243.067172) (xy 99.754547 -243.101264)
			(xy 99.714044 -243.12922) (xy 99.669582 -243.150318) (xy 99.622311 -243.16401) (xy 99.573456 -243.169942)
			(xy 99.524281 -243.167961) (xy 99.476062 -243.158117) (xy 99.430046 -243.140665) (xy 99.387425 -243.116058)
			(xy 99.349304 -243.084933) (xy 99.316669 -243.048096) (xy 99.290366 -243.0065) (xy 99.271075 -242.961224)
			(xy 99.259298 -242.91344) (xy 99.255338 -242.864386) (xy 98.926396 -242.864386) (xy 98.925901 -242.888993)
			(xy 98.918006 -242.93757) (xy 98.902422 -242.984251) (xy 98.879551 -243.027828) (xy 98.849986 -243.067172)
			(xy 98.814493 -243.101264) (xy 98.77399 -243.12922) (xy 98.729528 -243.150318) (xy 98.682257 -243.16401)
			(xy 98.633402 -243.169942) (xy 98.584227 -243.167961) (xy 98.536008 -243.158117) (xy 98.489992 -243.140665)
			(xy 98.447371 -243.116058) (xy 98.40925 -243.084933) (xy 98.376615 -243.048096) (xy 98.350312 -243.0065)
			(xy 98.331021 -242.961224) (xy 98.319244 -242.91344) (xy 98.315284 -242.864386) (xy 97.986342 -242.864386)
			(xy 97.985847 -242.888993) (xy 97.977952 -242.93757) (xy 97.962368 -242.984251) (xy 97.939497 -243.027828)
			(xy 97.909932 -243.067172) (xy 97.874439 -243.101264) (xy 97.833936 -243.12922) (xy 97.789474 -243.150318)
			(xy 97.742203 -243.16401) (xy 97.693348 -243.169942) (xy 97.644173 -243.167961) (xy 97.595954 -243.158117)
			(xy 97.549938 -243.140665) (xy 97.507317 -243.116058) (xy 97.469196 -243.084933) (xy 97.436561 -243.048096)
			(xy 97.410258 -243.0065) (xy 97.390967 -242.961224) (xy 97.37919 -242.91344) (xy 97.37523 -242.864386)
			(xy 97.047061 -242.864386) (xy 97.047062 -242.864393) (xy 97.043096 -242.913512) (xy 97.031299 -242.961357)
			(xy 97.011976 -243.006689) (xy 96.985628 -243.048332) (xy 96.952939 -243.085207) (xy 96.914755 -243.116358)
			(xy 96.893634 -243.129054) (xy 96.881696 -243.135912) (xy 96.868234 -243.15928) (xy 96.868234 -243.349272)
			(xy 96.868234 -243.352066) (xy 96.869504 -243.364344) (xy 96.882161 -243.385503) (xy 96.892364 -243.392452)
			(xy 96.896174 -243.394738) (xy 96.988376 -243.440966) (xy 97.016824 -243.438426) (xy 97.028508 -243.42979)
			(xy 97.048414 -243.415521) (xy 97.091824 -243.392847) (xy 97.1383 -243.377401) (xy 97.186646 -243.369581)
			(xy 97.211134 -243.369084) (xy 97.236388 -243.369608) (xy 97.286207 -243.377927) (xy 97.333977 -243.394331)
			(xy 97.378396 -243.418374) (xy 97.418252 -243.449399) (xy 97.452459 -243.486561) (xy 97.480082 -243.528846)
			(xy 97.50037 -243.575101) (xy 97.512768 -243.624064) (xy 97.516938 -243.674392) (xy 97.84513 -243.674392)
			(xy 97.84909 -243.625338) (xy 97.860867 -243.577554) (xy 97.880158 -243.532278) (xy 97.906461 -243.490682)
			(xy 97.939096 -243.453845) (xy 97.977217 -243.42272) (xy 98.019838 -243.398113) (xy 98.065854 -243.380661)
			(xy 98.114073 -243.370817) (xy 98.163248 -243.368836) (xy 98.212103 -243.374768) (xy 98.259374 -243.38846)
			(xy 98.303836 -243.409558) (xy 98.344339 -243.437514) (xy 98.379832 -243.471606) (xy 98.409397 -243.51095)
			(xy 98.432268 -243.554527) (xy 98.447852 -243.601208) (xy 98.455747 -243.649785) (xy 98.456242 -243.674392)
			(xy 98.785184 -243.674392) (xy 98.789144 -243.625338) (xy 98.800921 -243.577554) (xy 98.820212 -243.532278)
			(xy 98.846515 -243.490682) (xy 98.87915 -243.453845) (xy 98.917271 -243.42272) (xy 98.959892 -243.398113)
			(xy 99.005908 -243.380661) (xy 99.054127 -243.370817) (xy 99.103302 -243.368836) (xy 99.152157 -243.374768)
			(xy 99.199428 -243.38846) (xy 99.24389 -243.409558) (xy 99.284393 -243.437514) (xy 99.319886 -243.471606)
			(xy 99.349451 -243.51095) (xy 99.372322 -243.554527) (xy 99.387906 -243.601208) (xy 99.395801 -243.649785)
			(xy 99.396296 -243.674392) (xy 99.725238 -243.674392) (xy 99.729198 -243.625338) (xy 99.740975 -243.577554)
			(xy 99.760266 -243.532278) (xy 99.786569 -243.490682) (xy 99.819204 -243.453845) (xy 99.857325 -243.42272)
			(xy 99.899946 -243.398113) (xy 99.945962 -243.380661) (xy 99.994181 -243.370817) (xy 100.043356 -243.368836)
			(xy 100.092211 -243.374768) (xy 100.139482 -243.38846) (xy 100.183944 -243.409558) (xy 100.224447 -243.437514)
			(xy 100.25994 -243.471606) (xy 100.289505 -243.51095) (xy 100.312376 -243.554527) (xy 100.32796 -243.601208)
			(xy 100.335855 -243.649785) (xy 100.33635 -243.674392) (xy 100.665292 -243.674392) (xy 100.669252 -243.625338)
			(xy 100.681029 -243.577554) (xy 100.70032 -243.532278) (xy 100.726623 -243.490682) (xy 100.759258 -243.453845)
			(xy 100.797379 -243.42272) (xy 100.84 -243.398113) (xy 100.886016 -243.380661) (xy 100.934235 -243.370817)
			(xy 100.98341 -243.368836) (xy 101.032265 -243.374768) (xy 101.079536 -243.38846) (xy 101.123998 -243.409558)
			(xy 101.164501 -243.437514) (xy 101.199994 -243.471606) (xy 101.229559 -243.51095) (xy 101.25243 -243.554527)
			(xy 101.268014 -243.601208) (xy 101.275909 -243.649785) (xy 101.276404 -243.674392) (xy 101.605346 -243.674392)
			(xy 101.609306 -243.625338) (xy 101.621083 -243.577554) (xy 101.640374 -243.532278) (xy 101.666677 -243.490682)
			(xy 101.699312 -243.453845) (xy 101.737433 -243.42272) (xy 101.780054 -243.398113) (xy 101.82607 -243.380661)
			(xy 101.874289 -243.370817) (xy 101.923464 -243.368836) (xy 101.972319 -243.374768) (xy 102.01959 -243.38846)
			(xy 102.064052 -243.409558) (xy 102.104555 -243.437514) (xy 102.140048 -243.471606) (xy 102.169613 -243.51095)
			(xy 102.192484 -243.554527) (xy 102.208068 -243.601208) (xy 102.215963 -243.649785) (xy 102.216458 -243.674392)
			(xy 102.545146 -243.674392) (xy 102.549106 -243.625338) (xy 102.560883 -243.577554) (xy 102.580174 -243.532278)
			(xy 102.606477 -243.490682) (xy 102.639112 -243.453845) (xy 102.677233 -243.42272) (xy 102.719854 -243.398113)
			(xy 102.76587 -243.380661) (xy 102.814089 -243.370817) (xy 102.863264 -243.368836) (xy 102.912119 -243.374768)
			(xy 102.95939 -243.38846) (xy 103.003852 -243.409558) (xy 103.044355 -243.437514) (xy 103.079848 -243.471606)
			(xy 103.109413 -243.51095) (xy 103.132284 -243.554527) (xy 103.147868 -243.601208) (xy 103.155763 -243.649785)
			(xy 103.156258 -243.674392) (xy 103.4852 -243.674392) (xy 103.48916 -243.625338) (xy 103.500937 -243.577554)
			(xy 103.520228 -243.532278) (xy 103.546531 -243.490682) (xy 103.579166 -243.453845) (xy 103.617287 -243.42272)
			(xy 103.659908 -243.398113) (xy 103.705924 -243.380661) (xy 103.754143 -243.370817) (xy 103.803318 -243.368836)
			(xy 103.852173 -243.374768) (xy 103.899444 -243.38846) (xy 103.943906 -243.409558) (xy 103.984409 -243.437514)
			(xy 104.019902 -243.471606) (xy 104.049467 -243.51095) (xy 104.072338 -243.554527) (xy 104.087922 -243.601208)
			(xy 104.095817 -243.649785) (xy 104.096312 -243.674392) (xy 104.425254 -243.674392) (xy 104.429214 -243.625338)
			(xy 104.440991 -243.577554) (xy 104.460282 -243.532278) (xy 104.486585 -243.490682) (xy 104.51922 -243.453845)
			(xy 104.557341 -243.42272) (xy 104.599962 -243.398113) (xy 104.645978 -243.380661) (xy 104.694197 -243.370817)
			(xy 104.743372 -243.368836) (xy 104.792227 -243.374768) (xy 104.839498 -243.38846) (xy 104.88396 -243.409558)
			(xy 104.924463 -243.437514) (xy 104.959956 -243.471606) (xy 104.989521 -243.51095) (xy 105.012392 -243.554527)
			(xy 105.027976 -243.601208) (xy 105.035871 -243.649785) (xy 105.036366 -243.674392) (xy 105.365308 -243.674392)
			(xy 105.369268 -243.625338) (xy 105.381045 -243.577554) (xy 105.400336 -243.532278) (xy 105.426639 -243.490682)
			(xy 105.459274 -243.453845) (xy 105.497395 -243.42272) (xy 105.540016 -243.398113) (xy 105.586032 -243.380661)
			(xy 105.634251 -243.370817) (xy 105.683426 -243.368836) (xy 105.732281 -243.374768) (xy 105.779552 -243.38846)
			(xy 105.824014 -243.409558) (xy 105.864517 -243.437514) (xy 105.90001 -243.471606) (xy 105.929575 -243.51095)
			(xy 105.952446 -243.554527) (xy 105.96803 -243.601208) (xy 105.975925 -243.649785) (xy 105.97642 -243.674392)
			(xy 106.305362 -243.674392) (xy 106.309322 -243.625338) (xy 106.321099 -243.577554) (xy 106.34039 -243.532278)
			(xy 106.366693 -243.490682) (xy 106.399328 -243.453845) (xy 106.437449 -243.42272) (xy 106.48007 -243.398113)
			(xy 106.526086 -243.380661) (xy 106.574305 -243.370817) (xy 106.62348 -243.368836) (xy 106.672335 -243.374768)
			(xy 106.719606 -243.38846) (xy 106.764068 -243.409558) (xy 106.804571 -243.437514) (xy 106.840064 -243.471606)
			(xy 106.869629 -243.51095) (xy 106.8925 -243.554527) (xy 106.908084 -243.601208) (xy 106.915979 -243.649785)
			(xy 106.916474 -243.674392) (xy 107.245162 -243.674392) (xy 107.249122 -243.625338) (xy 107.260899 -243.577554)
			(xy 107.28019 -243.532278) (xy 107.306493 -243.490682) (xy 107.339128 -243.453845) (xy 107.377249 -243.42272)
			(xy 107.41987 -243.398113) (xy 107.465886 -243.380661) (xy 107.514105 -243.370817) (xy 107.56328 -243.368836)
			(xy 107.612135 -243.374768) (xy 107.659406 -243.38846) (xy 107.703868 -243.409558) (xy 107.744371 -243.437514)
			(xy 107.779864 -243.471606) (xy 107.809429 -243.51095) (xy 107.8323 -243.554527) (xy 107.847884 -243.601208)
			(xy 107.855779 -243.649785) (xy 107.856274 -243.674392) (xy 107.856274 -243.6744) (xy 108.185132 -243.6744)
			(xy 108.189304 -243.624054) (xy 108.201706 -243.575081) (xy 108.222 -243.528817) (xy 108.249632 -243.486525)
			(xy 108.283849 -243.449358) (xy 108.323717 -243.418331) (xy 108.368148 -243.394288) (xy 108.41593 -243.377887)
			(xy 108.465761 -243.369575) (xy 108.49102 -243.369084) (xy 109.431074 -243.369084) (xy 109.456332 -243.369591)
			(xy 109.506161 -243.377902) (xy 109.553942 -243.394301) (xy 109.598371 -243.418342) (xy 109.638238 -243.449368)
			(xy 109.672453 -243.486533) (xy 109.700085 -243.528823) (xy 109.720378 -243.575085) (xy 109.73278 -243.624056)
			(xy 109.736951 -243.674392) (xy 110.065324 -243.674392) (xy 110.069284 -243.625338) (xy 110.081061 -243.577554)
			(xy 110.100352 -243.532278) (xy 110.126655 -243.490682) (xy 110.15929 -243.453845) (xy 110.197411 -243.42272)
			(xy 110.240032 -243.398113) (xy 110.286048 -243.380661) (xy 110.334267 -243.370817) (xy 110.383442 -243.368836)
			(xy 110.432297 -243.374768) (xy 110.479568 -243.38846) (xy 110.52403 -243.409558) (xy 110.564533 -243.437514)
			(xy 110.600026 -243.471606) (xy 110.629591 -243.51095) (xy 110.652462 -243.554527) (xy 110.668046 -243.601208)
			(xy 110.675941 -243.649785) (xy 110.676436 -243.674392) (xy 112.878882 -243.674392) (xy 112.882842 -243.625338)
			(xy 112.894619 -243.577554) (xy 112.91391 -243.532278) (xy 112.940213 -243.490682) (xy 112.972848 -243.453845)
			(xy 113.010969 -243.42272) (xy 113.05359 -243.398113) (xy 113.099606 -243.380661) (xy 113.147825 -243.370817)
			(xy 113.197 -243.368836) (xy 113.245855 -243.374768) (xy 113.293126 -243.38846) (xy 113.337588 -243.409558)
			(xy 113.378091 -243.437514) (xy 113.413584 -243.471606) (xy 113.443149 -243.51095) (xy 113.46602 -243.554527)
			(xy 113.481604 -243.601208) (xy 113.489499 -243.649785) (xy 113.489994 -243.674392) (xy 113.818936 -243.674392)
			(xy 113.822896 -243.625338) (xy 113.834673 -243.577554) (xy 113.853964 -243.532278) (xy 113.880267 -243.490682)
			(xy 113.912902 -243.453845) (xy 113.951023 -243.42272) (xy 113.993644 -243.398113) (xy 114.03966 -243.380661)
			(xy 114.087879 -243.370817) (xy 114.137054 -243.368836) (xy 114.185909 -243.374768) (xy 114.23318 -243.38846)
			(xy 114.277642 -243.409558) (xy 114.318145 -243.437514) (xy 114.353638 -243.471606) (xy 114.383203 -243.51095)
			(xy 114.406074 -243.554527) (xy 114.421658 -243.601208) (xy 114.429553 -243.649785) (xy 114.430048 -243.674392)
			(xy 114.75899 -243.674392) (xy 114.76295 -243.625338) (xy 114.774727 -243.577554) (xy 114.794018 -243.532278)
			(xy 114.820321 -243.490682) (xy 114.852956 -243.453845) (xy 114.891077 -243.42272) (xy 114.933698 -243.398113)
			(xy 114.979714 -243.380661) (xy 115.027933 -243.370817) (xy 115.077108 -243.368836) (xy 115.125963 -243.374768)
			(xy 115.173234 -243.38846) (xy 115.217696 -243.409558) (xy 115.258199 -243.437514) (xy 115.293692 -243.471606)
			(xy 115.323257 -243.51095) (xy 115.346128 -243.554527) (xy 115.361712 -243.601208) (xy 115.369607 -243.649785)
			(xy 115.370102 -243.674392) (xy 115.699044 -243.674392) (xy 115.703004 -243.625338) (xy 115.714781 -243.577554)
			(xy 115.734072 -243.532278) (xy 115.760375 -243.490682) (xy 115.79301 -243.453845) (xy 115.831131 -243.42272)
			(xy 115.873752 -243.398113) (xy 115.919768 -243.380661) (xy 115.967987 -243.370817) (xy 116.017162 -243.368836)
			(xy 116.066017 -243.374768) (xy 116.113288 -243.38846) (xy 116.15775 -243.409558) (xy 116.198253 -243.437514)
			(xy 116.233746 -243.471606) (xy 116.263311 -243.51095) (xy 116.286182 -243.554527) (xy 116.301766 -243.601208)
			(xy 116.309661 -243.649785) (xy 116.310156 -243.674392) (xy 116.638844 -243.674392) (xy 116.642804 -243.625338)
			(xy 116.654581 -243.577554) (xy 116.673872 -243.532278) (xy 116.700175 -243.490682) (xy 116.73281 -243.453845)
			(xy 116.770931 -243.42272) (xy 116.813552 -243.398113) (xy 116.859568 -243.380661) (xy 116.907787 -243.370817)
			(xy 116.956962 -243.368836) (xy 117.005817 -243.374768) (xy 117.053088 -243.38846) (xy 117.09755 -243.409558)
			(xy 117.138053 -243.437514) (xy 117.173546 -243.471606) (xy 117.203111 -243.51095) (xy 117.225982 -243.554527)
			(xy 117.241566 -243.601208) (xy 117.249461 -243.649785) (xy 117.249956 -243.674392) (xy 117.578898 -243.674392)
			(xy 117.582858 -243.625338) (xy 117.594635 -243.577554) (xy 117.613926 -243.532278) (xy 117.640229 -243.490682)
			(xy 117.672864 -243.453845) (xy 117.710985 -243.42272) (xy 117.753606 -243.398113) (xy 117.799622 -243.380661)
			(xy 117.847841 -243.370817) (xy 117.897016 -243.368836) (xy 117.945871 -243.374768) (xy 117.993142 -243.38846)
			(xy 118.037604 -243.409558) (xy 118.078107 -243.437514) (xy 118.1136 -243.471606) (xy 118.143165 -243.51095)
			(xy 118.166036 -243.554527) (xy 118.18162 -243.601208) (xy 118.189515 -243.649785) (xy 118.19001 -243.674392)
			(xy 118.518952 -243.674392) (xy 118.522912 -243.625338) (xy 118.534689 -243.577554) (xy 118.55398 -243.532278)
			(xy 118.580283 -243.490682) (xy 118.612918 -243.453845) (xy 118.651039 -243.42272) (xy 118.69366 -243.398113)
			(xy 118.739676 -243.380661) (xy 118.787895 -243.370817) (xy 118.83707 -243.368836) (xy 118.885925 -243.374768)
			(xy 118.933196 -243.38846) (xy 118.977658 -243.409558) (xy 119.018161 -243.437514) (xy 119.053654 -243.471606)
			(xy 119.083219 -243.51095) (xy 119.10609 -243.554527) (xy 119.121674 -243.601208) (xy 119.129569 -243.649785)
			(xy 119.130064 -243.674392) (xy 119.459006 -243.674392) (xy 119.462966 -243.625338) (xy 119.474743 -243.577554)
			(xy 119.494034 -243.532278) (xy 119.520337 -243.490682) (xy 119.552972 -243.453845) (xy 119.591093 -243.42272)
			(xy 119.633714 -243.398113) (xy 119.67973 -243.380661) (xy 119.727949 -243.370817) (xy 119.777124 -243.368836)
			(xy 119.825979 -243.374768) (xy 119.87325 -243.38846) (xy 119.917712 -243.409558) (xy 119.958215 -243.437514)
			(xy 119.993708 -243.471606) (xy 120.023273 -243.51095) (xy 120.046144 -243.554527) (xy 120.061728 -243.601208)
			(xy 120.069623 -243.649785) (xy 120.070118 -243.674392) (xy 120.398806 -243.674392) (xy 120.402766 -243.625338)
			(xy 120.414543 -243.577554) (xy 120.433834 -243.532278) (xy 120.460137 -243.490682) (xy 120.492772 -243.453845)
			(xy 120.530893 -243.42272) (xy 120.573514 -243.398113) (xy 120.61953 -243.380661) (xy 120.667749 -243.370817)
			(xy 120.716924 -243.368836) (xy 120.765779 -243.374768) (xy 120.81305 -243.38846) (xy 120.857512 -243.409558)
			(xy 120.898015 -243.437514) (xy 120.933508 -243.471606) (xy 120.963073 -243.51095) (xy 120.985944 -243.554527)
			(xy 121.001528 -243.601208) (xy 121.009423 -243.649785) (xy 121.009918 -243.674392) (xy 121.33886 -243.674392)
			(xy 121.34282 -243.625338) (xy 121.354597 -243.577554) (xy 121.373888 -243.532278) (xy 121.400191 -243.490682)
			(xy 121.432826 -243.453845) (xy 121.470947 -243.42272) (xy 121.513568 -243.398113) (xy 121.559584 -243.380661)
			(xy 121.607803 -243.370817) (xy 121.656978 -243.368836) (xy 121.705833 -243.374768) (xy 121.753104 -243.38846)
			(xy 121.797566 -243.409558) (xy 121.838069 -243.437514) (xy 121.873562 -243.471606) (xy 121.903127 -243.51095)
			(xy 121.925998 -243.554527) (xy 121.941582 -243.601208) (xy 121.949477 -243.649785) (xy 121.949972 -243.674392)
			(xy 122.278914 -243.674392) (xy 122.282874 -243.625338) (xy 122.294651 -243.577554) (xy 122.313942 -243.532278)
			(xy 122.340245 -243.490682) (xy 122.37288 -243.453845) (xy 122.411001 -243.42272) (xy 122.453622 -243.398113)
			(xy 122.499638 -243.380661) (xy 122.547857 -243.370817) (xy 122.597032 -243.368836) (xy 122.645887 -243.374768)
			(xy 122.693158 -243.38846) (xy 122.73762 -243.409558) (xy 122.778123 -243.437514) (xy 122.813616 -243.471606)
			(xy 122.843181 -243.51095) (xy 122.866052 -243.554527) (xy 122.881636 -243.601208) (xy 122.889531 -243.649785)
			(xy 122.890026 -243.674392) (xy 123.218968 -243.674392) (xy 123.222928 -243.625338) (xy 123.234705 -243.577554)
			(xy 123.253996 -243.532278) (xy 123.280299 -243.490682) (xy 123.312934 -243.453845) (xy 123.351055 -243.42272)
			(xy 123.393676 -243.398113) (xy 123.439692 -243.380661) (xy 123.487911 -243.370817) (xy 123.537086 -243.368836)
			(xy 123.585941 -243.374768) (xy 123.633212 -243.38846) (xy 123.677674 -243.409558) (xy 123.718177 -243.437514)
			(xy 123.75367 -243.471606) (xy 123.783235 -243.51095) (xy 123.806106 -243.554527) (xy 123.82169 -243.601208)
			(xy 123.829585 -243.649785) (xy 123.83008 -243.674392) (xy 124.159022 -243.674392) (xy 124.162982 -243.625338)
			(xy 124.174759 -243.577554) (xy 124.19405 -243.532278) (xy 124.220353 -243.490682) (xy 124.252988 -243.453845)
			(xy 124.291109 -243.42272) (xy 124.33373 -243.398113) (xy 124.379746 -243.380661) (xy 124.427965 -243.370817)
			(xy 124.47714 -243.368836) (xy 124.525995 -243.374768) (xy 124.573266 -243.38846) (xy 124.617728 -243.409558)
			(xy 124.658231 -243.437514) (xy 124.693724 -243.471606) (xy 124.723289 -243.51095) (xy 124.74616 -243.554527)
			(xy 124.761744 -243.601208) (xy 124.769639 -243.649785) (xy 124.770134 -243.674392) (xy 125.098822 -243.674392)
			(xy 125.102782 -243.625338) (xy 125.114559 -243.577554) (xy 125.13385 -243.532278) (xy 125.160153 -243.490682)
			(xy 125.192788 -243.453845) (xy 125.230909 -243.42272) (xy 125.27353 -243.398113) (xy 125.319546 -243.380661)
			(xy 125.367765 -243.370817) (xy 125.41694 -243.368836) (xy 125.465795 -243.374768) (xy 125.513066 -243.38846)
			(xy 125.557528 -243.409558) (xy 125.598031 -243.437514) (xy 125.633524 -243.471606) (xy 125.663089 -243.51095)
			(xy 125.68596 -243.554527) (xy 125.701544 -243.601208) (xy 125.709439 -243.649785) (xy 125.709934 -243.674392)
			(xy 126.038876 -243.674392) (xy 126.042836 -243.625338) (xy 126.054613 -243.577554) (xy 126.073904 -243.532278)
			(xy 126.100207 -243.490682) (xy 126.132842 -243.453845) (xy 126.170963 -243.42272) (xy 126.213584 -243.398113)
			(xy 126.2596 -243.380661) (xy 126.307819 -243.370817) (xy 126.356994 -243.368836) (xy 126.405849 -243.374768)
			(xy 126.45312 -243.38846) (xy 126.497582 -243.409558) (xy 126.538085 -243.437514) (xy 126.573578 -243.471606)
			(xy 126.603143 -243.51095) (xy 126.626014 -243.554527) (xy 126.641598 -243.601208) (xy 126.649493 -243.649785)
			(xy 126.649988 -243.674392) (xy 126.97893 -243.674392) (xy 126.98289 -243.625338) (xy 126.994667 -243.577554)
			(xy 127.013958 -243.532278) (xy 127.040261 -243.490682) (xy 127.072896 -243.453845) (xy 127.111017 -243.42272)
			(xy 127.153638 -243.398113) (xy 127.199654 -243.380661) (xy 127.247873 -243.370817) (xy 127.297048 -243.368836)
			(xy 127.345903 -243.374768) (xy 127.393174 -243.38846) (xy 127.437636 -243.409558) (xy 127.478139 -243.437514)
			(xy 127.513632 -243.471606) (xy 127.543197 -243.51095) (xy 127.566068 -243.554527) (xy 127.581652 -243.601208)
			(xy 127.589547 -243.649785) (xy 127.590042 -243.674392) (xy 127.908553 -243.674392) (xy 127.912648 -243.623664)
			(xy 127.924827 -243.57425) (xy 127.944775 -243.52743) (xy 127.971976 -243.484416) (xy 128.005724 -243.446322)
			(xy 128.045146 -243.414135) (xy 128.08922 -243.388689) (xy 128.136806 -243.370642) (xy 128.18667 -243.360462)
			(xy 128.237522 -243.358413) (xy 128.288043 -243.364547) (xy 128.336927 -243.378707) (xy 128.382906 -243.400524)
			(xy 128.42479 -243.429434) (xy 128.461494 -243.464689) (xy 128.492067 -243.505375) (xy 128.515718 -243.550438)
			(xy 128.531834 -243.598712) (xy 128.539998 -243.648946) (xy 128.54051 -243.674392) (xy 128.848607 -243.674392)
			(xy 128.852702 -243.623664) (xy 128.864881 -243.57425) (xy 128.884829 -243.52743) (xy 128.91203 -243.484416)
			(xy 128.945778 -243.446322) (xy 128.9852 -243.414135) (xy 129.029274 -243.388689) (xy 129.07686 -243.370642)
			(xy 129.126724 -243.360462) (xy 129.177576 -243.358413) (xy 129.228097 -243.364547) (xy 129.276981 -243.378707)
			(xy 129.32296 -243.400524) (xy 129.364844 -243.429434) (xy 129.401548 -243.464689) (xy 129.432121 -243.505375)
			(xy 129.455772 -243.550438) (xy 129.471888 -243.598712) (xy 129.480052 -243.648946) (xy 129.480564 -243.674392)
			(xy 129.480052 -243.699838) (xy 129.471888 -243.750072) (xy 129.455772 -243.798346) (xy 129.432121 -243.843409)
			(xy 129.401548 -243.884095) (xy 129.364844 -243.91935) (xy 129.32296 -243.94826) (xy 129.276981 -243.970077)
			(xy 129.228097 -243.984237) (xy 129.177576 -243.990371) (xy 129.126724 -243.988322) (xy 129.07686 -243.978142)
			(xy 129.029274 -243.960095) (xy 128.9852 -243.934649) (xy 128.945778 -243.902462) (xy 128.91203 -243.864368)
			(xy 128.884829 -243.821354) (xy 128.864881 -243.774534) (xy 128.852702 -243.72512) (xy 128.848607 -243.674392)
			(xy 128.54051 -243.674392) (xy 128.539998 -243.699838) (xy 128.531834 -243.750072) (xy 128.515718 -243.798346)
			(xy 128.492067 -243.843409) (xy 128.461494 -243.884095) (xy 128.42479 -243.91935) (xy 128.382906 -243.94826)
			(xy 128.336927 -243.970077) (xy 128.288043 -243.984237) (xy 128.237522 -243.990371) (xy 128.18667 -243.988322)
			(xy 128.136806 -243.978142) (xy 128.08922 -243.960095) (xy 128.045146 -243.934649) (xy 128.005724 -243.902462)
			(xy 127.971976 -243.864368) (xy 127.944775 -243.821354) (xy 127.924827 -243.774534) (xy 127.912648 -243.72512)
			(xy 127.908553 -243.674392) (xy 127.590042 -243.674392) (xy 127.589547 -243.698999) (xy 127.581652 -243.747576)
			(xy 127.566068 -243.794257) (xy 127.543197 -243.837834) (xy 127.513632 -243.877178) (xy 127.478139 -243.91127)
			(xy 127.437636 -243.939226) (xy 127.393174 -243.960324) (xy 127.345903 -243.974016) (xy 127.297048 -243.979948)
			(xy 127.247873 -243.977967) (xy 127.199654 -243.968123) (xy 127.153638 -243.950671) (xy 127.111017 -243.926064)
			(xy 127.072896 -243.894939) (xy 127.040261 -243.858102) (xy 127.013958 -243.816506) (xy 126.994667 -243.77123)
			(xy 126.98289 -243.723446) (xy 126.97893 -243.674392) (xy 126.649988 -243.674392) (xy 126.649493 -243.698999)
			(xy 126.641598 -243.747576) (xy 126.626014 -243.794257) (xy 126.603143 -243.837834) (xy 126.573578 -243.877178)
			(xy 126.538085 -243.91127) (xy 126.497582 -243.939226) (xy 126.45312 -243.960324) (xy 126.405849 -243.974016)
			(xy 126.356994 -243.979948) (xy 126.307819 -243.977967) (xy 126.2596 -243.968123) (xy 126.213584 -243.950671)
			(xy 126.170963 -243.926064) (xy 126.132842 -243.894939) (xy 126.100207 -243.858102) (xy 126.073904 -243.816506)
			(xy 126.054613 -243.77123) (xy 126.042836 -243.723446) (xy 126.038876 -243.674392) (xy 125.709934 -243.674392)
			(xy 125.709439 -243.698999) (xy 125.701544 -243.747576) (xy 125.68596 -243.794257) (xy 125.663089 -243.837834)
			(xy 125.633524 -243.877178) (xy 125.598031 -243.91127) (xy 125.557528 -243.939226) (xy 125.513066 -243.960324)
			(xy 125.465795 -243.974016) (xy 125.41694 -243.979948) (xy 125.367765 -243.977967) (xy 125.319546 -243.968123)
			(xy 125.27353 -243.950671) (xy 125.230909 -243.926064) (xy 125.192788 -243.894939) (xy 125.160153 -243.858102)
			(xy 125.13385 -243.816506) (xy 125.114559 -243.77123) (xy 125.102782 -243.723446) (xy 125.098822 -243.674392)
			(xy 124.770134 -243.674392) (xy 124.769639 -243.698999) (xy 124.761744 -243.747576) (xy 124.74616 -243.794257)
			(xy 124.723289 -243.837834) (xy 124.693724 -243.877178) (xy 124.658231 -243.91127) (xy 124.617728 -243.939226)
			(xy 124.573266 -243.960324) (xy 124.525995 -243.974016) (xy 124.47714 -243.979948) (xy 124.427965 -243.977967)
			(xy 124.379746 -243.968123) (xy 124.33373 -243.950671) (xy 124.291109 -243.926064) (xy 124.252988 -243.894939)
			(xy 124.220353 -243.858102) (xy 124.19405 -243.816506) (xy 124.174759 -243.77123) (xy 124.162982 -243.723446)
			(xy 124.159022 -243.674392) (xy 123.83008 -243.674392) (xy 123.829585 -243.698999) (xy 123.82169 -243.747576)
			(xy 123.806106 -243.794257) (xy 123.783235 -243.837834) (xy 123.75367 -243.877178) (xy 123.718177 -243.91127)
			(xy 123.677674 -243.939226) (xy 123.633212 -243.960324) (xy 123.585941 -243.974016) (xy 123.537086 -243.979948)
			(xy 123.487911 -243.977967) (xy 123.439692 -243.968123) (xy 123.393676 -243.950671) (xy 123.351055 -243.926064)
			(xy 123.312934 -243.894939) (xy 123.280299 -243.858102) (xy 123.253996 -243.816506) (xy 123.234705 -243.77123)
			(xy 123.222928 -243.723446) (xy 123.218968 -243.674392) (xy 122.890026 -243.674392) (xy 122.889531 -243.698999)
			(xy 122.881636 -243.747576) (xy 122.866052 -243.794257) (xy 122.843181 -243.837834) (xy 122.813616 -243.877178)
			(xy 122.778123 -243.91127) (xy 122.73762 -243.939226) (xy 122.693158 -243.960324) (xy 122.645887 -243.974016)
			(xy 122.597032 -243.979948) (xy 122.547857 -243.977967) (xy 122.499638 -243.968123) (xy 122.453622 -243.950671)
			(xy 122.411001 -243.926064) (xy 122.37288 -243.894939) (xy 122.340245 -243.858102) (xy 122.313942 -243.816506)
			(xy 122.294651 -243.77123) (xy 122.282874 -243.723446) (xy 122.278914 -243.674392) (xy 121.949972 -243.674392)
			(xy 121.949477 -243.698999) (xy 121.941582 -243.747576) (xy 121.925998 -243.794257) (xy 121.903127 -243.837834)
			(xy 121.873562 -243.877178) (xy 121.838069 -243.91127) (xy 121.797566 -243.939226) (xy 121.753104 -243.960324)
			(xy 121.705833 -243.974016) (xy 121.656978 -243.979948) (xy 121.607803 -243.977967) (xy 121.559584 -243.968123)
			(xy 121.513568 -243.950671) (xy 121.470947 -243.926064) (xy 121.432826 -243.894939) (xy 121.400191 -243.858102)
			(xy 121.373888 -243.816506) (xy 121.354597 -243.77123) (xy 121.34282 -243.723446) (xy 121.33886 -243.674392)
			(xy 121.009918 -243.674392) (xy 121.009423 -243.698999) (xy 121.001528 -243.747576) (xy 120.985944 -243.794257)
			(xy 120.963073 -243.837834) (xy 120.933508 -243.877178) (xy 120.898015 -243.91127) (xy 120.857512 -243.939226)
			(xy 120.81305 -243.960324) (xy 120.765779 -243.974016) (xy 120.716924 -243.979948) (xy 120.667749 -243.977967)
			(xy 120.61953 -243.968123) (xy 120.573514 -243.950671) (xy 120.530893 -243.926064) (xy 120.492772 -243.894939)
			(xy 120.460137 -243.858102) (xy 120.433834 -243.816506) (xy 120.414543 -243.77123) (xy 120.402766 -243.723446)
			(xy 120.398806 -243.674392) (xy 120.070118 -243.674392) (xy 120.069623 -243.698999) (xy 120.061728 -243.747576)
			(xy 120.046144 -243.794257) (xy 120.023273 -243.837834) (xy 119.993708 -243.877178) (xy 119.958215 -243.91127)
			(xy 119.917712 -243.939226) (xy 119.87325 -243.960324) (xy 119.825979 -243.974016) (xy 119.777124 -243.979948)
			(xy 119.727949 -243.977967) (xy 119.67973 -243.968123) (xy 119.633714 -243.950671) (xy 119.591093 -243.926064)
			(xy 119.552972 -243.894939) (xy 119.520337 -243.858102) (xy 119.494034 -243.816506) (xy 119.474743 -243.77123)
			(xy 119.462966 -243.723446) (xy 119.459006 -243.674392) (xy 119.130064 -243.674392) (xy 119.129569 -243.698999)
			(xy 119.121674 -243.747576) (xy 119.10609 -243.794257) (xy 119.083219 -243.837834) (xy 119.053654 -243.877178)
			(xy 119.018161 -243.91127) (xy 118.977658 -243.939226) (xy 118.933196 -243.960324) (xy 118.885925 -243.974016)
			(xy 118.83707 -243.979948) (xy 118.787895 -243.977967) (xy 118.739676 -243.968123) (xy 118.69366 -243.950671)
			(xy 118.651039 -243.926064) (xy 118.612918 -243.894939) (xy 118.580283 -243.858102) (xy 118.55398 -243.816506)
			(xy 118.534689 -243.77123) (xy 118.522912 -243.723446) (xy 118.518952 -243.674392) (xy 118.19001 -243.674392)
			(xy 118.189515 -243.698999) (xy 118.18162 -243.747576) (xy 118.166036 -243.794257) (xy 118.143165 -243.837834)
			(xy 118.1136 -243.877178) (xy 118.078107 -243.91127) (xy 118.037604 -243.939226) (xy 117.993142 -243.960324)
			(xy 117.945871 -243.974016) (xy 117.897016 -243.979948) (xy 117.847841 -243.977967) (xy 117.799622 -243.968123)
			(xy 117.753606 -243.950671) (xy 117.710985 -243.926064) (xy 117.672864 -243.894939) (xy 117.640229 -243.858102)
			(xy 117.613926 -243.816506) (xy 117.594635 -243.77123) (xy 117.582858 -243.723446) (xy 117.578898 -243.674392)
			(xy 117.249956 -243.674392) (xy 117.249461 -243.698999) (xy 117.241566 -243.747576) (xy 117.225982 -243.794257)
			(xy 117.203111 -243.837834) (xy 117.173546 -243.877178) (xy 117.138053 -243.91127) (xy 117.09755 -243.939226)
			(xy 117.053088 -243.960324) (xy 117.005817 -243.974016) (xy 116.956962 -243.979948) (xy 116.907787 -243.977967)
			(xy 116.859568 -243.968123) (xy 116.813552 -243.950671) (xy 116.770931 -243.926064) (xy 116.73281 -243.894939)
			(xy 116.700175 -243.858102) (xy 116.673872 -243.816506) (xy 116.654581 -243.77123) (xy 116.642804 -243.723446)
			(xy 116.638844 -243.674392) (xy 116.310156 -243.674392) (xy 116.309661 -243.698999) (xy 116.301766 -243.747576)
			(xy 116.286182 -243.794257) (xy 116.263311 -243.837834) (xy 116.233746 -243.877178) (xy 116.198253 -243.91127)
			(xy 116.15775 -243.939226) (xy 116.113288 -243.960324) (xy 116.066017 -243.974016) (xy 116.017162 -243.979948)
			(xy 115.967987 -243.977967) (xy 115.919768 -243.968123) (xy 115.873752 -243.950671) (xy 115.831131 -243.926064)
			(xy 115.79301 -243.894939) (xy 115.760375 -243.858102) (xy 115.734072 -243.816506) (xy 115.714781 -243.77123)
			(xy 115.703004 -243.723446) (xy 115.699044 -243.674392) (xy 115.370102 -243.674392) (xy 115.369607 -243.698999)
			(xy 115.361712 -243.747576) (xy 115.346128 -243.794257) (xy 115.323257 -243.837834) (xy 115.293692 -243.877178)
			(xy 115.258199 -243.91127) (xy 115.217696 -243.939226) (xy 115.173234 -243.960324) (xy 115.125963 -243.974016)
			(xy 115.077108 -243.979948) (xy 115.027933 -243.977967) (xy 114.979714 -243.968123) (xy 114.933698 -243.950671)
			(xy 114.891077 -243.926064) (xy 114.852956 -243.894939) (xy 114.820321 -243.858102) (xy 114.794018 -243.816506)
			(xy 114.774727 -243.77123) (xy 114.76295 -243.723446) (xy 114.75899 -243.674392) (xy 114.430048 -243.674392)
			(xy 114.429553 -243.698999) (xy 114.421658 -243.747576) (xy 114.406074 -243.794257) (xy 114.383203 -243.837834)
			(xy 114.353638 -243.877178) (xy 114.318145 -243.91127) (xy 114.277642 -243.939226) (xy 114.23318 -243.960324)
			(xy 114.185909 -243.974016) (xy 114.137054 -243.979948) (xy 114.087879 -243.977967) (xy 114.03966 -243.968123)
			(xy 113.993644 -243.950671) (xy 113.951023 -243.926064) (xy 113.912902 -243.894939) (xy 113.880267 -243.858102)
			(xy 113.853964 -243.816506) (xy 113.834673 -243.77123) (xy 113.822896 -243.723446) (xy 113.818936 -243.674392)
			(xy 113.489994 -243.674392) (xy 113.489499 -243.698999) (xy 113.481604 -243.747576) (xy 113.46602 -243.794257)
			(xy 113.443149 -243.837834) (xy 113.413584 -243.877178) (xy 113.378091 -243.91127) (xy 113.337588 -243.939226)
			(xy 113.293126 -243.960324) (xy 113.245855 -243.974016) (xy 113.197 -243.979948) (xy 113.147825 -243.977967)
			(xy 113.099606 -243.968123) (xy 113.05359 -243.950671) (xy 113.010969 -243.926064) (xy 112.972848 -243.894939)
			(xy 112.940213 -243.858102) (xy 112.91391 -243.816506) (xy 112.894619 -243.77123) (xy 112.882842 -243.723446)
			(xy 112.878882 -243.674392) (xy 110.676436 -243.674392) (xy 110.675941 -243.698999) (xy 110.668046 -243.747576)
			(xy 110.652462 -243.794257) (xy 110.629591 -243.837834) (xy 110.600026 -243.877178) (xy 110.564533 -243.91127)
			(xy 110.52403 -243.939226) (xy 110.479568 -243.960324) (xy 110.432297 -243.974016) (xy 110.383442 -243.979948)
			(xy 110.334267 -243.977967) (xy 110.286048 -243.968123) (xy 110.240032 -243.950671) (xy 110.197411 -243.926064)
			(xy 110.15929 -243.894939) (xy 110.126655 -243.858102) (xy 110.100352 -243.816506) (xy 110.081061 -243.77123)
			(xy 110.069284 -243.723446) (xy 110.065324 -243.674392) (xy 109.736951 -243.674392) (xy 109.736952 -243.6744)
			(xy 109.73278 -243.724744) (xy 109.720378 -243.773715) (xy 109.700085 -243.819977) (xy 109.672453 -243.862267)
			(xy 109.638238 -243.899432) (xy 109.598371 -243.930458) (xy 109.553942 -243.954499) (xy 109.506161 -243.970898)
			(xy 109.456332 -243.979209) (xy 109.431074 -243.9797) (xy 108.49102 -243.9797) (xy 108.465761 -243.979225)
			(xy 108.41593 -243.970913) (xy 108.368148 -243.954512) (xy 108.323717 -243.930469) (xy 108.283849 -243.899442)
			(xy 108.249632 -243.862275) (xy 108.222 -243.819983) (xy 108.201706 -243.773719) (xy 108.189304 -243.724746)
			(xy 108.185132 -243.6744) (xy 107.856274 -243.6744) (xy 107.855779 -243.698999) (xy 107.847884 -243.747576)
			(xy 107.8323 -243.794257) (xy 107.809429 -243.837834) (xy 107.779864 -243.877178) (xy 107.744371 -243.91127)
			(xy 107.703868 -243.939226) (xy 107.659406 -243.960324) (xy 107.612135 -243.974016) (xy 107.56328 -243.979948)
			(xy 107.514105 -243.977967) (xy 107.465886 -243.968123) (xy 107.41987 -243.950671) (xy 107.377249 -243.926064)
			(xy 107.339128 -243.894939) (xy 107.306493 -243.858102) (xy 107.28019 -243.816506) (xy 107.260899 -243.77123)
			(xy 107.249122 -243.723446) (xy 107.245162 -243.674392) (xy 106.916474 -243.674392) (xy 106.915979 -243.698999)
			(xy 106.908084 -243.747576) (xy 106.8925 -243.794257) (xy 106.869629 -243.837834) (xy 106.840064 -243.877178)
			(xy 106.804571 -243.91127) (xy 106.764068 -243.939226) (xy 106.719606 -243.960324) (xy 106.672335 -243.974016)
			(xy 106.62348 -243.979948) (xy 106.574305 -243.977967) (xy 106.526086 -243.968123) (xy 106.48007 -243.950671)
			(xy 106.437449 -243.926064) (xy 106.399328 -243.894939) (xy 106.366693 -243.858102) (xy 106.34039 -243.816506)
			(xy 106.321099 -243.77123) (xy 106.309322 -243.723446) (xy 106.305362 -243.674392) (xy 105.97642 -243.674392)
			(xy 105.975925 -243.698999) (xy 105.96803 -243.747576) (xy 105.952446 -243.794257) (xy 105.929575 -243.837834)
			(xy 105.90001 -243.877178) (xy 105.864517 -243.91127) (xy 105.824014 -243.939226) (xy 105.779552 -243.960324)
			(xy 105.732281 -243.974016) (xy 105.683426 -243.979948) (xy 105.634251 -243.977967) (xy 105.586032 -243.968123)
			(xy 105.540016 -243.950671) (xy 105.497395 -243.926064) (xy 105.459274 -243.894939) (xy 105.426639 -243.858102)
			(xy 105.400336 -243.816506) (xy 105.381045 -243.77123) (xy 105.369268 -243.723446) (xy 105.365308 -243.674392)
			(xy 105.036366 -243.674392) (xy 105.035871 -243.698999) (xy 105.027976 -243.747576) (xy 105.012392 -243.794257)
			(xy 104.989521 -243.837834) (xy 104.959956 -243.877178) (xy 104.924463 -243.91127) (xy 104.88396 -243.939226)
			(xy 104.839498 -243.960324) (xy 104.792227 -243.974016) (xy 104.743372 -243.979948) (xy 104.694197 -243.977967)
			(xy 104.645978 -243.968123) (xy 104.599962 -243.950671) (xy 104.557341 -243.926064) (xy 104.51922 -243.894939)
			(xy 104.486585 -243.858102) (xy 104.460282 -243.816506) (xy 104.440991 -243.77123) (xy 104.429214 -243.723446)
			(xy 104.425254 -243.674392) (xy 104.096312 -243.674392) (xy 104.095817 -243.698999) (xy 104.087922 -243.747576)
			(xy 104.072338 -243.794257) (xy 104.049467 -243.837834) (xy 104.019902 -243.877178) (xy 103.984409 -243.91127)
			(xy 103.943906 -243.939226) (xy 103.899444 -243.960324) (xy 103.852173 -243.974016) (xy 103.803318 -243.979948)
			(xy 103.754143 -243.977967) (xy 103.705924 -243.968123) (xy 103.659908 -243.950671) (xy 103.617287 -243.926064)
			(xy 103.579166 -243.894939) (xy 103.546531 -243.858102) (xy 103.520228 -243.816506) (xy 103.500937 -243.77123)
			(xy 103.48916 -243.723446) (xy 103.4852 -243.674392) (xy 103.156258 -243.674392) (xy 103.155763 -243.698999)
			(xy 103.147868 -243.747576) (xy 103.132284 -243.794257) (xy 103.109413 -243.837834) (xy 103.079848 -243.877178)
			(xy 103.044355 -243.91127) (xy 103.003852 -243.939226) (xy 102.95939 -243.960324) (xy 102.912119 -243.974016)
			(xy 102.863264 -243.979948) (xy 102.814089 -243.977967) (xy 102.76587 -243.968123) (xy 102.719854 -243.950671)
			(xy 102.677233 -243.926064) (xy 102.639112 -243.894939) (xy 102.606477 -243.858102) (xy 102.580174 -243.816506)
			(xy 102.560883 -243.77123) (xy 102.549106 -243.723446) (xy 102.545146 -243.674392) (xy 102.216458 -243.674392)
			(xy 102.215963 -243.698999) (xy 102.208068 -243.747576) (xy 102.192484 -243.794257) (xy 102.169613 -243.837834)
			(xy 102.140048 -243.877178) (xy 102.104555 -243.91127) (xy 102.064052 -243.939226) (xy 102.01959 -243.960324)
			(xy 101.972319 -243.974016) (xy 101.923464 -243.979948) (xy 101.874289 -243.977967) (xy 101.82607 -243.968123)
			(xy 101.780054 -243.950671) (xy 101.737433 -243.926064) (xy 101.699312 -243.894939) (xy 101.666677 -243.858102)
			(xy 101.640374 -243.816506) (xy 101.621083 -243.77123) (xy 101.609306 -243.723446) (xy 101.605346 -243.674392)
			(xy 101.276404 -243.674392) (xy 101.275909 -243.698999) (xy 101.268014 -243.747576) (xy 101.25243 -243.794257)
			(xy 101.229559 -243.837834) (xy 101.199994 -243.877178) (xy 101.164501 -243.91127) (xy 101.123998 -243.939226)
			(xy 101.079536 -243.960324) (xy 101.032265 -243.974016) (xy 100.98341 -243.979948) (xy 100.934235 -243.977967)
			(xy 100.886016 -243.968123) (xy 100.84 -243.950671) (xy 100.797379 -243.926064) (xy 100.759258 -243.894939)
			(xy 100.726623 -243.858102) (xy 100.70032 -243.816506) (xy 100.681029 -243.77123) (xy 100.669252 -243.723446)
			(xy 100.665292 -243.674392) (xy 100.33635 -243.674392) (xy 100.335855 -243.698999) (xy 100.32796 -243.747576)
			(xy 100.312376 -243.794257) (xy 100.289505 -243.837834) (xy 100.25994 -243.877178) (xy 100.224447 -243.91127)
			(xy 100.183944 -243.939226) (xy 100.139482 -243.960324) (xy 100.092211 -243.974016) (xy 100.043356 -243.979948)
			(xy 99.994181 -243.977967) (xy 99.945962 -243.968123) (xy 99.899946 -243.950671) (xy 99.857325 -243.926064)
			(xy 99.819204 -243.894939) (xy 99.786569 -243.858102) (xy 99.760266 -243.816506) (xy 99.740975 -243.77123)
			(xy 99.729198 -243.723446) (xy 99.725238 -243.674392) (xy 99.396296 -243.674392) (xy 99.395801 -243.698999)
			(xy 99.387906 -243.747576) (xy 99.372322 -243.794257) (xy 99.349451 -243.837834) (xy 99.319886 -243.877178)
			(xy 99.284393 -243.91127) (xy 99.24389 -243.939226) (xy 99.199428 -243.960324) (xy 99.152157 -243.974016)
			(xy 99.103302 -243.979948) (xy 99.054127 -243.977967) (xy 99.005908 -243.968123) (xy 98.959892 -243.950671)
			(xy 98.917271 -243.926064) (xy 98.87915 -243.894939) (xy 98.846515 -243.858102) (xy 98.820212 -243.816506)
			(xy 98.800921 -243.77123) (xy 98.789144 -243.723446) (xy 98.785184 -243.674392) (xy 98.456242 -243.674392)
			(xy 98.455747 -243.698999) (xy 98.447852 -243.747576) (xy 98.432268 -243.794257) (xy 98.409397 -243.837834)
			(xy 98.379832 -243.877178) (xy 98.344339 -243.91127) (xy 98.303836 -243.939226) (xy 98.259374 -243.960324)
			(xy 98.212103 -243.974016) (xy 98.163248 -243.979948) (xy 98.114073 -243.977967) (xy 98.065854 -243.968123)
			(xy 98.019838 -243.950671) (xy 97.977217 -243.926064) (xy 97.939096 -243.894939) (xy 97.906461 -243.858102)
			(xy 97.880158 -243.816506) (xy 97.860867 -243.77123) (xy 97.84909 -243.723446) (xy 97.84513 -243.674392)
			(xy 97.516938 -243.674392) (xy 97.516939 -243.6744) (xy 97.512768 -243.724736) (xy 97.50037 -243.773699)
			(xy 97.480082 -243.819954) (xy 97.452459 -243.862239) (xy 97.418252 -243.899401) (xy 97.378396 -243.930426)
			(xy 97.333977 -243.954469) (xy 97.286207 -243.970873) (xy 97.236388 -243.979192) (xy 97.211134 -243.9797)
			(xy 97.186645 -243.979216) (xy 97.138295 -243.971397) (xy 97.091816 -243.955955) (xy 97.0484 -243.933285)
			(xy 97.028508 -243.918994) (xy 97.016824 -243.910358) (xy 96.988376 -243.907818) (xy 96.896174 -243.954046)
			(xy 96.892364 -243.956332) (xy 96.882296 -243.963408) (xy 96.869689 -243.984499) (xy 96.868234 -243.996718)
			(xy 96.868234 -244.189504) (xy 96.881696 -244.212872) (xy 96.893634 -244.21973) (xy 96.914743 -244.232446)
			(xy 96.952926 -244.263595) (xy 96.985615 -244.300468) (xy 97.011963 -244.342109) (xy 97.031286 -244.387439)
			(xy 97.043084 -244.435282) (xy 97.047051 -244.484399) (xy 97.047051 -244.4844) (xy 97.374883 -244.4844)
			(xy 97.379059 -244.434011) (xy 97.391472 -244.384997) (xy 97.411784 -244.338695) (xy 97.43944 -244.296368)
			(xy 97.473686 -244.259171) (xy 97.513588 -244.228118) (xy 97.558057 -244.204057) (xy 97.605881 -244.187644)
			(xy 97.655753 -244.179326) (xy 97.681034 -244.178836) (xy 98.621088 -244.178836) (xy 98.646367 -244.179332)
			(xy 98.696236 -244.187652) (xy 98.744056 -244.204067) (xy 98.788521 -244.228129) (xy 98.82842 -244.259181)
			(xy 98.862663 -244.296378) (xy 98.890316 -244.338703) (xy 98.910626 -244.385003) (xy 98.923037 -244.434014)
			(xy 98.927213 -244.484398) (xy 99.255338 -244.484398) (xy 99.259298 -244.435344) (xy 99.271075 -244.38756)
			(xy 99.290366 -244.342284) (xy 99.316669 -244.300688) (xy 99.349304 -244.263851) (xy 99.387425 -244.232726)
			(xy 99.430046 -244.208119) (xy 99.476062 -244.190667) (xy 99.524281 -244.180823) (xy 99.573456 -244.178842)
			(xy 99.622311 -244.184774) (xy 99.669582 -244.198466) (xy 99.714044 -244.219564) (xy 99.754547 -244.24752)
			(xy 99.79004 -244.281612) (xy 99.819605 -244.320956) (xy 99.842476 -244.364533) (xy 99.85806 -244.411214)
			(xy 99.865955 -244.459791) (xy 99.86645 -244.484398) (xy 99.86645 -244.4844) (xy 100.194783 -244.4844)
			(xy 100.198959 -244.434011) (xy 100.211373 -244.384996) (xy 100.231685 -244.338693) (xy 100.259342 -244.296365)
			(xy 100.293589 -244.259168) (xy 100.333492 -244.228115) (xy 100.377963 -244.204054) (xy 100.425787 -244.187642)
			(xy 100.475661 -244.179326) (xy 100.500942 -244.178836) (xy 101.440996 -244.178836) (xy 101.466275 -244.179333)
			(xy 101.516143 -244.187654) (xy 101.563961 -244.204069) (xy 101.608426 -244.228131) (xy 101.648323 -244.259184)
			(xy 101.682565 -244.29638) (xy 101.710217 -244.338705) (xy 101.730526 -244.385005) (xy 101.742937 -244.434015)
			(xy 101.747113 -244.484398) (xy 102.075246 -244.484398) (xy 102.079206 -244.435344) (xy 102.090983 -244.38756)
			(xy 102.110274 -244.342284) (xy 102.136577 -244.300688) (xy 102.169212 -244.263851) (xy 102.207333 -244.232726)
			(xy 102.249954 -244.208119) (xy 102.29597 -244.190667) (xy 102.344189 -244.180823) (xy 102.393364 -244.178842)
			(xy 102.442219 -244.184774) (xy 102.48949 -244.198466) (xy 102.533952 -244.219564) (xy 102.574455 -244.24752)
			(xy 102.609948 -244.281612) (xy 102.639513 -244.320956) (xy 102.662384 -244.364533) (xy 102.677968 -244.411214)
			(xy 102.685863 -244.459791) (xy 102.686358 -244.484398) (xy 102.686358 -244.4844) (xy 103.014983 -244.4844)
			(xy 103.019159 -244.434014) (xy 103.03157 -244.385003) (xy 103.051879 -244.338704) (xy 103.079532 -244.296378)
			(xy 103.113774 -244.259181) (xy 103.153672 -244.228128) (xy 103.198137 -244.204065) (xy 103.245956 -244.18765)
			(xy 103.295825 -244.179329) (xy 103.321104 -244.178836) (xy 104.261158 -244.178836) (xy 104.286439 -244.17933)
			(xy 104.336312 -244.187646) (xy 104.384136 -244.204058) (xy 104.428605 -244.228118) (xy 104.468508 -244.259171)
			(xy 104.502755 -244.296368) (xy 104.530412 -244.338695) (xy 104.550724 -244.384997) (xy 104.563137 -244.434011)
			(xy 104.567313 -244.484398) (xy 104.895154 -244.484398) (xy 104.899114 -244.435344) (xy 104.910891 -244.38756)
			(xy 104.930182 -244.342284) (xy 104.956485 -244.300688) (xy 104.98912 -244.263851) (xy 105.027241 -244.232726)
			(xy 105.069862 -244.208119) (xy 105.115878 -244.190667) (xy 105.164097 -244.180823) (xy 105.213272 -244.178842)
			(xy 105.262127 -244.184774) (xy 105.309398 -244.198466) (xy 105.35386 -244.219564) (xy 105.394363 -244.24752)
			(xy 105.429856 -244.281612) (xy 105.459421 -244.320956) (xy 105.482292 -244.364533) (xy 105.497876 -244.411214)
			(xy 105.505771 -244.459791) (xy 105.506266 -244.484398) (xy 105.506266 -244.4844) (xy 105.834883 -244.4844)
			(xy 105.839059 -244.434014) (xy 105.851471 -244.385002) (xy 105.87178 -244.338701) (xy 105.899434 -244.296375)
			(xy 105.933678 -244.259178) (xy 105.973577 -244.228125) (xy 106.018043 -244.204063) (xy 106.065863 -244.187648)
			(xy 106.115732 -244.179328) (xy 106.141012 -244.178836) (xy 107.081066 -244.178836) (xy 107.106346 -244.17933)
			(xy 107.156218 -244.187647) (xy 107.204041 -244.20406) (xy 107.24851 -244.228121) (xy 107.288411 -244.259174)
			(xy 107.322657 -244.29637) (xy 107.350313 -244.338697) (xy 107.370624 -244.384999) (xy 107.383037 -244.434012)
			(xy 107.387213 -244.484398) (xy 107.715316 -244.484398) (xy 107.719276 -244.435344) (xy 107.731053 -244.38756)
			(xy 107.750344 -244.342284) (xy 107.776647 -244.300688) (xy 107.809282 -244.263851) (xy 107.847403 -244.232726)
			(xy 107.890024 -244.208119) (xy 107.93604 -244.190667) (xy 107.984259 -244.180823) (xy 108.033434 -244.178842)
			(xy 108.082289 -244.184774) (xy 108.12956 -244.198466) (xy 108.174022 -244.219564) (xy 108.214525 -244.24752)
			(xy 108.250018 -244.281612) (xy 108.279583 -244.320956) (xy 108.302454 -244.364533) (xy 108.318038 -244.411214)
			(xy 108.325933 -244.459791) (xy 108.326428 -244.484398) (xy 108.65537 -244.484398) (xy 108.65933 -244.435344)
			(xy 108.671107 -244.38756) (xy 108.690398 -244.342284) (xy 108.716701 -244.300688) (xy 108.749336 -244.263851)
			(xy 108.787457 -244.232726) (xy 108.830078 -244.208119) (xy 108.876094 -244.190667) (xy 108.924313 -244.180823)
			(xy 108.973488 -244.178842) (xy 109.022343 -244.184774) (xy 109.069614 -244.198466) (xy 109.114076 -244.219564)
			(xy 109.154579 -244.24752) (xy 109.190072 -244.281612) (xy 109.219637 -244.320956) (xy 109.242508 -244.364533)
			(xy 109.258092 -244.411214) (xy 109.265987 -244.459791) (xy 109.266482 -244.484398) (xy 109.59517 -244.484398)
			(xy 109.59913 -244.435344) (xy 109.610907 -244.38756) (xy 109.630198 -244.342284) (xy 109.656501 -244.300688)
			(xy 109.689136 -244.263851) (xy 109.727257 -244.232726) (xy 109.769878 -244.208119) (xy 109.815894 -244.190667)
			(xy 109.864113 -244.180823) (xy 109.913288 -244.178842) (xy 109.962143 -244.184774) (xy 110.009414 -244.198466)
			(xy 110.053876 -244.219564) (xy 110.094379 -244.24752) (xy 110.129872 -244.281612) (xy 110.159437 -244.320956)
			(xy 110.182308 -244.364533) (xy 110.197892 -244.411214) (xy 110.205787 -244.459791) (xy 110.206282 -244.484398)
			(xy 113.349036 -244.484398) (xy 113.352996 -244.435344) (xy 113.364773 -244.38756) (xy 113.384064 -244.342284)
			(xy 113.410367 -244.300688) (xy 113.443002 -244.263851) (xy 113.481123 -244.232726) (xy 113.523744 -244.208119)
			(xy 113.56976 -244.190667) (xy 113.617979 -244.180823) (xy 113.667154 -244.178842) (xy 113.716009 -244.184774)
			(xy 113.76328 -244.198466) (xy 113.807742 -244.219564) (xy 113.848245 -244.24752) (xy 113.883738 -244.281612)
			(xy 113.913303 -244.320956) (xy 113.936174 -244.364533) (xy 113.951758 -244.411214) (xy 113.959653 -244.459791)
			(xy 113.960148 -244.484398) (xy 114.288836 -244.484398) (xy 114.292796 -244.435344) (xy 114.304573 -244.38756)
			(xy 114.323864 -244.342284) (xy 114.350167 -244.300688) (xy 114.382802 -244.263851) (xy 114.420923 -244.232726)
			(xy 114.463544 -244.208119) (xy 114.50956 -244.190667) (xy 114.557779 -244.180823) (xy 114.606954 -244.178842)
			(xy 114.655809 -244.184774) (xy 114.70308 -244.198466) (xy 114.747542 -244.219564) (xy 114.788045 -244.24752)
			(xy 114.823538 -244.281612) (xy 114.853103 -244.320956) (xy 114.875974 -244.364533) (xy 114.891558 -244.411214)
			(xy 114.899453 -244.459791) (xy 114.899948 -244.484398) (xy 115.22889 -244.484398) (xy 115.23285 -244.435344)
			(xy 115.244627 -244.38756) (xy 115.263918 -244.342284) (xy 115.290221 -244.300688) (xy 115.322856 -244.263851)
			(xy 115.360977 -244.232726) (xy 115.403598 -244.208119) (xy 115.449614 -244.190667) (xy 115.497833 -244.180823)
			(xy 115.547008 -244.178842) (xy 115.595863 -244.184774) (xy 115.643134 -244.198466) (xy 115.687596 -244.219564)
			(xy 115.728099 -244.24752) (xy 115.763592 -244.281612) (xy 115.793157 -244.320956) (xy 115.816028 -244.364533)
			(xy 115.831612 -244.411214) (xy 115.839507 -244.459791) (xy 115.840002 -244.484398) (xy 116.168944 -244.484398)
			(xy 116.172904 -244.435344) (xy 116.184681 -244.38756) (xy 116.203972 -244.342284) (xy 116.230275 -244.300688)
			(xy 116.26291 -244.263851) (xy 116.301031 -244.232726) (xy 116.343652 -244.208119) (xy 116.389668 -244.190667)
			(xy 116.437887 -244.180823) (xy 116.487062 -244.178842) (xy 116.535917 -244.184774) (xy 116.583188 -244.198466)
			(xy 116.62765 -244.219564) (xy 116.668153 -244.24752) (xy 116.703646 -244.281612) (xy 116.733211 -244.320956)
			(xy 116.756082 -244.364533) (xy 116.771666 -244.411214) (xy 116.779561 -244.459791) (xy 116.780056 -244.484398)
			(xy 117.108998 -244.484398) (xy 117.112958 -244.435344) (xy 117.124735 -244.38756) (xy 117.144026 -244.342284)
			(xy 117.170329 -244.300688) (xy 117.202964 -244.263851) (xy 117.241085 -244.232726) (xy 117.283706 -244.208119)
			(xy 117.329722 -244.190667) (xy 117.377941 -244.180823) (xy 117.427116 -244.178842) (xy 117.475971 -244.184774)
			(xy 117.523242 -244.198466) (xy 117.567704 -244.219564) (xy 117.608207 -244.24752) (xy 117.6437 -244.281612)
			(xy 117.673265 -244.320956) (xy 117.696136 -244.364533) (xy 117.71172 -244.411214) (xy 117.719615 -244.459791)
			(xy 117.72011 -244.484398) (xy 118.049052 -244.484398) (xy 118.053012 -244.435344) (xy 118.064789 -244.38756)
			(xy 118.08408 -244.342284) (xy 118.110383 -244.300688) (xy 118.143018 -244.263851) (xy 118.181139 -244.232726)
			(xy 118.22376 -244.208119) (xy 118.269776 -244.190667) (xy 118.317995 -244.180823) (xy 118.36717 -244.178842)
			(xy 118.416025 -244.184774) (xy 118.463296 -244.198466) (xy 118.507758 -244.219564) (xy 118.548261 -244.24752)
			(xy 118.583754 -244.281612) (xy 118.613319 -244.320956) (xy 118.63619 -244.364533) (xy 118.651774 -244.411214)
			(xy 118.659669 -244.459791) (xy 118.660164 -244.484398) (xy 118.988852 -244.484398) (xy 118.992812 -244.435344)
			(xy 119.004589 -244.38756) (xy 119.02388 -244.342284) (xy 119.050183 -244.300688) (xy 119.082818 -244.263851)
			(xy 119.120939 -244.232726) (xy 119.16356 -244.208119) (xy 119.209576 -244.190667) (xy 119.257795 -244.180823)
			(xy 119.30697 -244.178842) (xy 119.355825 -244.184774) (xy 119.403096 -244.198466) (xy 119.447558 -244.219564)
			(xy 119.488061 -244.24752) (xy 119.523554 -244.281612) (xy 119.553119 -244.320956) (xy 119.57599 -244.364533)
			(xy 119.591574 -244.411214) (xy 119.599469 -244.459791) (xy 119.599964 -244.484398) (xy 119.928906 -244.484398)
			(xy 119.932866 -244.435344) (xy 119.944643 -244.38756) (xy 119.963934 -244.342284) (xy 119.990237 -244.300688)
			(xy 120.022872 -244.263851) (xy 120.060993 -244.232726) (xy 120.103614 -244.208119) (xy 120.14963 -244.190667)
			(xy 120.197849 -244.180823) (xy 120.247024 -244.178842) (xy 120.295879 -244.184774) (xy 120.34315 -244.198466)
			(xy 120.387612 -244.219564) (xy 120.428115 -244.24752) (xy 120.463608 -244.281612) (xy 120.493173 -244.320956)
			(xy 120.516044 -244.364533) (xy 120.531628 -244.411214) (xy 120.539523 -244.459791) (xy 120.540018 -244.484398)
			(xy 120.86896 -244.484398) (xy 120.87292 -244.435344) (xy 120.884697 -244.38756) (xy 120.903988 -244.342284)
			(xy 120.930291 -244.300688) (xy 120.962926 -244.263851) (xy 121.001047 -244.232726) (xy 121.043668 -244.208119)
			(xy 121.089684 -244.190667) (xy 121.137903 -244.180823) (xy 121.187078 -244.178842) (xy 121.235933 -244.184774)
			(xy 121.283204 -244.198466) (xy 121.327666 -244.219564) (xy 121.368169 -244.24752) (xy 121.403662 -244.281612)
			(xy 121.433227 -244.320956) (xy 121.456098 -244.364533) (xy 121.471682 -244.411214) (xy 121.479577 -244.459791)
			(xy 121.480072 -244.484398) (xy 121.809014 -244.484398) (xy 121.812974 -244.435344) (xy 121.824751 -244.38756)
			(xy 121.844042 -244.342284) (xy 121.870345 -244.300688) (xy 121.90298 -244.263851) (xy 121.941101 -244.232726)
			(xy 121.983722 -244.208119) (xy 122.029738 -244.190667) (xy 122.077957 -244.180823) (xy 122.127132 -244.178842)
			(xy 122.175987 -244.184774) (xy 122.223258 -244.198466) (xy 122.26772 -244.219564) (xy 122.308223 -244.24752)
			(xy 122.343716 -244.281612) (xy 122.373281 -244.320956) (xy 122.396152 -244.364533) (xy 122.411736 -244.411214)
			(xy 122.419631 -244.459791) (xy 122.420126 -244.484398) (xy 122.748814 -244.484398) (xy 122.752774 -244.435344)
			(xy 122.764551 -244.38756) (xy 122.783842 -244.342284) (xy 122.810145 -244.300688) (xy 122.84278 -244.263851)
			(xy 122.880901 -244.232726) (xy 122.923522 -244.208119) (xy 122.969538 -244.190667) (xy 123.017757 -244.180823)
			(xy 123.066932 -244.178842) (xy 123.115787 -244.184774) (xy 123.163058 -244.198466) (xy 123.20752 -244.219564)
			(xy 123.248023 -244.24752) (xy 123.283516 -244.281612) (xy 123.313081 -244.320956) (xy 123.335952 -244.364533)
			(xy 123.351536 -244.411214) (xy 123.359431 -244.459791) (xy 123.359926 -244.484398) (xy 123.688868 -244.484398)
			(xy 123.692828 -244.435344) (xy 123.704605 -244.38756) (xy 123.723896 -244.342284) (xy 123.750199 -244.300688)
			(xy 123.782834 -244.263851) (xy 123.820955 -244.232726) (xy 123.863576 -244.208119) (xy 123.909592 -244.190667)
			(xy 123.957811 -244.180823) (xy 124.006986 -244.178842) (xy 124.055841 -244.184774) (xy 124.103112 -244.198466)
			(xy 124.147574 -244.219564) (xy 124.188077 -244.24752) (xy 124.22357 -244.281612) (xy 124.253135 -244.320956)
			(xy 124.276006 -244.364533) (xy 124.29159 -244.411214) (xy 124.299485 -244.459791) (xy 124.29998 -244.484398)
			(xy 124.628922 -244.484398) (xy 124.632882 -244.435344) (xy 124.644659 -244.38756) (xy 124.66395 -244.342284)
			(xy 124.690253 -244.300688) (xy 124.722888 -244.263851) (xy 124.761009 -244.232726) (xy 124.80363 -244.208119)
			(xy 124.849646 -244.190667) (xy 124.897865 -244.180823) (xy 124.94704 -244.178842) (xy 124.995895 -244.184774)
			(xy 125.043166 -244.198466) (xy 125.087628 -244.219564) (xy 125.128131 -244.24752) (xy 125.163624 -244.281612)
			(xy 125.193189 -244.320956) (xy 125.21606 -244.364533) (xy 125.231644 -244.411214) (xy 125.239539 -244.459791)
			(xy 125.240034 -244.484398) (xy 125.568976 -244.484398) (xy 125.572936 -244.435344) (xy 125.584713 -244.38756)
			(xy 125.604004 -244.342284) (xy 125.630307 -244.300688) (xy 125.662942 -244.263851) (xy 125.701063 -244.232726)
			(xy 125.743684 -244.208119) (xy 125.7897 -244.190667) (xy 125.837919 -244.180823) (xy 125.887094 -244.178842)
			(xy 125.935949 -244.184774) (xy 125.98322 -244.198466) (xy 126.027682 -244.219564) (xy 126.068185 -244.24752)
			(xy 126.103678 -244.281612) (xy 126.133243 -244.320956) (xy 126.156114 -244.364533) (xy 126.171698 -244.411214)
			(xy 126.179593 -244.459791) (xy 126.180088 -244.484398) (xy 126.50903 -244.484398) (xy 126.51299 -244.435344)
			(xy 126.524767 -244.38756) (xy 126.544058 -244.342284) (xy 126.570361 -244.300688) (xy 126.602996 -244.263851)
			(xy 126.641117 -244.232726) (xy 126.683738 -244.208119) (xy 126.729754 -244.190667) (xy 126.777973 -244.180823)
			(xy 126.827148 -244.178842) (xy 126.876003 -244.184774) (xy 126.923274 -244.198466) (xy 126.967736 -244.219564)
			(xy 127.008239 -244.24752) (xy 127.043732 -244.281612) (xy 127.073297 -244.320956) (xy 127.096168 -244.364533)
			(xy 127.111752 -244.411214) (xy 127.119647 -244.459791) (xy 127.120142 -244.484398) (xy 127.438399 -244.484398)
			(xy 127.442494 -244.43367) (xy 127.454673 -244.384256) (xy 127.474621 -244.337436) (xy 127.501822 -244.294422)
			(xy 127.53557 -244.256328) (xy 127.574992 -244.224141) (xy 127.619066 -244.198695) (xy 127.666652 -244.180648)
			(xy 127.716516 -244.170468) (xy 127.767368 -244.168419) (xy 127.817889 -244.174553) (xy 127.866773 -244.188713)
			(xy 127.912752 -244.21053) (xy 127.954636 -244.23944) (xy 127.99134 -244.274695) (xy 128.021913 -244.315381)
			(xy 128.045564 -244.360444) (xy 128.06168 -244.408718) (xy 128.069844 -244.458952) (xy 128.070356 -244.484398)
			(xy 128.388884 -244.484398) (xy 128.392844 -244.435344) (xy 128.404621 -244.38756) (xy 128.423912 -244.342284)
			(xy 128.450215 -244.300688) (xy 128.48285 -244.263851) (xy 128.520971 -244.232726) (xy 128.563592 -244.208119)
			(xy 128.609608 -244.190667) (xy 128.657827 -244.180823) (xy 128.707002 -244.178842) (xy 128.755857 -244.184774)
			(xy 128.803128 -244.198466) (xy 128.84759 -244.219564) (xy 128.888093 -244.24752) (xy 128.923586 -244.281612)
			(xy 128.953151 -244.320956) (xy 128.976022 -244.364533) (xy 128.991606 -244.411214) (xy 128.999501 -244.459791)
			(xy 128.999996 -244.484398) (xy 129.318507 -244.484398) (xy 129.322602 -244.43367) (xy 129.334781 -244.384256)
			(xy 129.354729 -244.337436) (xy 129.38193 -244.294422) (xy 129.415678 -244.256328) (xy 129.4551 -244.224141)
			(xy 129.499174 -244.198695) (xy 129.54676 -244.180648) (xy 129.596624 -244.170468) (xy 129.647476 -244.168419)
			(xy 129.697997 -244.174553) (xy 129.746881 -244.188713) (xy 129.79286 -244.21053) (xy 129.834744 -244.23944)
			(xy 129.871448 -244.274695) (xy 129.902021 -244.315381) (xy 129.925672 -244.360444) (xy 129.941788 -244.408718)
			(xy 129.949952 -244.458952) (xy 129.950464 -244.484398) (xy 129.949952 -244.509844) (xy 129.941788 -244.560078)
			(xy 129.925672 -244.608352) (xy 129.902021 -244.653415) (xy 129.871448 -244.694101) (xy 129.834744 -244.729356)
			(xy 129.79286 -244.758266) (xy 129.746881 -244.780083) (xy 129.697997 -244.794243) (xy 129.647476 -244.800377)
			(xy 129.596624 -244.798328) (xy 129.54676 -244.788148) (xy 129.499174 -244.770101) (xy 129.4551 -244.744655)
			(xy 129.415678 -244.712468) (xy 129.38193 -244.674374) (xy 129.354729 -244.63136) (xy 129.334781 -244.58454)
			(xy 129.322602 -244.535126) (xy 129.318507 -244.484398) (xy 128.999996 -244.484398) (xy 128.999501 -244.509005)
			(xy 128.991606 -244.557582) (xy 128.976022 -244.604263) (xy 128.953151 -244.64784) (xy 128.923586 -244.687184)
			(xy 128.888093 -244.721276) (xy 128.84759 -244.749232) (xy 128.803128 -244.77033) (xy 128.755857 -244.784022)
			(xy 128.707002 -244.789954) (xy 128.657827 -244.787973) (xy 128.609608 -244.778129) (xy 128.563592 -244.760677)
			(xy 128.520971 -244.73607) (xy 128.48285 -244.704945) (xy 128.450215 -244.668108) (xy 128.423912 -244.626512)
			(xy 128.404621 -244.581236) (xy 128.392844 -244.533452) (xy 128.388884 -244.484398) (xy 128.070356 -244.484398)
			(xy 128.069844 -244.509844) (xy 128.06168 -244.560078) (xy 128.045564 -244.608352) (xy 128.021913 -244.653415)
			(xy 127.99134 -244.694101) (xy 127.954636 -244.729356) (xy 127.912752 -244.758266) (xy 127.866773 -244.780083)
			(xy 127.817889 -244.794243) (xy 127.767368 -244.800377) (xy 127.716516 -244.798328) (xy 127.666652 -244.788148)
			(xy 127.619066 -244.770101) (xy 127.574992 -244.744655) (xy 127.53557 -244.712468) (xy 127.501822 -244.674374)
			(xy 127.474621 -244.63136) (xy 127.454673 -244.58454) (xy 127.442494 -244.535126) (xy 127.438399 -244.484398)
			(xy 127.120142 -244.484398) (xy 127.119647 -244.509005) (xy 127.111752 -244.557582) (xy 127.096168 -244.604263)
			(xy 127.073297 -244.64784) (xy 127.043732 -244.687184) (xy 127.008239 -244.721276) (xy 126.967736 -244.749232)
			(xy 126.923274 -244.77033) (xy 126.876003 -244.784022) (xy 126.827148 -244.789954) (xy 126.777973 -244.787973)
			(xy 126.729754 -244.778129) (xy 126.683738 -244.760677) (xy 126.641117 -244.73607) (xy 126.602996 -244.704945)
			(xy 126.570361 -244.668108) (xy 126.544058 -244.626512) (xy 126.524767 -244.581236) (xy 126.51299 -244.533452)
			(xy 126.50903 -244.484398) (xy 126.180088 -244.484398) (xy 126.179593 -244.509005) (xy 126.171698 -244.557582)
			(xy 126.156114 -244.604263) (xy 126.133243 -244.64784) (xy 126.103678 -244.687184) (xy 126.068185 -244.721276)
			(xy 126.027682 -244.749232) (xy 125.98322 -244.77033) (xy 125.935949 -244.784022) (xy 125.887094 -244.789954)
			(xy 125.837919 -244.787973) (xy 125.7897 -244.778129) (xy 125.743684 -244.760677) (xy 125.701063 -244.73607)
			(xy 125.662942 -244.704945) (xy 125.630307 -244.668108) (xy 125.604004 -244.626512) (xy 125.584713 -244.581236)
			(xy 125.572936 -244.533452) (xy 125.568976 -244.484398) (xy 125.240034 -244.484398) (xy 125.239539 -244.509005)
			(xy 125.231644 -244.557582) (xy 125.21606 -244.604263) (xy 125.193189 -244.64784) (xy 125.163624 -244.687184)
			(xy 125.128131 -244.721276) (xy 125.087628 -244.749232) (xy 125.043166 -244.77033) (xy 124.995895 -244.784022)
			(xy 124.94704 -244.789954) (xy 124.897865 -244.787973) (xy 124.849646 -244.778129) (xy 124.80363 -244.760677)
			(xy 124.761009 -244.73607) (xy 124.722888 -244.704945) (xy 124.690253 -244.668108) (xy 124.66395 -244.626512)
			(xy 124.644659 -244.581236) (xy 124.632882 -244.533452) (xy 124.628922 -244.484398) (xy 124.29998 -244.484398)
			(xy 124.299485 -244.509005) (xy 124.29159 -244.557582) (xy 124.276006 -244.604263) (xy 124.253135 -244.64784)
			(xy 124.22357 -244.687184) (xy 124.188077 -244.721276) (xy 124.147574 -244.749232) (xy 124.103112 -244.77033)
			(xy 124.055841 -244.784022) (xy 124.006986 -244.789954) (xy 123.957811 -244.787973) (xy 123.909592 -244.778129)
			(xy 123.863576 -244.760677) (xy 123.820955 -244.73607) (xy 123.782834 -244.704945) (xy 123.750199 -244.668108)
			(xy 123.723896 -244.626512) (xy 123.704605 -244.581236) (xy 123.692828 -244.533452) (xy 123.688868 -244.484398)
			(xy 123.359926 -244.484398) (xy 123.359431 -244.509005) (xy 123.351536 -244.557582) (xy 123.335952 -244.604263)
			(xy 123.313081 -244.64784) (xy 123.283516 -244.687184) (xy 123.248023 -244.721276) (xy 123.20752 -244.749232)
			(xy 123.163058 -244.77033) (xy 123.115787 -244.784022) (xy 123.066932 -244.789954) (xy 123.017757 -244.787973)
			(xy 122.969538 -244.778129) (xy 122.923522 -244.760677) (xy 122.880901 -244.73607) (xy 122.84278 -244.704945)
			(xy 122.810145 -244.668108) (xy 122.783842 -244.626512) (xy 122.764551 -244.581236) (xy 122.752774 -244.533452)
			(xy 122.748814 -244.484398) (xy 122.420126 -244.484398) (xy 122.419631 -244.509005) (xy 122.411736 -244.557582)
			(xy 122.396152 -244.604263) (xy 122.373281 -244.64784) (xy 122.343716 -244.687184) (xy 122.308223 -244.721276)
			(xy 122.26772 -244.749232) (xy 122.223258 -244.77033) (xy 122.175987 -244.784022) (xy 122.127132 -244.789954)
			(xy 122.077957 -244.787973) (xy 122.029738 -244.778129) (xy 121.983722 -244.760677) (xy 121.941101 -244.73607)
			(xy 121.90298 -244.704945) (xy 121.870345 -244.668108) (xy 121.844042 -244.626512) (xy 121.824751 -244.581236)
			(xy 121.812974 -244.533452) (xy 121.809014 -244.484398) (xy 121.480072 -244.484398) (xy 121.479577 -244.509005)
			(xy 121.471682 -244.557582) (xy 121.456098 -244.604263) (xy 121.433227 -244.64784) (xy 121.403662 -244.687184)
			(xy 121.368169 -244.721276) (xy 121.327666 -244.749232) (xy 121.283204 -244.77033) (xy 121.235933 -244.784022)
			(xy 121.187078 -244.789954) (xy 121.137903 -244.787973) (xy 121.089684 -244.778129) (xy 121.043668 -244.760677)
			(xy 121.001047 -244.73607) (xy 120.962926 -244.704945) (xy 120.930291 -244.668108) (xy 120.903988 -244.626512)
			(xy 120.884697 -244.581236) (xy 120.87292 -244.533452) (xy 120.86896 -244.484398) (xy 120.540018 -244.484398)
			(xy 120.539523 -244.509005) (xy 120.531628 -244.557582) (xy 120.516044 -244.604263) (xy 120.493173 -244.64784)
			(xy 120.463608 -244.687184) (xy 120.428115 -244.721276) (xy 120.387612 -244.749232) (xy 120.34315 -244.77033)
			(xy 120.295879 -244.784022) (xy 120.247024 -244.789954) (xy 120.197849 -244.787973) (xy 120.14963 -244.778129)
			(xy 120.103614 -244.760677) (xy 120.060993 -244.73607) (xy 120.022872 -244.704945) (xy 119.990237 -244.668108)
			(xy 119.963934 -244.626512) (xy 119.944643 -244.581236) (xy 119.932866 -244.533452) (xy 119.928906 -244.484398)
			(xy 119.599964 -244.484398) (xy 119.599469 -244.509005) (xy 119.591574 -244.557582) (xy 119.57599 -244.604263)
			(xy 119.553119 -244.64784) (xy 119.523554 -244.687184) (xy 119.488061 -244.721276) (xy 119.447558 -244.749232)
			(xy 119.403096 -244.77033) (xy 119.355825 -244.784022) (xy 119.30697 -244.789954) (xy 119.257795 -244.787973)
			(xy 119.209576 -244.778129) (xy 119.16356 -244.760677) (xy 119.120939 -244.73607) (xy 119.082818 -244.704945)
			(xy 119.050183 -244.668108) (xy 119.02388 -244.626512) (xy 119.004589 -244.581236) (xy 118.992812 -244.533452)
			(xy 118.988852 -244.484398) (xy 118.660164 -244.484398) (xy 118.659669 -244.509005) (xy 118.651774 -244.557582)
			(xy 118.63619 -244.604263) (xy 118.613319 -244.64784) (xy 118.583754 -244.687184) (xy 118.548261 -244.721276)
			(xy 118.507758 -244.749232) (xy 118.463296 -244.77033) (xy 118.416025 -244.784022) (xy 118.36717 -244.789954)
			(xy 118.317995 -244.787973) (xy 118.269776 -244.778129) (xy 118.22376 -244.760677) (xy 118.181139 -244.73607)
			(xy 118.143018 -244.704945) (xy 118.110383 -244.668108) (xy 118.08408 -244.626512) (xy 118.064789 -244.581236)
			(xy 118.053012 -244.533452) (xy 118.049052 -244.484398) (xy 117.72011 -244.484398) (xy 117.719615 -244.509005)
			(xy 117.71172 -244.557582) (xy 117.696136 -244.604263) (xy 117.673265 -244.64784) (xy 117.6437 -244.687184)
			(xy 117.608207 -244.721276) (xy 117.567704 -244.749232) (xy 117.523242 -244.77033) (xy 117.475971 -244.784022)
			(xy 117.427116 -244.789954) (xy 117.377941 -244.787973) (xy 117.329722 -244.778129) (xy 117.283706 -244.760677)
			(xy 117.241085 -244.73607) (xy 117.202964 -244.704945) (xy 117.170329 -244.668108) (xy 117.144026 -244.626512)
			(xy 117.124735 -244.581236) (xy 117.112958 -244.533452) (xy 117.108998 -244.484398) (xy 116.780056 -244.484398)
			(xy 116.779561 -244.509005) (xy 116.771666 -244.557582) (xy 116.756082 -244.604263) (xy 116.733211 -244.64784)
			(xy 116.703646 -244.687184) (xy 116.668153 -244.721276) (xy 116.62765 -244.749232) (xy 116.583188 -244.77033)
			(xy 116.535917 -244.784022) (xy 116.487062 -244.789954) (xy 116.437887 -244.787973) (xy 116.389668 -244.778129)
			(xy 116.343652 -244.760677) (xy 116.301031 -244.73607) (xy 116.26291 -244.704945) (xy 116.230275 -244.668108)
			(xy 116.203972 -244.626512) (xy 116.184681 -244.581236) (xy 116.172904 -244.533452) (xy 116.168944 -244.484398)
			(xy 115.840002 -244.484398) (xy 115.839507 -244.509005) (xy 115.831612 -244.557582) (xy 115.816028 -244.604263)
			(xy 115.793157 -244.64784) (xy 115.763592 -244.687184) (xy 115.728099 -244.721276) (xy 115.687596 -244.749232)
			(xy 115.643134 -244.77033) (xy 115.595863 -244.784022) (xy 115.547008 -244.789954) (xy 115.497833 -244.787973)
			(xy 115.449614 -244.778129) (xy 115.403598 -244.760677) (xy 115.360977 -244.73607) (xy 115.322856 -244.704945)
			(xy 115.290221 -244.668108) (xy 115.263918 -244.626512) (xy 115.244627 -244.581236) (xy 115.23285 -244.533452)
			(xy 115.22889 -244.484398) (xy 114.899948 -244.484398) (xy 114.899453 -244.509005) (xy 114.891558 -244.557582)
			(xy 114.875974 -244.604263) (xy 114.853103 -244.64784) (xy 114.823538 -244.687184) (xy 114.788045 -244.721276)
			(xy 114.747542 -244.749232) (xy 114.70308 -244.77033) (xy 114.655809 -244.784022) (xy 114.606954 -244.789954)
			(xy 114.557779 -244.787973) (xy 114.50956 -244.778129) (xy 114.463544 -244.760677) (xy 114.420923 -244.73607)
			(xy 114.382802 -244.704945) (xy 114.350167 -244.668108) (xy 114.323864 -244.626512) (xy 114.304573 -244.581236)
			(xy 114.292796 -244.533452) (xy 114.288836 -244.484398) (xy 113.960148 -244.484398) (xy 113.959653 -244.509005)
			(xy 113.951758 -244.557582) (xy 113.936174 -244.604263) (xy 113.913303 -244.64784) (xy 113.883738 -244.687184)
			(xy 113.848245 -244.721276) (xy 113.807742 -244.749232) (xy 113.76328 -244.77033) (xy 113.716009 -244.784022)
			(xy 113.667154 -244.789954) (xy 113.617979 -244.787973) (xy 113.56976 -244.778129) (xy 113.523744 -244.760677)
			(xy 113.481123 -244.73607) (xy 113.443002 -244.704945) (xy 113.410367 -244.668108) (xy 113.384064 -244.626512)
			(xy 113.364773 -244.581236) (xy 113.352996 -244.533452) (xy 113.349036 -244.484398) (xy 110.206282 -244.484398)
			(xy 110.205787 -244.509005) (xy 110.197892 -244.557582) (xy 110.182308 -244.604263) (xy 110.159437 -244.64784)
			(xy 110.129872 -244.687184) (xy 110.094379 -244.721276) (xy 110.053876 -244.749232) (xy 110.009414 -244.77033)
			(xy 109.962143 -244.784022) (xy 109.913288 -244.789954) (xy 109.864113 -244.787973) (xy 109.815894 -244.778129)
			(xy 109.769878 -244.760677) (xy 109.727257 -244.73607) (xy 109.689136 -244.704945) (xy 109.656501 -244.668108)
			(xy 109.630198 -244.626512) (xy 109.610907 -244.581236) (xy 109.59913 -244.533452) (xy 109.59517 -244.484398)
			(xy 109.266482 -244.484398) (xy 109.265987 -244.509005) (xy 109.258092 -244.557582) (xy 109.242508 -244.604263)
			(xy 109.219637 -244.64784) (xy 109.190072 -244.687184) (xy 109.154579 -244.721276) (xy 109.114076 -244.749232)
			(xy 109.069614 -244.77033) (xy 109.022343 -244.784022) (xy 108.973488 -244.789954) (xy 108.924313 -244.787973)
			(xy 108.876094 -244.778129) (xy 108.830078 -244.760677) (xy 108.787457 -244.73607) (xy 108.749336 -244.704945)
			(xy 108.716701 -244.668108) (xy 108.690398 -244.626512) (xy 108.671107 -244.581236) (xy 108.65933 -244.533452)
			(xy 108.65537 -244.484398) (xy 108.326428 -244.484398) (xy 108.325933 -244.509005) (xy 108.318038 -244.557582)
			(xy 108.302454 -244.604263) (xy 108.279583 -244.64784) (xy 108.250018 -244.687184) (xy 108.214525 -244.721276)
			(xy 108.174022 -244.749232) (xy 108.12956 -244.77033) (xy 108.082289 -244.784022) (xy 108.033434 -244.789954)
			(xy 107.984259 -244.787973) (xy 107.93604 -244.778129) (xy 107.890024 -244.760677) (xy 107.847403 -244.73607)
			(xy 107.809282 -244.704945) (xy 107.776647 -244.668108) (xy 107.750344 -244.626512) (xy 107.731053 -244.581236)
			(xy 107.719276 -244.533452) (xy 107.715316 -244.484398) (xy 107.387213 -244.484398) (xy 107.387213 -244.4844)
			(xy 107.383037 -244.534788) (xy 107.370624 -244.583801) (xy 107.350313 -244.630103) (xy 107.322657 -244.67243)
			(xy 107.288411 -244.709626) (xy 107.24851 -244.740679) (xy 107.204041 -244.76474) (xy 107.156218 -244.781153)
			(xy 107.106346 -244.78947) (xy 107.081066 -244.78996) (xy 106.141012 -244.78996) (xy 106.115732 -244.789472)
			(xy 106.065863 -244.781152) (xy 106.018043 -244.764737) (xy 105.973577 -244.740675) (xy 105.933678 -244.709622)
			(xy 105.899434 -244.672425) (xy 105.87178 -244.630099) (xy 105.851471 -244.583798) (xy 105.839059 -244.534786)
			(xy 105.834883 -244.4844) (xy 105.506266 -244.4844) (xy 105.505771 -244.509005) (xy 105.497876 -244.557582)
			(xy 105.482292 -244.604263) (xy 105.459421 -244.64784) (xy 105.429856 -244.687184) (xy 105.394363 -244.721276)
			(xy 105.35386 -244.749232) (xy 105.309398 -244.77033) (xy 105.262127 -244.784022) (xy 105.213272 -244.789954)
			(xy 105.164097 -244.787973) (xy 105.115878 -244.778129) (xy 105.069862 -244.760677) (xy 105.027241 -244.73607)
			(xy 104.98912 -244.704945) (xy 104.956485 -244.668108) (xy 104.930182 -244.626512) (xy 104.910891 -244.581236)
			(xy 104.899114 -244.533452) (xy 104.895154 -244.484398) (xy 104.567313 -244.484398) (xy 104.567313 -244.4844)
			(xy 104.563137 -244.534789) (xy 104.550724 -244.583803) (xy 104.530412 -244.630105) (xy 104.502755 -244.672432)
			(xy 104.468508 -244.709629) (xy 104.428605 -244.740682) (xy 104.384136 -244.764742) (xy 104.336312 -244.781154)
			(xy 104.286439 -244.78947) (xy 104.261158 -244.78996) (xy 103.321104 -244.78996) (xy 103.295825 -244.789471)
			(xy 103.245956 -244.78115) (xy 103.198137 -244.764735) (xy 103.153672 -244.740672) (xy 103.113774 -244.709619)
			(xy 103.079532 -244.672422) (xy 103.051879 -244.630096) (xy 103.03157 -244.583797) (xy 103.019159 -244.534786)
			(xy 103.014983 -244.4844) (xy 102.686358 -244.4844) (xy 102.685863 -244.509005) (xy 102.677968 -244.557582)
			(xy 102.662384 -244.604263) (xy 102.639513 -244.64784) (xy 102.609948 -244.687184) (xy 102.574455 -244.721276)
			(xy 102.533952 -244.749232) (xy 102.48949 -244.77033) (xy 102.442219 -244.784022) (xy 102.393364 -244.789954)
			(xy 102.344189 -244.787973) (xy 102.29597 -244.778129) (xy 102.249954 -244.760677) (xy 102.207333 -244.73607)
			(xy 102.169212 -244.704945) (xy 102.136577 -244.668108) (xy 102.110274 -244.626512) (xy 102.090983 -244.581236)
			(xy 102.079206 -244.533452) (xy 102.075246 -244.484398) (xy 101.747113 -244.484398) (xy 101.747113 -244.4844)
			(xy 101.742937 -244.534785) (xy 101.730526 -244.583795) (xy 101.710217 -244.630095) (xy 101.682565 -244.67242)
			(xy 101.648323 -244.709616) (xy 101.608426 -244.740669) (xy 101.563961 -244.764731) (xy 101.516143 -244.781146)
			(xy 101.466275 -244.789467) (xy 101.440996 -244.78996) (xy 100.500942 -244.78996) (xy 100.475661 -244.789474)
			(xy 100.425787 -244.781158) (xy 100.377963 -244.764746) (xy 100.333492 -244.740685) (xy 100.293589 -244.709632)
			(xy 100.259342 -244.672435) (xy 100.231685 -244.630107) (xy 100.211373 -244.583804) (xy 100.198959 -244.534789)
			(xy 100.194783 -244.4844) (xy 99.86645 -244.4844) (xy 99.865955 -244.509005) (xy 99.85806 -244.557582)
			(xy 99.842476 -244.604263) (xy 99.819605 -244.64784) (xy 99.79004 -244.687184) (xy 99.754547 -244.721276)
			(xy 99.714044 -244.749232) (xy 99.669582 -244.77033) (xy 99.622311 -244.784022) (xy 99.573456 -244.789954)
			(xy 99.524281 -244.787973) (xy 99.476062 -244.778129) (xy 99.430046 -244.760677) (xy 99.387425 -244.73607)
			(xy 99.349304 -244.704945) (xy 99.316669 -244.668108) (xy 99.290366 -244.626512) (xy 99.271075 -244.581236)
			(xy 99.259298 -244.533452) (xy 99.255338 -244.484398) (xy 98.927213 -244.484398) (xy 98.927213 -244.4844)
			(xy 98.923037 -244.534786) (xy 98.910626 -244.583797) (xy 98.890316 -244.630097) (xy 98.862663 -244.672422)
			(xy 98.82842 -244.709619) (xy 98.788521 -244.740671) (xy 98.744056 -244.764733) (xy 98.696236 -244.781148)
			(xy 98.646367 -244.789468) (xy 98.621088 -244.78996) (xy 97.681034 -244.78996) (xy 97.655753 -244.789474)
			(xy 97.605881 -244.781156) (xy 97.558057 -244.764743) (xy 97.513588 -244.740682) (xy 97.473686 -244.709629)
			(xy 97.43944 -244.672432) (xy 97.411784 -244.630105) (xy 97.391472 -244.583803) (xy 97.379059 -244.534789)
			(xy 97.374883 -244.4844) (xy 97.047051 -244.4844) (xy 97.043085 -244.533516) (xy 97.031287 -244.581359)
			(xy 97.011964 -244.626689) (xy 96.985616 -244.668331) (xy 96.952927 -244.705204) (xy 96.914744 -244.736353)
			(xy 96.893634 -244.749066) (xy 96.881696 -244.755924) (xy 96.868234 -244.779292) (xy 96.868234 -245.294404)
			(xy 98.785184 -245.294404) (xy 98.789144 -245.24535) (xy 98.800921 -245.197566) (xy 98.820212 -245.15229)
			(xy 98.846515 -245.110694) (xy 98.87915 -245.073857) (xy 98.917271 -245.042732) (xy 98.959892 -245.018125)
			(xy 99.005908 -245.000673) (xy 99.054127 -244.990829) (xy 99.103302 -244.988848) (xy 99.152157 -244.99478)
			(xy 99.199428 -245.008472) (xy 99.24389 -245.02957) (xy 99.284393 -245.057526) (xy 99.319886 -245.091618)
			(xy 99.349451 -245.130962) (xy 99.372322 -245.174539) (xy 99.387906 -245.22122) (xy 99.395801 -245.269797)
			(xy 99.396296 -245.294404) (xy 101.605346 -245.294404) (xy 101.609306 -245.24535) (xy 101.621083 -245.197566)
			(xy 101.640374 -245.15229) (xy 101.666677 -245.110694) (xy 101.699312 -245.073857) (xy 101.737433 -245.042732)
			(xy 101.780054 -245.018125) (xy 101.82607 -245.000673) (xy 101.874289 -244.990829) (xy 101.923464 -244.988848)
			(xy 101.972319 -244.99478) (xy 102.01959 -245.008472) (xy 102.064052 -245.02957) (xy 102.104555 -245.057526)
			(xy 102.140048 -245.091618) (xy 102.169613 -245.130962) (xy 102.192484 -245.174539) (xy 102.208068 -245.22122)
			(xy 102.215963 -245.269797) (xy 102.216458 -245.294404) (xy 104.425254 -245.294404) (xy 104.429214 -245.24535)
			(xy 104.440991 -245.197566) (xy 104.460282 -245.15229) (xy 104.486585 -245.110694) (xy 104.51922 -245.073857)
			(xy 104.557341 -245.042732) (xy 104.599962 -245.018125) (xy 104.645978 -245.000673) (xy 104.694197 -244.990829)
			(xy 104.743372 -244.988848) (xy 104.792227 -244.99478) (xy 104.839498 -245.008472) (xy 104.88396 -245.02957)
			(xy 104.924463 -245.057526) (xy 104.959956 -245.091618) (xy 104.989521 -245.130962) (xy 105.012392 -245.174539)
			(xy 105.027976 -245.22122) (xy 105.035871 -245.269797) (xy 105.036366 -245.294404) (xy 107.245162 -245.294404)
			(xy 107.249122 -245.24535) (xy 107.260899 -245.197566) (xy 107.28019 -245.15229) (xy 107.306493 -245.110694)
			(xy 107.339128 -245.073857) (xy 107.377249 -245.042732) (xy 107.41987 -245.018125) (xy 107.465886 -245.000673)
			(xy 107.514105 -244.990829) (xy 107.56328 -244.988848) (xy 107.612135 -244.99478) (xy 107.659406 -245.008472)
			(xy 107.703868 -245.02957) (xy 107.744371 -245.057526) (xy 107.779864 -245.091618) (xy 107.809429 -245.130962)
			(xy 107.8323 -245.174539) (xy 107.847884 -245.22122) (xy 107.855779 -245.269797) (xy 107.856274 -245.2944)
			(xy 108.185144 -245.2944) (xy 108.189316 -245.244056) (xy 108.201717 -245.195085) (xy 108.222011 -245.148823)
			(xy 108.249642 -245.106533) (xy 108.283857 -245.069367) (xy 108.323723 -245.038341) (xy 108.368153 -245.014299)
			(xy 108.415933 -244.997899) (xy 108.465762 -244.989587) (xy 108.49102 -244.989096) (xy 109.431074 -244.989096)
			(xy 109.456333 -244.989579) (xy 109.506164 -244.99789) (xy 109.553947 -245.01429) (xy 109.598378 -245.038332)
			(xy 109.638246 -245.069359) (xy 109.672463 -245.106526) (xy 109.700095 -245.148818) (xy 109.72039 -245.195081)
			(xy 109.732792 -245.244054) (xy 109.736964 -245.2944) (xy 109.736964 -245.294404) (xy 110.065324 -245.294404)
			(xy 110.069284 -245.24535) (xy 110.081061 -245.197566) (xy 110.100352 -245.15229) (xy 110.126655 -245.110694)
			(xy 110.15929 -245.073857) (xy 110.197411 -245.042732) (xy 110.240032 -245.018125) (xy 110.286048 -245.000673)
			(xy 110.334267 -244.990829) (xy 110.383442 -244.988848) (xy 110.432297 -244.99478) (xy 110.479568 -245.008472)
			(xy 110.52403 -245.02957) (xy 110.564533 -245.057526) (xy 110.600026 -245.091618) (xy 110.629591 -245.130962)
			(xy 110.652462 -245.174539) (xy 110.668046 -245.22122) (xy 110.675941 -245.269797) (xy 110.676436 -245.294404)
			(xy 110.675941 -245.319011) (xy 110.668046 -245.367588) (xy 110.652462 -245.414269) (xy 110.629591 -245.457846)
			(xy 110.600026 -245.49719) (xy 110.564533 -245.531282) (xy 110.534206 -245.552214) (xy 111.456473 -245.552214)
			(xy 111.460503 -245.499716) (xy 111.4725 -245.448448) (xy 111.492183 -245.399613) (xy 111.519089 -245.354354)
			(xy 111.552589 -245.313733) (xy 111.591897 -245.278702) (xy 111.636092 -245.250082) (xy 111.684137 -245.228543)
			(xy 111.734908 -245.214591) (xy 111.787213 -245.208553) (xy 111.839827 -245.21057) (xy 111.891517 -245.220594)
			(xy 111.94107 -245.238392) (xy 111.987326 -245.263545) (xy 112.027809 -245.294404) (xy 112.878882 -245.294404)
			(xy 112.882842 -245.24535) (xy 112.894619 -245.197566) (xy 112.91391 -245.15229) (xy 112.940213 -245.110694)
			(xy 112.972848 -245.073857) (xy 113.010969 -245.042732) (xy 113.05359 -245.018125) (xy 113.099606 -245.000673)
			(xy 113.147825 -244.990829) (xy 113.197 -244.988848) (xy 113.245855 -244.99478) (xy 113.293126 -245.008472)
			(xy 113.337588 -245.02957) (xy 113.378091 -245.057526) (xy 113.413584 -245.091618) (xy 113.443149 -245.130962)
			(xy 113.46602 -245.174539) (xy 113.481604 -245.22122) (xy 113.489499 -245.269797) (xy 113.489994 -245.294404)
			(xy 113.818936 -245.294404) (xy 113.822896 -245.24535) (xy 113.834673 -245.197566) (xy 113.853964 -245.15229)
			(xy 113.880267 -245.110694) (xy 113.912902 -245.073857) (xy 113.951023 -245.042732) (xy 113.993644 -245.018125)
			(xy 114.03966 -245.000673) (xy 114.087879 -244.990829) (xy 114.137054 -244.988848) (xy 114.185909 -244.99478)
			(xy 114.23318 -245.008472) (xy 114.277642 -245.02957) (xy 114.318145 -245.057526) (xy 114.353638 -245.091618)
			(xy 114.383203 -245.130962) (xy 114.406074 -245.174539) (xy 114.421658 -245.22122) (xy 114.429553 -245.269797)
			(xy 114.430048 -245.294404) (xy 114.75899 -245.294404) (xy 114.76295 -245.24535) (xy 114.774727 -245.197566)
			(xy 114.794018 -245.15229) (xy 114.820321 -245.110694) (xy 114.852956 -245.073857) (xy 114.891077 -245.042732)
			(xy 114.933698 -245.018125) (xy 114.979714 -245.000673) (xy 115.027933 -244.990829) (xy 115.077108 -244.988848)
			(xy 115.125963 -244.99478) (xy 115.173234 -245.008472) (xy 115.217696 -245.02957) (xy 115.258199 -245.057526)
			(xy 115.293692 -245.091618) (xy 115.323257 -245.130962) (xy 115.346128 -245.174539) (xy 115.361712 -245.22122)
			(xy 115.369607 -245.269797) (xy 115.370102 -245.294404) (xy 115.699044 -245.294404) (xy 115.703004 -245.24535)
			(xy 115.714781 -245.197566) (xy 115.734072 -245.15229) (xy 115.760375 -245.110694) (xy 115.79301 -245.073857)
			(xy 115.831131 -245.042732) (xy 115.873752 -245.018125) (xy 115.919768 -245.000673) (xy 115.967987 -244.990829)
			(xy 116.017162 -244.988848) (xy 116.066017 -244.99478) (xy 116.113288 -245.008472) (xy 116.15775 -245.02957)
			(xy 116.198253 -245.057526) (xy 116.233746 -245.091618) (xy 116.263311 -245.130962) (xy 116.286182 -245.174539)
			(xy 116.301766 -245.22122) (xy 116.309661 -245.269797) (xy 116.310156 -245.294404) (xy 118.518952 -245.294404)
			(xy 118.522912 -245.24535) (xy 118.534689 -245.197566) (xy 118.55398 -245.15229) (xy 118.580283 -245.110694)
			(xy 118.612918 -245.073857) (xy 118.651039 -245.042732) (xy 118.69366 -245.018125) (xy 118.739676 -245.000673)
			(xy 118.787895 -244.990829) (xy 118.83707 -244.988848) (xy 118.885925 -244.99478) (xy 118.933196 -245.008472)
			(xy 118.977658 -245.02957) (xy 119.018161 -245.057526) (xy 119.053654 -245.091618) (xy 119.083219 -245.130962)
			(xy 119.10609 -245.174539) (xy 119.121674 -245.22122) (xy 119.129569 -245.269797) (xy 119.130064 -245.294404)
			(xy 121.33886 -245.294404) (xy 121.34282 -245.24535) (xy 121.354597 -245.197566) (xy 121.373888 -245.15229)
			(xy 121.400191 -245.110694) (xy 121.432826 -245.073857) (xy 121.470947 -245.042732) (xy 121.513568 -245.018125)
			(xy 121.559584 -245.000673) (xy 121.607803 -244.990829) (xy 121.656978 -244.988848) (xy 121.705833 -244.99478)
			(xy 121.753104 -245.008472) (xy 121.797566 -245.02957) (xy 121.838069 -245.057526) (xy 121.873562 -245.091618)
			(xy 121.903127 -245.130962) (xy 121.925998 -245.174539) (xy 121.941582 -245.22122) (xy 121.949477 -245.269797)
			(xy 121.949972 -245.294404) (xy 124.159022 -245.294404) (xy 124.162982 -245.24535) (xy 124.174759 -245.197566)
			(xy 124.19405 -245.15229) (xy 124.220353 -245.110694) (xy 124.252988 -245.073857) (xy 124.291109 -245.042732)
			(xy 124.33373 -245.018125) (xy 124.379746 -245.000673) (xy 124.427965 -244.990829) (xy 124.47714 -244.988848)
			(xy 124.525995 -244.99478) (xy 124.573266 -245.008472) (xy 124.617728 -245.02957) (xy 124.658231 -245.057526)
			(xy 124.693724 -245.091618) (xy 124.723289 -245.130962) (xy 124.74616 -245.174539) (xy 124.761744 -245.22122)
			(xy 124.769639 -245.269797) (xy 124.770134 -245.294404) (xy 126.97893 -245.294404) (xy 126.98289 -245.24535)
			(xy 126.994667 -245.197566) (xy 127.013958 -245.15229) (xy 127.040261 -245.110694) (xy 127.072896 -245.073857)
			(xy 127.111017 -245.042732) (xy 127.153638 -245.018125) (xy 127.199654 -245.000673) (xy 127.247873 -244.990829)
			(xy 127.297048 -244.988848) (xy 127.345903 -244.99478) (xy 127.393174 -245.008472) (xy 127.437636 -245.02957)
			(xy 127.478139 -245.057526) (xy 127.513632 -245.091618) (xy 127.543197 -245.130962) (xy 127.566068 -245.174539)
			(xy 127.581652 -245.22122) (xy 127.589547 -245.269797) (xy 127.590042 -245.294404) (xy 127.908553 -245.294404)
			(xy 127.912648 -245.243676) (xy 127.924827 -245.194262) (xy 127.944775 -245.147442) (xy 127.971976 -245.104428)
			(xy 128.005724 -245.066334) (xy 128.045146 -245.034147) (xy 128.08922 -245.008701) (xy 128.136806 -244.990654)
			(xy 128.18667 -244.980474) (xy 128.237522 -244.978425) (xy 128.288043 -244.984559) (xy 128.336927 -244.998719)
			(xy 128.382906 -245.020536) (xy 128.42479 -245.049446) (xy 128.461494 -245.084701) (xy 128.492067 -245.125387)
			(xy 128.515718 -245.17045) (xy 128.531834 -245.218724) (xy 128.539998 -245.268958) (xy 128.54051 -245.294404)
			(xy 128.848607 -245.294404) (xy 128.852702 -245.243676) (xy 128.864881 -245.194262) (xy 128.884829 -245.147442)
			(xy 128.91203 -245.104428) (xy 128.945778 -245.066334) (xy 128.9852 -245.034147) (xy 129.029274 -245.008701)
			(xy 129.07686 -244.990654) (xy 129.126724 -244.980474) (xy 129.177576 -244.978425) (xy 129.228097 -244.984559)
			(xy 129.276981 -244.998719) (xy 129.32296 -245.020536) (xy 129.364844 -245.049446) (xy 129.401548 -245.084701)
			(xy 129.432121 -245.125387) (xy 129.455772 -245.17045) (xy 129.471888 -245.218724) (xy 129.480052 -245.268958)
			(xy 129.480564 -245.294404) (xy 129.480052 -245.31985) (xy 129.471888 -245.370084) (xy 129.455772 -245.418358)
			(xy 129.432121 -245.463421) (xy 129.401548 -245.504107) (xy 129.364844 -245.539362) (xy 129.32296 -245.568272)
			(xy 129.276981 -245.590089) (xy 129.228097 -245.604249) (xy 129.177576 -245.610383) (xy 129.126724 -245.608334)
			(xy 129.07686 -245.598154) (xy 129.029274 -245.580107) (xy 128.9852 -245.554661) (xy 128.945778 -245.522474)
			(xy 128.91203 -245.48438) (xy 128.884829 -245.441366) (xy 128.864881 -245.394546) (xy 128.852702 -245.345132)
			(xy 128.848607 -245.294404) (xy 128.54051 -245.294404) (xy 128.539998 -245.31985) (xy 128.531834 -245.370084)
			(xy 128.515718 -245.418358) (xy 128.492067 -245.463421) (xy 128.461494 -245.504107) (xy 128.42479 -245.539362)
			(xy 128.382906 -245.568272) (xy 128.336927 -245.590089) (xy 128.288043 -245.604249) (xy 128.237522 -245.610383)
			(xy 128.18667 -245.608334) (xy 128.136806 -245.598154) (xy 128.08922 -245.580107) (xy 128.045146 -245.554661)
			(xy 128.005724 -245.522474) (xy 127.971976 -245.48438) (xy 127.944775 -245.441366) (xy 127.924827 -245.394546)
			(xy 127.912648 -245.345132) (xy 127.908553 -245.294404) (xy 127.590042 -245.294404) (xy 127.589547 -245.319011)
			(xy 127.581652 -245.367588) (xy 127.566068 -245.414269) (xy 127.543197 -245.457846) (xy 127.513632 -245.49719)
			(xy 127.478139 -245.531282) (xy 127.437636 -245.559238) (xy 127.393174 -245.580336) (xy 127.345903 -245.594028)
			(xy 127.297048 -245.59996) (xy 127.247873 -245.597979) (xy 127.199654 -245.588135) (xy 127.153638 -245.570683)
			(xy 127.111017 -245.546076) (xy 127.072896 -245.514951) (xy 127.040261 -245.478114) (xy 127.013958 -245.436518)
			(xy 126.994667 -245.391242) (xy 126.98289 -245.343458) (xy 126.97893 -245.294404) (xy 124.770134 -245.294404)
			(xy 124.769639 -245.319011) (xy 124.761744 -245.367588) (xy 124.74616 -245.414269) (xy 124.723289 -245.457846)
			(xy 124.693724 -245.49719) (xy 124.658231 -245.531282) (xy 124.617728 -245.559238) (xy 124.573266 -245.580336)
			(xy 124.525995 -245.594028) (xy 124.47714 -245.59996) (xy 124.427965 -245.597979) (xy 124.379746 -245.588135)
			(xy 124.33373 -245.570683) (xy 124.291109 -245.546076) (xy 124.252988 -245.514951) (xy 124.220353 -245.478114)
			(xy 124.19405 -245.436518) (xy 124.174759 -245.391242) (xy 124.162982 -245.343458) (xy 124.159022 -245.294404)
			(xy 121.949972 -245.294404) (xy 121.949477 -245.319011) (xy 121.941582 -245.367588) (xy 121.925998 -245.414269)
			(xy 121.903127 -245.457846) (xy 121.873562 -245.49719) (xy 121.838069 -245.531282) (xy 121.797566 -245.559238)
			(xy 121.753104 -245.580336) (xy 121.705833 -245.594028) (xy 121.656978 -245.59996) (xy 121.607803 -245.597979)
			(xy 121.559584 -245.588135) (xy 121.513568 -245.570683) (xy 121.470947 -245.546076) (xy 121.432826 -245.514951)
			(xy 121.400191 -245.478114) (xy 121.373888 -245.436518) (xy 121.354597 -245.391242) (xy 121.34282 -245.343458)
			(xy 121.33886 -245.294404) (xy 119.130064 -245.294404) (xy 119.129569 -245.319011) (xy 119.121674 -245.367588)
			(xy 119.10609 -245.414269) (xy 119.083219 -245.457846) (xy 119.053654 -245.49719) (xy 119.018161 -245.531282)
			(xy 118.977658 -245.559238) (xy 118.933196 -245.580336) (xy 118.885925 -245.594028) (xy 118.83707 -245.59996)
			(xy 118.787895 -245.597979) (xy 118.739676 -245.588135) (xy 118.69366 -245.570683) (xy 118.651039 -245.546076)
			(xy 118.612918 -245.514951) (xy 118.580283 -245.478114) (xy 118.55398 -245.436518) (xy 118.534689 -245.391242)
			(xy 118.522912 -245.343458) (xy 118.518952 -245.294404) (xy 116.310156 -245.294404) (xy 116.309661 -245.319011)
			(xy 116.301766 -245.367588) (xy 116.286182 -245.414269) (xy 116.263311 -245.457846) (xy 116.233746 -245.49719)
			(xy 116.198253 -245.531282) (xy 116.15775 -245.559238) (xy 116.113288 -245.580336) (xy 116.066017 -245.594028)
			(xy 116.017162 -245.59996) (xy 115.967987 -245.597979) (xy 115.919768 -245.588135) (xy 115.873752 -245.570683)
			(xy 115.831131 -245.546076) (xy 115.79301 -245.514951) (xy 115.760375 -245.478114) (xy 115.734072 -245.436518)
			(xy 115.714781 -245.391242) (xy 115.703004 -245.343458) (xy 115.699044 -245.294404) (xy 115.370102 -245.294404)
			(xy 115.369607 -245.319011) (xy 115.361712 -245.367588) (xy 115.346128 -245.414269) (xy 115.323257 -245.457846)
			(xy 115.293692 -245.49719) (xy 115.258199 -245.531282) (xy 115.217696 -245.559238) (xy 115.173234 -245.580336)
			(xy 115.125963 -245.594028) (xy 115.077108 -245.59996) (xy 115.027933 -245.597979) (xy 114.979714 -245.588135)
			(xy 114.933698 -245.570683) (xy 114.891077 -245.546076) (xy 114.852956 -245.514951) (xy 114.820321 -245.478114)
			(xy 114.794018 -245.436518) (xy 114.774727 -245.391242) (xy 114.76295 -245.343458) (xy 114.75899 -245.294404)
			(xy 114.430048 -245.294404) (xy 114.429553 -245.319011) (xy 114.421658 -245.367588) (xy 114.406074 -245.414269)
			(xy 114.383203 -245.457846) (xy 114.353638 -245.49719) (xy 114.318145 -245.531282) (xy 114.277642 -245.559238)
			(xy 114.23318 -245.580336) (xy 114.185909 -245.594028) (xy 114.137054 -245.59996) (xy 114.087879 -245.597979)
			(xy 114.03966 -245.588135) (xy 113.993644 -245.570683) (xy 113.951023 -245.546076) (xy 113.912902 -245.514951)
			(xy 113.880267 -245.478114) (xy 113.853964 -245.436518) (xy 113.834673 -245.391242) (xy 113.822896 -245.343458)
			(xy 113.818936 -245.294404) (xy 113.489994 -245.294404) (xy 113.489499 -245.319011) (xy 113.481604 -245.367588)
			(xy 113.46602 -245.414269) (xy 113.443149 -245.457846) (xy 113.413584 -245.49719) (xy 113.378091 -245.531282)
			(xy 113.337588 -245.559238) (xy 113.293126 -245.580336) (xy 113.245855 -245.594028) (xy 113.197 -245.59996)
			(xy 113.147825 -245.597979) (xy 113.099606 -245.588135) (xy 113.05359 -245.570683) (xy 113.010969 -245.546076)
			(xy 112.972848 -245.514951) (xy 112.940213 -245.478114) (xy 112.91391 -245.436518) (xy 112.894619 -245.391242)
			(xy 112.882842 -245.343458) (xy 112.878882 -245.294404) (xy 112.027809 -245.294404) (xy 112.0292 -245.295464)
			(xy 112.065712 -245.333402) (xy 112.096004 -245.376468) (xy 112.119367 -245.423653) (xy 112.135253 -245.473852)
			(xy 112.14329 -245.525888) (xy 112.143794 -245.552214) (xy 112.14329 -245.57854) (xy 112.135253 -245.630576)
			(xy 112.119367 -245.680775) (xy 112.096004 -245.72796) (xy 112.065712 -245.771026) (xy 112.0292 -245.808964)
			(xy 111.987326 -245.840883) (xy 111.94107 -245.866036) (xy 111.891517 -245.883834) (xy 111.839827 -245.893858)
			(xy 111.787213 -245.895875) (xy 111.734908 -245.889837) (xy 111.684137 -245.875885) (xy 111.636092 -245.854346)
			(xy 111.591897 -245.825726) (xy 111.552589 -245.790695) (xy 111.519089 -245.750074) (xy 111.492183 -245.704815)
			(xy 111.4725 -245.65598) (xy 111.460503 -245.604712) (xy 111.456473 -245.552214) (xy 110.534206 -245.552214)
			(xy 110.52403 -245.559238) (xy 110.479568 -245.580336) (xy 110.432297 -245.594028) (xy 110.383442 -245.59996)
			(xy 110.334267 -245.597979) (xy 110.286048 -245.588135) (xy 110.240032 -245.570683) (xy 110.197411 -245.546076)
			(xy 110.15929 -245.514951) (xy 110.126655 -245.478114) (xy 110.100352 -245.436518) (xy 110.081061 -245.391242)
			(xy 110.069284 -245.343458) (xy 110.065324 -245.294404) (xy 109.736964 -245.294404) (xy 109.732792 -245.344746)
			(xy 109.72039 -245.393719) (xy 109.700095 -245.439982) (xy 109.672463 -245.482274) (xy 109.638246 -245.519441)
			(xy 109.598378 -245.550468) (xy 109.553947 -245.57451) (xy 109.506164 -245.59091) (xy 109.456333 -245.599221)
			(xy 109.431074 -245.599712) (xy 108.49102 -245.599712) (xy 108.465762 -245.599213) (xy 108.415933 -245.590901)
			(xy 108.368153 -245.574501) (xy 108.323723 -245.550459) (xy 108.283857 -245.519433) (xy 108.249642 -245.482267)
			(xy 108.222011 -245.439977) (xy 108.201717 -245.393715) (xy 108.189316 -245.344744) (xy 108.185144 -245.2944)
			(xy 107.856274 -245.2944) (xy 107.856274 -245.294404) (xy 107.855779 -245.319011) (xy 107.847884 -245.367588)
			(xy 107.8323 -245.414269) (xy 107.809429 -245.457846) (xy 107.779864 -245.49719) (xy 107.744371 -245.531282)
			(xy 107.703868 -245.559238) (xy 107.659406 -245.580336) (xy 107.612135 -245.594028) (xy 107.56328 -245.59996)
			(xy 107.514105 -245.597979) (xy 107.465886 -245.588135) (xy 107.41987 -245.570683) (xy 107.377249 -245.546076)
			(xy 107.339128 -245.514951) (xy 107.306493 -245.478114) (xy 107.28019 -245.436518) (xy 107.260899 -245.391242)
			(xy 107.249122 -245.343458) (xy 107.245162 -245.294404) (xy 105.036366 -245.294404) (xy 105.035871 -245.319011)
			(xy 105.027976 -245.367588) (xy 105.012392 -245.414269) (xy 104.989521 -245.457846) (xy 104.959956 -245.49719)
			(xy 104.924463 -245.531282) (xy 104.88396 -245.559238) (xy 104.839498 -245.580336) (xy 104.792227 -245.594028)
			(xy 104.743372 -245.59996) (xy 104.694197 -245.597979) (xy 104.645978 -245.588135) (xy 104.599962 -245.570683)
			(xy 104.557341 -245.546076) (xy 104.51922 -245.514951) (xy 104.486585 -245.478114) (xy 104.460282 -245.436518)
			(xy 104.440991 -245.391242) (xy 104.429214 -245.343458) (xy 104.425254 -245.294404) (xy 102.216458 -245.294404)
			(xy 102.215963 -245.319011) (xy 102.208068 -245.367588) (xy 102.192484 -245.414269) (xy 102.169613 -245.457846)
			(xy 102.140048 -245.49719) (xy 102.104555 -245.531282) (xy 102.064052 -245.559238) (xy 102.01959 -245.580336)
			(xy 101.972319 -245.594028) (xy 101.923464 -245.59996) (xy 101.874289 -245.597979) (xy 101.82607 -245.588135)
			(xy 101.780054 -245.570683) (xy 101.737433 -245.546076) (xy 101.699312 -245.514951) (xy 101.666677 -245.478114)
			(xy 101.640374 -245.436518) (xy 101.621083 -245.391242) (xy 101.609306 -245.343458) (xy 101.605346 -245.294404)
			(xy 99.396296 -245.294404) (xy 99.395801 -245.319011) (xy 99.387906 -245.367588) (xy 99.372322 -245.414269)
			(xy 99.349451 -245.457846) (xy 99.319886 -245.49719) (xy 99.284393 -245.531282) (xy 99.24389 -245.559238)
			(xy 99.199428 -245.580336) (xy 99.152157 -245.594028) (xy 99.103302 -245.59996) (xy 99.054127 -245.597979)
			(xy 99.005908 -245.588135) (xy 98.959892 -245.570683) (xy 98.917271 -245.546076) (xy 98.87915 -245.514951)
			(xy 98.846515 -245.478114) (xy 98.820212 -245.436518) (xy 98.800921 -245.391242) (xy 98.789144 -245.343458)
			(xy 98.785184 -245.294404) (xy 96.868234 -245.294404) (xy 96.868234 -245.681246) (xy 96.868698 -245.691122)
			(xy 96.876141 -245.709419) (xy 96.882712 -245.716806) (xy 96.882966 -245.71706) (xy 96.911922 -245.746016)
			(xy 96.918633 -245.753255) (xy 96.926224 -245.77146) (xy 96.926654 -245.781322) (xy 96.926654 -245.82755)
			(xy 96.926775 -245.832911) (xy 96.928957 -245.843408) (xy 96.930972 -245.848378) (xy 96.943164 -245.875556)
			(xy 96.95053 -245.882414) (xy 96.96828 -245.899842) (xy 96.998439 -245.9394) (xy 97.021786 -245.983323)
			(xy 97.037701 -246.030451) (xy 97.045765 -246.079536) (xy 97.045765 -246.1044) (xy 97.374895 -246.1044)
			(xy 97.379071 -246.054013) (xy 97.391483 -246.005001) (xy 97.411794 -245.958701) (xy 97.439449 -245.916375)
			(xy 97.473694 -245.879179) (xy 97.513595 -245.848128) (xy 97.558062 -245.824068) (xy 97.605884 -245.807655)
			(xy 97.655754 -245.799338) (xy 97.681034 -245.798848) (xy 98.621088 -245.798848) (xy 98.646368 -245.79932)
			(xy 98.696239 -245.80764) (xy 98.744061 -245.824056) (xy 98.788528 -245.848119) (xy 98.828428 -245.879173)
			(xy 98.862672 -245.91637) (xy 98.890327 -245.958698) (xy 98.910637 -246.004999) (xy 98.923049 -246.054012)
			(xy 98.927225 -246.1044) (xy 98.927224 -246.10441) (xy 99.255338 -246.10441) (xy 99.259298 -246.055356)
			(xy 99.271075 -246.007572) (xy 99.290366 -245.962296) (xy 99.316669 -245.9207) (xy 99.349304 -245.883863)
			(xy 99.387425 -245.852738) (xy 99.430046 -245.828131) (xy 99.476062 -245.810679) (xy 99.524281 -245.800835)
			(xy 99.573456 -245.798854) (xy 99.622311 -245.804786) (xy 99.669582 -245.818478) (xy 99.714044 -245.839576)
			(xy 99.754547 -245.867532) (xy 99.79004 -245.901624) (xy 99.819605 -245.940968) (xy 99.842476 -245.984545)
			(xy 99.85806 -246.031226) (xy 99.865955 -246.079803) (xy 99.86645 -246.1044) (xy 100.194795 -246.1044)
			(xy 100.198971 -246.054012) (xy 100.211384 -246.005) (xy 100.231695 -245.958699) (xy 100.259351 -245.916373)
			(xy 100.293597 -245.879177) (xy 100.333499 -245.848125) (xy 100.377968 -245.824065) (xy 100.42579 -245.807654)
			(xy 100.475662 -245.799338) (xy 100.500942 -245.798848) (xy 101.440996 -245.798848) (xy 101.466276 -245.799321)
			(xy 101.516146 -245.807642) (xy 101.563966 -245.824058) (xy 101.608432 -245.848121) (xy 101.648331 -245.879175)
			(xy 101.682574 -245.916373) (xy 101.710228 -245.9587) (xy 101.730538 -246.005001) (xy 101.742949 -246.054013)
			(xy 101.747125 -246.1044) (xy 101.747124 -246.10441) (xy 102.075246 -246.10441) (xy 102.079206 -246.055356)
			(xy 102.090983 -246.007572) (xy 102.110274 -245.962296) (xy 102.136577 -245.9207) (xy 102.169212 -245.883863)
			(xy 102.207333 -245.852738) (xy 102.249954 -245.828131) (xy 102.29597 -245.810679) (xy 102.344189 -245.800835)
			(xy 102.393364 -245.798854) (xy 102.442219 -245.804786) (xy 102.48949 -245.818478) (xy 102.533952 -245.839576)
			(xy 102.574455 -245.867532) (xy 102.609948 -245.901624) (xy 102.639513 -245.940968) (xy 102.662384 -245.984545)
			(xy 102.677968 -246.031226) (xy 102.685863 -246.079803) (xy 102.686358 -246.1044) (xy 103.014995 -246.1044)
			(xy 103.01917 -246.054016) (xy 103.031581 -246.005007) (xy 103.05189 -245.958709) (xy 103.079542 -245.916385)
			(xy 103.113783 -245.87919) (xy 103.153679 -245.848138) (xy 103.198142 -245.824076) (xy 103.245959 -245.807661)
			(xy 103.295826 -245.799341) (xy 103.321104 -245.798848) (xy 104.261158 -245.798848) (xy 104.28644 -245.799318)
			(xy 104.336315 -245.807634) (xy 104.38414 -245.824047) (xy 104.428612 -245.848108) (xy 104.468516 -245.879162)
			(xy 104.502764 -245.91636) (xy 104.530422 -245.958689) (xy 104.550735 -246.004993) (xy 104.563149 -246.054009)
			(xy 104.567325 -246.1044) (xy 104.567324 -246.10441) (xy 104.895154 -246.10441) (xy 104.899114 -246.055356)
			(xy 104.910891 -246.007572) (xy 104.930182 -245.962296) (xy 104.956485 -245.9207) (xy 104.98912 -245.883863)
			(xy 105.027241 -245.852738) (xy 105.069862 -245.828131) (xy 105.115878 -245.810679) (xy 105.164097 -245.800835)
			(xy 105.213272 -245.798854) (xy 105.262127 -245.804786) (xy 105.309398 -245.818478) (xy 105.35386 -245.839576)
			(xy 105.394363 -245.867532) (xy 105.429856 -245.901624) (xy 105.459421 -245.940968) (xy 105.482292 -245.984545)
			(xy 105.497876 -246.031226) (xy 105.505771 -246.079803) (xy 105.506266 -246.1044) (xy 105.834895 -246.1044)
			(xy 105.839071 -246.054016) (xy 105.851482 -246.005006) (xy 105.871791 -245.958707) (xy 105.899444 -245.916383)
			(xy 105.933686 -245.879187) (xy 105.973583 -245.848135) (xy 106.018047 -245.824074) (xy 106.065866 -245.80766)
			(xy 106.115733 -245.79934) (xy 106.141012 -245.798848) (xy 107.081066 -245.798848) (xy 107.106347 -245.799318)
			(xy 107.156221 -245.807636) (xy 107.204046 -245.824049) (xy 107.248516 -245.848111) (xy 107.288419 -245.879165)
			(xy 107.322666 -245.916363) (xy 107.350323 -245.958691) (xy 107.370636 -246.004995) (xy 107.383049 -246.05401)
			(xy 107.387225 -246.1044) (xy 107.387224 -246.10441) (xy 107.715316 -246.10441) (xy 107.719276 -246.055356)
			(xy 107.731053 -246.007572) (xy 107.750344 -245.962296) (xy 107.776647 -245.9207) (xy 107.809282 -245.883863)
			(xy 107.847403 -245.852738) (xy 107.890024 -245.828131) (xy 107.93604 -245.810679) (xy 107.984259 -245.800835)
			(xy 108.033434 -245.798854) (xy 108.082289 -245.804786) (xy 108.12956 -245.818478) (xy 108.174022 -245.839576)
			(xy 108.214525 -245.867532) (xy 108.250018 -245.901624) (xy 108.279583 -245.940968) (xy 108.302454 -245.984545)
			(xy 108.318038 -246.031226) (xy 108.325933 -246.079803) (xy 108.326428 -246.10441) (xy 115.22889 -246.10441)
			(xy 115.23285 -246.055356) (xy 115.244627 -246.007572) (xy 115.263918 -245.962296) (xy 115.290221 -245.9207)
			(xy 115.322856 -245.883863) (xy 115.360977 -245.852738) (xy 115.403598 -245.828131) (xy 115.449614 -245.810679)
			(xy 115.497833 -245.800835) (xy 115.547008 -245.798854) (xy 115.595863 -245.804786) (xy 115.643134 -245.818478)
			(xy 115.687596 -245.839576) (xy 115.728099 -245.867532) (xy 115.763592 -245.901624) (xy 115.793157 -245.940968)
			(xy 115.816028 -245.984545) (xy 115.831612 -246.031226) (xy 115.839507 -246.079803) (xy 115.840002 -246.10441)
			(xy 116.168944 -246.10441) (xy 116.172904 -246.055356) (xy 116.184681 -246.007572) (xy 116.203972 -245.962296)
			(xy 116.230275 -245.9207) (xy 116.26291 -245.883863) (xy 116.301031 -245.852738) (xy 116.343652 -245.828131)
			(xy 116.389668 -245.810679) (xy 116.437887 -245.800835) (xy 116.487062 -245.798854) (xy 116.535917 -245.804786)
			(xy 116.583188 -245.818478) (xy 116.62765 -245.839576) (xy 116.668153 -245.867532) (xy 116.703646 -245.901624)
			(xy 116.733211 -245.940968) (xy 116.756082 -245.984545) (xy 116.771666 -246.031226) (xy 116.779561 -246.079803)
			(xy 116.780056 -246.10441) (xy 117.108998 -246.10441) (xy 117.112958 -246.055356) (xy 117.124735 -246.007572)
			(xy 117.144026 -245.962296) (xy 117.170329 -245.9207) (xy 117.202964 -245.883863) (xy 117.241085 -245.852738)
			(xy 117.283706 -245.828131) (xy 117.329722 -245.810679) (xy 117.377941 -245.800835) (xy 117.427116 -245.798854)
			(xy 117.475971 -245.804786) (xy 117.523242 -245.818478) (xy 117.567704 -245.839576) (xy 117.608207 -245.867532)
			(xy 117.6437 -245.901624) (xy 117.673265 -245.940968) (xy 117.696136 -245.984545) (xy 117.71172 -246.031226)
			(xy 117.719615 -246.079803) (xy 117.72011 -246.10441) (xy 118.049052 -246.10441) (xy 118.053012 -246.055356)
			(xy 118.064789 -246.007572) (xy 118.08408 -245.962296) (xy 118.110383 -245.9207) (xy 118.143018 -245.883863)
			(xy 118.181139 -245.852738) (xy 118.22376 -245.828131) (xy 118.269776 -245.810679) (xy 118.317995 -245.800835)
			(xy 118.36717 -245.798854) (xy 118.416025 -245.804786) (xy 118.463296 -245.818478) (xy 118.507758 -245.839576)
			(xy 118.548261 -245.867532) (xy 118.583754 -245.901624) (xy 118.613319 -245.940968) (xy 118.63619 -245.984545)
			(xy 118.651774 -246.031226) (xy 118.659669 -246.079803) (xy 118.660164 -246.10441) (xy 118.988852 -246.10441)
			(xy 118.992812 -246.055356) (xy 119.004589 -246.007572) (xy 119.02388 -245.962296) (xy 119.050183 -245.9207)
			(xy 119.082818 -245.883863) (xy 119.120939 -245.852738) (xy 119.16356 -245.828131) (xy 119.209576 -245.810679)
			(xy 119.257795 -245.800835) (xy 119.30697 -245.798854) (xy 119.355825 -245.804786) (xy 119.403096 -245.818478)
			(xy 119.447558 -245.839576) (xy 119.488061 -245.867532) (xy 119.523554 -245.901624) (xy 119.553119 -245.940968)
			(xy 119.57599 -245.984545) (xy 119.591574 -246.031226) (xy 119.599469 -246.079803) (xy 119.599964 -246.10441)
			(xy 119.928906 -246.10441) (xy 119.932866 -246.055356) (xy 119.944643 -246.007572) (xy 119.963934 -245.962296)
			(xy 119.990237 -245.9207) (xy 120.022872 -245.883863) (xy 120.060993 -245.852738) (xy 120.103614 -245.828131)
			(xy 120.14963 -245.810679) (xy 120.197849 -245.800835) (xy 120.247024 -245.798854) (xy 120.295879 -245.804786)
			(xy 120.34315 -245.818478) (xy 120.387612 -245.839576) (xy 120.428115 -245.867532) (xy 120.463608 -245.901624)
			(xy 120.493173 -245.940968) (xy 120.516044 -245.984545) (xy 120.531628 -246.031226) (xy 120.539523 -246.079803)
			(xy 120.540018 -246.10441) (xy 120.86896 -246.10441) (xy 120.87292 -246.055356) (xy 120.884697 -246.007572)
			(xy 120.903988 -245.962296) (xy 120.930291 -245.9207) (xy 120.962926 -245.883863) (xy 121.001047 -245.852738)
			(xy 121.043668 -245.828131) (xy 121.089684 -245.810679) (xy 121.137903 -245.800835) (xy 121.187078 -245.798854)
			(xy 121.235933 -245.804786) (xy 121.283204 -245.818478) (xy 121.327666 -245.839576) (xy 121.368169 -245.867532)
			(xy 121.403662 -245.901624) (xy 121.433227 -245.940968) (xy 121.456098 -245.984545) (xy 121.471682 -246.031226)
			(xy 121.479577 -246.079803) (xy 121.480072 -246.10441) (xy 121.809014 -246.10441) (xy 121.812974 -246.055356)
			(xy 121.824751 -246.007572) (xy 121.844042 -245.962296) (xy 121.870345 -245.9207) (xy 121.90298 -245.883863)
			(xy 121.941101 -245.852738) (xy 121.983722 -245.828131) (xy 122.029738 -245.810679) (xy 122.077957 -245.800835)
			(xy 122.127132 -245.798854) (xy 122.175987 -245.804786) (xy 122.223258 -245.818478) (xy 122.26772 -245.839576)
			(xy 122.308223 -245.867532) (xy 122.343716 -245.901624) (xy 122.373281 -245.940968) (xy 122.396152 -245.984545)
			(xy 122.411736 -246.031226) (xy 122.419631 -246.079803) (xy 122.420126 -246.10441) (xy 122.748814 -246.10441)
			(xy 122.752774 -246.055356) (xy 122.764551 -246.007572) (xy 122.783842 -245.962296) (xy 122.810145 -245.9207)
			(xy 122.84278 -245.883863) (xy 122.880901 -245.852738) (xy 122.923522 -245.828131) (xy 122.969538 -245.810679)
			(xy 123.017757 -245.800835) (xy 123.066932 -245.798854) (xy 123.115787 -245.804786) (xy 123.163058 -245.818478)
			(xy 123.20752 -245.839576) (xy 123.248023 -245.867532) (xy 123.283516 -245.901624) (xy 123.313081 -245.940968)
			(xy 123.335952 -245.984545) (xy 123.351536 -246.031226) (xy 123.359431 -246.079803) (xy 123.359926 -246.10441)
			(xy 123.688868 -246.10441) (xy 123.692828 -246.055356) (xy 123.704605 -246.007572) (xy 123.723896 -245.962296)
			(xy 123.750199 -245.9207) (xy 123.782834 -245.883863) (xy 123.820955 -245.852738) (xy 123.863576 -245.828131)
			(xy 123.909592 -245.810679) (xy 123.957811 -245.800835) (xy 124.006986 -245.798854) (xy 124.055841 -245.804786)
			(xy 124.103112 -245.818478) (xy 124.147574 -245.839576) (xy 124.188077 -245.867532) (xy 124.22357 -245.901624)
			(xy 124.253135 -245.940968) (xy 124.276006 -245.984545) (xy 124.29159 -246.031226) (xy 124.299485 -246.079803)
			(xy 124.29998 -246.10441) (xy 124.628922 -246.10441) (xy 124.632882 -246.055356) (xy 124.644659 -246.007572)
			(xy 124.66395 -245.962296) (xy 124.690253 -245.9207) (xy 124.722888 -245.883863) (xy 124.761009 -245.852738)
			(xy 124.80363 -245.828131) (xy 124.849646 -245.810679) (xy 124.897865 -245.800835) (xy 124.94704 -245.798854)
			(xy 124.995895 -245.804786) (xy 125.043166 -245.818478) (xy 125.087628 -245.839576) (xy 125.128131 -245.867532)
			(xy 125.163624 -245.901624) (xy 125.193189 -245.940968) (xy 125.21606 -245.984545) (xy 125.231644 -246.031226)
			(xy 125.239539 -246.079803) (xy 125.240034 -246.10441) (xy 125.568976 -246.10441) (xy 125.572936 -246.055356)
			(xy 125.584713 -246.007572) (xy 125.604004 -245.962296) (xy 125.630307 -245.9207) (xy 125.662942 -245.883863)
			(xy 125.701063 -245.852738) (xy 125.743684 -245.828131) (xy 125.7897 -245.810679) (xy 125.837919 -245.800835)
			(xy 125.887094 -245.798854) (xy 125.935949 -245.804786) (xy 125.98322 -245.818478) (xy 126.027682 -245.839576)
			(xy 126.068185 -245.867532) (xy 126.103678 -245.901624) (xy 126.133243 -245.940968) (xy 126.156114 -245.984545)
			(xy 126.171698 -246.031226) (xy 126.179593 -246.079803) (xy 126.180088 -246.10441) (xy 126.50903 -246.10441)
			(xy 126.51299 -246.055356) (xy 126.524767 -246.007572) (xy 126.544058 -245.962296) (xy 126.570361 -245.9207)
			(xy 126.602996 -245.883863) (xy 126.641117 -245.852738) (xy 126.683738 -245.828131) (xy 126.729754 -245.810679)
			(xy 126.777973 -245.800835) (xy 126.827148 -245.798854) (xy 126.876003 -245.804786) (xy 126.923274 -245.818478)
			(xy 126.967736 -245.839576) (xy 127.008239 -245.867532) (xy 127.043732 -245.901624) (xy 127.073297 -245.940968)
			(xy 127.096168 -245.984545) (xy 127.111752 -246.031226) (xy 127.119647 -246.079803) (xy 127.120142 -246.10441)
			(xy 127.438399 -246.10441) (xy 127.442494 -246.053682) (xy 127.454673 -246.004268) (xy 127.474621 -245.957448)
			(xy 127.501822 -245.914434) (xy 127.53557 -245.87634) (xy 127.574992 -245.844153) (xy 127.619066 -245.818707)
			(xy 127.666652 -245.80066) (xy 127.716516 -245.79048) (xy 127.767368 -245.788431) (xy 127.817889 -245.794565)
			(xy 127.866773 -245.808725) (xy 127.912752 -245.830542) (xy 127.954636 -245.859452) (xy 127.99134 -245.894707)
			(xy 128.021913 -245.935393) (xy 128.045564 -245.980456) (xy 128.06168 -246.02873) (xy 128.069844 -246.078964)
			(xy 128.070356 -246.10441) (xy 128.388884 -246.10441) (xy 128.392844 -246.055356) (xy 128.404621 -246.007572)
			(xy 128.423912 -245.962296) (xy 128.450215 -245.9207) (xy 128.48285 -245.883863) (xy 128.520971 -245.852738)
			(xy 128.563592 -245.828131) (xy 128.609608 -245.810679) (xy 128.657827 -245.800835) (xy 128.707002 -245.798854)
			(xy 128.755857 -245.804786) (xy 128.803128 -245.818478) (xy 128.84759 -245.839576) (xy 128.888093 -245.867532)
			(xy 128.923586 -245.901624) (xy 128.953151 -245.940968) (xy 128.976022 -245.984545) (xy 128.991606 -246.031226)
			(xy 128.999501 -246.079803) (xy 128.999996 -246.10441) (xy 129.318507 -246.10441) (xy 129.322602 -246.053682)
			(xy 129.334781 -246.004268) (xy 129.354729 -245.957448) (xy 129.38193 -245.914434) (xy 129.415678 -245.87634)
			(xy 129.4551 -245.844153) (xy 129.499174 -245.818707) (xy 129.54676 -245.80066) (xy 129.596624 -245.79048)
			(xy 129.647476 -245.788431) (xy 129.697997 -245.794565) (xy 129.746881 -245.808725) (xy 129.79286 -245.830542)
			(xy 129.834744 -245.859452) (xy 129.871448 -245.894707) (xy 129.902021 -245.935393) (xy 129.925672 -245.980456)
			(xy 129.941788 -246.02873) (xy 129.949952 -246.078964) (xy 129.950464 -246.10441) (xy 129.949952 -246.129856)
			(xy 129.941788 -246.18009) (xy 129.925672 -246.228364) (xy 129.902021 -246.273427) (xy 129.871448 -246.314113)
			(xy 129.834744 -246.349368) (xy 129.79286 -246.378278) (xy 129.746881 -246.400095) (xy 129.697997 -246.414255)
			(xy 129.647476 -246.420389) (xy 129.596624 -246.41834) (xy 129.54676 -246.40816) (xy 129.499174 -246.390113)
			(xy 129.4551 -246.364667) (xy 129.415678 -246.33248) (xy 129.38193 -246.294386) (xy 129.354729 -246.251372)
			(xy 129.334781 -246.204552) (xy 129.322602 -246.155138) (xy 129.318507 -246.10441) (xy 128.999996 -246.10441)
			(xy 128.999501 -246.129017) (xy 128.991606 -246.177594) (xy 128.976022 -246.224275) (xy 128.953151 -246.267852)
			(xy 128.923586 -246.307196) (xy 128.888093 -246.341288) (xy 128.84759 -246.369244) (xy 128.803128 -246.390342)
			(xy 128.755857 -246.404034) (xy 128.707002 -246.409966) (xy 128.657827 -246.407985) (xy 128.609608 -246.398141)
			(xy 128.563592 -246.380689) (xy 128.520971 -246.356082) (xy 128.48285 -246.324957) (xy 128.450215 -246.28812)
			(xy 128.423912 -246.246524) (xy 128.404621 -246.201248) (xy 128.392844 -246.153464) (xy 128.388884 -246.10441)
			(xy 128.070356 -246.10441) (xy 128.069844 -246.129856) (xy 128.06168 -246.18009) (xy 128.045564 -246.228364)
			(xy 128.021913 -246.273427) (xy 127.99134 -246.314113) (xy 127.954636 -246.349368) (xy 127.912752 -246.378278)
			(xy 127.866773 -246.400095) (xy 127.817889 -246.414255) (xy 127.767368 -246.420389) (xy 127.716516 -246.41834)
			(xy 127.666652 -246.40816) (xy 127.619066 -246.390113) (xy 127.574992 -246.364667) (xy 127.53557 -246.33248)
			(xy 127.501822 -246.294386) (xy 127.474621 -246.251372) (xy 127.454673 -246.204552) (xy 127.442494 -246.155138)
			(xy 127.438399 -246.10441) (xy 127.120142 -246.10441) (xy 127.119647 -246.129017) (xy 127.111752 -246.177594)
			(xy 127.096168 -246.224275) (xy 127.073297 -246.267852) (xy 127.043732 -246.307196) (xy 127.008239 -246.341288)
			(xy 126.967736 -246.369244) (xy 126.923274 -246.390342) (xy 126.876003 -246.404034) (xy 126.827148 -246.409966)
			(xy 126.777973 -246.407985) (xy 126.729754 -246.398141) (xy 126.683738 -246.380689) (xy 126.641117 -246.356082)
			(xy 126.602996 -246.324957) (xy 126.570361 -246.28812) (xy 126.544058 -246.246524) (xy 126.524767 -246.201248)
			(xy 126.51299 -246.153464) (xy 126.50903 -246.10441) (xy 126.180088 -246.10441) (xy 126.179593 -246.129017)
			(xy 126.171698 -246.177594) (xy 126.156114 -246.224275) (xy 126.133243 -246.267852) (xy 126.103678 -246.307196)
			(xy 126.068185 -246.341288) (xy 126.027682 -246.369244) (xy 125.98322 -246.390342) (xy 125.935949 -246.404034)
			(xy 125.887094 -246.409966) (xy 125.837919 -246.407985) (xy 125.7897 -246.398141) (xy 125.743684 -246.380689)
			(xy 125.701063 -246.356082) (xy 125.662942 -246.324957) (xy 125.630307 -246.28812) (xy 125.604004 -246.246524)
			(xy 125.584713 -246.201248) (xy 125.572936 -246.153464) (xy 125.568976 -246.10441) (xy 125.240034 -246.10441)
			(xy 125.239539 -246.129017) (xy 125.231644 -246.177594) (xy 125.21606 -246.224275) (xy 125.193189 -246.267852)
			(xy 125.163624 -246.307196) (xy 125.128131 -246.341288) (xy 125.087628 -246.369244) (xy 125.043166 -246.390342)
			(xy 124.995895 -246.404034) (xy 124.94704 -246.409966) (xy 124.897865 -246.407985) (xy 124.849646 -246.398141)
			(xy 124.80363 -246.380689) (xy 124.761009 -246.356082) (xy 124.722888 -246.324957) (xy 124.690253 -246.28812)
			(xy 124.66395 -246.246524) (xy 124.644659 -246.201248) (xy 124.632882 -246.153464) (xy 124.628922 -246.10441)
			(xy 124.29998 -246.10441) (xy 124.299485 -246.129017) (xy 124.29159 -246.177594) (xy 124.276006 -246.224275)
			(xy 124.253135 -246.267852) (xy 124.22357 -246.307196) (xy 124.188077 -246.341288) (xy 124.147574 -246.369244)
			(xy 124.103112 -246.390342) (xy 124.055841 -246.404034) (xy 124.006986 -246.409966) (xy 123.957811 -246.407985)
			(xy 123.909592 -246.398141) (xy 123.863576 -246.380689) (xy 123.820955 -246.356082) (xy 123.782834 -246.324957)
			(xy 123.750199 -246.28812) (xy 123.723896 -246.246524) (xy 123.704605 -246.201248) (xy 123.692828 -246.153464)
			(xy 123.688868 -246.10441) (xy 123.359926 -246.10441) (xy 123.359431 -246.129017) (xy 123.351536 -246.177594)
			(xy 123.335952 -246.224275) (xy 123.313081 -246.267852) (xy 123.283516 -246.307196) (xy 123.248023 -246.341288)
			(xy 123.20752 -246.369244) (xy 123.163058 -246.390342) (xy 123.115787 -246.404034) (xy 123.066932 -246.409966)
			(xy 123.017757 -246.407985) (xy 122.969538 -246.398141) (xy 122.923522 -246.380689) (xy 122.880901 -246.356082)
			(xy 122.84278 -246.324957) (xy 122.810145 -246.28812) (xy 122.783842 -246.246524) (xy 122.764551 -246.201248)
			(xy 122.752774 -246.153464) (xy 122.748814 -246.10441) (xy 122.420126 -246.10441) (xy 122.419631 -246.129017)
			(xy 122.411736 -246.177594) (xy 122.396152 -246.224275) (xy 122.373281 -246.267852) (xy 122.343716 -246.307196)
			(xy 122.308223 -246.341288) (xy 122.26772 -246.369244) (xy 122.223258 -246.390342) (xy 122.175987 -246.404034)
			(xy 122.127132 -246.409966) (xy 122.077957 -246.407985) (xy 122.029738 -246.398141) (xy 121.983722 -246.380689)
			(xy 121.941101 -246.356082) (xy 121.90298 -246.324957) (xy 121.870345 -246.28812) (xy 121.844042 -246.246524)
			(xy 121.824751 -246.201248) (xy 121.812974 -246.153464) (xy 121.809014 -246.10441) (xy 121.480072 -246.10441)
			(xy 121.479577 -246.129017) (xy 121.471682 -246.177594) (xy 121.456098 -246.224275) (xy 121.433227 -246.267852)
			(xy 121.403662 -246.307196) (xy 121.368169 -246.341288) (xy 121.327666 -246.369244) (xy 121.283204 -246.390342)
			(xy 121.235933 -246.404034) (xy 121.187078 -246.409966) (xy 121.137903 -246.407985) (xy 121.089684 -246.398141)
			(xy 121.043668 -246.380689) (xy 121.001047 -246.356082) (xy 120.962926 -246.324957) (xy 120.930291 -246.28812)
			(xy 120.903988 -246.246524) (xy 120.884697 -246.201248) (xy 120.87292 -246.153464) (xy 120.86896 -246.10441)
			(xy 120.540018 -246.10441) (xy 120.539523 -246.129017) (xy 120.531628 -246.177594) (xy 120.516044 -246.224275)
			(xy 120.493173 -246.267852) (xy 120.463608 -246.307196) (xy 120.428115 -246.341288) (xy 120.387612 -246.369244)
			(xy 120.34315 -246.390342) (xy 120.295879 -246.404034) (xy 120.247024 -246.409966) (xy 120.197849 -246.407985)
			(xy 120.14963 -246.398141) (xy 120.103614 -246.380689) (xy 120.060993 -246.356082) (xy 120.022872 -246.324957)
			(xy 119.990237 -246.28812) (xy 119.963934 -246.246524) (xy 119.944643 -246.201248) (xy 119.932866 -246.153464)
			(xy 119.928906 -246.10441) (xy 119.599964 -246.10441) (xy 119.599469 -246.129017) (xy 119.591574 -246.177594)
			(xy 119.57599 -246.224275) (xy 119.553119 -246.267852) (xy 119.523554 -246.307196) (xy 119.488061 -246.341288)
			(xy 119.447558 -246.369244) (xy 119.403096 -246.390342) (xy 119.355825 -246.404034) (xy 119.30697 -246.409966)
			(xy 119.257795 -246.407985) (xy 119.209576 -246.398141) (xy 119.16356 -246.380689) (xy 119.120939 -246.356082)
			(xy 119.082818 -246.324957) (xy 119.050183 -246.28812) (xy 119.02388 -246.246524) (xy 119.004589 -246.201248)
			(xy 118.992812 -246.153464) (xy 118.988852 -246.10441) (xy 118.660164 -246.10441) (xy 118.659669 -246.129017)
			(xy 118.651774 -246.177594) (xy 118.63619 -246.224275) (xy 118.613319 -246.267852) (xy 118.583754 -246.307196)
			(xy 118.548261 -246.341288) (xy 118.507758 -246.369244) (xy 118.463296 -246.390342) (xy 118.416025 -246.404034)
			(xy 118.36717 -246.409966) (xy 118.317995 -246.407985) (xy 118.269776 -246.398141) (xy 118.22376 -246.380689)
			(xy 118.181139 -246.356082) (xy 118.143018 -246.324957) (xy 118.110383 -246.28812) (xy 118.08408 -246.246524)
			(xy 118.064789 -246.201248) (xy 118.053012 -246.153464) (xy 118.049052 -246.10441) (xy 117.72011 -246.10441)
			(xy 117.719615 -246.129017) (xy 117.71172 -246.177594) (xy 117.696136 -246.224275) (xy 117.673265 -246.267852)
			(xy 117.6437 -246.307196) (xy 117.608207 -246.341288) (xy 117.567704 -246.369244) (xy 117.523242 -246.390342)
			(xy 117.475971 -246.404034) (xy 117.427116 -246.409966) (xy 117.377941 -246.407985) (xy 117.329722 -246.398141)
			(xy 117.283706 -246.380689) (xy 117.241085 -246.356082) (xy 117.202964 -246.324957) (xy 117.170329 -246.28812)
			(xy 117.144026 -246.246524) (xy 117.124735 -246.201248) (xy 117.112958 -246.153464) (xy 117.108998 -246.10441)
			(xy 116.780056 -246.10441) (xy 116.779561 -246.129017) (xy 116.771666 -246.177594) (xy 116.756082 -246.224275)
			(xy 116.733211 -246.267852) (xy 116.703646 -246.307196) (xy 116.668153 -246.341288) (xy 116.62765 -246.369244)
			(xy 116.583188 -246.390342) (xy 116.535917 -246.404034) (xy 116.487062 -246.409966) (xy 116.437887 -246.407985)
			(xy 116.389668 -246.398141) (xy 116.343652 -246.380689) (xy 116.301031 -246.356082) (xy 116.26291 -246.324957)
			(xy 116.230275 -246.28812) (xy 116.203972 -246.246524) (xy 116.184681 -246.201248) (xy 116.172904 -246.153464)
			(xy 116.168944 -246.10441) (xy 115.840002 -246.10441) (xy 115.839507 -246.129017) (xy 115.831612 -246.177594)
			(xy 115.816028 -246.224275) (xy 115.793157 -246.267852) (xy 115.763592 -246.307196) (xy 115.728099 -246.341288)
			(xy 115.687596 -246.369244) (xy 115.643134 -246.390342) (xy 115.595863 -246.404034) (xy 115.547008 -246.409966)
			(xy 115.497833 -246.407985) (xy 115.449614 -246.398141) (xy 115.403598 -246.380689) (xy 115.360977 -246.356082)
			(xy 115.322856 -246.324957) (xy 115.290221 -246.28812) (xy 115.263918 -246.246524) (xy 115.244627 -246.201248)
			(xy 115.23285 -246.153464) (xy 115.22889 -246.10441) (xy 108.326428 -246.10441) (xy 108.325933 -246.129017)
			(xy 108.318038 -246.177594) (xy 108.302454 -246.224275) (xy 108.279583 -246.267852) (xy 108.250018 -246.307196)
			(xy 108.214525 -246.341288) (xy 108.174022 -246.369244) (xy 108.12956 -246.390342) (xy 108.082289 -246.404034)
			(xy 108.033434 -246.409966) (xy 107.984259 -246.407985) (xy 107.93604 -246.398141) (xy 107.890024 -246.380689)
			(xy 107.847403 -246.356082) (xy 107.809282 -246.324957) (xy 107.776647 -246.28812) (xy 107.750344 -246.246524)
			(xy 107.731053 -246.201248) (xy 107.719276 -246.153464) (xy 107.715316 -246.10441) (xy 107.387224 -246.10441)
			(xy 107.383049 -246.15479) (xy 107.370636 -246.203805) (xy 107.350323 -246.250109) (xy 107.322666 -246.292437)
			(xy 107.288419 -246.329635) (xy 107.248516 -246.360689) (xy 107.204046 -246.384751) (xy 107.156221 -246.401164)
			(xy 107.106347 -246.409482) (xy 107.081066 -246.409972) (xy 106.141012 -246.409972) (xy 106.115733 -246.40946)
			(xy 106.065866 -246.40114) (xy 106.018047 -246.384726) (xy 105.973583 -246.360665) (xy 105.933686 -246.329613)
			(xy 105.899444 -246.292417) (xy 105.871791 -246.250093) (xy 105.851482 -246.203794) (xy 105.839071 -246.154784)
			(xy 105.834895 -246.1044) (xy 105.506266 -246.1044) (xy 105.506266 -246.10441) (xy 105.505771 -246.129017)
			(xy 105.497876 -246.177594) (xy 105.482292 -246.224275) (xy 105.459421 -246.267852) (xy 105.429856 -246.307196)
			(xy 105.394363 -246.341288) (xy 105.35386 -246.369244) (xy 105.309398 -246.390342) (xy 105.262127 -246.404034)
			(xy 105.213272 -246.409966) (xy 105.164097 -246.407985) (xy 105.115878 -246.398141) (xy 105.069862 -246.380689)
			(xy 105.027241 -246.356082) (xy 104.98912 -246.324957) (xy 104.956485 -246.28812) (xy 104.930182 -246.246524)
			(xy 104.910891 -246.201248) (xy 104.899114 -246.153464) (xy 104.895154 -246.10441) (xy 104.567324 -246.10441)
			(xy 104.563149 -246.154791) (xy 104.550735 -246.203807) (xy 104.530422 -246.250111) (xy 104.502764 -246.29244)
			(xy 104.468516 -246.329638) (xy 104.428612 -246.360692) (xy 104.38414 -246.384753) (xy 104.336315 -246.401166)
			(xy 104.28644 -246.409482) (xy 104.261158 -246.409972) (xy 103.321104 -246.409972) (xy 103.295826 -246.409459)
			(xy 103.245959 -246.401139) (xy 103.198142 -246.384724) (xy 103.153679 -246.360662) (xy 103.113783 -246.32961)
			(xy 103.079542 -246.292415) (xy 103.05189 -246.250091) (xy 103.031581 -246.203793) (xy 103.01917 -246.154784)
			(xy 103.014995 -246.1044) (xy 102.686358 -246.1044) (xy 102.686358 -246.10441) (xy 102.685863 -246.129017)
			(xy 102.677968 -246.177594) (xy 102.662384 -246.224275) (xy 102.639513 -246.267852) (xy 102.609948 -246.307196)
			(xy 102.574455 -246.341288) (xy 102.533952 -246.369244) (xy 102.48949 -246.390342) (xy 102.442219 -246.404034)
			(xy 102.393364 -246.409966) (xy 102.344189 -246.407985) (xy 102.29597 -246.398141) (xy 102.249954 -246.380689)
			(xy 102.207333 -246.356082) (xy 102.169212 -246.324957) (xy 102.136577 -246.28812) (xy 102.110274 -246.246524)
			(xy 102.090983 -246.201248) (xy 102.079206 -246.153464) (xy 102.075246 -246.10441) (xy 101.747124 -246.10441)
			(xy 101.742949 -246.154787) (xy 101.730538 -246.203799) (xy 101.710228 -246.2501) (xy 101.682574 -246.292427)
			(xy 101.648331 -246.329625) (xy 101.608432 -246.360679) (xy 101.563966 -246.384742) (xy 101.516146 -246.401158)
			(xy 101.466276 -246.409479) (xy 101.440996 -246.409972) (xy 100.500942 -246.409972) (xy 100.475662 -246.409462)
			(xy 100.42579 -246.401146) (xy 100.377968 -246.384735) (xy 100.333499 -246.360675) (xy 100.293597 -246.329623)
			(xy 100.259351 -246.292427) (xy 100.231695 -246.250101) (xy 100.211384 -246.2038) (xy 100.198971 -246.154788)
			(xy 100.194795 -246.1044) (xy 99.86645 -246.1044) (xy 99.86645 -246.10441) (xy 99.865955 -246.129017)
			(xy 99.85806 -246.177594) (xy 99.842476 -246.224275) (xy 99.819605 -246.267852) (xy 99.79004 -246.307196)
			(xy 99.754547 -246.341288) (xy 99.714044 -246.369244) (xy 99.669582 -246.390342) (xy 99.622311 -246.404034)
			(xy 99.573456 -246.409966) (xy 99.524281 -246.407985) (xy 99.476062 -246.398141) (xy 99.430046 -246.380689)
			(xy 99.387425 -246.356082) (xy 99.349304 -246.324957) (xy 99.316669 -246.28812) (xy 99.290366 -246.246524)
			(xy 99.271075 -246.201248) (xy 99.259298 -246.153464) (xy 99.255338 -246.10441) (xy 98.927224 -246.10441)
			(xy 98.923049 -246.154788) (xy 98.910637 -246.203801) (xy 98.890327 -246.250102) (xy 98.862672 -246.29243)
			(xy 98.828428 -246.329627) (xy 98.788528 -246.360681) (xy 98.744061 -246.384744) (xy 98.696239 -246.40116)
			(xy 98.646368 -246.40948) (xy 98.621088 -246.409972) (xy 97.681034 -246.409972) (xy 97.655754 -246.409462)
			(xy 97.605884 -246.401145) (xy 97.558062 -246.384732) (xy 97.513595 -246.360672) (xy 97.473694 -246.329621)
			(xy 97.439449 -246.292425) (xy 97.411794 -246.250099) (xy 97.391483 -246.203799) (xy 97.379071 -246.154787)
			(xy 97.374895 -246.1044) (xy 97.045765 -246.1044) (xy 97.045764 -246.129278) (xy 97.037698 -246.178362)
			(xy 97.02178 -246.225489) (xy 96.998432 -246.269412) (xy 96.968271 -246.308968) (xy 96.95053 -246.326406)
			(xy 96.943164 -246.333264) (xy 96.930972 -246.360442) (xy 96.928921 -246.3654) (xy 96.926744 -246.375905)
			(xy 96.926654 -246.38127) (xy 96.926654 -246.54764) (xy 96.92767 -246.558054) (xy 96.929956 -246.568468)
			(xy 96.933258 -246.578628) (xy 96.937576 -246.58828) (xy 97.03435 -246.647462) (xy 97.060512 -246.648478)
			(xy 97.07245 -246.642382) (xy 97.094042 -246.631881) (xy 97.139706 -246.617046) (xy 97.187128 -246.609539)
			(xy 97.211134 -246.609108) (xy 97.236386 -246.609632) (xy 97.286201 -246.61795) (xy 97.333967 -246.634353)
			(xy 97.378383 -246.658394) (xy 97.418236 -246.689417) (xy 97.45244 -246.726576) (xy 97.480061 -246.768858)
			(xy 97.500347 -246.815109) (xy 97.512745 -246.864068) (xy 97.516915 -246.9144) (xy 97.516914 -246.914416)
			(xy 97.84513 -246.914416) (xy 97.84909 -246.865362) (xy 97.860867 -246.817578) (xy 97.880158 -246.772302)
			(xy 97.906461 -246.730706) (xy 97.939096 -246.693869) (xy 97.977217 -246.662744) (xy 98.019838 -246.638137)
			(xy 98.065854 -246.620685) (xy 98.114073 -246.610841) (xy 98.163248 -246.60886) (xy 98.212103 -246.614792)
			(xy 98.259374 -246.628484) (xy 98.303836 -246.649582) (xy 98.344339 -246.677538) (xy 98.379832 -246.71163)
			(xy 98.409397 -246.750974) (xy 98.432268 -246.794551) (xy 98.447852 -246.841232) (xy 98.455747 -246.889809)
			(xy 98.456242 -246.914416) (xy 98.785184 -246.914416) (xy 98.789144 -246.865362) (xy 98.800921 -246.817578)
			(xy 98.820212 -246.772302) (xy 98.846515 -246.730706) (xy 98.87915 -246.693869) (xy 98.917271 -246.662744)
			(xy 98.959892 -246.638137) (xy 99.005908 -246.620685) (xy 99.054127 -246.610841) (xy 99.103302 -246.60886)
			(xy 99.152157 -246.614792) (xy 99.199428 -246.628484) (xy 99.24389 -246.649582) (xy 99.284393 -246.677538)
			(xy 99.319886 -246.71163) (xy 99.349451 -246.750974) (xy 99.372322 -246.794551) (xy 99.387906 -246.841232)
			(xy 99.395801 -246.889809) (xy 99.396296 -246.914416) (xy 99.725238 -246.914416) (xy 99.729198 -246.865362)
			(xy 99.740975 -246.817578) (xy 99.760266 -246.772302) (xy 99.786569 -246.730706) (xy 99.819204 -246.693869)
			(xy 99.857325 -246.662744) (xy 99.899946 -246.638137) (xy 99.945962 -246.620685) (xy 99.994181 -246.610841)
			(xy 100.043356 -246.60886) (xy 100.092211 -246.614792) (xy 100.139482 -246.628484) (xy 100.183944 -246.649582)
			(xy 100.224447 -246.677538) (xy 100.25994 -246.71163) (xy 100.289505 -246.750974) (xy 100.312376 -246.794551)
			(xy 100.32796 -246.841232) (xy 100.335855 -246.889809) (xy 100.33635 -246.914416) (xy 100.665292 -246.914416)
			(xy 100.669252 -246.865362) (xy 100.681029 -246.817578) (xy 100.70032 -246.772302) (xy 100.726623 -246.730706)
			(xy 100.759258 -246.693869) (xy 100.797379 -246.662744) (xy 100.84 -246.638137) (xy 100.886016 -246.620685)
			(xy 100.934235 -246.610841) (xy 100.98341 -246.60886) (xy 101.032265 -246.614792) (xy 101.079536 -246.628484)
			(xy 101.123998 -246.649582) (xy 101.164501 -246.677538) (xy 101.199994 -246.71163) (xy 101.229559 -246.750974)
			(xy 101.25243 -246.794551) (xy 101.268014 -246.841232) (xy 101.275909 -246.889809) (xy 101.276404 -246.914416)
			(xy 101.605346 -246.914416) (xy 101.609306 -246.865362) (xy 101.621083 -246.817578) (xy 101.640374 -246.772302)
			(xy 101.666677 -246.730706) (xy 101.699312 -246.693869) (xy 101.737433 -246.662744) (xy 101.780054 -246.638137)
			(xy 101.82607 -246.620685) (xy 101.874289 -246.610841) (xy 101.923464 -246.60886) (xy 101.972319 -246.614792)
			(xy 102.01959 -246.628484) (xy 102.064052 -246.649582) (xy 102.104555 -246.677538) (xy 102.140048 -246.71163)
			(xy 102.169613 -246.750974) (xy 102.192484 -246.794551) (xy 102.208068 -246.841232) (xy 102.215963 -246.889809)
			(xy 102.216458 -246.914416) (xy 102.545146 -246.914416) (xy 102.549106 -246.865362) (xy 102.560883 -246.817578)
			(xy 102.580174 -246.772302) (xy 102.606477 -246.730706) (xy 102.639112 -246.693869) (xy 102.677233 -246.662744)
			(xy 102.719854 -246.638137) (xy 102.76587 -246.620685) (xy 102.814089 -246.610841) (xy 102.863264 -246.60886)
			(xy 102.912119 -246.614792) (xy 102.95939 -246.628484) (xy 103.003852 -246.649582) (xy 103.044355 -246.677538)
			(xy 103.079848 -246.71163) (xy 103.109413 -246.750974) (xy 103.132284 -246.794551) (xy 103.147868 -246.841232)
			(xy 103.155763 -246.889809) (xy 103.156258 -246.914416) (xy 103.4852 -246.914416) (xy 103.48916 -246.865362)
			(xy 103.500937 -246.817578) (xy 103.520228 -246.772302) (xy 103.546531 -246.730706) (xy 103.579166 -246.693869)
			(xy 103.617287 -246.662744) (xy 103.659908 -246.638137) (xy 103.705924 -246.620685) (xy 103.754143 -246.610841)
			(xy 103.803318 -246.60886) (xy 103.852173 -246.614792) (xy 103.899444 -246.628484) (xy 103.943906 -246.649582)
			(xy 103.984409 -246.677538) (xy 104.019902 -246.71163) (xy 104.049467 -246.750974) (xy 104.072338 -246.794551)
			(xy 104.087922 -246.841232) (xy 104.095817 -246.889809) (xy 104.096312 -246.914416) (xy 104.425254 -246.914416)
			(xy 104.429214 -246.865362) (xy 104.440991 -246.817578) (xy 104.460282 -246.772302) (xy 104.486585 -246.730706)
			(xy 104.51922 -246.693869) (xy 104.557341 -246.662744) (xy 104.599962 -246.638137) (xy 104.645978 -246.620685)
			(xy 104.694197 -246.610841) (xy 104.743372 -246.60886) (xy 104.792227 -246.614792) (xy 104.839498 -246.628484)
			(xy 104.88396 -246.649582) (xy 104.924463 -246.677538) (xy 104.959956 -246.71163) (xy 104.989521 -246.750974)
			(xy 105.012392 -246.794551) (xy 105.027976 -246.841232) (xy 105.035871 -246.889809) (xy 105.036366 -246.914416)
			(xy 105.365308 -246.914416) (xy 105.369268 -246.865362) (xy 105.381045 -246.817578) (xy 105.400336 -246.772302)
			(xy 105.426639 -246.730706) (xy 105.459274 -246.693869) (xy 105.497395 -246.662744) (xy 105.540016 -246.638137)
			(xy 105.586032 -246.620685) (xy 105.634251 -246.610841) (xy 105.683426 -246.60886) (xy 105.732281 -246.614792)
			(xy 105.779552 -246.628484) (xy 105.824014 -246.649582) (xy 105.864517 -246.677538) (xy 105.90001 -246.71163)
			(xy 105.929575 -246.750974) (xy 105.952446 -246.794551) (xy 105.96803 -246.841232) (xy 105.975925 -246.889809)
			(xy 105.97642 -246.914416) (xy 106.305362 -246.914416) (xy 106.309322 -246.865362) (xy 106.321099 -246.817578)
			(xy 106.34039 -246.772302) (xy 106.366693 -246.730706) (xy 106.399328 -246.693869) (xy 106.437449 -246.662744)
			(xy 106.48007 -246.638137) (xy 106.526086 -246.620685) (xy 106.574305 -246.610841) (xy 106.62348 -246.60886)
			(xy 106.672335 -246.614792) (xy 106.719606 -246.628484) (xy 106.764068 -246.649582) (xy 106.804571 -246.677538)
			(xy 106.840064 -246.71163) (xy 106.869629 -246.750974) (xy 106.8925 -246.794551) (xy 106.908084 -246.841232)
			(xy 106.915979 -246.889809) (xy 106.916474 -246.914416) (xy 107.245162 -246.914416) (xy 107.249122 -246.865362)
			(xy 107.260899 -246.817578) (xy 107.28019 -246.772302) (xy 107.306493 -246.730706) (xy 107.339128 -246.693869)
			(xy 107.377249 -246.662744) (xy 107.41987 -246.638137) (xy 107.465886 -246.620685) (xy 107.514105 -246.610841)
			(xy 107.56328 -246.60886) (xy 107.612135 -246.614792) (xy 107.659406 -246.628484) (xy 107.703868 -246.649582)
			(xy 107.744371 -246.677538) (xy 107.779864 -246.71163) (xy 107.809429 -246.750974) (xy 107.8323 -246.794551)
			(xy 107.847884 -246.841232) (xy 107.855779 -246.889809) (xy 107.856274 -246.9144) (xy 108.185156 -246.9144)
			(xy 108.189328 -246.864058) (xy 108.201729 -246.815089) (xy 108.222021 -246.768829) (xy 108.249651 -246.72654)
			(xy 108.283865 -246.689376) (xy 108.32373 -246.658351) (xy 108.368157 -246.63431) (xy 108.415936 -246.617911)
			(xy 108.465763 -246.609599) (xy 108.49102 -246.609108) (xy 109.431074 -246.609108) (xy 109.456334 -246.609567)
			(xy 109.506167 -246.617878) (xy 109.553951 -246.634279) (xy 109.598385 -246.658322) (xy 109.638254 -246.68935)
			(xy 109.672472 -246.726518) (xy 109.700106 -246.768812) (xy 109.720401 -246.815077) (xy 109.732804 -246.864052)
			(xy 109.736976 -246.9144) (xy 109.736975 -246.914416) (xy 110.065324 -246.914416) (xy 110.069284 -246.865362)
			(xy 110.081061 -246.817578) (xy 110.100352 -246.772302) (xy 110.126655 -246.730706) (xy 110.15929 -246.693869)
			(xy 110.197411 -246.662744) (xy 110.240032 -246.638137) (xy 110.286048 -246.620685) (xy 110.334267 -246.610841)
			(xy 110.383442 -246.60886) (xy 110.432297 -246.614792) (xy 110.479568 -246.628484) (xy 110.52403 -246.649582)
			(xy 110.564533 -246.677538) (xy 110.600026 -246.71163) (xy 110.629591 -246.750974) (xy 110.652462 -246.794551)
			(xy 110.668046 -246.841232) (xy 110.675941 -246.889809) (xy 110.676436 -246.914416) (xy 112.878882 -246.914416)
			(xy 112.882842 -246.865362) (xy 112.894619 -246.817578) (xy 112.91391 -246.772302) (xy 112.940213 -246.730706)
			(xy 112.972848 -246.693869) (xy 113.010969 -246.662744) (xy 113.05359 -246.638137) (xy 113.099606 -246.620685)
			(xy 113.147825 -246.610841) (xy 113.197 -246.60886) (xy 113.245855 -246.614792) (xy 113.293126 -246.628484)
			(xy 113.337588 -246.649582) (xy 113.378091 -246.677538) (xy 113.413584 -246.71163) (xy 113.443149 -246.750974)
			(xy 113.46602 -246.794551) (xy 113.481604 -246.841232) (xy 113.489499 -246.889809) (xy 113.489994 -246.914416)
			(xy 113.818936 -246.914416) (xy 113.822896 -246.865362) (xy 113.834673 -246.817578) (xy 113.853964 -246.772302)
			(xy 113.880267 -246.730706) (xy 113.912902 -246.693869) (xy 113.951023 -246.662744) (xy 113.993644 -246.638137)
			(xy 114.03966 -246.620685) (xy 114.087879 -246.610841) (xy 114.137054 -246.60886) (xy 114.185909 -246.614792)
			(xy 114.23318 -246.628484) (xy 114.277642 -246.649582) (xy 114.318145 -246.677538) (xy 114.353638 -246.71163)
			(xy 114.383203 -246.750974) (xy 114.406074 -246.794551) (xy 114.421658 -246.841232) (xy 114.429553 -246.889809)
			(xy 114.430048 -246.914416) (xy 114.75899 -246.914416) (xy 114.76295 -246.865362) (xy 114.774727 -246.817578)
			(xy 114.794018 -246.772302) (xy 114.820321 -246.730706) (xy 114.852956 -246.693869) (xy 114.891077 -246.662744)
			(xy 114.933698 -246.638137) (xy 114.979714 -246.620685) (xy 115.027933 -246.610841) (xy 115.077108 -246.60886)
			(xy 115.125963 -246.614792) (xy 115.173234 -246.628484) (xy 115.217696 -246.649582) (xy 115.258199 -246.677538)
			(xy 115.293692 -246.71163) (xy 115.323257 -246.750974) (xy 115.346128 -246.794551) (xy 115.361712 -246.841232)
			(xy 115.369607 -246.889809) (xy 115.370102 -246.914416) (xy 115.699044 -246.914416) (xy 115.703004 -246.865362)
			(xy 115.714781 -246.817578) (xy 115.734072 -246.772302) (xy 115.760375 -246.730706) (xy 115.79301 -246.693869)
			(xy 115.831131 -246.662744) (xy 115.873752 -246.638137) (xy 115.919768 -246.620685) (xy 115.967987 -246.610841)
			(xy 116.017162 -246.60886) (xy 116.066017 -246.614792) (xy 116.113288 -246.628484) (xy 116.15775 -246.649582)
			(xy 116.198253 -246.677538) (xy 116.233746 -246.71163) (xy 116.263311 -246.750974) (xy 116.286182 -246.794551)
			(xy 116.301766 -246.841232) (xy 116.309661 -246.889809) (xy 116.310156 -246.914416) (xy 116.638844 -246.914416)
			(xy 116.642804 -246.865362) (xy 116.654581 -246.817578) (xy 116.673872 -246.772302) (xy 116.700175 -246.730706)
			(xy 116.73281 -246.693869) (xy 116.770931 -246.662744) (xy 116.813552 -246.638137) (xy 116.859568 -246.620685)
			(xy 116.907787 -246.610841) (xy 116.956962 -246.60886) (xy 117.005817 -246.614792) (xy 117.053088 -246.628484)
			(xy 117.09755 -246.649582) (xy 117.138053 -246.677538) (xy 117.173546 -246.71163) (xy 117.203111 -246.750974)
			(xy 117.225982 -246.794551) (xy 117.241566 -246.841232) (xy 117.249461 -246.889809) (xy 117.249956 -246.914416)
			(xy 117.578898 -246.914416) (xy 117.582858 -246.865362) (xy 117.594635 -246.817578) (xy 117.613926 -246.772302)
			(xy 117.640229 -246.730706) (xy 117.672864 -246.693869) (xy 117.710985 -246.662744) (xy 117.753606 -246.638137)
			(xy 117.799622 -246.620685) (xy 117.847841 -246.610841) (xy 117.897016 -246.60886) (xy 117.945871 -246.614792)
			(xy 117.993142 -246.628484) (xy 118.037604 -246.649582) (xy 118.078107 -246.677538) (xy 118.1136 -246.71163)
			(xy 118.143165 -246.750974) (xy 118.166036 -246.794551) (xy 118.18162 -246.841232) (xy 118.189515 -246.889809)
			(xy 118.19001 -246.914416) (xy 118.518952 -246.914416) (xy 118.522912 -246.865362) (xy 118.534689 -246.817578)
			(xy 118.55398 -246.772302) (xy 118.580283 -246.730706) (xy 118.612918 -246.693869) (xy 118.651039 -246.662744)
			(xy 118.69366 -246.638137) (xy 118.739676 -246.620685) (xy 118.787895 -246.610841) (xy 118.83707 -246.60886)
			(xy 118.885925 -246.614792) (xy 118.933196 -246.628484) (xy 118.977658 -246.649582) (xy 119.018161 -246.677538)
			(xy 119.053654 -246.71163) (xy 119.083219 -246.750974) (xy 119.10609 -246.794551) (xy 119.121674 -246.841232)
			(xy 119.129569 -246.889809) (xy 119.130064 -246.914416) (xy 119.459006 -246.914416) (xy 119.462966 -246.865362)
			(xy 119.474743 -246.817578) (xy 119.494034 -246.772302) (xy 119.520337 -246.730706) (xy 119.552972 -246.693869)
			(xy 119.591093 -246.662744) (xy 119.633714 -246.638137) (xy 119.67973 -246.620685) (xy 119.727949 -246.610841)
			(xy 119.777124 -246.60886) (xy 119.825979 -246.614792) (xy 119.87325 -246.628484) (xy 119.917712 -246.649582)
			(xy 119.958215 -246.677538) (xy 119.993708 -246.71163) (xy 120.023273 -246.750974) (xy 120.046144 -246.794551)
			(xy 120.061728 -246.841232) (xy 120.069623 -246.889809) (xy 120.070118 -246.914416) (xy 120.398806 -246.914416)
			(xy 120.402766 -246.865362) (xy 120.414543 -246.817578) (xy 120.433834 -246.772302) (xy 120.460137 -246.730706)
			(xy 120.492772 -246.693869) (xy 120.530893 -246.662744) (xy 120.573514 -246.638137) (xy 120.61953 -246.620685)
			(xy 120.667749 -246.610841) (xy 120.716924 -246.60886) (xy 120.765779 -246.614792) (xy 120.81305 -246.628484)
			(xy 120.857512 -246.649582) (xy 120.898015 -246.677538) (xy 120.933508 -246.71163) (xy 120.963073 -246.750974)
			(xy 120.985944 -246.794551) (xy 121.001528 -246.841232) (xy 121.009423 -246.889809) (xy 121.009918 -246.914416)
			(xy 121.33886 -246.914416) (xy 121.34282 -246.865362) (xy 121.354597 -246.817578) (xy 121.373888 -246.772302)
			(xy 121.400191 -246.730706) (xy 121.432826 -246.693869) (xy 121.470947 -246.662744) (xy 121.513568 -246.638137)
			(xy 121.559584 -246.620685) (xy 121.607803 -246.610841) (xy 121.656978 -246.60886) (xy 121.705833 -246.614792)
			(xy 121.753104 -246.628484) (xy 121.797566 -246.649582) (xy 121.838069 -246.677538) (xy 121.873562 -246.71163)
			(xy 121.903127 -246.750974) (xy 121.925998 -246.794551) (xy 121.941582 -246.841232) (xy 121.949477 -246.889809)
			(xy 121.949972 -246.914416) (xy 122.278914 -246.914416) (xy 122.282874 -246.865362) (xy 122.294651 -246.817578)
			(xy 122.313942 -246.772302) (xy 122.340245 -246.730706) (xy 122.37288 -246.693869) (xy 122.411001 -246.662744)
			(xy 122.453622 -246.638137) (xy 122.499638 -246.620685) (xy 122.547857 -246.610841) (xy 122.597032 -246.60886)
			(xy 122.645887 -246.614792) (xy 122.693158 -246.628484) (xy 122.73762 -246.649582) (xy 122.778123 -246.677538)
			(xy 122.813616 -246.71163) (xy 122.843181 -246.750974) (xy 122.866052 -246.794551) (xy 122.881636 -246.841232)
			(xy 122.889531 -246.889809) (xy 122.890026 -246.914416) (xy 123.218968 -246.914416) (xy 123.222928 -246.865362)
			(xy 123.234705 -246.817578) (xy 123.253996 -246.772302) (xy 123.280299 -246.730706) (xy 123.312934 -246.693869)
			(xy 123.351055 -246.662744) (xy 123.393676 -246.638137) (xy 123.439692 -246.620685) (xy 123.487911 -246.610841)
			(xy 123.537086 -246.60886) (xy 123.585941 -246.614792) (xy 123.633212 -246.628484) (xy 123.677674 -246.649582)
			(xy 123.718177 -246.677538) (xy 123.75367 -246.71163) (xy 123.783235 -246.750974) (xy 123.806106 -246.794551)
			(xy 123.82169 -246.841232) (xy 123.829585 -246.889809) (xy 123.83008 -246.914416) (xy 124.159022 -246.914416)
			(xy 124.162982 -246.865362) (xy 124.174759 -246.817578) (xy 124.19405 -246.772302) (xy 124.220353 -246.730706)
			(xy 124.252988 -246.693869) (xy 124.291109 -246.662744) (xy 124.33373 -246.638137) (xy 124.379746 -246.620685)
			(xy 124.427965 -246.610841) (xy 124.47714 -246.60886) (xy 124.525995 -246.614792) (xy 124.573266 -246.628484)
			(xy 124.617728 -246.649582) (xy 124.658231 -246.677538) (xy 124.693724 -246.71163) (xy 124.723289 -246.750974)
			(xy 124.74616 -246.794551) (xy 124.761744 -246.841232) (xy 124.769639 -246.889809) (xy 124.770134 -246.914416)
			(xy 125.098822 -246.914416) (xy 125.102782 -246.865362) (xy 125.114559 -246.817578) (xy 125.13385 -246.772302)
			(xy 125.160153 -246.730706) (xy 125.192788 -246.693869) (xy 125.230909 -246.662744) (xy 125.27353 -246.638137)
			(xy 125.319546 -246.620685) (xy 125.367765 -246.610841) (xy 125.41694 -246.60886) (xy 125.465795 -246.614792)
			(xy 125.513066 -246.628484) (xy 125.557528 -246.649582) (xy 125.598031 -246.677538) (xy 125.633524 -246.71163)
			(xy 125.663089 -246.750974) (xy 125.68596 -246.794551) (xy 125.701544 -246.841232) (xy 125.709439 -246.889809)
			(xy 125.709934 -246.914416) (xy 126.038876 -246.914416) (xy 126.042836 -246.865362) (xy 126.054613 -246.817578)
			(xy 126.073904 -246.772302) (xy 126.100207 -246.730706) (xy 126.132842 -246.693869) (xy 126.170963 -246.662744)
			(xy 126.213584 -246.638137) (xy 126.2596 -246.620685) (xy 126.307819 -246.610841) (xy 126.356994 -246.60886)
			(xy 126.405849 -246.614792) (xy 126.45312 -246.628484) (xy 126.497582 -246.649582) (xy 126.538085 -246.677538)
			(xy 126.573578 -246.71163) (xy 126.603143 -246.750974) (xy 126.626014 -246.794551) (xy 126.641598 -246.841232)
			(xy 126.649493 -246.889809) (xy 126.649988 -246.914416) (xy 126.97893 -246.914416) (xy 126.98289 -246.865362)
			(xy 126.994667 -246.817578) (xy 127.013958 -246.772302) (xy 127.040261 -246.730706) (xy 127.072896 -246.693869)
			(xy 127.111017 -246.662744) (xy 127.153638 -246.638137) (xy 127.199654 -246.620685) (xy 127.247873 -246.610841)
			(xy 127.297048 -246.60886) (xy 127.345903 -246.614792) (xy 127.393174 -246.628484) (xy 127.437636 -246.649582)
			(xy 127.478139 -246.677538) (xy 127.513632 -246.71163) (xy 127.543197 -246.750974) (xy 127.566068 -246.794551)
			(xy 127.581652 -246.841232) (xy 127.589547 -246.889809) (xy 127.590042 -246.914416) (xy 127.908553 -246.914416)
			(xy 127.912648 -246.863688) (xy 127.924827 -246.814274) (xy 127.944775 -246.767454) (xy 127.971976 -246.72444)
			(xy 128.005724 -246.686346) (xy 128.045146 -246.654159) (xy 128.08922 -246.628713) (xy 128.136806 -246.610666)
			(xy 128.18667 -246.600486) (xy 128.237522 -246.598437) (xy 128.288043 -246.604571) (xy 128.336927 -246.618731)
			(xy 128.382906 -246.640548) (xy 128.42479 -246.669458) (xy 128.461494 -246.704713) (xy 128.492067 -246.745399)
			(xy 128.515718 -246.790462) (xy 128.531834 -246.838736) (xy 128.539998 -246.88897) (xy 128.54051 -246.914416)
			(xy 128.848607 -246.914416) (xy 128.852702 -246.863688) (xy 128.864881 -246.814274) (xy 128.884829 -246.767454)
			(xy 128.91203 -246.72444) (xy 128.945778 -246.686346) (xy 128.9852 -246.654159) (xy 129.029274 -246.628713)
			(xy 129.07686 -246.610666) (xy 129.126724 -246.600486) (xy 129.177576 -246.598437) (xy 129.228097 -246.604571)
			(xy 129.276981 -246.618731) (xy 129.32296 -246.640548) (xy 129.364844 -246.669458) (xy 129.401548 -246.704713)
			(xy 129.432121 -246.745399) (xy 129.455772 -246.790462) (xy 129.471888 -246.838736) (xy 129.480052 -246.88897)
			(xy 129.480564 -246.914416) (xy 129.480052 -246.939862) (xy 129.471888 -246.990096) (xy 129.455772 -247.03837)
			(xy 129.432121 -247.083433) (xy 129.401548 -247.124119) (xy 129.364844 -247.159374) (xy 129.32296 -247.188284)
			(xy 129.276981 -247.210101) (xy 129.228097 -247.224261) (xy 129.177576 -247.230395) (xy 129.126724 -247.228346)
			(xy 129.07686 -247.218166) (xy 129.029274 -247.200119) (xy 128.9852 -247.174673) (xy 128.945778 -247.142486)
			(xy 128.91203 -247.104392) (xy 128.884829 -247.061378) (xy 128.864881 -247.014558) (xy 128.852702 -246.965144)
			(xy 128.848607 -246.914416) (xy 128.54051 -246.914416) (xy 128.539998 -246.939862) (xy 128.531834 -246.990096)
			(xy 128.515718 -247.03837) (xy 128.492067 -247.083433) (xy 128.461494 -247.124119) (xy 128.42479 -247.159374)
			(xy 128.382906 -247.188284) (xy 128.336927 -247.210101) (xy 128.288043 -247.224261) (xy 128.237522 -247.230395)
			(xy 128.18667 -247.228346) (xy 128.136806 -247.218166) (xy 128.08922 -247.200119) (xy 128.045146 -247.174673)
			(xy 128.005724 -247.142486) (xy 127.971976 -247.104392) (xy 127.944775 -247.061378) (xy 127.924827 -247.014558)
			(xy 127.912648 -246.965144) (xy 127.908553 -246.914416) (xy 127.590042 -246.914416) (xy 127.589547 -246.939023)
			(xy 127.581652 -246.9876) (xy 127.566068 -247.034281) (xy 127.543197 -247.077858) (xy 127.513632 -247.117202)
			(xy 127.478139 -247.151294) (xy 127.437636 -247.17925) (xy 127.393174 -247.200348) (xy 127.345903 -247.21404)
			(xy 127.297048 -247.219972) (xy 127.247873 -247.217991) (xy 127.199654 -247.208147) (xy 127.153638 -247.190695)
			(xy 127.111017 -247.166088) (xy 127.072896 -247.134963) (xy 127.040261 -247.098126) (xy 127.013958 -247.05653)
			(xy 126.994667 -247.011254) (xy 126.98289 -246.96347) (xy 126.97893 -246.914416) (xy 126.649988 -246.914416)
			(xy 126.649493 -246.939023) (xy 126.641598 -246.9876) (xy 126.626014 -247.034281) (xy 126.603143 -247.077858)
			(xy 126.573578 -247.117202) (xy 126.538085 -247.151294) (xy 126.497582 -247.17925) (xy 126.45312 -247.200348)
			(xy 126.405849 -247.21404) (xy 126.356994 -247.219972) (xy 126.307819 -247.217991) (xy 126.2596 -247.208147)
			(xy 126.213584 -247.190695) (xy 126.170963 -247.166088) (xy 126.132842 -247.134963) (xy 126.100207 -247.098126)
			(xy 126.073904 -247.05653) (xy 126.054613 -247.011254) (xy 126.042836 -246.96347) (xy 126.038876 -246.914416)
			(xy 125.709934 -246.914416) (xy 125.709439 -246.939023) (xy 125.701544 -246.9876) (xy 125.68596 -247.034281)
			(xy 125.663089 -247.077858) (xy 125.633524 -247.117202) (xy 125.598031 -247.151294) (xy 125.557528 -247.17925)
			(xy 125.513066 -247.200348) (xy 125.465795 -247.21404) (xy 125.41694 -247.219972) (xy 125.367765 -247.217991)
			(xy 125.319546 -247.208147) (xy 125.27353 -247.190695) (xy 125.230909 -247.166088) (xy 125.192788 -247.134963)
			(xy 125.160153 -247.098126) (xy 125.13385 -247.05653) (xy 125.114559 -247.011254) (xy 125.102782 -246.96347)
			(xy 125.098822 -246.914416) (xy 124.770134 -246.914416) (xy 124.769639 -246.939023) (xy 124.761744 -246.9876)
			(xy 124.74616 -247.034281) (xy 124.723289 -247.077858) (xy 124.693724 -247.117202) (xy 124.658231 -247.151294)
			(xy 124.617728 -247.17925) (xy 124.573266 -247.200348) (xy 124.525995 -247.21404) (xy 124.47714 -247.219972)
			(xy 124.427965 -247.217991) (xy 124.379746 -247.208147) (xy 124.33373 -247.190695) (xy 124.291109 -247.166088)
			(xy 124.252988 -247.134963) (xy 124.220353 -247.098126) (xy 124.19405 -247.05653) (xy 124.174759 -247.011254)
			(xy 124.162982 -246.96347) (xy 124.159022 -246.914416) (xy 123.83008 -246.914416) (xy 123.829585 -246.939023)
			(xy 123.82169 -246.9876) (xy 123.806106 -247.034281) (xy 123.783235 -247.077858) (xy 123.75367 -247.117202)
			(xy 123.718177 -247.151294) (xy 123.677674 -247.17925) (xy 123.633212 -247.200348) (xy 123.585941 -247.21404)
			(xy 123.537086 -247.219972) (xy 123.487911 -247.217991) (xy 123.439692 -247.208147) (xy 123.393676 -247.190695)
			(xy 123.351055 -247.166088) (xy 123.312934 -247.134963) (xy 123.280299 -247.098126) (xy 123.253996 -247.05653)
			(xy 123.234705 -247.011254) (xy 123.222928 -246.96347) (xy 123.218968 -246.914416) (xy 122.890026 -246.914416)
			(xy 122.889531 -246.939023) (xy 122.881636 -246.9876) (xy 122.866052 -247.034281) (xy 122.843181 -247.077858)
			(xy 122.813616 -247.117202) (xy 122.778123 -247.151294) (xy 122.73762 -247.17925) (xy 122.693158 -247.200348)
			(xy 122.645887 -247.21404) (xy 122.597032 -247.219972) (xy 122.547857 -247.217991) (xy 122.499638 -247.208147)
			(xy 122.453622 -247.190695) (xy 122.411001 -247.166088) (xy 122.37288 -247.134963) (xy 122.340245 -247.098126)
			(xy 122.313942 -247.05653) (xy 122.294651 -247.011254) (xy 122.282874 -246.96347) (xy 122.278914 -246.914416)
			(xy 121.949972 -246.914416) (xy 121.949477 -246.939023) (xy 121.941582 -246.9876) (xy 121.925998 -247.034281)
			(xy 121.903127 -247.077858) (xy 121.873562 -247.117202) (xy 121.838069 -247.151294) (xy 121.797566 -247.17925)
			(xy 121.753104 -247.200348) (xy 121.705833 -247.21404) (xy 121.656978 -247.219972) (xy 121.607803 -247.217991)
			(xy 121.559584 -247.208147) (xy 121.513568 -247.190695) (xy 121.470947 -247.166088) (xy 121.432826 -247.134963)
			(xy 121.400191 -247.098126) (xy 121.373888 -247.05653) (xy 121.354597 -247.011254) (xy 121.34282 -246.96347)
			(xy 121.33886 -246.914416) (xy 121.009918 -246.914416) (xy 121.009423 -246.939023) (xy 121.001528 -246.9876)
			(xy 120.985944 -247.034281) (xy 120.963073 -247.077858) (xy 120.933508 -247.117202) (xy 120.898015 -247.151294)
			(xy 120.857512 -247.17925) (xy 120.81305 -247.200348) (xy 120.765779 -247.21404) (xy 120.716924 -247.219972)
			(xy 120.667749 -247.217991) (xy 120.61953 -247.208147) (xy 120.573514 -247.190695) (xy 120.530893 -247.166088)
			(xy 120.492772 -247.134963) (xy 120.460137 -247.098126) (xy 120.433834 -247.05653) (xy 120.414543 -247.011254)
			(xy 120.402766 -246.96347) (xy 120.398806 -246.914416) (xy 120.070118 -246.914416) (xy 120.069623 -246.939023)
			(xy 120.061728 -246.9876) (xy 120.046144 -247.034281) (xy 120.023273 -247.077858) (xy 119.993708 -247.117202)
			(xy 119.958215 -247.151294) (xy 119.917712 -247.17925) (xy 119.87325 -247.200348) (xy 119.825979 -247.21404)
			(xy 119.777124 -247.219972) (xy 119.727949 -247.217991) (xy 119.67973 -247.208147) (xy 119.633714 -247.190695)
			(xy 119.591093 -247.166088) (xy 119.552972 -247.134963) (xy 119.520337 -247.098126) (xy 119.494034 -247.05653)
			(xy 119.474743 -247.011254) (xy 119.462966 -246.96347) (xy 119.459006 -246.914416) (xy 119.130064 -246.914416)
			(xy 119.129569 -246.939023) (xy 119.121674 -246.9876) (xy 119.10609 -247.034281) (xy 119.083219 -247.077858)
			(xy 119.053654 -247.117202) (xy 119.018161 -247.151294) (xy 118.977658 -247.17925) (xy 118.933196 -247.200348)
			(xy 118.885925 -247.21404) (xy 118.83707 -247.219972) (xy 118.787895 -247.217991) (xy 118.739676 -247.208147)
			(xy 118.69366 -247.190695) (xy 118.651039 -247.166088) (xy 118.612918 -247.134963) (xy 118.580283 -247.098126)
			(xy 118.55398 -247.05653) (xy 118.534689 -247.011254) (xy 118.522912 -246.96347) (xy 118.518952 -246.914416)
			(xy 118.19001 -246.914416) (xy 118.189515 -246.939023) (xy 118.18162 -246.9876) (xy 118.166036 -247.034281)
			(xy 118.143165 -247.077858) (xy 118.1136 -247.117202) (xy 118.078107 -247.151294) (xy 118.037604 -247.17925)
			(xy 117.993142 -247.200348) (xy 117.945871 -247.21404) (xy 117.897016 -247.219972) (xy 117.847841 -247.217991)
			(xy 117.799622 -247.208147) (xy 117.753606 -247.190695) (xy 117.710985 -247.166088) (xy 117.672864 -247.134963)
			(xy 117.640229 -247.098126) (xy 117.613926 -247.05653) (xy 117.594635 -247.011254) (xy 117.582858 -246.96347)
			(xy 117.578898 -246.914416) (xy 117.249956 -246.914416) (xy 117.249461 -246.939023) (xy 117.241566 -246.9876)
			(xy 117.225982 -247.034281) (xy 117.203111 -247.077858) (xy 117.173546 -247.117202) (xy 117.138053 -247.151294)
			(xy 117.09755 -247.17925) (xy 117.053088 -247.200348) (xy 117.005817 -247.21404) (xy 116.956962 -247.219972)
			(xy 116.907787 -247.217991) (xy 116.859568 -247.208147) (xy 116.813552 -247.190695) (xy 116.770931 -247.166088)
			(xy 116.73281 -247.134963) (xy 116.700175 -247.098126) (xy 116.673872 -247.05653) (xy 116.654581 -247.011254)
			(xy 116.642804 -246.96347) (xy 116.638844 -246.914416) (xy 116.310156 -246.914416) (xy 116.309661 -246.939023)
			(xy 116.301766 -246.9876) (xy 116.286182 -247.034281) (xy 116.263311 -247.077858) (xy 116.233746 -247.117202)
			(xy 116.198253 -247.151294) (xy 116.15775 -247.17925) (xy 116.113288 -247.200348) (xy 116.066017 -247.21404)
			(xy 116.017162 -247.219972) (xy 115.967987 -247.217991) (xy 115.919768 -247.208147) (xy 115.873752 -247.190695)
			(xy 115.831131 -247.166088) (xy 115.79301 -247.134963) (xy 115.760375 -247.098126) (xy 115.734072 -247.05653)
			(xy 115.714781 -247.011254) (xy 115.703004 -246.96347) (xy 115.699044 -246.914416) (xy 115.370102 -246.914416)
			(xy 115.369607 -246.939023) (xy 115.361712 -246.9876) (xy 115.346128 -247.034281) (xy 115.323257 -247.077858)
			(xy 115.293692 -247.117202) (xy 115.258199 -247.151294) (xy 115.217696 -247.17925) (xy 115.173234 -247.200348)
			(xy 115.125963 -247.21404) (xy 115.077108 -247.219972) (xy 115.027933 -247.217991) (xy 114.979714 -247.208147)
			(xy 114.933698 -247.190695) (xy 114.891077 -247.166088) (xy 114.852956 -247.134963) (xy 114.820321 -247.098126)
			(xy 114.794018 -247.05653) (xy 114.774727 -247.011254) (xy 114.76295 -246.96347) (xy 114.75899 -246.914416)
			(xy 114.430048 -246.914416) (xy 114.429553 -246.939023) (xy 114.421658 -246.9876) (xy 114.406074 -247.034281)
			(xy 114.383203 -247.077858) (xy 114.353638 -247.117202) (xy 114.318145 -247.151294) (xy 114.277642 -247.17925)
			(xy 114.23318 -247.200348) (xy 114.185909 -247.21404) (xy 114.137054 -247.219972) (xy 114.087879 -247.217991)
			(xy 114.03966 -247.208147) (xy 113.993644 -247.190695) (xy 113.951023 -247.166088) (xy 113.912902 -247.134963)
			(xy 113.880267 -247.098126) (xy 113.853964 -247.05653) (xy 113.834673 -247.011254) (xy 113.822896 -246.96347)
			(xy 113.818936 -246.914416) (xy 113.489994 -246.914416) (xy 113.489499 -246.939023) (xy 113.481604 -246.9876)
			(xy 113.46602 -247.034281) (xy 113.443149 -247.077858) (xy 113.413584 -247.117202) (xy 113.378091 -247.151294)
			(xy 113.337588 -247.17925) (xy 113.293126 -247.200348) (xy 113.245855 -247.21404) (xy 113.197 -247.219972)
			(xy 113.147825 -247.217991) (xy 113.099606 -247.208147) (xy 113.05359 -247.190695) (xy 113.010969 -247.166088)
			(xy 112.972848 -247.134963) (xy 112.940213 -247.098126) (xy 112.91391 -247.05653) (xy 112.894619 -247.011254)
			(xy 112.882842 -246.96347) (xy 112.878882 -246.914416) (xy 110.676436 -246.914416) (xy 110.675941 -246.939023)
			(xy 110.668046 -246.9876) (xy 110.652462 -247.034281) (xy 110.629591 -247.077858) (xy 110.600026 -247.117202)
			(xy 110.564533 -247.151294) (xy 110.52403 -247.17925) (xy 110.479568 -247.200348) (xy 110.432297 -247.21404)
			(xy 110.383442 -247.219972) (xy 110.334267 -247.217991) (xy 110.286048 -247.208147) (xy 110.240032 -247.190695)
			(xy 110.197411 -247.166088) (xy 110.15929 -247.134963) (xy 110.126655 -247.098126) (xy 110.100352 -247.05653)
			(xy 110.081061 -247.011254) (xy 110.069284 -246.96347) (xy 110.065324 -246.914416) (xy 109.736975 -246.914416)
			(xy 109.732804 -246.964748) (xy 109.720401 -247.013723) (xy 109.700106 -247.059988) (xy 109.672472 -247.102282)
			(xy 109.638254 -247.13945) (xy 109.598385 -247.170478) (xy 109.553951 -247.194521) (xy 109.506167 -247.210922)
			(xy 109.456334 -247.219233) (xy 109.431074 -247.219724) (xy 108.49102 -247.219724) (xy 108.465763 -247.219201)
			(xy 108.415936 -247.210889) (xy 108.368157 -247.19449) (xy 108.32373 -247.170449) (xy 108.283865 -247.139424)
			(xy 108.249651 -247.10226) (xy 108.222021 -247.059971) (xy 108.201729 -247.013711) (xy 108.189328 -246.964742)
			(xy 108.185156 -246.9144) (xy 107.856274 -246.9144) (xy 107.856274 -246.914416) (xy 107.855779 -246.939023)
			(xy 107.847884 -246.9876) (xy 107.8323 -247.034281) (xy 107.809429 -247.077858) (xy 107.779864 -247.117202)
			(xy 107.744371 -247.151294) (xy 107.703868 -247.17925) (xy 107.659406 -247.200348) (xy 107.612135 -247.21404)
			(xy 107.56328 -247.219972) (xy 107.514105 -247.217991) (xy 107.465886 -247.208147) (xy 107.41987 -247.190695)
			(xy 107.377249 -247.166088) (xy 107.339128 -247.134963) (xy 107.306493 -247.098126) (xy 107.28019 -247.05653)
			(xy 107.260899 -247.011254) (xy 107.249122 -246.96347) (xy 107.245162 -246.914416) (xy 106.916474 -246.914416)
			(xy 106.915979 -246.939023) (xy 106.908084 -246.9876) (xy 106.8925 -247.034281) (xy 106.869629 -247.077858)
			(xy 106.840064 -247.117202) (xy 106.804571 -247.151294) (xy 106.764068 -247.17925) (xy 106.719606 -247.200348)
			(xy 106.672335 -247.21404) (xy 106.62348 -247.219972) (xy 106.574305 -247.217991) (xy 106.526086 -247.208147)
			(xy 106.48007 -247.190695) (xy 106.437449 -247.166088) (xy 106.399328 -247.134963) (xy 106.366693 -247.098126)
			(xy 106.34039 -247.05653) (xy 106.321099 -247.011254) (xy 106.309322 -246.96347) (xy 106.305362 -246.914416)
			(xy 105.97642 -246.914416) (xy 105.975925 -246.939023) (xy 105.96803 -246.9876) (xy 105.952446 -247.034281)
			(xy 105.929575 -247.077858) (xy 105.90001 -247.117202) (xy 105.864517 -247.151294) (xy 105.824014 -247.17925)
			(xy 105.779552 -247.200348) (xy 105.732281 -247.21404) (xy 105.683426 -247.219972) (xy 105.634251 -247.217991)
			(xy 105.586032 -247.208147) (xy 105.540016 -247.190695) (xy 105.497395 -247.166088) (xy 105.459274 -247.134963)
			(xy 105.426639 -247.098126) (xy 105.400336 -247.05653) (xy 105.381045 -247.011254) (xy 105.369268 -246.96347)
			(xy 105.365308 -246.914416) (xy 105.036366 -246.914416) (xy 105.035871 -246.939023) (xy 105.027976 -246.9876)
			(xy 105.012392 -247.034281) (xy 104.989521 -247.077858) (xy 104.959956 -247.117202) (xy 104.924463 -247.151294)
			(xy 104.88396 -247.17925) (xy 104.839498 -247.200348) (xy 104.792227 -247.21404) (xy 104.743372 -247.219972)
			(xy 104.694197 -247.217991) (xy 104.645978 -247.208147) (xy 104.599962 -247.190695) (xy 104.557341 -247.166088)
			(xy 104.51922 -247.134963) (xy 104.486585 -247.098126) (xy 104.460282 -247.05653) (xy 104.440991 -247.011254)
			(xy 104.429214 -246.96347) (xy 104.425254 -246.914416) (xy 104.096312 -246.914416) (xy 104.095817 -246.939023)
			(xy 104.087922 -246.9876) (xy 104.072338 -247.034281) (xy 104.049467 -247.077858) (xy 104.019902 -247.117202)
			(xy 103.984409 -247.151294) (xy 103.943906 -247.17925) (xy 103.899444 -247.200348) (xy 103.852173 -247.21404)
			(xy 103.803318 -247.219972) (xy 103.754143 -247.217991) (xy 103.705924 -247.208147) (xy 103.659908 -247.190695)
			(xy 103.617287 -247.166088) (xy 103.579166 -247.134963) (xy 103.546531 -247.098126) (xy 103.520228 -247.05653)
			(xy 103.500937 -247.011254) (xy 103.48916 -246.96347) (xy 103.4852 -246.914416) (xy 103.156258 -246.914416)
			(xy 103.155763 -246.939023) (xy 103.147868 -246.9876) (xy 103.132284 -247.034281) (xy 103.109413 -247.077858)
			(xy 103.079848 -247.117202) (xy 103.044355 -247.151294) (xy 103.003852 -247.17925) (xy 102.95939 -247.200348)
			(xy 102.912119 -247.21404) (xy 102.863264 -247.219972) (xy 102.814089 -247.217991) (xy 102.76587 -247.208147)
			(xy 102.719854 -247.190695) (xy 102.677233 -247.166088) (xy 102.639112 -247.134963) (xy 102.606477 -247.098126)
			(xy 102.580174 -247.05653) (xy 102.560883 -247.011254) (xy 102.549106 -246.96347) (xy 102.545146 -246.914416)
			(xy 102.216458 -246.914416) (xy 102.215963 -246.939023) (xy 102.208068 -246.9876) (xy 102.192484 -247.034281)
			(xy 102.169613 -247.077858) (xy 102.140048 -247.117202) (xy 102.104555 -247.151294) (xy 102.064052 -247.17925)
			(xy 102.01959 -247.200348) (xy 101.972319 -247.21404) (xy 101.923464 -247.219972) (xy 101.874289 -247.217991)
			(xy 101.82607 -247.208147) (xy 101.780054 -247.190695) (xy 101.737433 -247.166088) (xy 101.699312 -247.134963)
			(xy 101.666677 -247.098126) (xy 101.640374 -247.05653) (xy 101.621083 -247.011254) (xy 101.609306 -246.96347)
			(xy 101.605346 -246.914416) (xy 101.276404 -246.914416) (xy 101.275909 -246.939023) (xy 101.268014 -246.9876)
			(xy 101.25243 -247.034281) (xy 101.229559 -247.077858) (xy 101.199994 -247.117202) (xy 101.164501 -247.151294)
			(xy 101.123998 -247.17925) (xy 101.079536 -247.200348) (xy 101.032265 -247.21404) (xy 100.98341 -247.219972)
			(xy 100.934235 -247.217991) (xy 100.886016 -247.208147) (xy 100.84 -247.190695) (xy 100.797379 -247.166088)
			(xy 100.759258 -247.134963) (xy 100.726623 -247.098126) (xy 100.70032 -247.05653) (xy 100.681029 -247.011254)
			(xy 100.669252 -246.96347) (xy 100.665292 -246.914416) (xy 100.33635 -246.914416) (xy 100.335855 -246.939023)
			(xy 100.32796 -246.9876) (xy 100.312376 -247.034281) (xy 100.289505 -247.077858) (xy 100.25994 -247.117202)
			(xy 100.224447 -247.151294) (xy 100.183944 -247.17925) (xy 100.139482 -247.200348) (xy 100.092211 -247.21404)
			(xy 100.043356 -247.219972) (xy 99.994181 -247.217991) (xy 99.945962 -247.208147) (xy 99.899946 -247.190695)
			(xy 99.857325 -247.166088) (xy 99.819204 -247.134963) (xy 99.786569 -247.098126) (xy 99.760266 -247.05653)
			(xy 99.740975 -247.011254) (xy 99.729198 -246.96347) (xy 99.725238 -246.914416) (xy 99.396296 -246.914416)
			(xy 99.395801 -246.939023) (xy 99.387906 -246.9876) (xy 99.372322 -247.034281) (xy 99.349451 -247.077858)
			(xy 99.319886 -247.117202) (xy 99.284393 -247.151294) (xy 99.24389 -247.17925) (xy 99.199428 -247.200348)
			(xy 99.152157 -247.21404) (xy 99.103302 -247.219972) (xy 99.054127 -247.217991) (xy 99.005908 -247.208147)
			(xy 98.959892 -247.190695) (xy 98.917271 -247.166088) (xy 98.87915 -247.134963) (xy 98.846515 -247.098126)
			(xy 98.820212 -247.05653) (xy 98.800921 -247.011254) (xy 98.789144 -246.96347) (xy 98.785184 -246.914416)
			(xy 98.456242 -246.914416) (xy 98.455747 -246.939023) (xy 98.447852 -246.9876) (xy 98.432268 -247.034281)
			(xy 98.409397 -247.077858) (xy 98.379832 -247.117202) (xy 98.344339 -247.151294) (xy 98.303836 -247.17925)
			(xy 98.259374 -247.200348) (xy 98.212103 -247.21404) (xy 98.163248 -247.219972) (xy 98.114073 -247.217991)
			(xy 98.065854 -247.208147) (xy 98.019838 -247.190695) (xy 97.977217 -247.166088) (xy 97.939096 -247.134963)
			(xy 97.906461 -247.098126) (xy 97.880158 -247.05653) (xy 97.860867 -247.011254) (xy 97.84909 -246.96347)
			(xy 97.84513 -246.914416) (xy 97.516914 -246.914416) (xy 97.512745 -246.964732) (xy 97.500347 -247.013691)
			(xy 97.480061 -247.059942) (xy 97.45244 -247.102224) (xy 97.418236 -247.139383) (xy 97.378383 -247.170406)
			(xy 97.333967 -247.194447) (xy 97.286201 -247.21085) (xy 97.236386 -247.219168) (xy 97.211134 -247.219724)
			(xy 97.187132 -247.219249) (xy 97.139718 -247.211736) (xy 97.094062 -247.196904) (xy 97.07245 -247.18645)
			(xy 97.060512 -247.180354) (xy 97.03435 -247.18137) (xy 96.951038 -247.232424) (xy 96.944584 -247.236619)
			(xy 96.934363 -247.24812) (xy 96.930972 -247.25503) (xy 96.926654 -247.264936) (xy 96.926654 -247.447562)
			(xy 96.926776 -247.452923) (xy 96.92896 -247.463419) (xy 96.930972 -247.46839) (xy 96.943164 -247.495568)
			(xy 96.95053 -247.502426) (xy 96.968279 -247.519854) (xy 96.998436 -247.559411) (xy 97.021781 -247.603334)
			(xy 97.037695 -247.650461) (xy 97.045757 -247.699544) (xy 97.045756 -247.7244) (xy 97.374907 -247.7244)
			(xy 97.379083 -247.674015) (xy 97.391495 -247.625005) (xy 97.411805 -247.578707) (xy 97.439459 -247.536383)
			(xy 97.473702 -247.499188) (xy 97.513601 -247.468138) (xy 97.558067 -247.444079) (xy 97.605887 -247.427667)
			(xy 97.655755 -247.41935) (xy 97.681034 -247.41886) (xy 98.621088 -247.41886) (xy 98.646369 -247.419308)
			(xy 98.696242 -247.427629) (xy 98.744066 -247.444045) (xy 98.788534 -247.468109) (xy 98.828436 -247.499164)
			(xy 98.862682 -247.536363) (xy 98.890337 -247.578692) (xy 98.910648 -247.624995) (xy 98.923061 -247.67401)
			(xy 98.927237 -247.7244) (xy 98.927235 -247.724422) (xy 99.255338 -247.724422) (xy 99.259298 -247.675368)
			(xy 99.271075 -247.627584) (xy 99.290366 -247.582308) (xy 99.316669 -247.540712) (xy 99.349304 -247.503875)
			(xy 99.387425 -247.47275) (xy 99.430046 -247.448143) (xy 99.476062 -247.430691) (xy 99.524281 -247.420847)
			(xy 99.573456 -247.418866) (xy 99.622311 -247.424798) (xy 99.669582 -247.43849) (xy 99.714044 -247.459588)
			(xy 99.754547 -247.487544) (xy 99.79004 -247.521636) (xy 99.819605 -247.56098) (xy 99.842476 -247.604557)
			(xy 99.85806 -247.651238) (xy 99.865955 -247.699815) (xy 99.86645 -247.7244) (xy 100.194807 -247.7244)
			(xy 100.198983 -247.674014) (xy 100.211395 -247.625004) (xy 100.231706 -247.578704) (xy 100.259361 -247.53638)
			(xy 100.293605 -247.499185) (xy 100.333506 -247.468135) (xy 100.377972 -247.444076) (xy 100.425793 -247.427665)
			(xy 100.475663 -247.41935) (xy 100.500942 -247.41886) (xy 101.440996 -247.41886) (xy 101.466277 -247.419309)
			(xy 101.516149 -247.42763) (xy 101.563971 -247.444047) (xy 101.608439 -247.468111) (xy 101.648339 -247.499167)
			(xy 101.682584 -247.536366) (xy 101.710238 -247.578694) (xy 101.730549 -247.624997) (xy 101.742961 -247.674011)
			(xy 101.747137 -247.7244) (xy 101.747135 -247.724422) (xy 102.075246 -247.724422) (xy 102.079206 -247.675368)
			(xy 102.090983 -247.627584) (xy 102.110274 -247.582308) (xy 102.136577 -247.540712) (xy 102.169212 -247.503875)
			(xy 102.207333 -247.47275) (xy 102.249954 -247.448143) (xy 102.29597 -247.430691) (xy 102.344189 -247.420847)
			(xy 102.393364 -247.418866) (xy 102.442219 -247.424798) (xy 102.48949 -247.43849) (xy 102.533952 -247.459588)
			(xy 102.574455 -247.487544) (xy 102.609948 -247.521636) (xy 102.639513 -247.56098) (xy 102.662384 -247.604557)
			(xy 102.677968 -247.651238) (xy 102.685863 -247.699815) (xy 102.686358 -247.7244) (xy 103.015007 -247.7244)
			(xy 103.019182 -247.674018) (xy 103.031593 -247.625011) (xy 103.0519 -247.578715) (xy 103.079551 -247.536393)
			(xy 103.113791 -247.499199) (xy 103.153685 -247.468148) (xy 103.198147 -247.444087) (xy 103.245962 -247.427673)
			(xy 103.295827 -247.419353) (xy 103.321104 -247.41886) (xy 104.261158 -247.41886) (xy 104.286441 -247.419306)
			(xy 104.336318 -247.427622) (xy 104.384145 -247.444036) (xy 104.428619 -247.468098) (xy 104.468524 -247.499153)
			(xy 104.502774 -247.536353) (xy 104.530433 -247.578683) (xy 104.550746 -247.624989) (xy 104.56316 -247.674007)
			(xy 104.567337 -247.7244) (xy 104.567335 -247.724422) (xy 104.895154 -247.724422) (xy 104.899114 -247.675368)
			(xy 104.910891 -247.627584) (xy 104.930182 -247.582308) (xy 104.956485 -247.540712) (xy 104.98912 -247.503875)
			(xy 105.027241 -247.47275) (xy 105.069862 -247.448143) (xy 105.115878 -247.430691) (xy 105.164097 -247.420847)
			(xy 105.213272 -247.418866) (xy 105.262127 -247.424798) (xy 105.309398 -247.43849) (xy 105.35386 -247.459588)
			(xy 105.394363 -247.487544) (xy 105.429856 -247.521636) (xy 105.459421 -247.56098) (xy 105.482292 -247.604557)
			(xy 105.497876 -247.651238) (xy 105.505771 -247.699815) (xy 105.506266 -247.7244) (xy 105.834907 -247.7244)
			(xy 105.839082 -247.674018) (xy 105.851493 -247.62501) (xy 105.871801 -247.578713) (xy 105.899453 -247.53639)
			(xy 105.933694 -247.499196) (xy 105.97359 -247.468145) (xy 106.018052 -247.444085) (xy 106.065869 -247.427671)
			(xy 106.115734 -247.419352) (xy 106.141012 -247.41886) (xy 107.081066 -247.41886) (xy 107.106348 -247.419306)
			(xy 107.156224 -247.427624) (xy 107.204051 -247.444038) (xy 107.248523 -247.468101) (xy 107.288427 -247.499156)
			(xy 107.322676 -247.536356) (xy 107.350334 -247.578686) (xy 107.370647 -247.624991) (xy 107.383061 -247.674008)
			(xy 107.387237 -247.7244) (xy 107.387235 -247.724422) (xy 107.715316 -247.724422) (xy 107.719276 -247.675368)
			(xy 107.731053 -247.627584) (xy 107.750344 -247.582308) (xy 107.776647 -247.540712) (xy 107.809282 -247.503875)
			(xy 107.847403 -247.47275) (xy 107.890024 -247.448143) (xy 107.93604 -247.430691) (xy 107.984259 -247.420847)
			(xy 108.033434 -247.418866) (xy 108.082289 -247.424798) (xy 108.12956 -247.43849) (xy 108.174022 -247.459588)
			(xy 108.214525 -247.487544) (xy 108.250018 -247.521636) (xy 108.279583 -247.56098) (xy 108.302454 -247.604557)
			(xy 108.318038 -247.651238) (xy 108.325933 -247.699815) (xy 108.326428 -247.724422) (xy 108.65537 -247.724422)
			(xy 108.65933 -247.675368) (xy 108.671107 -247.627584) (xy 108.690398 -247.582308) (xy 108.716701 -247.540712)
			(xy 108.749336 -247.503875) (xy 108.787457 -247.47275) (xy 108.830078 -247.448143) (xy 108.876094 -247.430691)
			(xy 108.924313 -247.420847) (xy 108.973488 -247.418866) (xy 109.022343 -247.424798) (xy 109.069614 -247.43849)
			(xy 109.114076 -247.459588) (xy 109.154579 -247.487544) (xy 109.190072 -247.521636) (xy 109.219637 -247.56098)
			(xy 109.242508 -247.604557) (xy 109.258092 -247.651238) (xy 109.265987 -247.699815) (xy 109.266482 -247.724422)
			(xy 109.59517 -247.724422) (xy 109.59913 -247.675368) (xy 109.610907 -247.627584) (xy 109.630198 -247.582308)
			(xy 109.656501 -247.540712) (xy 109.689136 -247.503875) (xy 109.727257 -247.47275) (xy 109.769878 -247.448143)
			(xy 109.815894 -247.430691) (xy 109.864113 -247.420847) (xy 109.913288 -247.418866) (xy 109.962143 -247.424798)
			(xy 110.009414 -247.43849) (xy 110.048873 -247.457214) (xy 111.456473 -247.457214) (xy 111.460503 -247.404716)
			(xy 111.4725 -247.353448) (xy 111.492183 -247.304613) (xy 111.519089 -247.259354) (xy 111.552589 -247.218733)
			(xy 111.591897 -247.183702) (xy 111.636092 -247.155082) (xy 111.684137 -247.133543) (xy 111.734908 -247.119591)
			(xy 111.787213 -247.113553) (xy 111.839827 -247.11557) (xy 111.891517 -247.125594) (xy 111.94107 -247.143392)
			(xy 111.987326 -247.168545) (xy 112.0292 -247.200464) (xy 112.065712 -247.238402) (xy 112.096004 -247.281468)
			(xy 112.119367 -247.328653) (xy 112.135253 -247.378852) (xy 112.14329 -247.430888) (xy 112.143794 -247.457214)
			(xy 112.14329 -247.48354) (xy 112.135253 -247.535576) (xy 112.119367 -247.585775) (xy 112.096004 -247.63296)
			(xy 112.065712 -247.676026) (xy 112.0292 -247.713964) (xy 112.01548 -247.724422) (xy 113.349036 -247.724422)
			(xy 113.352996 -247.675368) (xy 113.364773 -247.627584) (xy 113.384064 -247.582308) (xy 113.410367 -247.540712)
			(xy 113.443002 -247.503875) (xy 113.481123 -247.47275) (xy 113.523744 -247.448143) (xy 113.56976 -247.430691)
			(xy 113.617979 -247.420847) (xy 113.667154 -247.418866) (xy 113.716009 -247.424798) (xy 113.76328 -247.43849)
			(xy 113.807742 -247.459588) (xy 113.848245 -247.487544) (xy 113.883738 -247.521636) (xy 113.913303 -247.56098)
			(xy 113.936174 -247.604557) (xy 113.951758 -247.651238) (xy 113.959653 -247.699815) (xy 113.960148 -247.724422)
			(xy 114.288836 -247.724422) (xy 114.292796 -247.675368) (xy 114.304573 -247.627584) (xy 114.323864 -247.582308)
			(xy 114.350167 -247.540712) (xy 114.382802 -247.503875) (xy 114.420923 -247.47275) (xy 114.463544 -247.448143)
			(xy 114.50956 -247.430691) (xy 114.557779 -247.420847) (xy 114.606954 -247.418866) (xy 114.655809 -247.424798)
			(xy 114.70308 -247.43849) (xy 114.747542 -247.459588) (xy 114.788045 -247.487544) (xy 114.823538 -247.521636)
			(xy 114.853103 -247.56098) (xy 114.875974 -247.604557) (xy 114.891558 -247.651238) (xy 114.899453 -247.699815)
			(xy 114.899948 -247.724422) (xy 115.22889 -247.724422) (xy 115.23285 -247.675368) (xy 115.244627 -247.627584)
			(xy 115.263918 -247.582308) (xy 115.290221 -247.540712) (xy 115.322856 -247.503875) (xy 115.360977 -247.47275)
			(xy 115.403598 -247.448143) (xy 115.449614 -247.430691) (xy 115.497833 -247.420847) (xy 115.547008 -247.418866)
			(xy 115.595863 -247.424798) (xy 115.643134 -247.43849) (xy 115.687596 -247.459588) (xy 115.728099 -247.487544)
			(xy 115.763592 -247.521636) (xy 115.793157 -247.56098) (xy 115.816028 -247.604557) (xy 115.831612 -247.651238)
			(xy 115.839507 -247.699815) (xy 115.840002 -247.724422) (xy 116.168944 -247.724422) (xy 116.172904 -247.675368)
			(xy 116.184681 -247.627584) (xy 116.203972 -247.582308) (xy 116.230275 -247.540712) (xy 116.26291 -247.503875)
			(xy 116.301031 -247.47275) (xy 116.343652 -247.448143) (xy 116.389668 -247.430691) (xy 116.437887 -247.420847)
			(xy 116.487062 -247.418866) (xy 116.535917 -247.424798) (xy 116.583188 -247.43849) (xy 116.62765 -247.459588)
			(xy 116.668153 -247.487544) (xy 116.703646 -247.521636) (xy 116.733211 -247.56098) (xy 116.756082 -247.604557)
			(xy 116.771666 -247.651238) (xy 116.779561 -247.699815) (xy 116.780056 -247.724422) (xy 117.108998 -247.724422)
			(xy 117.112958 -247.675368) (xy 117.124735 -247.627584) (xy 117.144026 -247.582308) (xy 117.170329 -247.540712)
			(xy 117.202964 -247.503875) (xy 117.241085 -247.47275) (xy 117.283706 -247.448143) (xy 117.329722 -247.430691)
			(xy 117.377941 -247.420847) (xy 117.427116 -247.418866) (xy 117.475971 -247.424798) (xy 117.523242 -247.43849)
			(xy 117.567704 -247.459588) (xy 117.608207 -247.487544) (xy 117.6437 -247.521636) (xy 117.673265 -247.56098)
			(xy 117.696136 -247.604557) (xy 117.71172 -247.651238) (xy 117.719615 -247.699815) (xy 117.72011 -247.724422)
			(xy 118.049052 -247.724422) (xy 118.053012 -247.675368) (xy 118.064789 -247.627584) (xy 118.08408 -247.582308)
			(xy 118.110383 -247.540712) (xy 118.143018 -247.503875) (xy 118.181139 -247.47275) (xy 118.22376 -247.448143)
			(xy 118.269776 -247.430691) (xy 118.317995 -247.420847) (xy 118.36717 -247.418866) (xy 118.416025 -247.424798)
			(xy 118.463296 -247.43849) (xy 118.507758 -247.459588) (xy 118.548261 -247.487544) (xy 118.583754 -247.521636)
			(xy 118.613319 -247.56098) (xy 118.63619 -247.604557) (xy 118.651774 -247.651238) (xy 118.659669 -247.699815)
			(xy 118.660164 -247.724422) (xy 118.988852 -247.724422) (xy 118.992812 -247.675368) (xy 119.004589 -247.627584)
			(xy 119.02388 -247.582308) (xy 119.050183 -247.540712) (xy 119.082818 -247.503875) (xy 119.120939 -247.47275)
			(xy 119.16356 -247.448143) (xy 119.209576 -247.430691) (xy 119.257795 -247.420847) (xy 119.30697 -247.418866)
			(xy 119.355825 -247.424798) (xy 119.403096 -247.43849) (xy 119.447558 -247.459588) (xy 119.488061 -247.487544)
			(xy 119.523554 -247.521636) (xy 119.553119 -247.56098) (xy 119.57599 -247.604557) (xy 119.591574 -247.651238)
			(xy 119.599469 -247.699815) (xy 119.599964 -247.724422) (xy 119.928906 -247.724422) (xy 119.932866 -247.675368)
			(xy 119.944643 -247.627584) (xy 119.963934 -247.582308) (xy 119.990237 -247.540712) (xy 120.022872 -247.503875)
			(xy 120.060993 -247.47275) (xy 120.103614 -247.448143) (xy 120.14963 -247.430691) (xy 120.197849 -247.420847)
			(xy 120.247024 -247.418866) (xy 120.295879 -247.424798) (xy 120.34315 -247.43849) (xy 120.387612 -247.459588)
			(xy 120.428115 -247.487544) (xy 120.463608 -247.521636) (xy 120.493173 -247.56098) (xy 120.516044 -247.604557)
			(xy 120.531628 -247.651238) (xy 120.539523 -247.699815) (xy 120.540018 -247.724422) (xy 120.86896 -247.724422)
			(xy 120.87292 -247.675368) (xy 120.884697 -247.627584) (xy 120.903988 -247.582308) (xy 120.930291 -247.540712)
			(xy 120.962926 -247.503875) (xy 121.001047 -247.47275) (xy 121.043668 -247.448143) (xy 121.089684 -247.430691)
			(xy 121.137903 -247.420847) (xy 121.187078 -247.418866) (xy 121.235933 -247.424798) (xy 121.283204 -247.43849)
			(xy 121.327666 -247.459588) (xy 121.368169 -247.487544) (xy 121.403662 -247.521636) (xy 121.433227 -247.56098)
			(xy 121.456098 -247.604557) (xy 121.471682 -247.651238) (xy 121.479577 -247.699815) (xy 121.480072 -247.724422)
			(xy 121.809014 -247.724422) (xy 121.812974 -247.675368) (xy 121.824751 -247.627584) (xy 121.844042 -247.582308)
			(xy 121.870345 -247.540712) (xy 121.90298 -247.503875) (xy 121.941101 -247.47275) (xy 121.983722 -247.448143)
			(xy 122.029738 -247.430691) (xy 122.077957 -247.420847) (xy 122.127132 -247.418866) (xy 122.175987 -247.424798)
			(xy 122.223258 -247.43849) (xy 122.26772 -247.459588) (xy 122.308223 -247.487544) (xy 122.343716 -247.521636)
			(xy 122.373281 -247.56098) (xy 122.396152 -247.604557) (xy 122.411736 -247.651238) (xy 122.419631 -247.699815)
			(xy 122.420126 -247.724422) (xy 122.748814 -247.724422) (xy 122.752774 -247.675368) (xy 122.764551 -247.627584)
			(xy 122.783842 -247.582308) (xy 122.810145 -247.540712) (xy 122.84278 -247.503875) (xy 122.880901 -247.47275)
			(xy 122.923522 -247.448143) (xy 122.969538 -247.430691) (xy 123.017757 -247.420847) (xy 123.066932 -247.418866)
			(xy 123.115787 -247.424798) (xy 123.163058 -247.43849) (xy 123.20752 -247.459588) (xy 123.248023 -247.487544)
			(xy 123.283516 -247.521636) (xy 123.313081 -247.56098) (xy 123.335952 -247.604557) (xy 123.351536 -247.651238)
			(xy 123.359431 -247.699815) (xy 123.359926 -247.724422) (xy 123.688868 -247.724422) (xy 123.692828 -247.675368)
			(xy 123.704605 -247.627584) (xy 123.723896 -247.582308) (xy 123.750199 -247.540712) (xy 123.782834 -247.503875)
			(xy 123.820955 -247.47275) (xy 123.863576 -247.448143) (xy 123.909592 -247.430691) (xy 123.957811 -247.420847)
			(xy 124.006986 -247.418866) (xy 124.055841 -247.424798) (xy 124.103112 -247.43849) (xy 124.147574 -247.459588)
			(xy 124.188077 -247.487544) (xy 124.22357 -247.521636) (xy 124.253135 -247.56098) (xy 124.276006 -247.604557)
			(xy 124.29159 -247.651238) (xy 124.299485 -247.699815) (xy 124.29998 -247.724422) (xy 124.628922 -247.724422)
			(xy 124.632882 -247.675368) (xy 124.644659 -247.627584) (xy 124.66395 -247.582308) (xy 124.690253 -247.540712)
			(xy 124.722888 -247.503875) (xy 124.761009 -247.47275) (xy 124.80363 -247.448143) (xy 124.849646 -247.430691)
			(xy 124.897865 -247.420847) (xy 124.94704 -247.418866) (xy 124.995895 -247.424798) (xy 125.043166 -247.43849)
			(xy 125.087628 -247.459588) (xy 125.128131 -247.487544) (xy 125.163624 -247.521636) (xy 125.193189 -247.56098)
			(xy 125.21606 -247.604557) (xy 125.231644 -247.651238) (xy 125.239539 -247.699815) (xy 125.240034 -247.724422)
			(xy 125.568976 -247.724422) (xy 125.572936 -247.675368) (xy 125.584713 -247.627584) (xy 125.604004 -247.582308)
			(xy 125.630307 -247.540712) (xy 125.662942 -247.503875) (xy 125.701063 -247.47275) (xy 125.743684 -247.448143)
			(xy 125.7897 -247.430691) (xy 125.837919 -247.420847) (xy 125.887094 -247.418866) (xy 125.935949 -247.424798)
			(xy 125.98322 -247.43849) (xy 126.027682 -247.459588) (xy 126.068185 -247.487544) (xy 126.103678 -247.521636)
			(xy 126.133243 -247.56098) (xy 126.156114 -247.604557) (xy 126.171698 -247.651238) (xy 126.179593 -247.699815)
			(xy 126.180088 -247.724422) (xy 126.50903 -247.724422) (xy 126.51299 -247.675368) (xy 126.524767 -247.627584)
			(xy 126.544058 -247.582308) (xy 126.570361 -247.540712) (xy 126.602996 -247.503875) (xy 126.641117 -247.47275)
			(xy 126.683738 -247.448143) (xy 126.729754 -247.430691) (xy 126.777973 -247.420847) (xy 126.827148 -247.418866)
			(xy 126.876003 -247.424798) (xy 126.923274 -247.43849) (xy 126.967736 -247.459588) (xy 127.008239 -247.487544)
			(xy 127.043732 -247.521636) (xy 127.073297 -247.56098) (xy 127.096168 -247.604557) (xy 127.111752 -247.651238)
			(xy 127.119647 -247.699815) (xy 127.120142 -247.724422) (xy 127.438399 -247.724422) (xy 127.442494 -247.673694)
			(xy 127.454673 -247.62428) (xy 127.474621 -247.57746) (xy 127.501822 -247.534446) (xy 127.53557 -247.496352)
			(xy 127.574992 -247.464165) (xy 127.619066 -247.438719) (xy 127.666652 -247.420672) (xy 127.716516 -247.410492)
			(xy 127.767368 -247.408443) (xy 127.817889 -247.414577) (xy 127.866773 -247.428737) (xy 127.912752 -247.450554)
			(xy 127.954636 -247.479464) (xy 127.99134 -247.514719) (xy 128.021913 -247.555405) (xy 128.045564 -247.600468)
			(xy 128.06168 -247.648742) (xy 128.069844 -247.698976) (xy 128.070356 -247.724422) (xy 128.388884 -247.724422)
			(xy 128.392844 -247.675368) (xy 128.404621 -247.627584) (xy 128.423912 -247.582308) (xy 128.450215 -247.540712)
			(xy 128.48285 -247.503875) (xy 128.520971 -247.47275) (xy 128.563592 -247.448143) (xy 128.609608 -247.430691)
			(xy 128.657827 -247.420847) (xy 128.707002 -247.418866) (xy 128.755857 -247.424798) (xy 128.803128 -247.43849)
			(xy 128.84759 -247.459588) (xy 128.888093 -247.487544) (xy 128.923586 -247.521636) (xy 128.953151 -247.56098)
			(xy 128.976022 -247.604557) (xy 128.991606 -247.651238) (xy 128.999501 -247.699815) (xy 128.999996 -247.724422)
			(xy 129.318507 -247.724422) (xy 129.322602 -247.673694) (xy 129.334781 -247.62428) (xy 129.354729 -247.57746)
			(xy 129.38193 -247.534446) (xy 129.415678 -247.496352) (xy 129.4551 -247.464165) (xy 129.499174 -247.438719)
			(xy 129.54676 -247.420672) (xy 129.596624 -247.410492) (xy 129.647476 -247.408443) (xy 129.697997 -247.414577)
			(xy 129.746881 -247.428737) (xy 129.79286 -247.450554) (xy 129.834744 -247.479464) (xy 129.871448 -247.514719)
			(xy 129.902021 -247.555405) (xy 129.925672 -247.600468) (xy 129.941788 -247.648742) (xy 129.949952 -247.698976)
			(xy 129.950464 -247.724422) (xy 129.949952 -247.749868) (xy 129.941788 -247.800102) (xy 129.925672 -247.848376)
			(xy 129.902021 -247.893439) (xy 129.871448 -247.934125) (xy 129.834744 -247.96938) (xy 129.79286 -247.99829)
			(xy 129.746881 -248.020107) (xy 129.697997 -248.034267) (xy 129.647476 -248.040401) (xy 129.596624 -248.038352)
			(xy 129.54676 -248.028172) (xy 129.499174 -248.010125) (xy 129.4551 -247.984679) (xy 129.415678 -247.952492)
			(xy 129.38193 -247.914398) (xy 129.354729 -247.871384) (xy 129.334781 -247.824564) (xy 129.322602 -247.77515)
			(xy 129.318507 -247.724422) (xy 128.999996 -247.724422) (xy 128.999501 -247.749029) (xy 128.991606 -247.797606)
			(xy 128.976022 -247.844287) (xy 128.953151 -247.887864) (xy 128.923586 -247.927208) (xy 128.888093 -247.9613)
			(xy 128.84759 -247.989256) (xy 128.803128 -248.010354) (xy 128.755857 -248.024046) (xy 128.707002 -248.029978)
			(xy 128.657827 -248.027997) (xy 128.609608 -248.018153) (xy 128.563592 -248.000701) (xy 128.520971 -247.976094)
			(xy 128.48285 -247.944969) (xy 128.450215 -247.908132) (xy 128.423912 -247.866536) (xy 128.404621 -247.82126)
			(xy 128.392844 -247.773476) (xy 128.388884 -247.724422) (xy 128.070356 -247.724422) (xy 128.069844 -247.749868)
			(xy 128.06168 -247.800102) (xy 128.045564 -247.848376) (xy 128.021913 -247.893439) (xy 127.99134 -247.934125)
			(xy 127.954636 -247.96938) (xy 127.912752 -247.99829) (xy 127.866773 -248.020107) (xy 127.817889 -248.034267)
			(xy 127.767368 -248.040401) (xy 127.716516 -248.038352) (xy 127.666652 -248.028172) (xy 127.619066 -248.010125)
			(xy 127.574992 -247.984679) (xy 127.53557 -247.952492) (xy 127.501822 -247.914398) (xy 127.474621 -247.871384)
			(xy 127.454673 -247.824564) (xy 127.442494 -247.77515) (xy 127.438399 -247.724422) (xy 127.120142 -247.724422)
			(xy 127.119647 -247.749029) (xy 127.111752 -247.797606) (xy 127.096168 -247.844287) (xy 127.073297 -247.887864)
			(xy 127.043732 -247.927208) (xy 127.008239 -247.9613) (xy 126.967736 -247.989256) (xy 126.923274 -248.010354)
			(xy 126.876003 -248.024046) (xy 126.827148 -248.029978) (xy 126.777973 -248.027997) (xy 126.729754 -248.018153)
			(xy 126.683738 -248.000701) (xy 126.641117 -247.976094) (xy 126.602996 -247.944969) (xy 126.570361 -247.908132)
			(xy 126.544058 -247.866536) (xy 126.524767 -247.82126) (xy 126.51299 -247.773476) (xy 126.50903 -247.724422)
			(xy 126.180088 -247.724422) (xy 126.179593 -247.749029) (xy 126.171698 -247.797606) (xy 126.156114 -247.844287)
			(xy 126.133243 -247.887864) (xy 126.103678 -247.927208) (xy 126.068185 -247.9613) (xy 126.027682 -247.989256)
			(xy 125.98322 -248.010354) (xy 125.935949 -248.024046) (xy 125.887094 -248.029978) (xy 125.837919 -248.027997)
			(xy 125.7897 -248.018153) (xy 125.743684 -248.000701) (xy 125.701063 -247.976094) (xy 125.662942 -247.944969)
			(xy 125.630307 -247.908132) (xy 125.604004 -247.866536) (xy 125.584713 -247.82126) (xy 125.572936 -247.773476)
			(xy 125.568976 -247.724422) (xy 125.240034 -247.724422) (xy 125.239539 -247.749029) (xy 125.231644 -247.797606)
			(xy 125.21606 -247.844287) (xy 125.193189 -247.887864) (xy 125.163624 -247.927208) (xy 125.128131 -247.9613)
			(xy 125.087628 -247.989256) (xy 125.043166 -248.010354) (xy 124.995895 -248.024046) (xy 124.94704 -248.029978)
			(xy 124.897865 -248.027997) (xy 124.849646 -248.018153) (xy 124.80363 -248.000701) (xy 124.761009 -247.976094)
			(xy 124.722888 -247.944969) (xy 124.690253 -247.908132) (xy 124.66395 -247.866536) (xy 124.644659 -247.82126)
			(xy 124.632882 -247.773476) (xy 124.628922 -247.724422) (xy 124.29998 -247.724422) (xy 124.299485 -247.749029)
			(xy 124.29159 -247.797606) (xy 124.276006 -247.844287) (xy 124.253135 -247.887864) (xy 124.22357 -247.927208)
			(xy 124.188077 -247.9613) (xy 124.147574 -247.989256) (xy 124.103112 -248.010354) (xy 124.055841 -248.024046)
			(xy 124.006986 -248.029978) (xy 123.957811 -248.027997) (xy 123.909592 -248.018153) (xy 123.863576 -248.000701)
			(xy 123.820955 -247.976094) (xy 123.782834 -247.944969) (xy 123.750199 -247.908132) (xy 123.723896 -247.866536)
			(xy 123.704605 -247.82126) (xy 123.692828 -247.773476) (xy 123.688868 -247.724422) (xy 123.359926 -247.724422)
			(xy 123.359431 -247.749029) (xy 123.351536 -247.797606) (xy 123.335952 -247.844287) (xy 123.313081 -247.887864)
			(xy 123.283516 -247.927208) (xy 123.248023 -247.9613) (xy 123.20752 -247.989256) (xy 123.163058 -248.010354)
			(xy 123.115787 -248.024046) (xy 123.066932 -248.029978) (xy 123.017757 -248.027997) (xy 122.969538 -248.018153)
			(xy 122.923522 -248.000701) (xy 122.880901 -247.976094) (xy 122.84278 -247.944969) (xy 122.810145 -247.908132)
			(xy 122.783842 -247.866536) (xy 122.764551 -247.82126) (xy 122.752774 -247.773476) (xy 122.748814 -247.724422)
			(xy 122.420126 -247.724422) (xy 122.419631 -247.749029) (xy 122.411736 -247.797606) (xy 122.396152 -247.844287)
			(xy 122.373281 -247.887864) (xy 122.343716 -247.927208) (xy 122.308223 -247.9613) (xy 122.26772 -247.989256)
			(xy 122.223258 -248.010354) (xy 122.175987 -248.024046) (xy 122.127132 -248.029978) (xy 122.077957 -248.027997)
			(xy 122.029738 -248.018153) (xy 121.983722 -248.000701) (xy 121.941101 -247.976094) (xy 121.90298 -247.944969)
			(xy 121.870345 -247.908132) (xy 121.844042 -247.866536) (xy 121.824751 -247.82126) (xy 121.812974 -247.773476)
			(xy 121.809014 -247.724422) (xy 121.480072 -247.724422) (xy 121.479577 -247.749029) (xy 121.471682 -247.797606)
			(xy 121.456098 -247.844287) (xy 121.433227 -247.887864) (xy 121.403662 -247.927208) (xy 121.368169 -247.9613)
			(xy 121.327666 -247.989256) (xy 121.283204 -248.010354) (xy 121.235933 -248.024046) (xy 121.187078 -248.029978)
			(xy 121.137903 -248.027997) (xy 121.089684 -248.018153) (xy 121.043668 -248.000701) (xy 121.001047 -247.976094)
			(xy 120.962926 -247.944969) (xy 120.930291 -247.908132) (xy 120.903988 -247.866536) (xy 120.884697 -247.82126)
			(xy 120.87292 -247.773476) (xy 120.86896 -247.724422) (xy 120.540018 -247.724422) (xy 120.539523 -247.749029)
			(xy 120.531628 -247.797606) (xy 120.516044 -247.844287) (xy 120.493173 -247.887864) (xy 120.463608 -247.927208)
			(xy 120.428115 -247.9613) (xy 120.387612 -247.989256) (xy 120.34315 -248.010354) (xy 120.295879 -248.024046)
			(xy 120.247024 -248.029978) (xy 120.197849 -248.027997) (xy 120.14963 -248.018153) (xy 120.103614 -248.000701)
			(xy 120.060993 -247.976094) (xy 120.022872 -247.944969) (xy 119.990237 -247.908132) (xy 119.963934 -247.866536)
			(xy 119.944643 -247.82126) (xy 119.932866 -247.773476) (xy 119.928906 -247.724422) (xy 119.599964 -247.724422)
			(xy 119.599469 -247.749029) (xy 119.591574 -247.797606) (xy 119.57599 -247.844287) (xy 119.553119 -247.887864)
			(xy 119.523554 -247.927208) (xy 119.488061 -247.9613) (xy 119.447558 -247.989256) (xy 119.403096 -248.010354)
			(xy 119.355825 -248.024046) (xy 119.30697 -248.029978) (xy 119.257795 -248.027997) (xy 119.209576 -248.018153)
			(xy 119.16356 -248.000701) (xy 119.120939 -247.976094) (xy 119.082818 -247.944969) (xy 119.050183 -247.908132)
			(xy 119.02388 -247.866536) (xy 119.004589 -247.82126) (xy 118.992812 -247.773476) (xy 118.988852 -247.724422)
			(xy 118.660164 -247.724422) (xy 118.659669 -247.749029) (xy 118.651774 -247.797606) (xy 118.63619 -247.844287)
			(xy 118.613319 -247.887864) (xy 118.583754 -247.927208) (xy 118.548261 -247.9613) (xy 118.507758 -247.989256)
			(xy 118.463296 -248.010354) (xy 118.416025 -248.024046) (xy 118.36717 -248.029978) (xy 118.317995 -248.027997)
			(xy 118.269776 -248.018153) (xy 118.22376 -248.000701) (xy 118.181139 -247.976094) (xy 118.143018 -247.944969)
			(xy 118.110383 -247.908132) (xy 118.08408 -247.866536) (xy 118.064789 -247.82126) (xy 118.053012 -247.773476)
			(xy 118.049052 -247.724422) (xy 117.72011 -247.724422) (xy 117.719615 -247.749029) (xy 117.71172 -247.797606)
			(xy 117.696136 -247.844287) (xy 117.673265 -247.887864) (xy 117.6437 -247.927208) (xy 117.608207 -247.9613)
			(xy 117.567704 -247.989256) (xy 117.523242 -248.010354) (xy 117.475971 -248.024046) (xy 117.427116 -248.029978)
			(xy 117.377941 -248.027997) (xy 117.329722 -248.018153) (xy 117.283706 -248.000701) (xy 117.241085 -247.976094)
			(xy 117.202964 -247.944969) (xy 117.170329 -247.908132) (xy 117.144026 -247.866536) (xy 117.124735 -247.82126)
			(xy 117.112958 -247.773476) (xy 117.108998 -247.724422) (xy 116.780056 -247.724422) (xy 116.779561 -247.749029)
			(xy 116.771666 -247.797606) (xy 116.756082 -247.844287) (xy 116.733211 -247.887864) (xy 116.703646 -247.927208)
			(xy 116.668153 -247.9613) (xy 116.62765 -247.989256) (xy 116.583188 -248.010354) (xy 116.535917 -248.024046)
			(xy 116.487062 -248.029978) (xy 116.437887 -248.027997) (xy 116.389668 -248.018153) (xy 116.343652 -248.000701)
			(xy 116.301031 -247.976094) (xy 116.26291 -247.944969) (xy 116.230275 -247.908132) (xy 116.203972 -247.866536)
			(xy 116.184681 -247.82126) (xy 116.172904 -247.773476) (xy 116.168944 -247.724422) (xy 115.840002 -247.724422)
			(xy 115.839507 -247.749029) (xy 115.831612 -247.797606) (xy 115.816028 -247.844287) (xy 115.793157 -247.887864)
			(xy 115.763592 -247.927208) (xy 115.728099 -247.9613) (xy 115.687596 -247.989256) (xy 115.643134 -248.010354)
			(xy 115.595863 -248.024046) (xy 115.547008 -248.029978) (xy 115.497833 -248.027997) (xy 115.449614 -248.018153)
			(xy 115.403598 -248.000701) (xy 115.360977 -247.976094) (xy 115.322856 -247.944969) (xy 115.290221 -247.908132)
			(xy 115.263918 -247.866536) (xy 115.244627 -247.82126) (xy 115.23285 -247.773476) (xy 115.22889 -247.724422)
			(xy 114.899948 -247.724422) (xy 114.899453 -247.749029) (xy 114.891558 -247.797606) (xy 114.875974 -247.844287)
			(xy 114.853103 -247.887864) (xy 114.823538 -247.927208) (xy 114.788045 -247.9613) (xy 114.747542 -247.989256)
			(xy 114.70308 -248.010354) (xy 114.655809 -248.024046) (xy 114.606954 -248.029978) (xy 114.557779 -248.027997)
			(xy 114.50956 -248.018153) (xy 114.463544 -248.000701) (xy 114.420923 -247.976094) (xy 114.382802 -247.944969)
			(xy 114.350167 -247.908132) (xy 114.323864 -247.866536) (xy 114.304573 -247.82126) (xy 114.292796 -247.773476)
			(xy 114.288836 -247.724422) (xy 113.960148 -247.724422) (xy 113.959653 -247.749029) (xy 113.951758 -247.797606)
			(xy 113.936174 -247.844287) (xy 113.913303 -247.887864) (xy 113.883738 -247.927208) (xy 113.848245 -247.9613)
			(xy 113.807742 -247.989256) (xy 113.76328 -248.010354) (xy 113.716009 -248.024046) (xy 113.667154 -248.029978)
			(xy 113.617979 -248.027997) (xy 113.56976 -248.018153) (xy 113.523744 -248.000701) (xy 113.481123 -247.976094)
			(xy 113.443002 -247.944969) (xy 113.410367 -247.908132) (xy 113.384064 -247.866536) (xy 113.364773 -247.82126)
			(xy 113.352996 -247.773476) (xy 113.349036 -247.724422) (xy 112.01548 -247.724422) (xy 111.987326 -247.745883)
			(xy 111.94107 -247.771036) (xy 111.891517 -247.788834) (xy 111.839827 -247.798858) (xy 111.787213 -247.800875)
			(xy 111.734908 -247.794837) (xy 111.684137 -247.780885) (xy 111.636092 -247.759346) (xy 111.591897 -247.730726)
			(xy 111.552589 -247.695695) (xy 111.519089 -247.655074) (xy 111.492183 -247.609815) (xy 111.4725 -247.56098)
			(xy 111.460503 -247.509712) (xy 111.456473 -247.457214) (xy 110.048873 -247.457214) (xy 110.053876 -247.459588)
			(xy 110.094379 -247.487544) (xy 110.129872 -247.521636) (xy 110.159437 -247.56098) (xy 110.182308 -247.604557)
			(xy 110.197892 -247.651238) (xy 110.205787 -247.699815) (xy 110.206282 -247.724422) (xy 110.205787 -247.749029)
			(xy 110.197892 -247.797606) (xy 110.182308 -247.844287) (xy 110.159437 -247.887864) (xy 110.129872 -247.927208)
			(xy 110.094379 -247.9613) (xy 110.053876 -247.989256) (xy 110.009414 -248.010354) (xy 109.962143 -248.024046)
			(xy 109.913288 -248.029978) (xy 109.864113 -248.027997) (xy 109.815894 -248.018153) (xy 109.769878 -248.000701)
			(xy 109.727257 -247.976094) (xy 109.689136 -247.944969) (xy 109.656501 -247.908132) (xy 109.630198 -247.866536)
			(xy 109.610907 -247.82126) (xy 109.59913 -247.773476) (xy 109.59517 -247.724422) (xy 109.266482 -247.724422)
			(xy 109.265987 -247.749029) (xy 109.258092 -247.797606) (xy 109.242508 -247.844287) (xy 109.219637 -247.887864)
			(xy 109.190072 -247.927208) (xy 109.154579 -247.9613) (xy 109.114076 -247.989256) (xy 109.069614 -248.010354)
			(xy 109.022343 -248.024046) (xy 108.973488 -248.029978) (xy 108.924313 -248.027997) (xy 108.876094 -248.018153)
			(xy 108.830078 -248.000701) (xy 108.787457 -247.976094) (xy 108.749336 -247.944969) (xy 108.716701 -247.908132)
			(xy 108.690398 -247.866536) (xy 108.671107 -247.82126) (xy 108.65933 -247.773476) (xy 108.65537 -247.724422)
			(xy 108.326428 -247.724422) (xy 108.325933 -247.749029) (xy 108.318038 -247.797606) (xy 108.302454 -247.844287)
			(xy 108.279583 -247.887864) (xy 108.250018 -247.927208) (xy 108.214525 -247.9613) (xy 108.174022 -247.989256)
			(xy 108.12956 -248.010354) (xy 108.082289 -248.024046) (xy 108.033434 -248.029978) (xy 107.984259 -248.027997)
			(xy 107.93604 -248.018153) (xy 107.890024 -248.000701) (xy 107.847403 -247.976094) (xy 107.809282 -247.944969)
			(xy 107.776647 -247.908132) (xy 107.750344 -247.866536) (xy 107.731053 -247.82126) (xy 107.719276 -247.773476)
			(xy 107.715316 -247.724422) (xy 107.387235 -247.724422) (xy 107.383061 -247.774792) (xy 107.370647 -247.823809)
			(xy 107.350334 -247.870114) (xy 107.322676 -247.912444) (xy 107.288427 -247.949644) (xy 107.248523 -247.980699)
			(xy 107.204051 -248.004762) (xy 107.156224 -248.021176) (xy 107.106348 -248.029494) (xy 107.081066 -248.029984)
			(xy 106.141012 -248.029984) (xy 106.115734 -248.029448) (xy 106.065869 -248.021129) (xy 106.018052 -248.004715)
			(xy 105.97359 -247.980655) (xy 105.933694 -247.949604) (xy 105.899453 -247.91241) (xy 105.871801 -247.870087)
			(xy 105.851493 -247.82379) (xy 105.839082 -247.774782) (xy 105.834907 -247.7244) (xy 105.506266 -247.7244)
			(xy 105.506266 -247.724422) (xy 105.505771 -247.749029) (xy 105.497876 -247.797606) (xy 105.482292 -247.844287)
			(xy 105.459421 -247.887864) (xy 105.429856 -247.927208) (xy 105.394363 -247.9613) (xy 105.35386 -247.989256)
			(xy 105.309398 -248.010354) (xy 105.262127 -248.024046) (xy 105.213272 -248.029978) (xy 105.164097 -248.027997)
			(xy 105.115878 -248.018153) (xy 105.069862 -248.000701) (xy 105.027241 -247.976094) (xy 104.98912 -247.944969)
			(xy 104.956485 -247.908132) (xy 104.930182 -247.866536) (xy 104.910891 -247.82126) (xy 104.899114 -247.773476)
			(xy 104.895154 -247.724422) (xy 104.567335 -247.724422) (xy 104.56316 -247.774793) (xy 104.550746 -247.823811)
			(xy 104.530433 -247.870117) (xy 104.502774 -247.912447) (xy 104.468524 -247.949647) (xy 104.428619 -247.980702)
			(xy 104.384145 -248.004764) (xy 104.336318 -248.021178) (xy 104.286441 -248.029494) (xy 104.261158 -248.029984)
			(xy 103.321104 -248.029984) (xy 103.295827 -248.029447) (xy 103.245962 -248.021127) (xy 103.198147 -248.004713)
			(xy 103.153685 -247.980652) (xy 103.113791 -247.949601) (xy 103.079551 -247.912407) (xy 103.0519 -247.870085)
			(xy 103.031593 -247.823789) (xy 103.019182 -247.774782) (xy 103.015007 -247.7244) (xy 102.686358 -247.7244)
			(xy 102.686358 -247.724422) (xy 102.685863 -247.749029) (xy 102.677968 -247.797606) (xy 102.662384 -247.844287)
			(xy 102.639513 -247.887864) (xy 102.609948 -247.927208) (xy 102.574455 -247.9613) (xy 102.533952 -247.989256)
			(xy 102.48949 -248.010354) (xy 102.442219 -248.024046) (xy 102.393364 -248.029978) (xy 102.344189 -248.027997)
			(xy 102.29597 -248.018153) (xy 102.249954 -248.000701) (xy 102.207333 -247.976094) (xy 102.169212 -247.944969)
			(xy 102.136577 -247.908132) (xy 102.110274 -247.866536) (xy 102.090983 -247.82126) (xy 102.079206 -247.773476)
			(xy 102.075246 -247.724422) (xy 101.747135 -247.724422) (xy 101.742961 -247.774789) (xy 101.730549 -247.823803)
			(xy 101.710238 -247.870106) (xy 101.682584 -247.912434) (xy 101.648339 -247.949633) (xy 101.608439 -247.980689)
			(xy 101.563971 -248.004753) (xy 101.516149 -248.02117) (xy 101.466277 -248.029491) (xy 101.440996 -248.029984)
			(xy 100.500942 -248.029984) (xy 100.475663 -248.02945) (xy 100.425793 -248.021135) (xy 100.377972 -248.004724)
			(xy 100.333506 -247.980665) (xy 100.293605 -247.949615) (xy 100.259361 -247.91242) (xy 100.231706 -247.870096)
			(xy 100.211395 -247.823796) (xy 100.198983 -247.774786) (xy 100.194807 -247.7244) (xy 99.86645 -247.7244)
			(xy 99.86645 -247.724422) (xy 99.865955 -247.749029) (xy 99.85806 -247.797606) (xy 99.842476 -247.844287)
			(xy 99.819605 -247.887864) (xy 99.79004 -247.927208) (xy 99.754547 -247.9613) (xy 99.714044 -247.989256)
			(xy 99.669582 -248.010354) (xy 99.622311 -248.024046) (xy 99.573456 -248.029978) (xy 99.524281 -248.027997)
			(xy 99.476062 -248.018153) (xy 99.430046 -248.000701) (xy 99.387425 -247.976094) (xy 99.349304 -247.944969)
			(xy 99.316669 -247.908132) (xy 99.290366 -247.866536) (xy 99.271075 -247.82126) (xy 99.259298 -247.773476)
			(xy 99.255338 -247.724422) (xy 98.927235 -247.724422) (xy 98.923061 -247.77479) (xy 98.910648 -247.823805)
			(xy 98.890337 -247.870108) (xy 98.862682 -247.912437) (xy 98.828436 -247.949636) (xy 98.788534 -247.980691)
			(xy 98.744066 -248.004755) (xy 98.696242 -248.021171) (xy 98.646369 -248.029492) (xy 98.621088 -248.029984)
			(xy 97.681034 -248.029984) (xy 97.655755 -248.02945) (xy 97.605887 -248.021133) (xy 97.558067 -248.004721)
			(xy 97.513601 -247.980662) (xy 97.473702 -247.949612) (xy 97.439459 -247.912417) (xy 97.411805 -247.870093)
			(xy 97.391495 -247.823795) (xy 97.379083 -247.774785) (xy 97.374907 -247.7244) (xy 97.045756 -247.7244)
			(xy 97.045755 -247.749286) (xy 97.037688 -247.798368) (xy 97.021769 -247.845494) (xy 96.99842 -247.889414)
			(xy 96.968259 -247.928968) (xy 96.95053 -247.946418) (xy 96.943164 -247.953276) (xy 96.930972 -247.980454)
			(xy 96.928922 -247.985413) (xy 96.926748 -247.995917) (xy 96.926654 -248.001282) (xy 96.926654 -248.65457)
			(xy 96.927122 -248.664444) (xy 96.934574 -248.682733) (xy 96.941132 -248.69013) (xy 96.941386 -248.690384)
			(xy 97.051368 -248.800366) (xy 97.051876 -248.800874) (xy 97.059259 -248.807451) (xy 97.077558 -248.814889)
			(xy 97.087436 -248.815352) (xy 98.727768 -248.815352) (xy 98.736406 -248.815012) (xy 98.752696 -248.809259)
			(xy 98.766134 -248.798402) (xy 98.770948 -248.791222) (xy 98.822256 -248.708418) (xy 98.823526 -248.682256)
			(xy 98.817684 -248.670318) (xy 98.807598 -248.649101) (xy 98.793349 -248.604337) (xy 98.786137 -248.557916)
			(xy 98.78568 -248.534428) (xy 98.786124 -248.510433) (xy 98.793627 -248.463033) (xy 98.808453 -248.417391)
			(xy 98.830237 -248.37463) (xy 98.858442 -248.335804) (xy 98.892373 -248.301868) (xy 98.931196 -248.273658)
			(xy 98.973954 -248.251869) (xy 99.019595 -248.237037) (xy 99.066993 -248.229527) (xy 99.090988 -248.22912)
			(xy 99.103751 -248.229256) (xy 99.129186 -248.231414) (xy 99.141788 -248.233438) (xy 99.141788 -248.233184)
			(xy 99.164832 -248.237498) (xy 99.209327 -248.252259) (xy 99.251043 -248.27365) (xy 99.288998 -248.301166)
			(xy 99.3223 -248.334162) (xy 99.350165 -248.371862) (xy 99.371939 -248.413379) (xy 99.387109 -248.457736)
			(xy 99.39532 -248.503892) (xy 99.396296 -248.527316) (xy 99.396296 -248.533412) (xy 99.396281 -248.534428)
			(xy 101.605346 -248.534428) (xy 101.609306 -248.485374) (xy 101.621083 -248.43759) (xy 101.640374 -248.392314)
			(xy 101.666677 -248.350718) (xy 101.699312 -248.313881) (xy 101.737433 -248.282756) (xy 101.780054 -248.258149)
			(xy 101.82607 -248.240697) (xy 101.874289 -248.230853) (xy 101.923464 -248.228872) (xy 101.972319 -248.234804)
			(xy 102.01959 -248.248496) (xy 102.064052 -248.269594) (xy 102.104555 -248.29755) (xy 102.140048 -248.331642)
			(xy 102.169613 -248.370986) (xy 102.192484 -248.414563) (xy 102.208068 -248.461244) (xy 102.215963 -248.509821)
			(xy 102.216458 -248.534428) (xy 104.425254 -248.534428) (xy 104.429214 -248.485374) (xy 104.440991 -248.43759)
			(xy 104.460282 -248.392314) (xy 104.486585 -248.350718) (xy 104.51922 -248.313881) (xy 104.557341 -248.282756)
			(xy 104.599962 -248.258149) (xy 104.645978 -248.240697) (xy 104.694197 -248.230853) (xy 104.743372 -248.228872)
			(xy 104.792227 -248.234804) (xy 104.839498 -248.248496) (xy 104.88396 -248.269594) (xy 104.924463 -248.29755)
			(xy 104.959956 -248.331642) (xy 104.989521 -248.370986) (xy 105.012392 -248.414563) (xy 105.027976 -248.461244)
			(xy 105.035871 -248.509821) (xy 105.036366 -248.534428) (xy 107.245162 -248.534428) (xy 107.249122 -248.485374)
			(xy 107.260899 -248.43759) (xy 107.28019 -248.392314) (xy 107.306493 -248.350718) (xy 107.339128 -248.313881)
			(xy 107.377249 -248.282756) (xy 107.41987 -248.258149) (xy 107.465886 -248.240697) (xy 107.514105 -248.230853)
			(xy 107.56328 -248.228872) (xy 107.612135 -248.234804) (xy 107.659406 -248.248496) (xy 107.703868 -248.269594)
			(xy 107.744371 -248.29755) (xy 107.779864 -248.331642) (xy 107.809429 -248.370986) (xy 107.8323 -248.414563)
			(xy 107.847884 -248.461244) (xy 107.855779 -248.509821) (xy 107.856273 -248.5344) (xy 108.185168 -248.5344)
			(xy 108.189339 -248.48406) (xy 108.20174 -248.435093) (xy 108.222032 -248.388834) (xy 108.249661 -248.346547)
			(xy 108.283873 -248.309385) (xy 108.323736 -248.278361) (xy 108.368162 -248.254321) (xy 108.415939 -248.237922)
			(xy 108.465764 -248.229611) (xy 108.49102 -248.22912) (xy 109.431074 -248.22912) (xy 109.456335 -248.229555)
			(xy 109.50617 -248.237867) (xy 109.553956 -248.254268) (xy 109.598391 -248.278312) (xy 109.638262 -248.309342)
			(xy 109.672482 -248.346511) (xy 109.700117 -248.388806) (xy 109.720412 -248.435073) (xy 109.732816 -248.48405)
			(xy 109.736988 -248.5344) (xy 109.736986 -248.534428) (xy 110.065324 -248.534428) (xy 110.069284 -248.485374)
			(xy 110.081061 -248.43759) (xy 110.100352 -248.392314) (xy 110.126655 -248.350718) (xy 110.15929 -248.313881)
			(xy 110.197411 -248.282756) (xy 110.240032 -248.258149) (xy 110.286048 -248.240697) (xy 110.334267 -248.230853)
			(xy 110.383442 -248.228872) (xy 110.432297 -248.234804) (xy 110.479568 -248.248496) (xy 110.52403 -248.269594)
			(xy 110.564533 -248.29755) (xy 110.600026 -248.331642) (xy 110.629591 -248.370986) (xy 110.652462 -248.414563)
			(xy 110.668046 -248.461244) (xy 110.675941 -248.509821) (xy 110.676436 -248.534428) (xy 112.878882 -248.534428)
			(xy 112.882842 -248.485374) (xy 112.894619 -248.43759) (xy 112.91391 -248.392314) (xy 112.940213 -248.350718)
			(xy 112.972848 -248.313881) (xy 113.010969 -248.282756) (xy 113.05359 -248.258149) (xy 113.099606 -248.240697)
			(xy 113.147825 -248.230853) (xy 113.197 -248.228872) (xy 113.245855 -248.234804) (xy 113.293126 -248.248496)
			(xy 113.337588 -248.269594) (xy 113.378091 -248.29755) (xy 113.413584 -248.331642) (xy 113.443149 -248.370986)
			(xy 113.46602 -248.414563) (xy 113.481604 -248.461244) (xy 113.489499 -248.509821) (xy 113.489994 -248.534428)
			(xy 113.818936 -248.534428) (xy 113.822896 -248.485374) (xy 113.834673 -248.43759) (xy 113.853964 -248.392314)
			(xy 113.880267 -248.350718) (xy 113.912902 -248.313881) (xy 113.951023 -248.282756) (xy 113.993644 -248.258149)
			(xy 114.03966 -248.240697) (xy 114.087879 -248.230853) (xy 114.137054 -248.228872) (xy 114.185909 -248.234804)
			(xy 114.23318 -248.248496) (xy 114.277642 -248.269594) (xy 114.318145 -248.29755) (xy 114.353638 -248.331642)
			(xy 114.383203 -248.370986) (xy 114.406074 -248.414563) (xy 114.421658 -248.461244) (xy 114.429553 -248.509821)
			(xy 114.430048 -248.534428) (xy 114.75899 -248.534428) (xy 114.76295 -248.485374) (xy 114.774727 -248.43759)
			(xy 114.794018 -248.392314) (xy 114.820321 -248.350718) (xy 114.852956 -248.313881) (xy 114.891077 -248.282756)
			(xy 114.933698 -248.258149) (xy 114.979714 -248.240697) (xy 115.027933 -248.230853) (xy 115.077108 -248.228872)
			(xy 115.125963 -248.234804) (xy 115.173234 -248.248496) (xy 115.217696 -248.269594) (xy 115.258199 -248.29755)
			(xy 115.293692 -248.331642) (xy 115.323257 -248.370986) (xy 115.346128 -248.414563) (xy 115.361712 -248.461244)
			(xy 115.369607 -248.509821) (xy 115.370102 -248.534428) (xy 115.699044 -248.534428) (xy 115.703004 -248.485374)
			(xy 115.714781 -248.43759) (xy 115.734072 -248.392314) (xy 115.760375 -248.350718) (xy 115.79301 -248.313881)
			(xy 115.831131 -248.282756) (xy 115.873752 -248.258149) (xy 115.919768 -248.240697) (xy 115.967987 -248.230853)
			(xy 116.017162 -248.228872) (xy 116.066017 -248.234804) (xy 116.113288 -248.248496) (xy 116.15775 -248.269594)
			(xy 116.198253 -248.29755) (xy 116.233746 -248.331642) (xy 116.263311 -248.370986) (xy 116.286182 -248.414563)
			(xy 116.301766 -248.461244) (xy 116.309661 -248.509821) (xy 116.310156 -248.534428) (xy 118.518952 -248.534428)
			(xy 118.522912 -248.485374) (xy 118.534689 -248.43759) (xy 118.55398 -248.392314) (xy 118.580283 -248.350718)
			(xy 118.612918 -248.313881) (xy 118.651039 -248.282756) (xy 118.69366 -248.258149) (xy 118.739676 -248.240697)
			(xy 118.787895 -248.230853) (xy 118.83707 -248.228872) (xy 118.885925 -248.234804) (xy 118.933196 -248.248496)
			(xy 118.977658 -248.269594) (xy 119.018161 -248.29755) (xy 119.053654 -248.331642) (xy 119.083219 -248.370986)
			(xy 119.10609 -248.414563) (xy 119.121674 -248.461244) (xy 119.129569 -248.509821) (xy 119.130064 -248.534428)
			(xy 121.33886 -248.534428) (xy 121.34282 -248.485374) (xy 121.354597 -248.43759) (xy 121.373888 -248.392314)
			(xy 121.400191 -248.350718) (xy 121.432826 -248.313881) (xy 121.470947 -248.282756) (xy 121.513568 -248.258149)
			(xy 121.559584 -248.240697) (xy 121.607803 -248.230853) (xy 121.656978 -248.228872) (xy 121.705833 -248.234804)
			(xy 121.753104 -248.248496) (xy 121.797566 -248.269594) (xy 121.838069 -248.29755) (xy 121.873562 -248.331642)
			(xy 121.903127 -248.370986) (xy 121.925998 -248.414563) (xy 121.941582 -248.461244) (xy 121.949477 -248.509821)
			(xy 121.949972 -248.534428) (xy 124.159022 -248.534428) (xy 124.162982 -248.485374) (xy 124.174759 -248.43759)
			(xy 124.19405 -248.392314) (xy 124.220353 -248.350718) (xy 124.252988 -248.313881) (xy 124.291109 -248.282756)
			(xy 124.33373 -248.258149) (xy 124.379746 -248.240697) (xy 124.427965 -248.230853) (xy 124.47714 -248.228872)
			(xy 124.525995 -248.234804) (xy 124.573266 -248.248496) (xy 124.617728 -248.269594) (xy 124.658231 -248.29755)
			(xy 124.693724 -248.331642) (xy 124.723289 -248.370986) (xy 124.74616 -248.414563) (xy 124.761744 -248.461244)
			(xy 124.769639 -248.509821) (xy 124.770134 -248.534428) (xy 126.97893 -248.534428) (xy 126.98289 -248.485374)
			(xy 126.994667 -248.43759) (xy 127.013958 -248.392314) (xy 127.040261 -248.350718) (xy 127.072896 -248.313881)
			(xy 127.111017 -248.282756) (xy 127.153638 -248.258149) (xy 127.199654 -248.240697) (xy 127.247873 -248.230853)
			(xy 127.297048 -248.228872) (xy 127.345903 -248.234804) (xy 127.393174 -248.248496) (xy 127.437636 -248.269594)
			(xy 127.478139 -248.29755) (xy 127.513632 -248.331642) (xy 127.543197 -248.370986) (xy 127.566068 -248.414563)
			(xy 127.581652 -248.461244) (xy 127.589547 -248.509821) (xy 127.590042 -248.534428) (xy 127.908553 -248.534428)
			(xy 127.912648 -248.4837) (xy 127.924827 -248.434286) (xy 127.944775 -248.387466) (xy 127.971976 -248.344452)
			(xy 128.005724 -248.306358) (xy 128.045146 -248.274171) (xy 128.08922 -248.248725) (xy 128.136806 -248.230678)
			(xy 128.18667 -248.220498) (xy 128.237522 -248.218449) (xy 128.288043 -248.224583) (xy 128.336927 -248.238743)
			(xy 128.382906 -248.26056) (xy 128.42479 -248.28947) (xy 128.461494 -248.324725) (xy 128.492067 -248.365411)
			(xy 128.515718 -248.410474) (xy 128.531834 -248.458748) (xy 128.539998 -248.508982) (xy 128.54051 -248.534428)
			(xy 128.848607 -248.534428) (xy 128.852702 -248.4837) (xy 128.864881 -248.434286) (xy 128.884829 -248.387466)
			(xy 128.91203 -248.344452) (xy 128.945778 -248.306358) (xy 128.9852 -248.274171) (xy 129.029274 -248.248725)
			(xy 129.07686 -248.230678) (xy 129.126724 -248.220498) (xy 129.177576 -248.218449) (xy 129.228097 -248.224583)
			(xy 129.276981 -248.238743) (xy 129.32296 -248.26056) (xy 129.364844 -248.28947) (xy 129.401548 -248.324725)
			(xy 129.432121 -248.365411) (xy 129.455772 -248.410474) (xy 129.471888 -248.458748) (xy 129.480052 -248.508982)
			(xy 129.480564 -248.534428) (xy 129.480052 -248.559874) (xy 129.471888 -248.610108) (xy 129.455772 -248.658382)
			(xy 129.432121 -248.703445) (xy 129.401548 -248.744131) (xy 129.364844 -248.779386) (xy 129.32296 -248.808296)
			(xy 129.276981 -248.830113) (xy 129.228097 -248.844273) (xy 129.177576 -248.850407) (xy 129.126724 -248.848358)
			(xy 129.07686 -248.838178) (xy 129.029274 -248.820131) (xy 128.9852 -248.794685) (xy 128.945778 -248.762498)
			(xy 128.91203 -248.724404) (xy 128.884829 -248.68139) (xy 128.864881 -248.63457) (xy 128.852702 -248.585156)
			(xy 128.848607 -248.534428) (xy 128.54051 -248.534428) (xy 128.539998 -248.559874) (xy 128.531834 -248.610108)
			(xy 128.515718 -248.658382) (xy 128.492067 -248.703445) (xy 128.461494 -248.744131) (xy 128.42479 -248.779386)
			(xy 128.382906 -248.808296) (xy 128.336927 -248.830113) (xy 128.288043 -248.844273) (xy 128.237522 -248.850407)
			(xy 128.18667 -248.848358) (xy 128.136806 -248.838178) (xy 128.08922 -248.820131) (xy 128.045146 -248.794685)
			(xy 128.005724 -248.762498) (xy 127.971976 -248.724404) (xy 127.944775 -248.68139) (xy 127.924827 -248.63457)
			(xy 127.912648 -248.585156) (xy 127.908553 -248.534428) (xy 127.590042 -248.534428) (xy 127.589547 -248.559035)
			(xy 127.581652 -248.607612) (xy 127.566068 -248.654293) (xy 127.543197 -248.69787) (xy 127.513632 -248.737214)
			(xy 127.478139 -248.771306) (xy 127.437636 -248.799262) (xy 127.393174 -248.82036) (xy 127.345903 -248.834052)
			(xy 127.297048 -248.839984) (xy 127.247873 -248.838003) (xy 127.199654 -248.828159) (xy 127.153638 -248.810707)
			(xy 127.111017 -248.7861) (xy 127.072896 -248.754975) (xy 127.040261 -248.718138) (xy 127.013958 -248.676542)
			(xy 126.994667 -248.631266) (xy 126.98289 -248.583482) (xy 126.97893 -248.534428) (xy 124.770134 -248.534428)
			(xy 124.769639 -248.559035) (xy 124.761744 -248.607612) (xy 124.74616 -248.654293) (xy 124.723289 -248.69787)
			(xy 124.693724 -248.737214) (xy 124.658231 -248.771306) (xy 124.617728 -248.799262) (xy 124.573266 -248.82036)
			(xy 124.525995 -248.834052) (xy 124.47714 -248.839984) (xy 124.427965 -248.838003) (xy 124.379746 -248.828159)
			(xy 124.33373 -248.810707) (xy 124.291109 -248.7861) (xy 124.252988 -248.754975) (xy 124.220353 -248.718138)
			(xy 124.19405 -248.676542) (xy 124.174759 -248.631266) (xy 124.162982 -248.583482) (xy 124.159022 -248.534428)
			(xy 121.949972 -248.534428) (xy 121.949477 -248.559035) (xy 121.941582 -248.607612) (xy 121.925998 -248.654293)
			(xy 121.903127 -248.69787) (xy 121.873562 -248.737214) (xy 121.838069 -248.771306) (xy 121.797566 -248.799262)
			(xy 121.753104 -248.82036) (xy 121.705833 -248.834052) (xy 121.656978 -248.839984) (xy 121.607803 -248.838003)
			(xy 121.559584 -248.828159) (xy 121.513568 -248.810707) (xy 121.470947 -248.7861) (xy 121.432826 -248.754975)
			(xy 121.400191 -248.718138) (xy 121.373888 -248.676542) (xy 121.354597 -248.631266) (xy 121.34282 -248.583482)
			(xy 121.33886 -248.534428) (xy 119.130064 -248.534428) (xy 119.129569 -248.559035) (xy 119.121674 -248.607612)
			(xy 119.10609 -248.654293) (xy 119.083219 -248.69787) (xy 119.053654 -248.737214) (xy 119.018161 -248.771306)
			(xy 118.977658 -248.799262) (xy 118.933196 -248.82036) (xy 118.885925 -248.834052) (xy 118.83707 -248.839984)
			(xy 118.787895 -248.838003) (xy 118.739676 -248.828159) (xy 118.69366 -248.810707) (xy 118.651039 -248.7861)
			(xy 118.612918 -248.754975) (xy 118.580283 -248.718138) (xy 118.55398 -248.676542) (xy 118.534689 -248.631266)
			(xy 118.522912 -248.583482) (xy 118.518952 -248.534428) (xy 116.310156 -248.534428) (xy 116.309661 -248.559035)
			(xy 116.301766 -248.607612) (xy 116.286182 -248.654293) (xy 116.263311 -248.69787) (xy 116.233746 -248.737214)
			(xy 116.198253 -248.771306) (xy 116.15775 -248.799262) (xy 116.113288 -248.82036) (xy 116.066017 -248.834052)
			(xy 116.017162 -248.839984) (xy 115.967987 -248.838003) (xy 115.919768 -248.828159) (xy 115.873752 -248.810707)
			(xy 115.831131 -248.7861) (xy 115.79301 -248.754975) (xy 115.760375 -248.718138) (xy 115.734072 -248.676542)
			(xy 115.714781 -248.631266) (xy 115.703004 -248.583482) (xy 115.699044 -248.534428) (xy 115.370102 -248.534428)
			(xy 115.369607 -248.559035) (xy 115.361712 -248.607612) (xy 115.346128 -248.654293) (xy 115.323257 -248.69787)
			(xy 115.293692 -248.737214) (xy 115.258199 -248.771306) (xy 115.217696 -248.799262) (xy 115.173234 -248.82036)
			(xy 115.125963 -248.834052) (xy 115.077108 -248.839984) (xy 115.027933 -248.838003) (xy 114.979714 -248.828159)
			(xy 114.933698 -248.810707) (xy 114.891077 -248.7861) (xy 114.852956 -248.754975) (xy 114.820321 -248.718138)
			(xy 114.794018 -248.676542) (xy 114.774727 -248.631266) (xy 114.76295 -248.583482) (xy 114.75899 -248.534428)
			(xy 114.430048 -248.534428) (xy 114.429553 -248.559035) (xy 114.421658 -248.607612) (xy 114.406074 -248.654293)
			(xy 114.383203 -248.69787) (xy 114.353638 -248.737214) (xy 114.318145 -248.771306) (xy 114.277642 -248.799262)
			(xy 114.23318 -248.82036) (xy 114.185909 -248.834052) (xy 114.137054 -248.839984) (xy 114.087879 -248.838003)
			(xy 114.03966 -248.828159) (xy 113.993644 -248.810707) (xy 113.951023 -248.7861) (xy 113.912902 -248.754975)
			(xy 113.880267 -248.718138) (xy 113.853964 -248.676542) (xy 113.834673 -248.631266) (xy 113.822896 -248.583482)
			(xy 113.818936 -248.534428) (xy 113.489994 -248.534428) (xy 113.489499 -248.559035) (xy 113.481604 -248.607612)
			(xy 113.46602 -248.654293) (xy 113.443149 -248.69787) (xy 113.413584 -248.737214) (xy 113.378091 -248.771306)
			(xy 113.337588 -248.799262) (xy 113.293126 -248.82036) (xy 113.245855 -248.834052) (xy 113.197 -248.839984)
			(xy 113.147825 -248.838003) (xy 113.099606 -248.828159) (xy 113.05359 -248.810707) (xy 113.010969 -248.7861)
			(xy 112.972848 -248.754975) (xy 112.940213 -248.718138) (xy 112.91391 -248.676542) (xy 112.894619 -248.631266)
			(xy 112.882842 -248.583482) (xy 112.878882 -248.534428) (xy 110.676436 -248.534428) (xy 110.675941 -248.559035)
			(xy 110.668046 -248.607612) (xy 110.652462 -248.654293) (xy 110.629591 -248.69787) (xy 110.600026 -248.737214)
			(xy 110.564533 -248.771306) (xy 110.52403 -248.799262) (xy 110.479568 -248.82036) (xy 110.432297 -248.834052)
			(xy 110.383442 -248.839984) (xy 110.334267 -248.838003) (xy 110.286048 -248.828159) (xy 110.240032 -248.810707)
			(xy 110.197411 -248.7861) (xy 110.15929 -248.754975) (xy 110.126655 -248.718138) (xy 110.100352 -248.676542)
			(xy 110.081061 -248.631266) (xy 110.069284 -248.583482) (xy 110.065324 -248.534428) (xy 109.736986 -248.534428)
			(xy 109.732816 -248.58475) (xy 109.720412 -248.633727) (xy 109.700117 -248.679994) (xy 109.672482 -248.722289)
			(xy 109.638262 -248.759458) (xy 109.598391 -248.790488) (xy 109.553956 -248.814532) (xy 109.50617 -248.830933)
			(xy 109.456335 -248.839245) (xy 109.431074 -248.839736) (xy 108.49102 -248.839736) (xy 108.465764 -248.839189)
			(xy 108.415939 -248.830878) (xy 108.368162 -248.814479) (xy 108.323736 -248.790439) (xy 108.283873 -248.759415)
			(xy 108.249661 -248.722253) (xy 108.222032 -248.679966) (xy 108.20174 -248.633707) (xy 108.189339 -248.58474)
			(xy 108.185168 -248.5344) (xy 107.856273 -248.5344) (xy 107.856274 -248.534428) (xy 107.855779 -248.559035)
			(xy 107.847884 -248.607612) (xy 107.8323 -248.654293) (xy 107.809429 -248.69787) (xy 107.779864 -248.737214)
			(xy 107.744371 -248.771306) (xy 107.703868 -248.799262) (xy 107.659406 -248.82036) (xy 107.612135 -248.834052)
			(xy 107.56328 -248.839984) (xy 107.514105 -248.838003) (xy 107.465886 -248.828159) (xy 107.41987 -248.810707)
			(xy 107.377249 -248.7861) (xy 107.339128 -248.754975) (xy 107.306493 -248.718138) (xy 107.28019 -248.676542)
			(xy 107.260899 -248.631266) (xy 107.249122 -248.583482) (xy 107.245162 -248.534428) (xy 105.036366 -248.534428)
			(xy 105.035871 -248.559035) (xy 105.027976 -248.607612) (xy 105.012392 -248.654293) (xy 104.989521 -248.69787)
			(xy 104.959956 -248.737214) (xy 104.924463 -248.771306) (xy 104.88396 -248.799262) (xy 104.839498 -248.82036)
			(xy 104.792227 -248.834052) (xy 104.743372 -248.839984) (xy 104.694197 -248.838003) (xy 104.645978 -248.828159)
			(xy 104.599962 -248.810707) (xy 104.557341 -248.7861) (xy 104.51922 -248.754975) (xy 104.486585 -248.718138)
			(xy 104.460282 -248.676542) (xy 104.440991 -248.631266) (xy 104.429214 -248.583482) (xy 104.425254 -248.534428)
			(xy 102.216458 -248.534428) (xy 102.215963 -248.559035) (xy 102.208068 -248.607612) (xy 102.192484 -248.654293)
			(xy 102.169613 -248.69787) (xy 102.140048 -248.737214) (xy 102.104555 -248.771306) (xy 102.064052 -248.799262)
			(xy 102.01959 -248.82036) (xy 101.972319 -248.834052) (xy 101.923464 -248.839984) (xy 101.874289 -248.838003)
			(xy 101.82607 -248.828159) (xy 101.780054 -248.810707) (xy 101.737433 -248.7861) (xy 101.699312 -248.754975)
			(xy 101.666677 -248.718138) (xy 101.640374 -248.676542) (xy 101.621083 -248.631266) (xy 101.609306 -248.583482)
			(xy 101.605346 -248.534428) (xy 99.396281 -248.534428) (xy 99.395954 -248.556115) (xy 99.389377 -248.601038)
			(xy 99.376222 -248.644493) (xy 99.356779 -248.685522) (xy 99.34448 -248.704608) (xy 99.340416 -248.710704)
			(xy 99.335336 -248.726706) (xy 99.332745 -248.735909) (xy 99.333913 -248.754978) (xy 99.337622 -248.76379)
			(xy 99.347782 -248.785888) (xy 99.35222 -248.794513) (xy 99.366292 -248.807838) (xy 99.384318 -248.814954)
			(xy 99.39401 -248.815352) (xy 99.398582 -248.815352) (xy 99.408419 -248.815889) (xy 99.426582 -248.823474)
			(xy 99.433888 -248.830084) (xy 99.658678 -249.054874) (xy 99.668838 -249.058684) (xy 99.693283 -249.068479)
			(xy 99.73865 -249.095213) (xy 99.778756 -249.129335) (xy 99.812414 -249.169832) (xy 99.838624 -249.215503)
			(xy 99.85661 -249.264994) (xy 99.865837 -249.316837) (xy 99.86645 -249.343164) (xy 99.86645 -249.344434)
			(xy 101.135192 -249.344434) (xy 101.139152 -249.29538) (xy 101.150929 -249.247596) (xy 101.17022 -249.20232)
			(xy 101.196523 -249.160724) (xy 101.229158 -249.123887) (xy 101.267279 -249.092762) (xy 101.3099 -249.068155)
			(xy 101.355916 -249.050703) (xy 101.404135 -249.040859) (xy 101.45331 -249.038878) (xy 101.502165 -249.04481)
			(xy 101.549436 -249.058502) (xy 101.593898 -249.0796) (xy 101.634401 -249.107556) (xy 101.669894 -249.141648)
			(xy 101.699459 -249.180992) (xy 101.72233 -249.224569) (xy 101.737914 -249.27125) (xy 101.745809 -249.319827)
			(xy 101.746304 -249.344434) (xy 103.0153 -249.344434) (xy 103.01926 -249.29538) (xy 103.031037 -249.247596)
			(xy 103.050328 -249.20232) (xy 103.076631 -249.160724) (xy 103.109266 -249.123887) (xy 103.147387 -249.092762)
			(xy 103.190008 -249.068155) (xy 103.236024 -249.050703) (xy 103.284243 -249.040859) (xy 103.333418 -249.038878)
			(xy 103.382273 -249.04481) (xy 103.429544 -249.058502) (xy 103.474006 -249.0796) (xy 103.514509 -249.107556)
			(xy 103.550002 -249.141648) (xy 103.579567 -249.180992) (xy 103.602438 -249.224569) (xy 103.618022 -249.27125)
			(xy 103.625917 -249.319827) (xy 103.626412 -249.344434) (xy 104.895154 -249.344434) (xy 104.899114 -249.29538)
			(xy 104.910891 -249.247596) (xy 104.930182 -249.20232) (xy 104.956485 -249.160724) (xy 104.98912 -249.123887)
			(xy 105.027241 -249.092762) (xy 105.069862 -249.068155) (xy 105.115878 -249.050703) (xy 105.164097 -249.040859)
			(xy 105.213272 -249.038878) (xy 105.262127 -249.04481) (xy 105.309398 -249.058502) (xy 105.35386 -249.0796)
			(xy 105.394363 -249.107556) (xy 105.429856 -249.141648) (xy 105.459421 -249.180992) (xy 105.482292 -249.224569)
			(xy 105.497876 -249.27125) (xy 105.505771 -249.319827) (xy 105.506266 -249.344434) (xy 106.775262 -249.344434)
			(xy 106.779222 -249.29538) (xy 106.790999 -249.247596) (xy 106.81029 -249.20232) (xy 106.836593 -249.160724)
			(xy 106.869228 -249.123887) (xy 106.907349 -249.092762) (xy 106.94997 -249.068155) (xy 106.995986 -249.050703)
			(xy 107.044205 -249.040859) (xy 107.09338 -249.038878) (xy 107.142235 -249.04481) (xy 107.189506 -249.058502)
			(xy 107.233968 -249.0796) (xy 107.274471 -249.107556) (xy 107.309964 -249.141648) (xy 107.339529 -249.180992)
			(xy 107.3624 -249.224569) (xy 107.377984 -249.27125) (xy 107.385879 -249.319827) (xy 107.386374 -249.344434)
			(xy 108.65537 -249.344434) (xy 108.65933 -249.29538) (xy 108.671107 -249.247596) (xy 108.690398 -249.20232)
			(xy 108.716701 -249.160724) (xy 108.749336 -249.123887) (xy 108.787457 -249.092762) (xy 108.830078 -249.068155)
			(xy 108.876094 -249.050703) (xy 108.924313 -249.040859) (xy 108.973488 -249.038878) (xy 109.022343 -249.04481)
			(xy 109.069614 -249.058502) (xy 109.114076 -249.0796) (xy 109.154579 -249.107556) (xy 109.190072 -249.141648)
			(xy 109.219637 -249.180992) (xy 109.242508 -249.224569) (xy 109.258092 -249.27125) (xy 109.265987 -249.319827)
			(xy 109.266482 -249.344434) (xy 109.266124 -249.362214) (xy 111.456473 -249.362214) (xy 111.460503 -249.309716)
			(xy 111.4725 -249.258448) (xy 111.492183 -249.209613) (xy 111.519089 -249.164354) (xy 111.552589 -249.123733)
			(xy 111.591897 -249.088702) (xy 111.636092 -249.060082) (xy 111.684137 -249.038543) (xy 111.734908 -249.024591)
			(xy 111.787213 -249.018553) (xy 111.839827 -249.02057) (xy 111.891517 -249.030594) (xy 111.94107 -249.048392)
			(xy 111.987326 -249.073545) (xy 112.0292 -249.105464) (xy 112.065712 -249.143402) (xy 112.096004 -249.186468)
			(xy 112.119367 -249.233653) (xy 112.135253 -249.283852) (xy 112.14329 -249.335888) (xy 112.143454 -249.344434)
			(xy 113.349036 -249.344434) (xy 113.352996 -249.29538) (xy 113.364773 -249.247596) (xy 113.384064 -249.20232)
			(xy 113.410367 -249.160724) (xy 113.443002 -249.123887) (xy 113.481123 -249.092762) (xy 113.523744 -249.068155)
			(xy 113.56976 -249.050703) (xy 113.617979 -249.040859) (xy 113.667154 -249.038878) (xy 113.716009 -249.04481)
			(xy 113.76328 -249.058502) (xy 113.807742 -249.0796) (xy 113.848245 -249.107556) (xy 113.883738 -249.141648)
			(xy 113.913303 -249.180992) (xy 113.936174 -249.224569) (xy 113.951758 -249.27125) (xy 113.959653 -249.319827)
			(xy 113.960148 -249.344434) (xy 115.22889 -249.344434) (xy 115.23285 -249.29538) (xy 115.244627 -249.247596)
			(xy 115.263918 -249.20232) (xy 115.290221 -249.160724) (xy 115.322856 -249.123887) (xy 115.360977 -249.092762)
			(xy 115.403598 -249.068155) (xy 115.449614 -249.050703) (xy 115.497833 -249.040859) (xy 115.547008 -249.038878)
			(xy 115.595863 -249.04481) (xy 115.643134 -249.058502) (xy 115.687596 -249.0796) (xy 115.728099 -249.107556)
			(xy 115.763592 -249.141648) (xy 115.793157 -249.180992) (xy 115.816028 -249.224569) (xy 115.831612 -249.27125)
			(xy 115.839507 -249.319827) (xy 115.840002 -249.344434) (xy 117.108998 -249.344434) (xy 117.112958 -249.29538)
			(xy 117.124735 -249.247596) (xy 117.144026 -249.20232) (xy 117.170329 -249.160724) (xy 117.202964 -249.123887)
			(xy 117.241085 -249.092762) (xy 117.283706 -249.068155) (xy 117.329722 -249.050703) (xy 117.377941 -249.040859)
			(xy 117.427116 -249.038878) (xy 117.475971 -249.04481) (xy 117.523242 -249.058502) (xy 117.567704 -249.0796)
			(xy 117.608207 -249.107556) (xy 117.6437 -249.141648) (xy 117.673265 -249.180992) (xy 117.696136 -249.224569)
			(xy 117.71172 -249.27125) (xy 117.719615 -249.319827) (xy 117.72011 -249.344434) (xy 118.988852 -249.344434)
			(xy 118.992812 -249.29538) (xy 119.004589 -249.247596) (xy 119.02388 -249.20232) (xy 119.050183 -249.160724)
			(xy 119.082818 -249.123887) (xy 119.120939 -249.092762) (xy 119.16356 -249.068155) (xy 119.209576 -249.050703)
			(xy 119.257795 -249.040859) (xy 119.30697 -249.038878) (xy 119.355825 -249.04481) (xy 119.403096 -249.058502)
			(xy 119.447558 -249.0796) (xy 119.488061 -249.107556) (xy 119.523554 -249.141648) (xy 119.553119 -249.180992)
			(xy 119.57599 -249.224569) (xy 119.591574 -249.27125) (xy 119.599469 -249.319827) (xy 119.599964 -249.344434)
			(xy 120.86896 -249.344434) (xy 120.87292 -249.29538) (xy 120.884697 -249.247596) (xy 120.903988 -249.20232)
			(xy 120.930291 -249.160724) (xy 120.962926 -249.123887) (xy 121.001047 -249.092762) (xy 121.043668 -249.068155)
			(xy 121.089684 -249.050703) (xy 121.137903 -249.040859) (xy 121.187078 -249.038878) (xy 121.235933 -249.04481)
			(xy 121.283204 -249.058502) (xy 121.327666 -249.0796) (xy 121.368169 -249.107556) (xy 121.403662 -249.141648)
			(xy 121.433227 -249.180992) (xy 121.456098 -249.224569) (xy 121.471682 -249.27125) (xy 121.479577 -249.319827)
			(xy 121.480072 -249.344434) (xy 122.748814 -249.344434) (xy 122.752774 -249.29538) (xy 122.764551 -249.247596)
			(xy 122.783842 -249.20232) (xy 122.810145 -249.160724) (xy 122.84278 -249.123887) (xy 122.880901 -249.092762)
			(xy 122.923522 -249.068155) (xy 122.969538 -249.050703) (xy 123.017757 -249.040859) (xy 123.066932 -249.038878)
			(xy 123.115787 -249.04481) (xy 123.163058 -249.058502) (xy 123.20752 -249.0796) (xy 123.248023 -249.107556)
			(xy 123.283516 -249.141648) (xy 123.313081 -249.180992) (xy 123.335952 -249.224569) (xy 123.351536 -249.27125)
			(xy 123.359431 -249.319827) (xy 123.359926 -249.344434) (xy 124.628922 -249.344434) (xy 124.632882 -249.29538)
			(xy 124.644659 -249.247596) (xy 124.66395 -249.20232) (xy 124.690253 -249.160724) (xy 124.722888 -249.123887)
			(xy 124.761009 -249.092762) (xy 124.80363 -249.068155) (xy 124.849646 -249.050703) (xy 124.897865 -249.040859)
			(xy 124.94704 -249.038878) (xy 124.995895 -249.04481) (xy 125.043166 -249.058502) (xy 125.087628 -249.0796)
			(xy 125.128131 -249.107556) (xy 125.163624 -249.141648) (xy 125.193189 -249.180992) (xy 125.21606 -249.224569)
			(xy 125.231644 -249.27125) (xy 125.239539 -249.319827) (xy 125.240034 -249.344434) (xy 126.50903 -249.344434)
			(xy 126.51299 -249.29538) (xy 126.524767 -249.247596) (xy 126.544058 -249.20232) (xy 126.570361 -249.160724)
			(xy 126.602996 -249.123887) (xy 126.641117 -249.092762) (xy 126.683738 -249.068155) (xy 126.729754 -249.050703)
			(xy 126.777973 -249.040859) (xy 126.827148 -249.038878) (xy 126.876003 -249.04481) (xy 126.923274 -249.058502)
			(xy 126.967736 -249.0796) (xy 127.008239 -249.107556) (xy 127.043732 -249.141648) (xy 127.073297 -249.180992)
			(xy 127.096168 -249.224569) (xy 127.111752 -249.27125) (xy 127.119647 -249.319827) (xy 127.120142 -249.344434)
			(xy 127.438399 -249.344434) (xy 127.442494 -249.293706) (xy 127.454673 -249.244292) (xy 127.474621 -249.197472)
			(xy 127.501822 -249.154458) (xy 127.53557 -249.116364) (xy 127.574992 -249.084177) (xy 127.619066 -249.058731)
			(xy 127.666652 -249.040684) (xy 127.716516 -249.030504) (xy 127.767368 -249.028455) (xy 127.817889 -249.034589)
			(xy 127.866773 -249.048749) (xy 127.912752 -249.070566) (xy 127.954636 -249.099476) (xy 127.99134 -249.134731)
			(xy 128.021913 -249.175417) (xy 128.045564 -249.22048) (xy 128.06168 -249.268754) (xy 128.069844 -249.318988)
			(xy 128.070356 -249.344434) (xy 128.388884 -249.344434) (xy 128.392844 -249.29538) (xy 128.404621 -249.247596)
			(xy 128.423912 -249.20232) (xy 128.450215 -249.160724) (xy 128.48285 -249.123887) (xy 128.520971 -249.092762)
			(xy 128.563592 -249.068155) (xy 128.609608 -249.050703) (xy 128.657827 -249.040859) (xy 128.707002 -249.038878)
			(xy 128.755857 -249.04481) (xy 128.803128 -249.058502) (xy 128.84759 -249.0796) (xy 128.888093 -249.107556)
			(xy 128.923586 -249.141648) (xy 128.953151 -249.180992) (xy 128.976022 -249.224569) (xy 128.991606 -249.27125)
			(xy 128.999501 -249.319827) (xy 128.999996 -249.344434) (xy 129.328938 -249.344434) (xy 129.332898 -249.29538)
			(xy 129.344675 -249.247596) (xy 129.363966 -249.20232) (xy 129.390269 -249.160724) (xy 129.422904 -249.123887)
			(xy 129.461025 -249.092762) (xy 129.503646 -249.068155) (xy 129.549662 -249.050703) (xy 129.597881 -249.040859)
			(xy 129.647056 -249.038878) (xy 129.695911 -249.04481) (xy 129.743182 -249.058502) (xy 129.787644 -249.0796)
			(xy 129.828147 -249.107556) (xy 129.86364 -249.141648) (xy 129.893205 -249.180992) (xy 129.916076 -249.224569)
			(xy 129.93166 -249.27125) (xy 129.939555 -249.319827) (xy 129.94005 -249.344434) (xy 129.939555 -249.369041)
			(xy 129.93166 -249.417618) (xy 129.916076 -249.464299) (xy 129.893205 -249.507876) (xy 129.86364 -249.54722)
			(xy 129.828147 -249.581312) (xy 129.787644 -249.609268) (xy 129.743182 -249.630366) (xy 129.695911 -249.644058)
			(xy 129.647056 -249.64999) (xy 129.597881 -249.648009) (xy 129.549662 -249.638165) (xy 129.503646 -249.620713)
			(xy 129.461025 -249.596106) (xy 129.422904 -249.564981) (xy 129.390269 -249.528144) (xy 129.363966 -249.486548)
			(xy 129.344675 -249.441272) (xy 129.332898 -249.393488) (xy 129.328938 -249.344434) (xy 128.999996 -249.344434)
			(xy 128.999501 -249.369041) (xy 128.991606 -249.417618) (xy 128.976022 -249.464299) (xy 128.953151 -249.507876)
			(xy 128.923586 -249.54722) (xy 128.888093 -249.581312) (xy 128.84759 -249.609268) (xy 128.803128 -249.630366)
			(xy 128.755857 -249.644058) (xy 128.707002 -249.64999) (xy 128.657827 -249.648009) (xy 128.609608 -249.638165)
			(xy 128.563592 -249.620713) (xy 128.520971 -249.596106) (xy 128.48285 -249.564981) (xy 128.450215 -249.528144)
			(xy 128.423912 -249.486548) (xy 128.404621 -249.441272) (xy 128.392844 -249.393488) (xy 128.388884 -249.344434)
			(xy 128.070356 -249.344434) (xy 128.069844 -249.36988) (xy 128.06168 -249.420114) (xy 128.045564 -249.468388)
			(xy 128.021913 -249.513451) (xy 127.99134 -249.554137) (xy 127.954636 -249.589392) (xy 127.912752 -249.618302)
			(xy 127.866773 -249.640119) (xy 127.817889 -249.654279) (xy 127.767368 -249.660413) (xy 127.716516 -249.658364)
			(xy 127.666652 -249.648184) (xy 127.619066 -249.630137) (xy 127.574992 -249.604691) (xy 127.53557 -249.572504)
			(xy 127.501822 -249.53441) (xy 127.474621 -249.491396) (xy 127.454673 -249.444576) (xy 127.442494 -249.395162)
			(xy 127.438399 -249.344434) (xy 127.120142 -249.344434) (xy 127.119647 -249.369041) (xy 127.111752 -249.417618)
			(xy 127.096168 -249.464299) (xy 127.073297 -249.507876) (xy 127.043732 -249.54722) (xy 127.008239 -249.581312)
			(xy 126.967736 -249.609268) (xy 126.923274 -249.630366) (xy 126.876003 -249.644058) (xy 126.827148 -249.64999)
			(xy 126.777973 -249.648009) (xy 126.729754 -249.638165) (xy 126.683738 -249.620713) (xy 126.641117 -249.596106)
			(xy 126.602996 -249.564981) (xy 126.570361 -249.528144) (xy 126.544058 -249.486548) (xy 126.524767 -249.441272)
			(xy 126.51299 -249.393488) (xy 126.50903 -249.344434) (xy 125.240034 -249.344434) (xy 125.239539 -249.369041)
			(xy 125.231644 -249.417618) (xy 125.21606 -249.464299) (xy 125.193189 -249.507876) (xy 125.163624 -249.54722)
			(xy 125.128131 -249.581312) (xy 125.087628 -249.609268) (xy 125.043166 -249.630366) (xy 124.995895 -249.644058)
			(xy 124.94704 -249.64999) (xy 124.897865 -249.648009) (xy 124.849646 -249.638165) (xy 124.80363 -249.620713)
			(xy 124.761009 -249.596106) (xy 124.722888 -249.564981) (xy 124.690253 -249.528144) (xy 124.66395 -249.486548)
			(xy 124.644659 -249.441272) (xy 124.632882 -249.393488) (xy 124.628922 -249.344434) (xy 123.359926 -249.344434)
			(xy 123.359431 -249.369041) (xy 123.351536 -249.417618) (xy 123.335952 -249.464299) (xy 123.313081 -249.507876)
			(xy 123.283516 -249.54722) (xy 123.248023 -249.581312) (xy 123.20752 -249.609268) (xy 123.163058 -249.630366)
			(xy 123.115787 -249.644058) (xy 123.066932 -249.64999) (xy 123.017757 -249.648009) (xy 122.969538 -249.638165)
			(xy 122.923522 -249.620713) (xy 122.880901 -249.596106) (xy 122.84278 -249.564981) (xy 122.810145 -249.528144)
			(xy 122.783842 -249.486548) (xy 122.764551 -249.441272) (xy 122.752774 -249.393488) (xy 122.748814 -249.344434)
			(xy 121.480072 -249.344434) (xy 121.479577 -249.369041) (xy 121.471682 -249.417618) (xy 121.456098 -249.464299)
			(xy 121.433227 -249.507876) (xy 121.403662 -249.54722) (xy 121.368169 -249.581312) (xy 121.327666 -249.609268)
			(xy 121.283204 -249.630366) (xy 121.235933 -249.644058) (xy 121.187078 -249.64999) (xy 121.137903 -249.648009)
			(xy 121.089684 -249.638165) (xy 121.043668 -249.620713) (xy 121.001047 -249.596106) (xy 120.962926 -249.564981)
			(xy 120.930291 -249.528144) (xy 120.903988 -249.486548) (xy 120.884697 -249.441272) (xy 120.87292 -249.393488)
			(xy 120.86896 -249.344434) (xy 119.599964 -249.344434) (xy 119.599469 -249.369041) (xy 119.591574 -249.417618)
			(xy 119.57599 -249.464299) (xy 119.553119 -249.507876) (xy 119.523554 -249.54722) (xy 119.488061 -249.581312)
			(xy 119.447558 -249.609268) (xy 119.403096 -249.630366) (xy 119.355825 -249.644058) (xy 119.30697 -249.64999)
			(xy 119.257795 -249.648009) (xy 119.209576 -249.638165) (xy 119.16356 -249.620713) (xy 119.120939 -249.596106)
			(xy 119.082818 -249.564981) (xy 119.050183 -249.528144) (xy 119.02388 -249.486548) (xy 119.004589 -249.441272)
			(xy 118.992812 -249.393488) (xy 118.988852 -249.344434) (xy 117.72011 -249.344434) (xy 117.719615 -249.369041)
			(xy 117.71172 -249.417618) (xy 117.696136 -249.464299) (xy 117.673265 -249.507876) (xy 117.6437 -249.54722)
			(xy 117.608207 -249.581312) (xy 117.567704 -249.609268) (xy 117.523242 -249.630366) (xy 117.475971 -249.644058)
			(xy 117.427116 -249.64999) (xy 117.377941 -249.648009) (xy 117.329722 -249.638165) (xy 117.283706 -249.620713)
			(xy 117.241085 -249.596106) (xy 117.202964 -249.564981) (xy 117.170329 -249.528144) (xy 117.144026 -249.486548)
			(xy 117.124735 -249.441272) (xy 117.112958 -249.393488) (xy 117.108998 -249.344434) (xy 115.840002 -249.344434)
			(xy 115.839507 -249.369041) (xy 115.831612 -249.417618) (xy 115.816028 -249.464299) (xy 115.793157 -249.507876)
			(xy 115.763592 -249.54722) (xy 115.728099 -249.581312) (xy 115.687596 -249.609268) (xy 115.643134 -249.630366)
			(xy 115.595863 -249.644058) (xy 115.547008 -249.64999) (xy 115.497833 -249.648009) (xy 115.449614 -249.638165)
			(xy 115.403598 -249.620713) (xy 115.360977 -249.596106) (xy 115.322856 -249.564981) (xy 115.290221 -249.528144)
			(xy 115.263918 -249.486548) (xy 115.244627 -249.441272) (xy 115.23285 -249.393488) (xy 115.22889 -249.344434)
			(xy 113.960148 -249.344434) (xy 113.959653 -249.369041) (xy 113.951758 -249.417618) (xy 113.936174 -249.464299)
			(xy 113.913303 -249.507876) (xy 113.883738 -249.54722) (xy 113.848245 -249.581312) (xy 113.807742 -249.609268)
			(xy 113.76328 -249.630366) (xy 113.716009 -249.644058) (xy 113.667154 -249.64999) (xy 113.617979 -249.648009)
			(xy 113.56976 -249.638165) (xy 113.523744 -249.620713) (xy 113.481123 -249.596106) (xy 113.443002 -249.564981)
			(xy 113.410367 -249.528144) (xy 113.384064 -249.486548) (xy 113.364773 -249.441272) (xy 113.352996 -249.393488)
			(xy 113.349036 -249.344434) (xy 112.143454 -249.344434) (xy 112.143794 -249.362214) (xy 112.14329 -249.38854)
			(xy 112.135253 -249.440576) (xy 112.119367 -249.490775) (xy 112.096004 -249.53796) (xy 112.065712 -249.581026)
			(xy 112.0292 -249.618964) (xy 111.987326 -249.650883) (xy 111.94107 -249.676036) (xy 111.891517 -249.693834)
			(xy 111.839827 -249.703858) (xy 111.787213 -249.705875) (xy 111.734908 -249.699837) (xy 111.684137 -249.685885)
			(xy 111.636092 -249.664346) (xy 111.591897 -249.635726) (xy 111.552589 -249.600695) (xy 111.519089 -249.560074)
			(xy 111.492183 -249.514815) (xy 111.4725 -249.46598) (xy 111.460503 -249.414712) (xy 111.456473 -249.362214)
			(xy 109.266124 -249.362214) (xy 109.265987 -249.369041) (xy 109.258092 -249.417618) (xy 109.242508 -249.464299)
			(xy 109.219637 -249.507876) (xy 109.190072 -249.54722) (xy 109.154579 -249.581312) (xy 109.114076 -249.609268)
			(xy 109.069614 -249.630366) (xy 109.022343 -249.644058) (xy 108.973488 -249.64999) (xy 108.924313 -249.648009)
			(xy 108.876094 -249.638165) (xy 108.830078 -249.620713) (xy 108.787457 -249.596106) (xy 108.749336 -249.564981)
			(xy 108.716701 -249.528144) (xy 108.690398 -249.486548) (xy 108.671107 -249.441272) (xy 108.65933 -249.393488)
			(xy 108.65537 -249.344434) (xy 107.386374 -249.344434) (xy 107.385879 -249.369041) (xy 107.377984 -249.417618)
			(xy 107.3624 -249.464299) (xy 107.339529 -249.507876) (xy 107.309964 -249.54722) (xy 107.274471 -249.581312)
			(xy 107.233968 -249.609268) (xy 107.189506 -249.630366) (xy 107.142235 -249.644058) (xy 107.09338 -249.64999)
			(xy 107.044205 -249.648009) (xy 106.995986 -249.638165) (xy 106.94997 -249.620713) (xy 106.907349 -249.596106)
			(xy 106.869228 -249.564981) (xy 106.836593 -249.528144) (xy 106.81029 -249.486548) (xy 106.790999 -249.441272)
			(xy 106.779222 -249.393488) (xy 106.775262 -249.344434) (xy 105.506266 -249.344434) (xy 105.505771 -249.369041)
			(xy 105.497876 -249.417618) (xy 105.482292 -249.464299) (xy 105.459421 -249.507876) (xy 105.429856 -249.54722)
			(xy 105.394363 -249.581312) (xy 105.35386 -249.609268) (xy 105.309398 -249.630366) (xy 105.262127 -249.644058)
			(xy 105.213272 -249.64999) (xy 105.164097 -249.648009) (xy 105.115878 -249.638165) (xy 105.069862 -249.620713)
			(xy 105.027241 -249.596106) (xy 104.98912 -249.564981) (xy 104.956485 -249.528144) (xy 104.930182 -249.486548)
			(xy 104.910891 -249.441272) (xy 104.899114 -249.393488) (xy 104.895154 -249.344434) (xy 103.626412 -249.344434)
			(xy 103.625917 -249.369041) (xy 103.618022 -249.417618) (xy 103.602438 -249.464299) (xy 103.579567 -249.507876)
			(xy 103.550002 -249.54722) (xy 103.514509 -249.581312) (xy 103.474006 -249.609268) (xy 103.429544 -249.630366)
			(xy 103.382273 -249.644058) (xy 103.333418 -249.64999) (xy 103.284243 -249.648009) (xy 103.236024 -249.638165)
			(xy 103.190008 -249.620713) (xy 103.147387 -249.596106) (xy 103.109266 -249.564981) (xy 103.076631 -249.528144)
			(xy 103.050328 -249.486548) (xy 103.031037 -249.441272) (xy 103.01926 -249.393488) (xy 103.0153 -249.344434)
			(xy 101.746304 -249.344434) (xy 101.745809 -249.369041) (xy 101.737914 -249.417618) (xy 101.72233 -249.464299)
			(xy 101.699459 -249.507876) (xy 101.669894 -249.54722) (xy 101.634401 -249.581312) (xy 101.593898 -249.609268)
			(xy 101.549436 -249.630366) (xy 101.502165 -249.644058) (xy 101.45331 -249.64999) (xy 101.404135 -249.648009)
			(xy 101.355916 -249.638165) (xy 101.3099 -249.620713) (xy 101.267279 -249.596106) (xy 101.229158 -249.564981)
			(xy 101.196523 -249.528144) (xy 101.17022 -249.486548) (xy 101.150929 -249.441272) (xy 101.139152 -249.393488)
			(xy 101.135192 -249.344434) (xy 99.86645 -249.344434) (xy 99.86645 -249.344942) (xy 99.866001 -249.367609)
			(xy 99.859217 -249.412435) (xy 99.845866 -249.45576) (xy 99.826241 -249.496629) (xy 99.813872 -249.51563)
			(xy 99.809808 -249.521726) (xy 99.804982 -249.53722) (xy 99.802533 -249.546186) (xy 99.803554 -249.564728)
			(xy 99.811149 -249.581675) (xy 99.817428 -249.588528) (xy 100.076762 -249.847862) (xy 100.089208 -249.85472)
			(xy 100.096574 -249.856244) (xy 100.120723 -249.862054) (xy 100.166864 -249.880434) (xy 100.209421 -249.90604)
			(xy 100.247271 -249.938198) (xy 100.279417 -249.976059) (xy 100.30501 -250.018624) (xy 100.323375 -250.06477)
			(xy 100.329238 -250.088908) (xy 100.330762 -250.096274) (xy 100.33762 -250.10872) (xy 100.38334 -250.15444)
			(xy 101.605346 -250.15444) (xy 101.609306 -250.105386) (xy 101.621083 -250.057602) (xy 101.640374 -250.012326)
			(xy 101.666677 -249.97073) (xy 101.699312 -249.933893) (xy 101.737433 -249.902768) (xy 101.780054 -249.878161)
			(xy 101.82607 -249.860709) (xy 101.874289 -249.850865) (xy 101.923464 -249.848884) (xy 101.972319 -249.854816)
			(xy 102.01959 -249.868508) (xy 102.064052 -249.889606) (xy 102.104555 -249.917562) (xy 102.140048 -249.951654)
			(xy 102.169613 -249.990998) (xy 102.192484 -250.034575) (xy 102.208068 -250.081256) (xy 102.215963 -250.129833)
			(xy 102.216458 -250.15444) (xy 103.4852 -250.15444) (xy 103.48916 -250.105386) (xy 103.500937 -250.057602)
			(xy 103.520228 -250.012326) (xy 103.546531 -249.97073) (xy 103.579166 -249.933893) (xy 103.617287 -249.902768)
			(xy 103.659908 -249.878161) (xy 103.705924 -249.860709) (xy 103.754143 -249.850865) (xy 103.803318 -249.848884)
			(xy 103.852173 -249.854816) (xy 103.899444 -249.868508) (xy 103.943906 -249.889606) (xy 103.984409 -249.917562)
			(xy 104.019902 -249.951654) (xy 104.049467 -249.990998) (xy 104.072338 -250.034575) (xy 104.087922 -250.081256)
			(xy 104.095817 -250.129833) (xy 104.096312 -250.15444) (xy 105.365308 -250.15444) (xy 105.369268 -250.105386)
			(xy 105.381045 -250.057602) (xy 105.400336 -250.012326) (xy 105.426639 -249.97073) (xy 105.459274 -249.933893)
			(xy 105.497395 -249.902768) (xy 105.540016 -249.878161) (xy 105.586032 -249.860709) (xy 105.634251 -249.850865)
			(xy 105.683426 -249.848884) (xy 105.732281 -249.854816) (xy 105.779552 -249.868508) (xy 105.824014 -249.889606)
			(xy 105.864517 -249.917562) (xy 105.90001 -249.951654) (xy 105.929575 -249.990998) (xy 105.952446 -250.034575)
			(xy 105.96803 -250.081256) (xy 105.975925 -250.129833) (xy 105.97642 -250.15444) (xy 107.245162 -250.15444)
			(xy 107.249122 -250.105386) (xy 107.260899 -250.057602) (xy 107.28019 -250.012326) (xy 107.306493 -249.97073)
			(xy 107.339128 -249.933893) (xy 107.377249 -249.902768) (xy 107.41987 -249.878161) (xy 107.465886 -249.860709)
			(xy 107.514105 -249.850865) (xy 107.56328 -249.848884) (xy 107.612135 -249.854816) (xy 107.659406 -249.868508)
			(xy 107.703868 -249.889606) (xy 107.744371 -249.917562) (xy 107.779864 -249.951654) (xy 107.809429 -249.990998)
			(xy 107.8323 -250.034575) (xy 107.847884 -250.081256) (xy 107.855779 -250.129833) (xy 107.856274 -250.15444)
			(xy 107.855779 -250.179047) (xy 107.847884 -250.227624) (xy 107.8323 -250.274305) (xy 107.809429 -250.317882)
			(xy 107.779864 -250.357226) (xy 107.744371 -250.391318) (xy 107.703868 -250.419274) (xy 107.659406 -250.440372)
			(xy 107.612135 -250.454064) (xy 107.56328 -250.459996) (xy 107.514105 -250.458015) (xy 107.465886 -250.448171)
			(xy 107.41987 -250.430719) (xy 107.377249 -250.406112) (xy 107.339128 -250.374987) (xy 107.306493 -250.33815)
			(xy 107.28019 -250.296554) (xy 107.260899 -250.251278) (xy 107.249122 -250.203494) (xy 107.245162 -250.15444)
			(xy 105.97642 -250.15444) (xy 105.975925 -250.179047) (xy 105.96803 -250.227624) (xy 105.952446 -250.274305)
			(xy 105.929575 -250.317882) (xy 105.90001 -250.357226) (xy 105.864517 -250.391318) (xy 105.824014 -250.419274)
			(xy 105.779552 -250.440372) (xy 105.732281 -250.454064) (xy 105.683426 -250.459996) (xy 105.634251 -250.458015)
			(xy 105.586032 -250.448171) (xy 105.540016 -250.430719) (xy 105.497395 -250.406112) (xy 105.459274 -250.374987)
			(xy 105.426639 -250.33815) (xy 105.400336 -250.296554) (xy 105.381045 -250.251278) (xy 105.369268 -250.203494)
			(xy 105.365308 -250.15444) (xy 104.096312 -250.15444) (xy 104.095817 -250.179047) (xy 104.087922 -250.227624)
			(xy 104.072338 -250.274305) (xy 104.049467 -250.317882) (xy 104.019902 -250.357226) (xy 103.984409 -250.391318)
			(xy 103.943906 -250.419274) (xy 103.899444 -250.440372) (xy 103.852173 -250.454064) (xy 103.803318 -250.459996)
			(xy 103.754143 -250.458015) (xy 103.705924 -250.448171) (xy 103.659908 -250.430719) (xy 103.617287 -250.406112)
			(xy 103.579166 -250.374987) (xy 103.546531 -250.33815) (xy 103.520228 -250.296554) (xy 103.500937 -250.251278)
			(xy 103.48916 -250.203494) (xy 103.4852 -250.15444) (xy 102.216458 -250.15444) (xy 102.215963 -250.179047)
			(xy 102.208068 -250.227624) (xy 102.192484 -250.274305) (xy 102.169613 -250.317882) (xy 102.140048 -250.357226)
			(xy 102.104555 -250.391318) (xy 102.064052 -250.419274) (xy 102.01959 -250.440372) (xy 101.972319 -250.454064)
			(xy 101.923464 -250.459996) (xy 101.874289 -250.458015) (xy 101.82607 -250.448171) (xy 101.780054 -250.430719)
			(xy 101.737433 -250.406112) (xy 101.699312 -250.374987) (xy 101.666677 -250.33815) (xy 101.640374 -250.296554)
			(xy 101.621083 -250.251278) (xy 101.609306 -250.203494) (xy 101.605346 -250.15444) (xy 100.38334 -250.15444)
			(xy 100.702618 -250.473718) (xy 100.703126 -250.474226) (xy 100.710505 -250.480815) (xy 100.728804 -250.48828)
			(xy 100.738686 -250.488704) (xy 101.23805 -250.488704) (xy 101.247889 -250.489237) (xy 101.266055 -250.496819)
			(xy 101.273356 -250.503436) (xy 101.407214 -250.637294) (xy 101.410745 -250.640607) (xy 101.418802 -250.645972)
			(xy 101.423216 -250.647962) (xy 101.448362 -250.658884) (xy 101.457506 -250.659392) (xy 101.482282 -250.66122)
			(xy 101.530799 -250.671896) (xy 101.576948 -250.690282) (xy 101.619514 -250.715894) (xy 101.657375 -250.748057)
			(xy 101.689532 -250.785922) (xy 101.715137 -250.828492) (xy 101.733517 -250.874644) (xy 101.744186 -250.923162)
			(xy 101.74605 -250.947936) (xy 101.746558 -250.95708) (xy 101.75748 -250.982226) (xy 101.759452 -250.986649)
			(xy 101.764828 -250.994703) (xy 101.768148 -250.998228) (xy 101.970078 -251.200158) (xy 101.970586 -251.200666)
			(xy 101.977969 -251.207242) (xy 101.996268 -251.214679) (xy 102.006146 -251.215144) (xy 102.944168 -251.215144)
			(xy 102.947216 -251.215144) (xy 102.958028 -251.213991) (xy 102.97724 -251.203856) (xy 102.9843 -251.195586)
			(xy 102.986332 -251.192792) (xy 103.039418 -251.114052) (xy 103.041958 -251.08916) (xy 103.037386 -251.077476)
			(xy 103.02739 -251.050554) (xy 103.016521 -250.994171) (xy 103.015796 -250.965462) (xy 103.015796 -250.960128)
			(xy 103.016653 -250.935107) (xy 103.025517 -250.885836) (xy 103.0423 -250.838671) (xy 103.066551 -250.794875)
			(xy 103.097622 -250.755622) (xy 103.134681 -250.721964) (xy 103.176733 -250.694801) (xy 103.222653 -250.674862)
			(xy 103.27121 -250.662681) (xy 103.321104 -250.658584) (xy 103.370998 -250.662681) (xy 103.419555 -250.674862)
			(xy 103.465475 -250.694801) (xy 103.507527 -250.721964) (xy 103.544586 -250.755622) (xy 103.575657 -250.794875)
			(xy 103.599908 -250.838671) (xy 103.616691 -250.885836) (xy 103.625555 -250.935107) (xy 103.626412 -250.960128)
			(xy 103.626412 -250.9647) (xy 103.625739 -250.993601) (xy 103.614873 -251.050371) (xy 103.604822 -251.077476)
			(xy 103.60025 -251.08916) (xy 103.60279 -251.114052) (xy 103.655876 -251.192792) (xy 103.657908 -251.195586)
			(xy 103.664974 -251.203849) (xy 103.684182 -251.213995) (xy 103.694992 -251.215144) (xy 104.824022 -251.215144)
			(xy 104.82707 -251.215144) (xy 104.837886 -251.213999) (xy 104.857113 -251.203875) (xy 104.864154 -251.195586)
			(xy 104.866186 -251.192792) (xy 104.919272 -251.114052) (xy 104.921812 -251.08916) (xy 104.91724 -251.077476)
			(xy 104.907242 -251.050554) (xy 104.896372 -250.994171) (xy 104.89565 -250.965462) (xy 104.89565 -250.960128)
			(xy 104.896507 -250.935107) (xy 104.905371 -250.885836) (xy 104.922154 -250.838671) (xy 104.946405 -250.794875)
			(xy 104.977476 -250.755622) (xy 105.014535 -250.721964) (xy 105.056587 -250.694801) (xy 105.102507 -250.674862)
			(xy 105.151064 -250.662681) (xy 105.200958 -250.658584) (xy 105.250852 -250.662681) (xy 105.299409 -250.674862)
			(xy 105.345329 -250.694801) (xy 105.387381 -250.721964) (xy 105.42444 -250.755622) (xy 105.455511 -250.794875)
			(xy 105.479762 -250.838671) (xy 105.496545 -250.885836) (xy 105.505409 -250.935107) (xy 105.506266 -250.960128)
			(xy 105.506266 -250.9647) (xy 105.505593 -250.993601) (xy 105.494726 -251.050371) (xy 105.484676 -251.077476)
			(xy 105.480104 -251.08916) (xy 105.482644 -251.114052) (xy 105.53573 -251.192792) (xy 105.537762 -251.195586)
			(xy 105.544832 -251.203841) (xy 105.564041 -251.213966) (xy 105.574846 -251.215144) (xy 106.70413 -251.215144)
			(xy 106.707178 -251.215144) (xy 106.717994 -251.213998) (xy 106.737218 -251.203872) (xy 106.744262 -251.195586)
			(xy 106.746294 -251.192792) (xy 106.79938 -251.114052) (xy 106.80192 -251.08916) (xy 106.797348 -251.077476)
			(xy 106.78735 -251.050554) (xy 106.77648 -250.994171) (xy 106.775758 -250.965462) (xy 106.775758 -250.960128)
			(xy 106.776615 -250.935107) (xy 106.785479 -250.885836) (xy 106.802262 -250.838671) (xy 106.826513 -250.794875)
			(xy 106.857584 -250.755622) (xy 106.894643 -250.721964) (xy 106.936695 -250.694801) (xy 106.982615 -250.674862)
			(xy 107.031172 -250.662681) (xy 107.081066 -250.658584) (xy 107.13096 -250.662681) (xy 107.179517 -250.674862)
			(xy 107.225437 -250.694801) (xy 107.267489 -250.721964) (xy 107.304548 -250.755622) (xy 107.335619 -250.794875)
			(xy 107.35987 -250.838671) (xy 107.376653 -250.885836) (xy 107.385517 -250.935107) (xy 107.386374 -250.960128)
			(xy 107.386374 -250.9647) (xy 107.385701 -250.993601) (xy 107.374834 -251.050371) (xy 107.364784 -251.077476)
			(xy 107.360212 -251.08916) (xy 107.362752 -251.114052) (xy 107.415838 -251.192792) (xy 107.41787 -251.195586)
			(xy 107.42494 -251.20384) (xy 107.44415 -251.213962) (xy 107.454954 -251.215144) (xy 108.108242 -251.215144)
			(xy 108.118118 -251.214681) (xy 108.136414 -251.207236) (xy 108.143802 -251.200666) (xy 108.144056 -251.200412)
			(xy 108.957872 -250.386596) (xy 108.965108 -250.379876) (xy 108.983312 -250.372266) (xy 108.993178 -250.371864)
			(xy 109.0422 -250.371864) (xy 109.054132 -250.371212) (xy 109.075447 -250.360475) (xy 109.083094 -250.35129)
			(xy 109.137958 -250.27763) (xy 109.142276 -250.254008) (xy 109.13872 -250.242324) (xy 109.13269 -250.220854)
			(xy 109.126184 -250.176737) (xy 109.125766 -250.15444) (xy 109.125766 -250.150122) (xy 109.126623 -250.125101)
			(xy 109.135487 -250.07583) (xy 109.15227 -250.028665) (xy 109.176521 -249.984869) (xy 109.207592 -249.945616)
			(xy 109.244651 -249.911958) (xy 109.286703 -249.884795) (xy 109.332623 -249.864856) (xy 109.38118 -249.852675)
			(xy 109.431074 -249.848578) (xy 109.480968 -249.852675) (xy 109.529525 -249.864856) (xy 109.575445 -249.884795)
			(xy 109.617497 -249.911958) (xy 109.654556 -249.945616) (xy 109.685627 -249.984869) (xy 109.709878 -250.028665)
			(xy 109.726661 -250.07583) (xy 109.735525 -250.125101) (xy 109.736382 -250.150122) (xy 109.736382 -250.152408)
			(xy 109.736382 -250.15444) (xy 109.735995 -250.176739) (xy 109.729487 -250.22086) (xy 109.723428 -250.242324)
			(xy 109.719872 -250.254008) (xy 109.72419 -250.27763) (xy 109.779054 -250.35129) (xy 109.786661 -250.360525)
			(xy 109.807999 -250.371276) (xy 109.819948 -250.371864) (xy 111.28375 -250.371864) (xy 111.29359 -250.372395)
			(xy 111.31176 -250.379973) (xy 111.319056 -250.386596) (xy 111.403638 -250.471178) (xy 111.404146 -250.471686)
			(xy 111.411529 -250.478266) (xy 111.429827 -250.485714) (xy 111.439706 -250.486164) (xy 112.851184 -250.486164)
			(xy 112.860417 -250.485767) (xy 112.877683 -250.479223) (xy 112.891506 -250.466979) (xy 112.896142 -250.458986)
			(xy 112.935512 -250.384056) (xy 112.93602 -250.38304) (xy 112.939963 -250.374103) (xy 112.941526 -250.354648)
			(xy 112.939068 -250.345194) (xy 112.933988 -250.328684) (xy 112.92967 -250.322334) (xy 112.917778 -250.303547)
			(xy 112.89897 -250.263257) (xy 112.886208 -250.220665) (xy 112.879764 -250.176672) (xy 112.879378 -250.15444)
			(xy 112.879378 -250.146058) (xy 112.879886 -250.138438) (xy 112.881775 -250.112739) (xy 112.893084 -250.06247)
			(xy 112.912669 -250.014813) (xy 112.939975 -249.971118) (xy 112.974228 -249.932627) (xy 113.014456 -249.900431)
			(xy 113.059517 -249.875444) (xy 113.108133 -249.858375) (xy 113.158924 -249.849708) (xy 113.184686 -249.849132)
			(xy 113.208679 -249.849577) (xy 113.256074 -249.857082) (xy 113.301711 -249.87191) (xy 113.344466 -249.893695)
			(xy 113.383286 -249.921902) (xy 113.417215 -249.955834) (xy 113.445418 -249.994657) (xy 113.4672 -250.037414)
			(xy 113.482024 -250.083052) (xy 113.489525 -250.130447) (xy 113.489994 -250.15444) (xy 113.489565 -250.177589)
			(xy 113.482577 -250.223355) (xy 113.468768 -250.267545) (xy 113.448454 -250.309148) (xy 113.435638 -250.32843)
			(xy 113.430684 -250.336265) (xy 113.426197 -250.354236) (xy 113.42837 -250.372631) (xy 113.432336 -250.381008)
			(xy 113.47323 -250.458986) (xy 113.476834 -250.465343) (xy 113.48703 -250.475801) (xy 113.493296 -250.47956)
			(xy 113.50498 -250.486164) (xy 114.731292 -250.486164) (xy 114.740524 -250.485766) (xy 114.757788 -250.47922)
			(xy 114.771608 -250.466976) (xy 114.77625 -250.458986) (xy 114.81562 -250.384056) (xy 114.816128 -250.38304)
			(xy 114.820071 -250.374103) (xy 114.821633 -250.354648) (xy 114.819176 -250.345194) (xy 114.814096 -250.328684)
			(xy 114.809778 -250.322334) (xy 114.797885 -250.303547) (xy 114.779077 -250.263258) (xy 114.766315 -250.220665)
			(xy 114.75987 -250.176672) (xy 114.759486 -250.15444) (xy 114.759486 -250.146058) (xy 114.759994 -250.138438)
			(xy 114.761883 -250.112736) (xy 114.77319 -250.062461) (xy 114.792774 -250.014797) (xy 114.820079 -249.971094)
			(xy 114.85433 -249.932594) (xy 114.894557 -249.900387) (xy 114.939617 -249.875388) (xy 114.988235 -249.858305)
			(xy 115.039029 -249.849624) (xy 115.064794 -249.849132) (xy 115.088786 -249.849578) (xy 115.13618 -249.857084)
			(xy 115.181816 -249.871913) (xy 115.22457 -249.893698) (xy 115.263389 -249.921904) (xy 115.297318 -249.955837)
			(xy 115.32552 -249.994659) (xy 115.3473 -250.037415) (xy 115.362124 -250.083053) (xy 115.369625 -250.130448)
			(xy 115.370102 -250.15444) (xy 116.638844 -250.15444) (xy 116.642804 -250.105386) (xy 116.654581 -250.057602)
			(xy 116.673872 -250.012326) (xy 116.700175 -249.97073) (xy 116.73281 -249.933893) (xy 116.770931 -249.902768)
			(xy 116.813552 -249.878161) (xy 116.859568 -249.860709) (xy 116.907787 -249.850865) (xy 116.956962 -249.848884)
			(xy 117.005817 -249.854816) (xy 117.053088 -249.868508) (xy 117.09755 -249.889606) (xy 117.138053 -249.917562)
			(xy 117.173546 -249.951654) (xy 117.203111 -249.990998) (xy 117.225982 -250.034575) (xy 117.241566 -250.081256)
			(xy 117.249461 -250.129833) (xy 117.249956 -250.15444) (xy 117.249461 -250.179047) (xy 117.241566 -250.227624)
			(xy 117.225982 -250.274305) (xy 117.203111 -250.317882) (xy 117.173546 -250.357226) (xy 117.138053 -250.391318)
			(xy 117.09755 -250.419274) (xy 117.053088 -250.440372) (xy 117.005817 -250.454064) (xy 116.956962 -250.459996)
			(xy 116.907787 -250.458015) (xy 116.859568 -250.448171) (xy 116.813552 -250.430719) (xy 116.770931 -250.406112)
			(xy 116.73281 -250.374987) (xy 116.700175 -250.33815) (xy 116.673872 -250.296554) (xy 116.654581 -250.251278)
			(xy 116.642804 -250.203494) (xy 116.638844 -250.15444) (xy 115.370102 -250.15444) (xy 115.369673 -250.177589)
			(xy 115.362685 -250.223356) (xy 115.348877 -250.267546) (xy 115.328563 -250.309148) (xy 115.315746 -250.32843)
			(xy 115.310791 -250.336265) (xy 115.306303 -250.354236) (xy 115.308477 -250.372632) (xy 115.312444 -250.381008)
			(xy 115.353338 -250.458986) (xy 115.356942 -250.465342) (xy 115.367139 -250.4758) (xy 115.373404 -250.47956)
			(xy 115.385088 -250.486164) (xy 115.50269 -250.486164) (xy 115.512527 -250.486703) (xy 115.530686 -250.494291)
			(xy 115.537996 -250.500896) (xy 116.244878 -251.207778) (xy 116.245386 -251.208286) (xy 116.25277 -251.21486)
			(xy 116.271069 -251.222293) (xy 116.280946 -251.222764) (xy 116.645182 -251.222764) (xy 116.655055 -251.222294)
			(xy 116.673343 -251.214841) (xy 116.680742 -251.208286) (xy 116.680996 -251.208032) (xy 117.489732 -250.399296)
			(xy 117.496971 -250.392585) (xy 117.515176 -250.384997) (xy 117.525038 -250.384564) (xy 118.4402 -250.384564)
			(xy 118.452263 -250.383883) (xy 118.473723 -250.372859) (xy 118.481348 -250.363482) (xy 118.528592 -250.297696)
			(xy 118.531945 -250.292695) (xy 118.536444 -250.281529) (xy 118.537482 -250.275598) (xy 118.53926 -250.26366)
			(xy 118.53545 -250.251976) (xy 118.53545 -250.251722) (xy 118.528094 -250.228398) (xy 118.520051 -250.180159)
			(xy 118.519448 -250.15571) (xy 118.519448 -250.150884) (xy 118.520179 -250.127075) (xy 118.528119 -250.08011)
			(xy 118.543256 -250.034948) (xy 118.565224 -249.992685) (xy 118.593489 -249.954347) (xy 118.627366 -249.920864)
			(xy 118.666032 -249.893049) (xy 118.708549 -249.871577) (xy 118.753886 -249.85697) (xy 118.80094 -249.84958)
			(xy 118.824756 -249.849132) (xy 118.848594 -249.849595) (xy 118.895689 -249.857013) (xy 118.941059 -249.87166)
			(xy 118.983602 -249.89318) (xy 119.022284 -249.92105) (xy 119.056164 -249.954593) (xy 119.084419 -249.992994)
			(xy 119.106363 -250.03532) (xy 119.121463 -250.080541) (xy 119.129351 -250.12756) (xy 119.130064 -250.151392)
			(xy 119.130064 -250.15444) (xy 120.398806 -250.15444) (xy 120.402766 -250.105386) (xy 120.414543 -250.057602)
			(xy 120.433834 -250.012326) (xy 120.460137 -249.97073) (xy 120.492772 -249.933893) (xy 120.530893 -249.902768)
			(xy 120.573514 -249.878161) (xy 120.61953 -249.860709) (xy 120.667749 -249.850865) (xy 120.716924 -249.848884)
			(xy 120.765779 -249.854816) (xy 120.81305 -249.868508) (xy 120.857512 -249.889606) (xy 120.898015 -249.917562)
			(xy 120.933508 -249.951654) (xy 120.963073 -249.990998) (xy 120.985944 -250.034575) (xy 121.001528 -250.081256)
			(xy 121.009423 -250.129833) (xy 121.009918 -250.15444) (xy 121.009423 -250.179047) (xy 121.001528 -250.227624)
			(xy 120.985944 -250.274305) (xy 120.963073 -250.317882) (xy 120.933508 -250.357226) (xy 120.898015 -250.391318)
			(xy 120.857512 -250.419274) (xy 120.81305 -250.440372) (xy 120.765779 -250.454064) (xy 120.716924 -250.459996)
			(xy 120.667749 -250.458015) (xy 120.61953 -250.448171) (xy 120.573514 -250.430719) (xy 120.530893 -250.406112)
			(xy 120.492772 -250.374987) (xy 120.460137 -250.33815) (xy 120.433834 -250.296554) (xy 120.414543 -250.251278)
			(xy 120.402766 -250.203494) (xy 120.398806 -250.15444) (xy 119.130064 -250.15444) (xy 119.130064 -250.154694)
			(xy 119.129599 -250.178888) (xy 119.121972 -250.226672) (xy 119.106925 -250.272662) (xy 119.096282 -250.294394)
			(xy 119.093488 -250.299728) (xy 119.090948 -250.310396) (xy 119.089162 -250.318958) (xy 119.090846 -250.336355)
			(xy 119.098284 -250.352171) (xy 119.104156 -250.358656) (xy 119.442992 -250.697492) (xy 119.44858 -250.700794)
			(xy 119.470908 -250.714451) (xy 119.510946 -250.748156) (xy 119.54465 -250.788195) (xy 119.558308 -250.810522)
			(xy 119.56161 -250.81611) (xy 119.953278 -251.207778) (xy 119.953786 -251.208286) (xy 119.96117 -251.21486)
			(xy 119.979469 -251.222293) (xy 119.989346 -251.222764) (xy 120.378982 -251.222764) (xy 120.388855 -251.222294)
			(xy 120.407143 -251.214841) (xy 120.414542 -251.208286) (xy 120.414796 -251.208032) (xy 121.248932 -250.373896)
			(xy 121.256171 -250.367185) (xy 121.274376 -250.359597) (xy 121.284238 -250.359164) (xy 122.192542 -250.359164)
			(xy 122.204203 -250.358583) (xy 122.225109 -250.348248) (xy 122.232674 -250.339352) (xy 122.279156 -250.2789)
			(xy 122.28394 -250.272061) (xy 122.28926 -250.256252) (xy 122.28957 -250.247912) (xy 122.28957 -250.233688)
			(xy 122.288046 -250.227592) (xy 122.283985 -250.209771) (xy 122.279649 -250.173478) (xy 122.27941 -250.155202)
			(xy 122.27941 -250.15444) (xy 122.279853 -250.130445) (xy 122.287355 -250.083046) (xy 122.30218 -250.037404)
			(xy 122.323964 -249.994644) (xy 122.352169 -249.955818) (xy 122.386101 -249.921883) (xy 122.424925 -249.893675)
			(xy 122.467684 -249.871889) (xy 122.513325 -249.85706) (xy 122.560723 -249.849555) (xy 122.584718 -249.849132)
			(xy 122.597481 -249.84927) (xy 122.622915 -249.85143) (xy 122.635518 -249.85345) (xy 122.658625 -249.857794)
			(xy 122.703236 -249.872639) (xy 122.745046 -249.894143) (xy 122.783069 -249.921798) (xy 122.816406 -249.954952)
			(xy 122.84427 -249.992821) (xy 122.866004 -250.034512) (xy 122.881094 -250.079041) (xy 122.889185 -250.125356)
			(xy 122.890026 -250.148852) (xy 122.890026 -250.150376) (xy 122.890026 -250.15444) (xy 124.159022 -250.15444)
			(xy 124.162982 -250.105386) (xy 124.174759 -250.057602) (xy 124.19405 -250.012326) (xy 124.220353 -249.97073)
			(xy 124.252988 -249.933893) (xy 124.291109 -249.902768) (xy 124.33373 -249.878161) (xy 124.379746 -249.860709)
			(xy 124.427965 -249.850865) (xy 124.47714 -249.848884) (xy 124.525995 -249.854816) (xy 124.573266 -249.868508)
			(xy 124.617728 -249.889606) (xy 124.658231 -249.917562) (xy 124.693724 -249.951654) (xy 124.723289 -249.990998)
			(xy 124.74616 -250.034575) (xy 124.761744 -250.081256) (xy 124.769639 -250.129833) (xy 124.770134 -250.15444)
			(xy 124.769639 -250.179047) (xy 124.761744 -250.227624) (xy 124.74616 -250.274305) (xy 124.723289 -250.317882)
			(xy 124.693724 -250.357226) (xy 124.658231 -250.391318) (xy 124.617728 -250.419274) (xy 124.573266 -250.440372)
			(xy 124.525995 -250.454064) (xy 124.47714 -250.459996) (xy 124.427965 -250.458015) (xy 124.379746 -250.448171)
			(xy 124.33373 -250.430719) (xy 124.291109 -250.406112) (xy 124.252988 -250.374987) (xy 124.220353 -250.33815)
			(xy 124.19405 -250.296554) (xy 124.174759 -250.251278) (xy 124.162982 -250.203494) (xy 124.159022 -250.15444)
			(xy 122.890026 -250.15444) (xy 122.88958 -250.177818) (xy 122.882459 -250.224029) (xy 122.868389 -250.268619)
			(xy 122.847698 -250.310548) (xy 122.834654 -250.329954) (xy 122.832622 -250.332748) (xy 122.827542 -250.342908)
			(xy 122.825002 -250.34875) (xy 122.823224 -250.353322) (xy 122.820455 -250.362098) (xy 122.820708 -250.380483)
			(xy 122.827469 -250.397582) (xy 122.833384 -250.40463) (xy 122.834146 -250.405646) (xy 123.077478 -250.648978)
			(xy 123.080406 -250.651866) (xy 123.087046 -250.656716) (xy 123.090686 -250.65863) (xy 123.097036 -250.661678)
			(xy 123.10491 -250.663202) (xy 123.105418 -250.663202) (xy 123.128669 -250.66757) (xy 123.173548 -250.682534)
			(xy 123.21558 -250.704242) (xy 123.25376 -250.732175) (xy 123.287174 -250.765664) (xy 123.315021 -250.803908)
			(xy 123.336634 -250.845989) (xy 123.351496 -250.890901) (xy 123.355862 -250.914154) (xy 123.357132 -250.922028)
			(xy 123.364244 -250.935744) (xy 123.687078 -251.258578) (xy 123.687586 -251.259086) (xy 123.69497 -251.26566)
			(xy 123.713269 -251.273093) (xy 123.723146 -251.273564)
		)
		(stroke
			(width 0)
			(type solid)
		)
		(fill yes)
		(layer "In4.Cu")
		(net "PVDDCR_CPU0_P1")
	)
	(gr_poly
		(pts
			(xy 365.040164 -251.253752) (xy 365.050003 -251.253218) (xy 365.068171 -251.245639) (xy 365.07547 -251.23902)
			(xy 365.101632 -251.212858) (xy 365.102902 -251.211588) (xy 365.108936 -251.204599) (xy 365.115987 -251.187552)
			(xy 365.116513 -251.169111) (xy 365.113824 -251.16028) (xy 365.111284 -251.15266) (xy 365.10468 -251.139706)
			(xy 365.102902 -251.137166) (xy 365.090335 -251.117998) (xy 365.070422 -251.076717) (xy 365.056879 -251.032931)
			(xy 365.050008 -250.987616) (xy 365.049562 -250.9647) (xy 365.049562 -250.964192) (xy 365.050033 -250.9402)
			(xy 365.05754 -250.892808) (xy 365.072368 -250.847173) (xy 365.094151 -250.804419) (xy 365.122354 -250.765599)
			(xy 365.156282 -250.731669) (xy 365.1951 -250.703463) (xy 365.237853 -250.681676) (xy 365.283486 -250.666845)
			(xy 365.330878 -250.659335) (xy 365.35487 -250.658884) (xy 365.355378 -250.658884) (xy 365.378299 -250.659286)
			(xy 365.423629 -250.666124) (xy 365.467427 -250.679665) (xy 365.508707 -250.699603) (xy 365.527844 -250.712224)
			(xy 365.530384 -250.714002) (xy 365.540036 -250.719082) (xy 365.54664 -250.721876) (xy 365.550958 -250.723146)
			(xy 365.5598 -250.725762) (xy 365.578217 -250.725214) (xy 365.595264 -250.718223) (xy 365.602266 -250.712224)
			(xy 365.602774 -250.711716) (xy 365.891826 -250.422664) (xy 365.899066 -250.415956) (xy 365.917271 -250.408371)
			(xy 365.927132 -250.407932) (xy 366.389412 -250.407932) (xy 366.401964 -250.407285) (xy 366.424084 -250.395419)
			(xy 366.431576 -250.385326) (xy 366.477296 -250.317254) (xy 366.483721 -250.306491) (xy 366.48627 -250.281583)
			(xy 366.482122 -250.269756) (xy 366.482122 -250.269502) (xy 366.47164 -250.242027) (xy 366.460247 -250.184345)
			(xy 366.459516 -250.154948) (xy 366.459516 -250.14936) (xy 366.460412 -250.124366) (xy 366.46934 -250.07516)
			(xy 366.486167 -250.028066) (xy 366.510443 -249.984344) (xy 366.54152 -249.945162) (xy 366.578566 -249.911567)
			(xy 366.620591 -249.884459) (xy 366.666472 -249.864561) (xy 366.714982 -249.852405) (xy 366.764824 -249.848317)
			(xy 366.814666 -249.852405) (xy 366.863176 -249.864561) (xy 366.909057 -249.884459) (xy 366.951082 -249.911567)
			(xy 366.988128 -249.945162) (xy 367.019205 -249.984344) (xy 367.043481 -250.028066) (xy 367.060308 -250.07516)
			(xy 367.069236 -250.124366) (xy 367.070132 -250.14936) (xy 367.070132 -250.154186) (xy 368.338874 -250.154186)
			(xy 368.342834 -250.105132) (xy 368.354611 -250.057348) (xy 368.373902 -250.012072) (xy 368.400205 -249.970476)
			(xy 368.43284 -249.933639) (xy 368.470961 -249.902514) (xy 368.513582 -249.877907) (xy 368.559598 -249.860455)
			(xy 368.607817 -249.850611) (xy 368.656992 -249.84863) (xy 368.705847 -249.854562) (xy 368.753118 -249.868254)
			(xy 368.79758 -249.889352) (xy 368.838083 -249.917308) (xy 368.873576 -249.9514) (xy 368.903141 -249.990744)
			(xy 368.926012 -250.034321) (xy 368.941596 -250.081002) (xy 368.949491 -250.129579) (xy 368.949986 -250.154186)
			(xy 368.949491 -250.178793) (xy 368.941596 -250.22737) (xy 368.926012 -250.274051) (xy 368.903141 -250.317628)
			(xy 368.873576 -250.356972) (xy 368.838083 -250.391064) (xy 368.79758 -250.41902) (xy 368.753118 -250.440118)
			(xy 368.705847 -250.45381) (xy 368.656992 -250.459742) (xy 368.607817 -250.457761) (xy 368.559598 -250.447917)
			(xy 368.513582 -250.430465) (xy 368.470961 -250.405858) (xy 368.43284 -250.374733) (xy 368.400205 -250.337896)
			(xy 368.373902 -250.2963) (xy 368.354611 -250.251024) (xy 368.342834 -250.20324) (xy 368.338874 -250.154186)
			(xy 367.070132 -250.154186) (xy 367.070132 -250.15444) (xy 367.069399 -250.183899) (xy 367.058014 -250.241709)
			(xy 367.047526 -250.269248) (xy 367.047526 -250.269502) (xy 367.047272 -250.27001) (xy 367.043254 -250.281812)
			(xy 367.045923 -250.306572) (xy 367.052352 -250.317254) (xy 367.098072 -250.385326) (xy 367.105584 -250.395396)
			(xy 367.127692 -250.407268) (xy 367.140236 -250.407932) (xy 367.146078 -250.407932) (xy 367.146078 -250.558554)
			(xy 367.146526 -250.56834) (xy 367.153845 -250.586492) (xy 367.160302 -250.59386) (xy 367.197132 -250.63196)
			(xy 367.208562 -250.643644) (xy 367.21571 -250.650321) (xy 367.233606 -250.658171) (xy 367.24336 -250.658884)
			(xy 367.26961 -250.660175) (xy 367.321112 -250.670627) (xy 367.370067 -250.689734) (xy 367.415034 -250.716933)
			(xy 367.454685 -250.751421) (xy 367.487854 -250.792183) (xy 367.513561 -250.838018) (xy 367.531051 -250.887574)
			(xy 367.535968 -250.913392) (xy 367.535968 -250.914408) (xy 367.536476 -250.918218) (xy 367.538127 -250.92964)
			(xy 367.539904 -250.952652) (xy 367.540032 -250.964192) (xy 367.53994 -250.97336) (xy 367.538797 -250.99166)
			(xy 367.537746 -251.000768) (xy 367.536476 -251.012452) (xy 367.544096 -251.03455) (xy 367.748312 -251.238766)
			(xy 367.74882 -251.239274) (xy 367.7562 -251.245859) (xy 367.774499 -251.253318) (xy 367.78438 -251.253752)
			(xy 368.375184 -251.253752) (xy 368.385021 -251.253215) (xy 368.403184 -251.24563) (xy 368.41049 -251.23902)
			(xy 368.87785 -250.77166) (xy 368.879374 -250.769628) (xy 368.888355 -250.759024) (xy 368.907947 -250.739312)
			(xy 368.91849 -250.730258) (xy 368.923824 -250.725686) (xy 369.262406 -250.387104) (xy 369.269643 -250.380388)
			(xy 369.287848 -250.372789) (xy 369.297712 -250.372372) (xy 370.136674 -250.372372) (xy 370.148609 -250.371726)
			(xy 370.169935 -250.360996) (xy 370.177568 -250.351798) (xy 370.232178 -250.277884) (xy 370.236242 -250.254516)
			(xy 370.232686 -250.242832) (xy 370.226514 -250.221192) (xy 370.219875 -250.176685) (xy 370.219478 -250.154186)
			(xy 370.219478 -250.150884) (xy 370.220194 -250.127063) (xy 370.228109 -250.08007) (xy 370.243228 -250.034877)
			(xy 370.265184 -249.992581) (xy 370.293445 -249.95421) (xy 370.327324 -249.920696) (xy 370.365998 -249.892852)
			(xy 370.408529 -249.871354) (xy 370.453883 -249.856724) (xy 370.500959 -249.849319) (xy 370.524786 -249.848878)
			(xy 370.548778 -249.849348) (xy 370.596173 -249.856852) (xy 370.641809 -249.871678) (xy 370.684565 -249.89346)
			(xy 370.723387 -249.921663) (xy 370.757318 -249.955592) (xy 370.785525 -249.994411) (xy 370.807311 -250.037165)
			(xy 370.822142 -250.0828) (xy 370.82965 -250.130194) (xy 370.830094 -250.154186) (xy 372.09909 -250.154186)
			(xy 372.10305 -250.105132) (xy 372.114827 -250.057348) (xy 372.134118 -250.012072) (xy 372.160421 -249.970476)
			(xy 372.193056 -249.933639) (xy 372.231177 -249.902514) (xy 372.273798 -249.877907) (xy 372.319814 -249.860455)
			(xy 372.368033 -249.850611) (xy 372.417208 -249.84863) (xy 372.466063 -249.854562) (xy 372.513334 -249.868254)
			(xy 372.557796 -249.889352) (xy 372.598299 -249.917308) (xy 372.633792 -249.9514) (xy 372.663357 -249.990744)
			(xy 372.686228 -250.034321) (xy 372.701812 -250.081002) (xy 372.709707 -250.129579) (xy 372.710202 -250.154186)
			(xy 372.709707 -250.178793) (xy 372.701812 -250.22737) (xy 372.686228 -250.274051) (xy 372.663357 -250.317628)
			(xy 372.633792 -250.356972) (xy 372.598299 -250.391064) (xy 372.557796 -250.41902) (xy 372.513334 -250.440118)
			(xy 372.466063 -250.45381) (xy 372.417208 -250.459742) (xy 372.368033 -250.457761) (xy 372.319814 -250.447917)
			(xy 372.273798 -250.430465) (xy 372.231177 -250.405858) (xy 372.193056 -250.374733) (xy 372.160421 -250.337896)
			(xy 372.134118 -250.2963) (xy 372.114827 -250.251024) (xy 372.10305 -250.20324) (xy 372.09909 -250.154186)
			(xy 370.830094 -250.154186) (xy 370.830094 -250.164346) (xy 370.828899 -250.187443) (xy 370.820406 -250.232906)
			(xy 370.805153 -250.276567) (xy 370.783489 -250.317428) (xy 370.755908 -250.354553) (xy 370.723043 -250.387092)
			(xy 370.704618 -250.401074) (xy 370.704364 -250.401328) (xy 370.6957 -250.408273) (xy 370.684904 -250.427646)
			(xy 370.683536 -250.438666) (xy 370.677694 -250.513342) (xy 370.67734 -250.52438) (xy 370.684968 -250.545077)
			(xy 370.692426 -250.55322) (xy 370.825268 -250.686062) (xy 370.856002 -250.69165) (xy 370.87048 -250.6853)
			(xy 370.890116 -250.676967) (xy 370.931119 -250.665213) (xy 370.973359 -250.659277) (xy 370.994686 -250.658884)
			(xy 371.01868 -250.659329) (xy 371.066078 -250.666834) (xy 371.111718 -250.681661) (xy 371.154476 -250.703446)
			(xy 371.193301 -250.731651) (xy 371.227235 -250.765583) (xy 371.255443 -250.804405) (xy 371.27723 -250.847162)
			(xy 371.292061 -250.892801) (xy 371.299569 -250.940198) (xy 371.299994 -250.964192) (xy 371.299639 -250.985521)
			(xy 371.293697 -251.027765) (xy 371.281929 -251.068768) (xy 371.273578 -251.088398) (xy 371.267228 -251.102876)
			(xy 371.272816 -251.133864) (xy 371.32006 -251.180854) (xy 371.367812 -251.228606) (xy 371.36832 -251.229114)
			(xy 371.375698 -251.235706) (xy 371.393997 -251.243174) (xy 371.40388 -251.243592) (xy 372.279164 -251.243592)
			(xy 372.289002 -251.243057) (xy 372.307164 -251.235471) (xy 372.31447 -251.22886) (xy 372.561866 -250.981464)
			(xy 372.569232 -250.964192) (xy 372.56974 -250.954286) (xy 372.571087 -250.928766) (xy 372.581229 -250.878682)
			(xy 372.59957 -250.830986) (xy 372.625599 -250.787011) (xy 372.658587 -250.747985) (xy 372.697613 -250.714997)
			(xy 372.741588 -250.68897) (xy 372.789284 -250.670629) (xy 372.839368 -250.660487) (xy 372.864888 -250.659138)
			(xy 372.874794 -250.65863) (xy 372.892066 -250.651264) (xy 373.052086 -250.491244) (xy 373.059325 -250.484532)
			(xy 373.077529 -250.476935) (xy 373.087392 -250.476512) (xy 373.945404 -250.476512) (xy 373.954543 -250.47613)
			(xy 373.971657 -250.469715) (xy 373.985432 -250.457703) (xy 373.990108 -250.449842) (xy 374.038114 -250.360688)
			(xy 374.036844 -250.333002) (xy 374.029224 -250.321318) (xy 374.017456 -250.302589) (xy 373.998854 -250.26246)
			(xy 373.986229 -250.220069) (xy 373.979843 -250.176301) (xy 373.97944 -250.154186) (xy 373.979962 -250.128931)
			(xy 373.988275 -250.079109) (xy 374.004676 -250.031335) (xy 374.028717 -249.986912) (xy 374.059741 -249.947052)
			(xy 374.096903 -249.912842) (xy 374.139189 -249.885216) (xy 374.185445 -249.864926) (xy 374.23441 -249.852526)
			(xy 374.284748 -249.848355) (xy 374.335086 -249.852526) (xy 374.384051 -249.864926) (xy 374.430307 -249.885216)
			(xy 374.472593 -249.912842) (xy 374.509755 -249.947052) (xy 374.540779 -249.986912) (xy 374.56482 -250.031335)
			(xy 374.581221 -250.079109) (xy 374.589534 -250.128931) (xy 374.590056 -250.154186) (xy 374.589425 -250.182676)
			(xy 374.578875 -250.238671) (xy 374.558138 -250.291744) (xy 374.543574 -250.316238) (xy 374.540272 -250.321572)
			(xy 374.5357 -250.335796) (xy 374.533003 -250.345789) (xy 374.534971 -250.366372) (xy 374.53951 -250.375674)
			(xy 374.54078 -250.378214) (xy 374.579388 -250.449842) (xy 374.584065 -250.457702) (xy 374.59784 -250.469715)
			(xy 374.614954 -250.476131) (xy 374.624092 -250.476512) (xy 374.885458 -250.476512) (xy 374.894601 -250.476138)
			(xy 374.911728 -250.469733) (xy 374.925516 -250.457723) (xy 374.930162 -250.449842) (xy 374.978168 -250.360688)
			(xy 374.976898 -250.333002) (xy 374.969278 -250.321318) (xy 374.957512 -250.302589) (xy 374.938913 -250.262459)
			(xy 374.926289 -250.220068) (xy 374.919904 -250.176301) (xy 374.919494 -250.154186) (xy 374.920016 -250.128931)
			(xy 374.928329 -250.079109) (xy 374.94473 -250.031335) (xy 374.968771 -249.986912) (xy 374.999795 -249.947052)
			(xy 375.036957 -249.912842) (xy 375.079243 -249.885216) (xy 375.125499 -249.864926) (xy 375.174464 -249.852526)
			(xy 375.224802 -249.848355) (xy 375.27514 -249.852526) (xy 375.324105 -249.864926) (xy 375.370361 -249.885216)
			(xy 375.412647 -249.912842) (xy 375.449809 -249.947052) (xy 375.480833 -249.986912) (xy 375.504874 -250.031335)
			(xy 375.521275 -250.079109) (xy 375.529588 -250.128931) (xy 375.53011 -250.154186) (xy 375.529478 -250.182676)
			(xy 375.518928 -250.23867) (xy 375.498188 -250.291741) (xy 375.483628 -250.316238) (xy 375.480326 -250.321572)
			(xy 375.475754 -250.335796) (xy 375.473059 -250.345789) (xy 375.475024 -250.366373) (xy 375.479564 -250.375674)
			(xy 375.480834 -250.378214) (xy 375.519442 -250.449842) (xy 375.524122 -250.457696) (xy 375.537899 -250.469694)
			(xy 375.555011 -250.476092) (xy 375.564146 -250.476512) (xy 375.825512 -250.476512) (xy 375.83465 -250.476129)
			(xy 375.851762 -250.469712) (xy 375.865535 -250.457699) (xy 375.870216 -250.449842) (xy 375.909586 -250.376944)
			(xy 375.912606 -250.370783) (xy 375.915561 -250.357389) (xy 375.915428 -250.350528) (xy 375.915428 -250.34748)
			(xy 375.899928 -250.326579) (xy 375.875261 -250.280765) (xy 375.858432 -250.231529) (xy 375.849896 -250.180202)
			(xy 375.849388 -250.154186) (xy 375.849874 -250.129396) (xy 375.85763 -250.080428) (xy 375.872951 -250.033275)
			(xy 375.89546 -249.9891) (xy 375.924602 -249.948989) (xy 375.959659 -249.913932) (xy 375.99977 -249.88479)
			(xy 376.043945 -249.862281) (xy 376.091098 -249.84696) (xy 376.140066 -249.839204) (xy 376.189646 -249.839204)
			(xy 376.238614 -249.84696) (xy 376.285767 -249.862281) (xy 376.329942 -249.88479) (xy 376.370053 -249.913932)
			(xy 376.40511 -249.948989) (xy 376.434252 -249.9891) (xy 376.456761 -250.033275) (xy 376.472082 -250.080428)
			(xy 376.479838 -250.129396) (xy 376.480324 -250.154186) (xy 376.479871 -250.178414) (xy 376.472503 -250.226305)
			(xy 376.457922 -250.272514) (xy 376.436469 -250.31596) (xy 376.42292 -250.33605) (xy 376.418935 -250.342096)
			(xy 376.414166 -250.355762) (xy 376.413522 -250.362974) (xy 376.413522 -250.364498) (xy 376.459496 -250.449842)
			(xy 376.464174 -250.457701) (xy 376.477948 -250.469712) (xy 376.495062 -250.476125) (xy 376.5042 -250.476512)
			(xy 376.765566 -250.476512) (xy 376.774708 -250.476136) (xy 376.791833 -250.46973) (xy 376.805619 -250.45772)
			(xy 376.81027 -250.449842) (xy 376.858276 -250.360688) (xy 376.857006 -250.333002) (xy 376.849386 -250.321318)
			(xy 376.837619 -250.302589) (xy 376.81902 -250.262459) (xy 376.806396 -250.220068) (xy 376.800011 -250.176301)
			(xy 376.799602 -250.154186) (xy 376.800074 -250.130196) (xy 376.807582 -250.082806) (xy 376.82241 -250.037175)
			(xy 376.844195 -249.994425) (xy 376.872399 -249.955609) (xy 376.906327 -249.921683) (xy 376.945145 -249.893482)
			(xy 376.987897 -249.871701) (xy 377.03353 -249.856876) (xy 377.08092 -249.849372) (xy 377.10491 -249.848878)
			(xy 377.128319 -249.849304) (xy 377.174589 -249.856455) (xy 377.219224 -249.870588) (xy 377.261177 -249.891371)
			(xy 377.299464 -249.918317) (xy 377.333188 -249.950793) (xy 377.361556 -249.988039) (xy 377.373134 -250.00839)
			(xy 377.378976 -250.019312) (xy 377.398534 -250.032774) (xy 377.489212 -250.045982) (xy 377.501031 -250.047092)
			(xy 377.523553 -250.039681) (xy 377.532392 -250.031758) (xy 377.669806 -249.894344) (xy 377.676529 -249.887109)
			(xy 377.684144 -249.868904) (xy 377.684538 -249.859038) (xy 377.684538 -249.749818) (xy 377.684083 -249.739665)
			(xy 377.676218 -249.720941) (xy 377.669298 -249.713496) (xy 377.627134 -249.672348) (xy 377.626626 -249.672348)
			(xy 377.619514 -249.664982) (xy 377.612061 -249.657934) (xy 377.593186 -249.64995) (xy 377.582938 -249.649488)
			(xy 377.57481 -249.649488) (xy 377.549553 -249.648996) (xy 377.499729 -249.640683) (xy 377.451952 -249.624283)
			(xy 377.407527 -249.600242) (xy 377.367664 -249.569217) (xy 377.333452 -249.532054) (xy 377.305823 -249.489767)
			(xy 377.285532 -249.443508) (xy 377.273131 -249.394541) (xy 377.26896 -249.3442) (xy 377.273131 -249.293859)
			(xy 377.285532 -249.244892) (xy 377.305823 -249.198633) (xy 377.333452 -249.156346) (xy 377.367664 -249.119183)
			(xy 377.407527 -249.088158) (xy 377.451952 -249.064117) (xy 377.499729 -249.047717) (xy 377.549553 -249.039404)
			(xy 377.57481 -249.038872) (xy 377.582938 -249.038872) (xy 377.59255 -249.038464) (xy 377.610439 -249.031424)
			(xy 377.617736 -249.025156) (xy 377.618244 -249.024648) (xy 377.669552 -248.97461) (xy 377.676364 -248.967344)
			(xy 377.684083 -248.949001) (xy 377.684538 -248.93905) (xy 377.684538 -248.129806) (xy 377.684099 -248.119645)
			(xy 377.676256 -248.100899) (xy 377.669298 -248.093484) (xy 377.614688 -248.040144) (xy 377.608846 -248.037858)
			(xy 377.57481 -248.039636) (xy 377.55002 -248.039176) (xy 377.501051 -248.031421) (xy 377.453898 -248.016102)
			(xy 377.409723 -247.993594) (xy 377.369612 -247.964453) (xy 377.334553 -247.929396) (xy 377.305411 -247.889286)
			(xy 377.282902 -247.845111) (xy 377.267581 -247.797958) (xy 377.259825 -247.74899) (xy 377.259825 -247.69941)
			(xy 377.267581 -247.650442) (xy 377.282902 -247.603289) (xy 377.305411 -247.559114) (xy 377.334553 -247.519004)
			(xy 377.369612 -247.483947) (xy 377.409723 -247.454806) (xy 377.453898 -247.432298) (xy 377.501051 -247.416979)
			(xy 377.55002 -247.409224) (xy 377.57481 -247.4087) (xy 377.608338 -247.410478) (xy 377.614688 -247.407938)
			(xy 377.669552 -247.354598) (xy 377.676363 -247.347331) (xy 377.684077 -247.328988) (xy 377.684538 -247.319038)
			(xy 377.684538 -246.509794) (xy 377.684097 -246.499634) (xy 377.676251 -246.480891) (xy 377.669298 -246.473472)
			(xy 377.614688 -246.420132) (xy 377.608846 -246.417846) (xy 377.57481 -246.419624) (xy 377.550021 -246.419164)
			(xy 377.501054 -246.41141) (xy 377.453903 -246.396091) (xy 377.409729 -246.373584) (xy 377.36962 -246.344444)
			(xy 377.334563 -246.309388) (xy 377.305421 -246.26928) (xy 377.282913 -246.225106) (xy 377.267593 -246.177955)
			(xy 377.259837 -246.128989) (xy 377.259837 -246.079411) (xy 377.267593 -246.030445) (xy 377.282913 -245.983294)
			(xy 377.305421 -245.93912) (xy 377.334563 -245.899012) (xy 377.36962 -245.863956) (xy 377.409729 -245.834816)
			(xy 377.453903 -245.812309) (xy 377.501054 -245.79699) (xy 377.550021 -245.789236) (xy 377.57481 -245.788688)
			(xy 377.608338 -245.790466) (xy 377.614688 -245.787926) (xy 377.669552 -245.734586) (xy 377.676377 -245.727324)
			(xy 377.684123 -245.708981) (xy 377.684538 -245.699026) (xy 377.684538 -244.889782) (xy 377.684095 -244.879623)
			(xy 377.676246 -244.860883) (xy 377.669298 -244.85346) (xy 377.614688 -244.80012) (xy 377.608846 -244.797834)
			(xy 377.57481 -244.799612) (xy 377.550014 -244.799152) (xy 377.501034 -244.791395) (xy 377.453869 -244.776072)
			(xy 377.409683 -244.753559) (xy 377.369562 -244.724411) (xy 377.334496 -244.689345) (xy 377.305346 -244.649226)
			(xy 377.282832 -244.60504) (xy 377.267507 -244.557876) (xy 377.259749 -244.508896) (xy 377.259749 -244.459304)
			(xy 377.267507 -244.410324) (xy 377.282832 -244.36316) (xy 377.305346 -244.318974) (xy 377.334496 -244.278855)
			(xy 377.369562 -244.243789) (xy 377.409683 -244.214641) (xy 377.453869 -244.192128) (xy 377.501034 -244.176805)
			(xy 377.550014 -244.169048) (xy 377.57481 -244.168676) (xy 377.608338 -244.170454) (xy 377.614688 -244.167914)
			(xy 377.669552 -244.114574) (xy 377.676374 -244.107311) (xy 377.684117 -244.088969) (xy 377.684538 -244.079014)
			(xy 377.684538 -243.26977) (xy 377.684092 -243.259612) (xy 377.67624 -243.240875) (xy 377.669298 -243.233448)
			(xy 377.614688 -243.180108) (xy 377.608846 -243.177822) (xy 377.57481 -243.1796) (xy 377.550015 -243.17914)
			(xy 377.501037 -243.171384) (xy 377.453874 -243.156061) (xy 377.409689 -243.133549) (xy 377.36957 -243.104402)
			(xy 377.334505 -243.069337) (xy 377.305356 -243.029219) (xy 377.282843 -242.985035) (xy 377.267519 -242.937873)
			(xy 377.259761 -242.888895) (xy 377.259761 -242.839305) (xy 377.267519 -242.790327) (xy 377.282843 -242.743165)
			(xy 377.305356 -242.698981) (xy 377.334505 -242.658863) (xy 377.36957 -242.623798) (xy 377.409689 -242.594651)
			(xy 377.453874 -242.572139) (xy 377.501037 -242.556816) (xy 377.550015 -242.54906) (xy 377.57481 -242.548664)
			(xy 377.608338 -242.550442) (xy 377.614688 -242.547902) (xy 377.669552 -242.494562) (xy 377.676373 -242.487299)
			(xy 377.68411 -242.468956) (xy 377.684538 -242.459002) (xy 377.684538 -241.649758) (xy 377.68409 -241.639601)
			(xy 377.676235 -241.620867) (xy 377.669298 -241.613436) (xy 377.614688 -241.560096) (xy 377.608846 -241.55781)
			(xy 377.57481 -241.559588) (xy 377.550016 -241.559128) (xy 377.501039 -241.551372) (xy 377.453879 -241.53605)
			(xy 377.409695 -241.513539) (xy 377.369578 -241.484393) (xy 377.334514 -241.44933) (xy 377.305367 -241.409213)
			(xy 377.282854 -241.365031) (xy 377.26753 -241.31787) (xy 377.259773 -241.268894) (xy 377.259773 -241.219306)
			(xy 377.26753 -241.17033) (xy 377.282854 -241.123169) (xy 377.305367 -241.078987) (xy 377.334514 -241.03887)
			(xy 377.369578 -241.003807) (xy 377.409695 -240.974661) (xy 377.453879 -240.95215) (xy 377.501039 -240.936828)
			(xy 377.550016 -240.929072) (xy 377.57481 -240.928652) (xy 377.608338 -240.93043) (xy 377.614688 -240.92789)
			(xy 377.669552 -240.87455) (xy 377.676371 -240.867286) (xy 377.684104 -240.848943) (xy 377.684538 -240.83899)
			(xy 377.684538 -240.034826) (xy 377.684084 -240.024672) (xy 377.676221 -240.005947) (xy 377.669298 -239.998504)
			(xy 377.609354 -239.940084) (xy 377.604528 -239.938306) (xy 377.57481 -239.939576) (xy 377.550017 -239.939116)
			(xy 377.501042 -239.93136) (xy 377.453883 -239.916039) (xy 377.409702 -239.893528) (xy 377.369586 -239.864383)
			(xy 377.334523 -239.829322) (xy 377.305377 -239.789207) (xy 377.282865 -239.745026) (xy 377.267542 -239.697868)
			(xy 377.259785 -239.648893) (xy 377.259785 -239.599307) (xy 377.267542 -239.550332) (xy 377.282865 -239.503174)
			(xy 377.305377 -239.458993) (xy 377.334523 -239.418878) (xy 377.369586 -239.383817) (xy 377.409702 -239.354672)
			(xy 377.453883 -239.332161) (xy 377.501042 -239.31684) (xy 377.550017 -239.309084) (xy 377.57481 -239.30864)
			(xy 377.604528 -239.30991) (xy 377.609354 -239.308132) (xy 377.669298 -239.249712) (xy 377.676247 -239.242287)
			(xy 377.684109 -239.22355) (xy 377.684538 -239.21339) (xy 377.684538 -238.414814) (xy 377.684082 -238.404661)
			(xy 377.676216 -238.385939) (xy 377.669298 -238.378492) (xy 377.609354 -238.320072) (xy 377.604528 -238.318294)
			(xy 377.57481 -238.319564) (xy 377.550018 -238.319104) (xy 377.501045 -238.311349) (xy 377.453888 -238.296028)
			(xy 377.409708 -238.273518) (xy 377.369594 -238.244374) (xy 377.334532 -238.209314) (xy 377.305387 -238.169201)
			(xy 377.282876 -238.125021) (xy 377.267554 -238.077865) (xy 377.259797 -238.028892) (xy 377.259797 -237.979308)
			(xy 377.267554 -237.930335) (xy 377.282876 -237.883179) (xy 377.305387 -237.838999) (xy 377.334532 -237.798886)
			(xy 377.369594 -237.763826) (xy 377.409708 -237.734682) (xy 377.453888 -237.712172) (xy 377.501045 -237.696851)
			(xy 377.550018 -237.689096) (xy 377.57481 -237.688628) (xy 377.604528 -237.689898) (xy 377.609354 -237.68812)
			(xy 377.669298 -237.6297) (xy 377.676245 -237.622274) (xy 377.684102 -237.603538) (xy 377.684538 -237.593378)
			(xy 377.684538 -236.794802) (xy 377.684098 -236.784642) (xy 377.676254 -236.765896) (xy 377.669298 -236.75848)
			(xy 377.609354 -236.70006) (xy 377.604528 -236.698282) (xy 377.57481 -236.699552) (xy 377.550019 -236.699092)
			(xy 377.501048 -236.691337) (xy 377.453892 -236.676016) (xy 377.409714 -236.653508) (xy 377.369601 -236.624365)
			(xy 377.334541 -236.589306) (xy 377.305397 -236.549194) (xy 377.282887 -236.505017) (xy 377.267565 -236.457862)
			(xy 377.259809 -236.408891) (xy 377.259809 -236.359309) (xy 377.267565 -236.310338) (xy 377.282887 -236.263183)
			(xy 377.305397 -236.219006) (xy 377.334541 -236.178894) (xy 377.369601 -236.143835) (xy 377.409714 -236.114692)
			(xy 377.453892 -236.092184) (xy 377.501048 -236.076863) (xy 377.550019 -236.069108) (xy 377.57481 -236.068616)
			(xy 377.604528 -236.069886) (xy 377.609354 -236.068108) (xy 377.669298 -236.009688) (xy 377.676243 -236.002262)
			(xy 377.684096 -235.983525) (xy 377.684538 -235.973366) (xy 377.684538 -235.17479) (xy 377.684096 -235.164631)
			(xy 377.676249 -235.145888) (xy 377.669298 -235.138468) (xy 377.609354 -235.080048) (xy 377.604528 -235.07827)
			(xy 377.57481 -235.07954) (xy 377.55002 -235.07908) (xy 377.501051 -235.071325) (xy 377.453897 -235.056005)
			(xy 377.409721 -235.033498) (xy 377.369609 -235.004356) (xy 377.33455 -234.969298) (xy 377.305408 -234.929188)
			(xy 377.282898 -234.885012) (xy 377.267577 -234.837859) (xy 377.259821 -234.78889) (xy 377.259821 -234.73931)
			(xy 377.267577 -234.690341) (xy 377.282898 -234.643188) (xy 377.305408 -234.599012) (xy 377.33455 -234.558902)
			(xy 377.369609 -234.523844) (xy 377.409721 -234.494702) (xy 377.453897 -234.472195) (xy 377.501051 -234.456875)
			(xy 377.55002 -234.44912) (xy 377.57481 -234.448604) (xy 377.604528 -234.449874) (xy 377.609354 -234.448096)
			(xy 377.669298 -234.389676) (xy 377.676241 -234.382249) (xy 377.68409 -234.363512) (xy 377.684538 -234.353354)
			(xy 377.684538 -233.554778) (xy 377.684094 -233.54462) (xy 377.676244 -233.52588) (xy 377.669298 -233.518456)
			(xy 377.609354 -233.460036) (xy 377.604528 -233.458258) (xy 377.57481 -233.459528) (xy 377.550021 -233.459068)
			(xy 377.501053 -233.451314) (xy 377.453902 -233.435994) (xy 377.409727 -233.413487) (xy 377.369617 -233.384347)
			(xy 377.33456 -233.349291) (xy 377.305418 -233.309182) (xy 377.28291 -233.265008) (xy 377.267589 -233.217856)
			(xy 377.259833 -233.168889) (xy 377.259833 -233.119311) (xy 377.267589 -233.070344) (xy 377.28291 -233.023192)
			(xy 377.305418 -232.979018) (xy 377.33456 -232.938909) (xy 377.369617 -232.903853) (xy 377.409727 -232.874713)
			(xy 377.453902 -232.852206) (xy 377.501053 -232.836886) (xy 377.550021 -232.829132) (xy 377.57481 -232.828592)
			(xy 377.604528 -232.829862) (xy 377.609354 -232.828084) (xy 377.669298 -232.769664) (xy 377.676239 -232.762236)
			(xy 377.684084 -232.7435) (xy 377.684538 -232.733342) (xy 377.684538 -231.934766) (xy 377.684092 -231.924609)
			(xy 377.676239 -231.905873) (xy 377.669298 -231.898444) (xy 377.609354 -231.840024) (xy 377.604528 -231.838246)
			(xy 377.57481 -231.839516) (xy 377.550014 -231.839056) (xy 377.501033 -231.831299) (xy 377.453868 -231.815976)
			(xy 377.409681 -231.793462) (xy 377.36956 -231.764314) (xy 377.334493 -231.729248) (xy 377.305343 -231.689128)
			(xy 377.282828 -231.644941) (xy 377.267503 -231.597777) (xy 377.259745 -231.548796) (xy 377.259745 -231.499204)
			(xy 377.267503 -231.450223) (xy 377.282828 -231.403059) (xy 377.305343 -231.358872) (xy 377.334493 -231.318752)
			(xy 377.36956 -231.283686) (xy 377.409681 -231.254538) (xy 377.453868 -231.232024) (xy 377.501033 -231.216701)
			(xy 377.550014 -231.208944) (xy 377.57481 -231.20858) (xy 377.604528 -231.20985) (xy 377.609354 -231.208072)
			(xy 377.669298 -231.149652) (xy 377.676253 -231.142229) (xy 377.68413 -231.123493) (xy 377.684538 -231.11333)
			(xy 377.684538 -230.314754) (xy 377.68409 -230.304598) (xy 377.676233 -230.285865) (xy 377.669298 -230.278432)
			(xy 377.609354 -230.220012) (xy 377.604528 -230.218234) (xy 377.57481 -230.219504) (xy 377.550015 -230.219044)
			(xy 377.501036 -230.211287) (xy 377.453872 -230.195965) (xy 377.409687 -230.173452) (xy 377.369568 -230.144305)
			(xy 377.334502 -230.10924) (xy 377.305353 -230.069121) (xy 377.282839 -230.024937) (xy 377.267515 -229.977774)
			(xy 377.259757 -229.928795) (xy 377.259757 -229.879205) (xy 377.267515 -229.830226) (xy 377.282839 -229.783063)
			(xy 377.305353 -229.738879) (xy 377.334502 -229.69876) (xy 377.369568 -229.663695) (xy 377.409687 -229.634548)
			(xy 377.453872 -229.612035) (xy 377.501036 -229.596713) (xy 377.550015 -229.588956) (xy 377.57481 -229.588568)
			(xy 377.604528 -229.589838) (xy 377.609354 -229.58806) (xy 377.669298 -229.52964) (xy 377.676251 -229.522216)
			(xy 377.684124 -229.50348) (xy 377.684538 -229.493318) (xy 377.684538 -228.694996) (xy 377.684097 -228.684836)
			(xy 377.676252 -228.666092) (xy 377.669298 -228.658674) (xy 377.615958 -228.606604) (xy 377.596908 -228.599238)
			(xy 377.58624 -228.599746) (xy 377.57481 -228.6) (xy 377.55 -228.599539) (xy 377.50099 -228.591778)
			(xy 377.453797 -228.576446) (xy 377.409584 -228.55392) (xy 377.36944 -228.524754) (xy 377.334352 -228.489668)
			(xy 377.305186 -228.449524) (xy 377.282658 -228.405312) (xy 377.267324 -228.35812) (xy 377.259561 -228.30911)
			(xy 377.259561 -228.25949) (xy 377.267324 -228.21048) (xy 377.282658 -228.163288) (xy 377.305186 -228.119076)
			(xy 377.334352 -228.078932) (xy 377.36944 -228.043846) (xy 377.409584 -228.01468) (xy 377.453797 -227.992154)
			(xy 377.50099 -227.976822) (xy 377.55 -227.969061) (xy 377.57481 -227.968556) (xy 377.58624 -227.96881)
			(xy 377.596908 -227.969318) (xy 377.615958 -227.961952) (xy 377.669298 -227.909882) (xy 377.676242 -227.902455)
			(xy 377.684093 -227.883719) (xy 377.684538 -227.87356) (xy 377.684538 -227.074984) (xy 377.684095 -227.064825)
			(xy 377.676247 -227.046084) (xy 377.669298 -227.038662) (xy 377.615958 -226.986592) (xy 377.596908 -226.979226)
			(xy 377.58624 -226.979734) (xy 377.57481 -226.979988) (xy 377.550001 -226.979528) (xy 377.500993 -226.971767)
			(xy 377.453802 -226.956435) (xy 377.409591 -226.93391) (xy 377.369448 -226.904745) (xy 377.334361 -226.86966)
			(xy 377.305196 -226.829518) (xy 377.282669 -226.785307) (xy 377.267336 -226.738117) (xy 377.259573 -226.689109)
			(xy 377.259573 -226.639491) (xy 377.267336 -226.590483) (xy 377.282669 -226.543293) (xy 377.305196 -226.499082)
			(xy 377.334361 -226.45894) (xy 377.369448 -226.423855) (xy 377.409591 -226.394691) (xy 377.453802 -226.372165)
			(xy 377.500993 -226.356833) (xy 377.550001 -226.349072) (xy 377.57481 -226.348544) (xy 377.58624 -226.348798)
			(xy 377.596908 -226.349306) (xy 377.615958 -226.34194) (xy 377.669298 -226.28987) (xy 377.67624 -226.282443)
			(xy 377.684087 -226.263706) (xy 377.684538 -226.253548) (xy 377.684538 -226.053904) (xy 377.684961 -226.043834)
			(xy 377.692679 -226.025232) (xy 377.699524 -226.017836) (xy 377.746006 -225.971354) (xy 377.753118 -225.945446)
			(xy 377.749562 -225.932238) (xy 377.744826 -225.913092) (xy 377.739732 -225.87398) (xy 377.739402 -225.85426)
			(xy 377.739876 -225.830271) (xy 377.747387 -225.782885) (xy 377.762218 -225.737257) (xy 377.784004 -225.69451)
			(xy 377.812208 -225.655698) (xy 377.846136 -225.621775) (xy 377.884953 -225.593577) (xy 377.927703 -225.571799)
			(xy 377.973334 -225.556975) (xy 378.020721 -225.549472) (xy 378.04471 -225.548952) (xy 378.064432 -225.549262)
			(xy 378.103544 -225.554363) (xy 378.122688 -225.559112) (xy 378.135896 -225.562668) (xy 378.161804 -225.555556)
			(xy 378.30633 -225.41103) (xy 378.313244 -225.403524) (xy 378.320966 -225.384654) (xy 378.321316 -225.374454)
			(xy 378.3203 -225.291396) (xy 378.312172 -225.272854) (xy 378.304552 -225.265742) (xy 378.286924 -225.248309)
			(xy 378.256991 -225.208792) (xy 378.233828 -225.164961) (xy 378.218043 -225.117967) (xy 378.210049 -225.069041)
			(xy 378.209556 -225.044254) (xy 378.21003 -225.020264) (xy 378.217542 -224.972876) (xy 378.232373 -224.927246)
			(xy 378.254158 -224.884497) (xy 378.282362 -224.845681) (xy 378.316289 -224.811755) (xy 378.355105 -224.783553)
			(xy 378.397855 -224.761769) (xy 378.443486 -224.746939) (xy 378.490874 -224.739429) (xy 378.514864 -224.738946)
			(xy 378.538476 -224.739391) (xy 378.585135 -224.746669) (xy 378.630119 -224.76104) (xy 378.672354 -224.782164)
			(xy 378.710836 -224.809536) (xy 378.744646 -224.842505) (xy 378.77298 -224.880284) (xy 378.795162 -224.921974)
			(xy 378.810663 -224.96658) (xy 378.819115 -225.013041) (xy 378.820172 -225.036634) (xy 378.820172 -225.044)
			(xy 378.819971 -225.062205) (xy 378.815773 -225.098371) (xy 378.81179 -225.116136) (xy 378.811028 -225.11893)
			(xy 378.810266 -225.12528) (xy 378.809474 -225.135249) (xy 378.81484 -225.1545) (xy 378.82068 -225.162618)
			(xy 378.869448 -225.225102) (xy 378.870718 -225.226626) (xy 378.878306 -225.234766) (xy 378.898465 -225.244132)
			(xy 378.90958 -225.24466) (xy 378.934218 -225.24466) (xy 378.9426 -225.243898) (xy 378.950205 -225.242383)
			(xy 378.964038 -225.235396) (xy 378.969778 -225.230182) (xy 379.134878 -225.065082) (xy 379.138166 -225.061602)
			(xy 379.143536 -225.053679) (xy 379.145546 -225.049334) (xy 379.149356 -225.040444) (xy 379.149864 -225.031046)
			(xy 379.151473 -225.005902) (xy 379.161893 -224.956612) (xy 379.180263 -224.909702) (xy 379.206085 -224.866443)
			(xy 379.238657 -224.82801) (xy 379.277097 -224.795446) (xy 379.320362 -224.769633) (xy 379.367277 -224.751274)
			(xy 379.416569 -224.740865) (xy 379.44171 -224.7392) (xy 379.451108 -224.738692) (xy 379.459998 -224.734882)
			(xy 379.464359 -224.7329) (xy 379.472288 -224.727528) (xy 379.475746 -224.724214) (xy 379.691392 -224.508568)
			(xy 379.697943 -224.501358) (xy 379.705524 -224.483432) (xy 379.705873 -224.463972) (xy 379.702822 -224.45472)
			(xy 379.695964 -224.436686) (xy 379.69063 -224.430082) (xy 379.674029 -224.409302) (xy 379.647517 -224.363199)
			(xy 379.629366 -224.313211) (xy 379.620122 -224.260838) (xy 379.61951 -224.234248) (xy 379.619979 -224.210012)
			(xy 379.627644 -224.16215) (xy 379.642773 -224.1161) (xy 379.664987 -224.073018) (xy 379.693727 -224.033986)
			(xy 379.728272 -223.999983) (xy 379.767754 -223.971865) (xy 379.811183 -223.950336) (xy 379.857467 -223.935938)
			(xy 379.881384 -223.931988) (xy 379.89383 -223.93021) (xy 379.924818 -223.928686) (xy 379.951485 -223.929267)
			(xy 380.00401 -223.938521) (xy 380.054134 -223.956747) (xy 380.100336 -223.983391) (xy 380.12116 -224.00006)
			(xy 380.127764 -224.005648) (xy 380.14529 -224.012252) (xy 380.154539 -224.015293) (xy 380.173989 -224.014921)
			(xy 380.191904 -224.007341) (xy 380.199138 -224.000822) (xy 380.212854 -223.987106) (xy 380.220255 -223.980267)
			(xy 380.238853 -223.972552) (xy 380.248922 -223.97212) (xy 380.70155 -223.97212) (xy 380.713488 -223.969072)
			(xy 380.719076 -223.966024) (xy 380.741585 -223.954349) (xy 380.789515 -223.937814) (xy 380.839521 -223.929431)
			(xy 380.890223 -223.929431) (xy 380.940229 -223.937814) (xy 380.988159 -223.954349) (xy 381.010668 -223.966024)
			(xy 381.016256 -223.969072) (xy 381.028194 -223.97212) (xy 382.581404 -223.97212) (xy 382.593342 -223.969072)
			(xy 382.59893 -223.966024) (xy 382.621439 -223.954349) (xy 382.669369 -223.937814) (xy 382.719375 -223.929431)
			(xy 382.770077 -223.929431) (xy 382.820083 -223.937814) (xy 382.868013 -223.954349) (xy 382.890522 -223.966024)
			(xy 382.89611 -223.969072) (xy 382.908048 -223.97212) (xy 383.244598 -223.97212) (xy 383.25298 -223.971358)
			(xy 383.260588 -223.969848) (xy 383.274431 -223.962871) (xy 383.280158 -223.957642) (xy 383.845816 -223.391984)
			(xy 383.852928 -223.378268) (xy 383.854452 -223.370394) (xy 383.858972 -223.347618) (xy 383.873985 -223.303681)
			(xy 383.895479 -223.262524) (xy 383.922959 -223.225098) (xy 383.955791 -223.192265) (xy 383.993216 -223.164784)
			(xy 384.034372 -223.143288) (xy 384.078309 -223.128274) (xy 384.101086 -223.12376) (xy 384.10896 -223.122236)
			(xy 384.122676 -223.115124) (xy 384.375152 -222.862648) (xy 384.381244 -222.856006) (xy 384.388711 -222.839615)
			(xy 384.390015 -222.821651) (xy 384.384993 -222.804355) (xy 384.379978 -222.796862) (xy 384.379978 -222.796354)
			(xy 384.365779 -222.776489) (xy 384.343218 -222.733187) (xy 384.327836 -222.686847) (xy 384.320027 -222.638649)
			(xy 384.319526 -222.614236) (xy 384.31997 -222.590242) (xy 384.327472 -222.542844) (xy 384.342298 -222.497204)
			(xy 384.364082 -222.454445) (xy 384.392287 -222.415621) (xy 384.42622 -222.381689) (xy 384.465043 -222.353483)
			(xy 384.507802 -222.331699) (xy 384.553442 -222.316872) (xy 384.60084 -222.30937) (xy 384.624834 -222.308928)
			(xy 384.649278 -222.309413) (xy 384.69754 -222.31721) (xy 384.743942 -222.332598) (xy 384.787299 -222.355186)
			(xy 384.807206 -222.36938) (xy 384.822446 -222.380556) (xy 384.859784 -222.378016) (xy 384.993388 -222.244412)
			(xy 384.993896 -222.243904) (xy 385.001892 -222.234741) (xy 385.009038 -222.211533) (xy 385.007612 -222.199454)
			(xy 384.995166 -222.129858) (xy 384.993983 -222.123906) (xy 384.989229 -222.112745) (xy 384.985768 -222.10776)
			(xy 384.968496 -222.085408) (xy 384.960368 -222.078296) (xy 384.955034 -222.075756) (xy 384.933986 -222.064408)
			(xy 384.895397 -222.036174) (xy 384.861684 -222.002266) (xy 384.833672 -221.963515) (xy 384.812047 -221.920869)
			(xy 384.797339 -221.875372) (xy 384.789907 -221.828138) (xy 384.789426 -221.80423) (xy 384.78987 -221.780236)
			(xy 384.797373 -221.732839) (xy 384.8122 -221.6872) (xy 384.833984 -221.644442) (xy 384.86219 -221.605619)
			(xy 384.896122 -221.571687) (xy 384.934945 -221.543482) (xy 384.977703 -221.521698) (xy 385.023343 -221.506872)
			(xy 385.07074 -221.49937) (xy 385.094734 -221.498922) (xy 385.118641 -221.499388) (xy 385.165869 -221.506842)
			(xy 385.21136 -221.521564) (xy 385.254001 -221.543193) (xy 385.292752 -221.571202) (xy 385.326665 -221.604906)
			(xy 385.354914 -221.643483) (xy 385.36626 -221.66453) (xy 385.3688 -221.669864) (xy 385.375912 -221.677992)
			(xy 385.398264 -221.695264) (xy 385.403216 -221.698784) (xy 385.414391 -221.703541) (xy 385.420362 -221.704662)
			(xy 385.489958 -221.717108) (xy 385.502032 -221.718542) (xy 385.525228 -221.711369) (xy 385.534408 -221.703392)
			(xy 385.534662 -221.703138) (xy 387.124194 -220.113606) (xy 387.131042 -220.106208) (xy 387.13878 -220.08761)
			(xy 387.13918 -220.077538) (xy 387.13918 -211.928202) (xy 387.139602 -211.918131) (xy 387.147314 -211.899524)
			(xy 387.154166 -211.892134) (xy 389.869934 -209.176366) (xy 389.877331 -209.169518) (xy 389.89593 -209.161785)
			(xy 389.906002 -209.16138) (xy 393.338558 -209.16138) (xy 393.34694 -209.160618) (xy 393.354543 -209.159099)
			(xy 393.36837 -209.152106) (xy 393.374118 -209.146902) (xy 396.237714 -206.283306) (xy 396.244571 -206.275912)
			(xy 396.252321 -206.257313) (xy 396.2527 -206.247238) (xy 396.2527 -199.253602) (xy 396.24508 -199.234806)
			(xy 396.237714 -199.227694) (xy 387.084316 -190.07455) (xy 387.076916 -190.067711) (xy 387.058317 -190.059999)
			(xy 387.048248 -190.059564) (xy 368.793522 -190.059564) (xy 368.788696 -190.05931) (xy 368.78768 -190.05931)
			(xy 368.688112 -190.05931) (xy 368.678041 -190.05889) (xy 368.659432 -190.051179) (xy 368.652044 -190.044324)
			(xy 368.58194 -189.97422) (xy 368.575082 -189.967616) (xy 364.100872 -185.493406) (xy 364.093525 -185.486599)
			(xy 364.075063 -185.478876) (xy 364.065058 -185.47842) (xy 360.838242 -185.47842) (xy 360.828176 -185.477987)
			(xy 360.809585 -185.47026) (xy 360.802174 -185.463434) (xy 359.788206 -184.449466) (xy 359.781364 -184.442066)
			(xy 359.773641 -184.423468) (xy 359.77322 -184.413398) (xy 359.77322 -181.186582) (xy 359.77268 -181.176596)
			(xy 359.764964 -181.158166) (xy 359.758234 -181.150768) (xy 355.660452 -177.052986) (xy 355.653108 -177.046173)
			(xy 355.634645 -177.038445) (xy 355.624638 -177.038) (xy 352.278442 -177.038) (xy 352.268377 -177.037566)
			(xy 352.249787 -177.029837) (xy 352.242374 -177.023014) (xy 351.698306 -176.478946) (xy 351.691467 -176.471545)
			(xy 351.683752 -176.452947) (xy 351.68332 -176.442878) (xy 351.68332 -173.096682) (xy 351.68278 -173.086696)
			(xy 351.675064 -173.068266) (xy 351.668334 -173.060868) (xy 350.908112 -172.300646) (xy 350.90077 -172.293829)
			(xy 350.882307 -172.286085) (xy 350.872298 -172.28566) (xy 344.104722 -172.28566) (xy 344.085926 -172.29328)
			(xy 344.078814 -172.300646) (xy 343.750646 -172.628814) (xy 343.743797 -172.636211) (xy 343.73606 -172.65481)
			(xy 343.73566 -172.664882) (xy 343.73566 -177.367438) (xy 343.736092 -177.377504) (xy 343.743822 -177.396093)
			(xy 343.750646 -177.403506) (xy 354.131372 -187.784232) (xy 354.135182 -187.787534) (xy 368.811302 -199.80783)
			(xy 368.837199 -199.829663) (xy 368.88423 -199.878412) (xy 368.925238 -199.932327) (xy 368.942874 -199.961246)
			(xy 369.585748 -201.049382) (xy 369.593622 -201.059542) (xy 371.752833 -203.218753) (xy 380.872994 -203.218753)
			(xy 380.872994 -203.154831) (xy 380.881005 -203.091413) (xy 380.896902 -203.029499) (xy 380.920434 -202.970066)
			(xy 380.951228 -202.914051) (xy 380.988801 -202.862336) (xy 381.032558 -202.815739) (xy 381.081811 -202.774994)
			(xy 381.135782 -202.740743) (xy 381.193621 -202.713526) (xy 381.254414 -202.693773) (xy 381.317204 -202.681795)
			(xy 381.381 -202.677782) (xy 381.444796 -202.681795) (xy 381.507586 -202.693773) (xy 381.568379 -202.713526)
			(xy 381.626218 -202.740743) (xy 381.680189 -202.774994) (xy 381.729442 -202.815739) (xy 381.772535 -202.861629)
			(xy 394.746728 -202.861629) (xy 394.746728 -202.797707) (xy 394.754739 -202.734289) (xy 394.770636 -202.672375)
			(xy 394.794168 -202.612942) (xy 394.824962 -202.556927) (xy 394.862535 -202.505212) (xy 394.906292 -202.458615)
			(xy 394.955545 -202.41787) (xy 395.009516 -202.383619) (xy 395.067355 -202.356402) (xy 395.128148 -202.336649)
			(xy 395.190938 -202.324671) (xy 395.254734 -202.320658) (xy 395.31853 -202.324671) (xy 395.38132 -202.336649)
			(xy 395.442113 -202.356402) (xy 395.499952 -202.383619) (xy 395.553923 -202.41787) (xy 395.603176 -202.458615)
			(xy 395.646933 -202.505212) (xy 395.684506 -202.556927) (xy 395.7153 -202.612942) (xy 395.738832 -202.672375)
			(xy 395.754729 -202.734289) (xy 395.76274 -202.797707) (xy 395.763242 -202.829668) (xy 395.76274 -202.861629)
			(xy 395.754729 -202.925047) (xy 395.738832 -202.986961) (xy 395.7153 -203.046394) (xy 395.684506 -203.102409)
			(xy 395.646933 -203.154124) (xy 395.603176 -203.200721) (xy 395.553923 -203.241466) (xy 395.499952 -203.275717)
			(xy 395.442113 -203.302934) (xy 395.38132 -203.322687) (xy 395.31853 -203.334665) (xy 395.254734 -203.338679)
			(xy 395.190938 -203.334665) (xy 395.128148 -203.322687) (xy 395.067355 -203.302934) (xy 395.009516 -203.275717)
			(xy 394.955545 -203.241466) (xy 394.906292 -203.200721) (xy 394.862535 -203.154124) (xy 394.824962 -203.102409)
			(xy 394.794168 -203.046394) (xy 394.770636 -202.986961) (xy 394.754739 -202.925047) (xy 394.746728 -202.861629)
			(xy 381.772535 -202.861629) (xy 381.773199 -202.862336) (xy 381.810772 -202.914051) (xy 381.841566 -202.970066)
			(xy 381.865098 -203.029499) (xy 381.880995 -203.091413) (xy 381.889006 -203.154831) (xy 381.889508 -203.186792)
			(xy 381.889006 -203.218753) (xy 381.880995 -203.282171) (xy 381.865098 -203.344085) (xy 381.841566 -203.403518)
			(xy 381.810772 -203.459533) (xy 381.773199 -203.511248) (xy 381.729442 -203.557845) (xy 381.727602 -203.559367)
			(xy 393.47749 -203.559367) (xy 393.47749 -203.495445) (xy 393.485501 -203.432027) (xy 393.501398 -203.370113)
			(xy 393.52493 -203.31068) (xy 393.555724 -203.254665) (xy 393.593297 -203.20295) (xy 393.637054 -203.156353)
			(xy 393.686307 -203.115608) (xy 393.740278 -203.081357) (xy 393.798117 -203.05414) (xy 393.85891 -203.034387)
			(xy 393.9217 -203.022409) (xy 393.985496 -203.018396) (xy 394.049292 -203.022409) (xy 394.112082 -203.034387)
			(xy 394.172875 -203.05414) (xy 394.230714 -203.081357) (xy 394.284685 -203.115608) (xy 394.333938 -203.156353)
			(xy 394.377695 -203.20295) (xy 394.415268 -203.254665) (xy 394.446062 -203.31068) (xy 394.469594 -203.370113)
			(xy 394.485491 -203.432027) (xy 394.493502 -203.495445) (xy 394.494004 -203.527406) (xy 394.493502 -203.559367)
			(xy 394.485491 -203.622785) (xy 394.469594 -203.684699) (xy 394.446062 -203.744132) (xy 394.415268 -203.800147)
			(xy 394.377695 -203.851862) (xy 394.333938 -203.898459) (xy 394.284685 -203.939204) (xy 394.230714 -203.973455)
			(xy 394.172875 -204.000672) (xy 394.112082 -204.020425) (xy 394.049292 -204.032403) (xy 393.985496 -204.036417)
			(xy 393.9217 -204.032403) (xy 393.85891 -204.020425) (xy 393.798117 -204.000672) (xy 393.740278 -203.973455)
			(xy 393.686307 -203.939204) (xy 393.637054 -203.898459) (xy 393.593297 -203.851862) (xy 393.555724 -203.800147)
			(xy 393.52493 -203.744132) (xy 393.501398 -203.684699) (xy 393.485501 -203.622785) (xy 393.47749 -203.559367)
			(xy 381.727602 -203.559367) (xy 381.680189 -203.59859) (xy 381.626218 -203.632841) (xy 381.568379 -203.660058)
			(xy 381.507586 -203.679811) (xy 381.444796 -203.691789) (xy 381.381 -203.695803) (xy 381.317204 -203.691789)
			(xy 381.254414 -203.679811) (xy 381.193621 -203.660058) (xy 381.135782 -203.632841) (xy 381.081811 -203.59859)
			(xy 381.032558 -203.557845) (xy 380.988801 -203.511248) (xy 380.951228 -203.459533) (xy 380.920434 -203.403518)
			(xy 380.896902 -203.344085) (xy 380.881005 -203.282171) (xy 380.872994 -203.218753) (xy 371.752833 -203.218753)
			(xy 372.620032 -204.085952) (xy 374.82094 -204.085952) (xy 374.825011 -204.03033) (xy 374.837137 -203.975893)
			(xy 374.85706 -203.923802) (xy 374.884356 -203.875167) (xy 374.918442 -203.831024) (xy 374.958591 -203.792315)
			(xy 375.003949 -203.759864) (xy 375.053549 -203.734363) (xy 375.106333 -203.716356) (xy 375.161176 -203.706226)
			(xy 375.21691 -203.704189) (xy 375.272347 -203.710289) (xy 375.326304 -203.724395) (xy 375.377633 -203.746207)
			(xy 375.425239 -203.775261) (xy 375.468107 -203.810936) (xy 375.505324 -203.852473) (xy 375.536097 -203.898986)
			(xy 375.559769 -203.949483) (xy 375.575837 -204.00289) (xy 375.583957 -204.058066) (xy 375.584466 -204.085952)
			(xy 375.584465 -204.086) (xy 375.709941 -204.086) (xy 375.713955 -204.022201) (xy 375.725932 -203.959409)
			(xy 375.745685 -203.898612) (xy 375.772902 -203.840771) (xy 375.807153 -203.786796) (xy 375.847898 -203.73754)
			(xy 375.894495 -203.693778) (xy 375.94621 -203.656202) (xy 376.002226 -203.625403) (xy 376.06166 -203.601867)
			(xy 376.123576 -203.585965) (xy 376.186996 -203.577948) (xy 376.218958 -203.577444) (xy 376.250236 -203.577916)
			(xy 376.312322 -203.585575) (xy 376.372999 -203.600794) (xy 376.431349 -203.623344) (xy 376.486492 -203.652883)
			(xy 376.537593 -203.688966) (xy 376.583881 -203.731046) (xy 376.624655 -203.778488) (xy 376.642376 -203.804266)
			(xy 376.649859 -203.814399) (xy 376.671966 -203.8264) (xy 376.68454 -203.827126) (xy 376.769376 -203.827126)
			(xy 376.781952 -203.8264) (xy 376.80407 -203.814409) (xy 376.81154 -203.804266) (xy 376.829249 -203.778481)
			(xy 376.870038 -203.731055) (xy 376.916334 -203.688988) (xy 376.967439 -203.652915) (xy 377.022581 -203.623379)
			(xy 377.080928 -203.600827) (xy 377.1416 -203.585599) (xy 377.203681 -203.577924) (xy 377.234958 -203.577444)
			(xy 377.266919 -203.578018) (xy 377.330338 -203.586025) (xy 377.392253 -203.601918) (xy 377.451687 -203.625445)
			(xy 377.507704 -203.656237) (xy 377.55942 -203.693806) (xy 377.606019 -203.737562) (xy 377.646766 -203.786813)
			(xy 377.681019 -203.840784) (xy 377.708237 -203.898621) (xy 377.727991 -203.959414) (xy 377.73997 -204.022204)
			(xy 377.743981 -204.085952) (xy 377.86894 -204.085952) (xy 377.873011 -204.03033) (xy 377.885137 -203.975893)
			(xy 377.90506 -203.923802) (xy 377.932356 -203.875167) (xy 377.966442 -203.831024) (xy 378.006591 -203.792315)
			(xy 378.051949 -203.759864) (xy 378.101549 -203.734363) (xy 378.154333 -203.716356) (xy 378.209176 -203.706226)
			(xy 378.26491 -203.704189) (xy 378.320347 -203.710289) (xy 378.374304 -203.724395) (xy 378.425633 -203.746207)
			(xy 378.473239 -203.775261) (xy 378.516107 -203.810936) (xy 378.553324 -203.852473) (xy 378.584097 -203.898986)
			(xy 378.607769 -203.949483) (xy 378.623837 -204.00289) (xy 378.631957 -204.058066) (xy 378.632466 -204.085952)
			(xy 378.63235 -204.0923) (xy 379.61007 -204.0923) (xy 379.614085 -204.028499) (xy 379.626064 -203.965705)
			(xy 379.645819 -203.904907) (xy 379.673038 -203.847065) (xy 379.707293 -203.793091) (xy 379.748043 -203.743836)
			(xy 379.794644 -203.700076) (xy 379.846364 -203.662503) (xy 379.902384 -203.631708) (xy 379.961823 -203.608177)
			(xy 380.023742 -203.592282) (xy 380.087165 -203.584273) (xy 380.119128 -203.583794) (xy 380.150231 -203.584273)
			(xy 380.211972 -203.591875) (xy 380.272326 -203.606948) (xy 380.33039 -203.629268) (xy 380.3853 -203.658502)
			(xy 380.436235 -203.694214) (xy 380.482435 -203.735871) (xy 380.503176 -203.759054) (xy 380.509565 -203.765729)
			(xy 380.525829 -203.774463) (xy 380.534926 -203.776072) (xy 380.565152 -203.780136) (xy 380.574178 -203.780993)
			(xy 380.591873 -203.777099) (xy 380.599696 -203.772516) (xy 380.623025 -203.757917) (xy 380.672985 -203.734839)
			(xy 380.725744 -203.719184) (xy 380.780206 -203.711275) (xy 380.807722 -203.710794) (xy 380.834972 -203.711277)
			(xy 380.888918 -203.719036) (xy 380.94121 -203.734393) (xy 380.990785 -203.757036) (xy 381.036633 -203.786503)
			(xy 381.077821 -203.822195) (xy 381.11351 -203.863385) (xy 381.142975 -203.909234) (xy 381.165614 -203.95881)
			(xy 381.180968 -204.011104) (xy 381.188724 -204.06505) (xy 381.188724 -204.117913) (xy 382.568952 -204.117913)
			(xy 382.568952 -204.053991) (xy 382.576963 -203.990573) (xy 382.59286 -203.928659) (xy 382.616392 -203.869226)
			(xy 382.647186 -203.813211) (xy 382.684759 -203.761496) (xy 382.728516 -203.714899) (xy 382.777769 -203.674154)
			(xy 382.83174 -203.639903) (xy 382.889579 -203.612686) (xy 382.950372 -203.592933) (xy 383.013162 -203.580955)
			(xy 383.076958 -203.576942) (xy 383.140754 -203.580955) (xy 383.203544 -203.592933) (xy 383.264337 -203.612686)
			(xy 383.322176 -203.639903) (xy 383.376147 -203.674154) (xy 383.4254 -203.714899) (xy 383.469157 -203.761496)
			(xy 383.50673 -203.813211) (xy 383.537524 -203.869226) (xy 383.561056 -203.928659) (xy 383.576953 -203.990573)
			(xy 383.584964 -204.053991) (xy 383.585466 -204.085952) (xy 383.584964 -204.117913) (xy 383.576953 -204.181331)
			(xy 383.561056 -204.243245) (xy 383.537524 -204.302678) (xy 383.50673 -204.358693) (xy 383.469157 -204.410408)
			(xy 383.4254 -204.457005) (xy 383.376147 -204.49775) (xy 383.322176 -204.532001) (xy 383.264337 -204.559218)
			(xy 383.203544 -204.578971) (xy 383.140754 -204.590949) (xy 383.076958 -204.594963) (xy 383.013162 -204.590949)
			(xy 382.950372 -204.578971) (xy 382.889579 -204.559218) (xy 382.83174 -204.532001) (xy 382.777769 -204.49775)
			(xy 382.728516 -204.457005) (xy 382.684759 -204.410408) (xy 382.647186 -204.358693) (xy 382.616392 -204.302678)
			(xy 382.59286 -204.243245) (xy 382.576963 -204.181331) (xy 382.568952 -204.117913) (xy 381.188724 -204.117913)
			(xy 381.188724 -204.11955) (xy 381.180968 -204.173496) (xy 381.165614 -204.22579) (xy 381.142975 -204.275366)
			(xy 381.11351 -204.321215) (xy 381.077821 -204.362405) (xy 381.036633 -204.398097) (xy 380.990785 -204.427564)
			(xy 380.94121 -204.450207) (xy 380.888918 -204.465564) (xy 380.834972 -204.473323) (xy 380.807722 -204.47381)
			(xy 380.780206 -204.473335) (xy 380.725745 -204.465419) (xy 380.672986 -204.449762) (xy 380.623024 -204.42669)
			(xy 380.599696 -204.412088) (xy 380.591893 -204.407454) (xy 380.574182 -204.403557) (xy 380.565152 -204.404468)
			(xy 380.534926 -204.408532) (xy 380.525811 -204.410091) (xy 380.509528 -204.418828) (xy 380.503176 -204.42555)
			(xy 380.482455 -204.448753) (xy 380.43626 -204.490423) (xy 380.385326 -204.526144) (xy 380.330413 -204.555382)
			(xy 380.272342 -204.577699) (xy 380.211982 -204.592762) (xy 380.150234 -204.600346) (xy 380.119128 -204.60081)
			(xy 380.087165 -204.600327) (xy 380.023742 -204.592318) (xy 379.961823 -204.576423) (xy 379.902384 -204.552892)
			(xy 379.846364 -204.522097) (xy 379.794644 -204.484524) (xy 379.748043 -204.440764) (xy 379.707293 -204.391509)
			(xy 379.673038 -204.337535) (xy 379.645819 -204.279693) (xy 379.626064 -204.218895) (xy 379.614085 -204.156101)
			(xy 379.61007 -204.0923) (xy 378.63235 -204.0923) (xy 378.631957 -204.113838) (xy 378.623837 -204.169014)
			(xy 378.607769 -204.222421) (xy 378.584097 -204.272918) (xy 378.553324 -204.319431) (xy 378.516107 -204.360968)
			(xy 378.473239 -204.396643) (xy 378.425633 -204.425697) (xy 378.374304 -204.447509) (xy 378.320347 -204.461615)
			(xy 378.26491 -204.467715) (xy 378.209176 -204.465678) (xy 378.154333 -204.455548) (xy 378.101549 -204.437541)
			(xy 378.051949 -204.41204) (xy 378.006591 -204.379589) (xy 377.966442 -204.34088) (xy 377.932356 -204.296737)
			(xy 377.90506 -204.248102) (xy 377.885137 -204.196011) (xy 377.873011 -204.141574) (xy 377.86894 -204.085952)
			(xy 377.743981 -204.085952) (xy 377.743984 -204.086) (xy 377.73997 -204.149796) (xy 377.727991 -204.212586)
			(xy 377.708237 -204.273379) (xy 377.681019 -204.331216) (xy 377.646766 -204.385187) (xy 377.606019 -204.434438)
			(xy 377.55942 -204.478194) (xy 377.507704 -204.515763) (xy 377.451687 -204.546555) (xy 377.392253 -204.570082)
			(xy 377.330338 -204.585975) (xy 377.266919 -204.593982) (xy 377.234958 -204.59446) (xy 377.20368 -204.593974)
			(xy 377.141595 -204.586317) (xy 377.080919 -204.5711) (xy 377.022569 -204.548552) (xy 376.967426 -204.519015)
			(xy 376.916324 -204.482934) (xy 376.870036 -204.440856) (xy 376.829262 -204.393415) (xy 376.81154 -204.367638)
			(xy 376.804048 -204.357513) (xy 376.781948 -204.345507) (xy 376.769376 -204.344778) (xy 376.68454 -204.344778)
			(xy 376.671965 -204.345512) (xy 376.649847 -204.357497) (xy 376.642376 -204.367638) (xy 376.624658 -204.393416)
			(xy 376.58387 -204.440842) (xy 376.537575 -204.482909) (xy 376.486472 -204.518983) (xy 376.431331 -204.54852)
			(xy 376.372985 -204.571073) (xy 376.312315 -204.586302) (xy 376.250234 -204.593979) (xy 376.218958 -204.59446)
			(xy 376.186996 -204.594052) (xy 376.123576 -204.586035) (xy 376.06166 -204.570133) (xy 376.002226 -204.546597)
			(xy 375.94621 -204.515798) (xy 375.894495 -204.478222) (xy 375.847898 -204.43446) (xy 375.807153 -204.385204)
			(xy 375.772902 -204.331229) (xy 375.745685 -204.273388) (xy 375.725932 -204.212591) (xy 375.713955 -204.149799)
			(xy 375.709941 -204.086) (xy 375.584465 -204.086) (xy 375.583957 -204.113838) (xy 375.575837 -204.169014)
			(xy 375.559769 -204.222421) (xy 375.536097 -204.272918) (xy 375.505324 -204.319431) (xy 375.468107 -204.360968)
			(xy 375.425239 -204.396643) (xy 375.377633 -204.425697) (xy 375.326304 -204.447509) (xy 375.272347 -204.461615)
			(xy 375.21691 -204.467715) (xy 375.161176 -204.465678) (xy 375.106333 -204.455548) (xy 375.053549 -204.437541)
			(xy 375.003949 -204.41204) (xy 374.958591 -204.379589) (xy 374.918442 -204.34088) (xy 374.884356 -204.296737)
			(xy 374.85706 -204.248102) (xy 374.837137 -204.196011) (xy 374.825011 -204.141574) (xy 374.82094 -204.085952)
			(xy 372.620032 -204.085952) (xy 374.772174 -206.238094) (xy 374.779024 -206.245491) (xy 374.786765 -206.264089)
			(xy 374.78716 -206.274162) (xy 374.78716 -206.4258) (xy 374.791478 -206.435452) (xy 374.803442 -206.463432)
			(xy 374.821371 -206.521585) (xy 374.832233 -206.581462) (xy 374.8349 -206.626) (xy 375.582941 -206.626)
			(xy 375.586955 -206.562201) (xy 375.598932 -206.499409) (xy 375.618685 -206.438612) (xy 375.645902 -206.380771)
			(xy 375.680153 -206.326796) (xy 375.720898 -206.27754) (xy 375.767495 -206.233778) (xy 375.81921 -206.196202)
			(xy 375.875226 -206.165403) (xy 375.93466 -206.141867) (xy 375.996576 -206.125965) (xy 376.059996 -206.117948)
			(xy 376.091958 -206.117444) (xy 376.12682 -206.11801) (xy 376.195888 -206.127542) (xy 376.263007 -206.146421)
			(xy 376.326918 -206.174292) (xy 376.386422 -206.210632) (xy 376.413776 -206.232252) (xy 376.422158 -206.23911)
			(xy 376.442224 -206.244698) (xy 376.537728 -206.230982) (xy 376.555762 -206.22006) (xy 376.561858 -206.21117)
			(xy 376.57968 -206.186038) (xy 376.620419 -206.139817) (xy 376.666447 -206.098861) (xy 376.717088 -206.063768)
			(xy 376.7716 -206.035055) (xy 376.829183 -206.013142) (xy 376.888993 -205.99835) (xy 376.950152 -205.990897)
			(xy 376.980958 -205.990444) (xy 377.012919 -205.991018) (xy 377.076338 -205.999025) (xy 377.138253 -206.014918)
			(xy 377.197687 -206.038445) (xy 377.253704 -206.069237) (xy 377.30542 -206.106806) (xy 377.352019 -206.150562)
			(xy 377.392766 -206.199813) (xy 377.427019 -206.253784) (xy 377.454237 -206.311621) (xy 377.473991 -206.372414)
			(xy 377.48597 -206.435204) (xy 377.489984 -206.499) (xy 377.48597 -206.562796) (xy 377.473991 -206.625586)
			(xy 377.454237 -206.686379) (xy 377.427019 -206.744216) (xy 377.392766 -206.798187) (xy 377.352019 -206.847438)
			(xy 377.30542 -206.891194) (xy 377.253704 -206.928763) (xy 377.197687 -206.959555) (xy 377.138253 -206.983082)
			(xy 377.076338 -206.998975) (xy 377.012919 -207.006982) (xy 376.980958 -207.00746) (xy 376.946097 -207.006885)
			(xy 376.877029 -206.997354) (xy 376.80991 -206.978478) (xy 376.745999 -206.950609) (xy 376.686494 -206.914271)
			(xy 376.65914 -206.892652) (xy 376.650758 -206.885794) (xy 376.630692 -206.880206) (xy 376.535188 -206.893922)
			(xy 376.517154 -206.904844) (xy 376.511058 -206.913734) (xy 376.493291 -206.938906) (xy 376.452544 -206.985126)
			(xy 376.406508 -207.02608) (xy 376.355858 -207.061169) (xy 376.301339 -207.089877) (xy 376.243748 -207.111784)
			(xy 376.183931 -207.126568) (xy 376.122766 -207.134012) (xy 376.091958 -207.13446) (xy 376.059996 -207.134052)
			(xy 375.996576 -207.126035) (xy 375.93466 -207.110133) (xy 375.875226 -207.086597) (xy 375.81921 -207.055798)
			(xy 375.767495 -207.018222) (xy 375.720898 -206.97446) (xy 375.680153 -206.925204) (xy 375.645902 -206.871229)
			(xy 375.618685 -206.813388) (xy 375.598932 -206.752591) (xy 375.586955 -206.689799) (xy 375.582941 -206.626)
			(xy 374.8349 -206.626) (xy 374.83587 -206.642207) (xy 374.832231 -206.702953) (xy 374.821368 -206.762829)
			(xy 374.803437 -206.820982) (xy 374.791478 -206.848964) (xy 374.78716 -206.858616) (xy 374.78716 -207.081628)
			(xy 374.78725 -207.086648) (xy 374.789164 -207.096502) (xy 374.79097 -207.101186) (xy 374.801892 -207.127094)
			(xy 374.808496 -207.133952) (xy 374.830489 -207.157687) (xy 374.868914 -207.20975) (xy 374.900426 -207.266267)
			(xy 374.924517 -207.326323) (xy 374.940797 -207.388949) (xy 374.949004 -207.453134) (xy 374.949466 -207.485488)
			(xy 374.948927 -207.518615) (xy 374.948575 -207.521302) (xy 375.07494 -207.521302) (xy 375.079011 -207.46568)
			(xy 375.091137 -207.411243) (xy 375.11106 -207.359152) (xy 375.138356 -207.310517) (xy 375.172442 -207.266374)
			(xy 375.212591 -207.227665) (xy 375.257949 -207.195214) (xy 375.307549 -207.169713) (xy 375.360333 -207.151706)
			(xy 375.415176 -207.141576) (xy 375.47091 -207.139539) (xy 375.526347 -207.145639) (xy 375.580304 -207.159745)
			(xy 375.631633 -207.181557) (xy 375.679239 -207.210611) (xy 375.722107 -207.246286) (xy 375.759324 -207.287823)
			(xy 375.790097 -207.334336) (xy 375.813769 -207.384833) (xy 375.829837 -207.43824) (xy 375.832978 -207.45958)
			(xy 377.423934 -207.45958) (xy 377.424504 -207.426563) (xy 377.433054 -207.361086) (xy 377.450007 -207.297266)
			(xy 377.475079 -207.236177) (xy 377.507848 -207.178847) (xy 377.547761 -207.126242) (xy 377.594148 -207.079245)
			(xy 377.646228 -207.038649) (xy 377.703125 -207.005135) (xy 377.763881 -206.979267) (xy 377.795536 -206.969868)
			(xy 377.807982 -206.966312) (xy 377.826016 -206.94904) (xy 377.86056 -206.8449) (xy 377.856496 -206.820008)
			(xy 377.848622 -206.809848) (xy 377.8286 -206.783027) (xy 377.794958 -206.725166) (xy 377.769202 -206.66339)
			(xy 377.751778 -206.598767) (xy 377.742986 -206.532417) (xy 377.74245 -206.498952) (xy 377.742952 -206.466991)
			(xy 377.750963 -206.403573) (xy 377.76686 -206.341659) (xy 377.790392 -206.282226) (xy 377.821186 -206.226211)
			(xy 377.858759 -206.174496) (xy 377.902516 -206.127899) (xy 377.951769 -206.087154) (xy 378.00574 -206.052903)
			(xy 378.063579 -206.025686) (xy 378.124372 -206.005933) (xy 378.187162 -205.993955) (xy 378.250958 -205.989942)
			(xy 378.314754 -205.993955) (xy 378.377544 -206.005933) (xy 378.438337 -206.025686) (xy 378.496176 -206.052903)
			(xy 378.550147 -206.087154) (xy 378.5994 -206.127899) (xy 378.643157 -206.174496) (xy 378.68073 -206.226211)
			(xy 378.711524 -206.282226) (xy 378.735056 -206.341659) (xy 378.750953 -206.403573) (xy 378.758964 -206.466991)
			(xy 378.759466 -206.498952) (xy 378.758925 -206.53197) (xy 378.750371 -206.597448) (xy 378.733414 -206.661269)
			(xy 378.708338 -206.722358) (xy 378.675566 -206.779688) (xy 378.63565 -206.832293) (xy 378.58926 -206.879289)
			(xy 378.537177 -206.919885) (xy 378.480278 -206.953398) (xy 378.41952 -206.979265) (xy 378.387864 -206.988664)
			(xy 378.375418 -206.99222) (xy 378.357384 -207.009492) (xy 378.32284 -207.113632) (xy 378.326904 -207.138524)
			(xy 378.334778 -207.148684) (xy 378.354815 -207.175494) (xy 378.388454 -207.233358) (xy 378.414207 -207.295137)
			(xy 378.431628 -207.359762) (xy 378.440416 -207.426114) (xy 378.44095 -207.45958) (xy 378.440448 -207.491541)
			(xy 378.440128 -207.494077) (xy 380.155978 -207.494077) (xy 380.16373 -207.44013) (xy 380.179081 -207.387836)
			(xy 380.201717 -207.338258) (xy 380.231178 -207.292407) (xy 380.266865 -207.251214) (xy 380.308051 -207.21552)
			(xy 380.353897 -207.18605) (xy 380.403471 -207.163405) (xy 380.455762 -207.148045) (xy 380.509708 -207.140283)
			(xy 380.536958 -207.139794) (xy 380.543054 -207.139794) (xy 380.556262 -207.140048) (xy 380.578868 -207.128364)
			(xy 380.641098 -207.036162) (xy 380.643384 -207.010762) (xy 380.638558 -206.998824) (xy 380.625961 -206.967506)
			(xy 380.608214 -206.902377) (xy 380.599247 -206.835472) (xy 380.59868 -206.80172) (xy 380.599139 -206.770319)
			(xy 380.606859 -206.707993) (xy 380.622197 -206.647093) (xy 380.644919 -206.588546) (xy 380.674679 -206.533243)
			(xy 380.711024 -206.482026) (xy 380.753401 -206.435676) (xy 380.801163 -206.394899) (xy 380.853584 -206.360314)
			(xy 380.909866 -206.332449) (xy 380.969152 -206.311729) (xy 380.999746 -206.304642) (xy 381.008357 -206.302352)
			(xy 381.02343 -206.29288) (xy 381.02921 -206.2861) (xy 381.047752 -206.26197) (xy 381.052783 -206.254755)
			(xy 381.058103 -206.238) (xy 381.058166 -206.229204) (xy 381.057912 -206.215488) (xy 381.05832 -206.190884)
			(xy 381.064692 -206.14209) (xy 381.070612 -206.118206) (xy 381.073152 -206.1083) (xy 381.070358 -206.088234)
			(xy 381.023876 -206.008732) (xy 381.007874 -205.99654) (xy 380.997968 -205.994) (xy 380.965752 -205.985037)
			(xy 380.903856 -205.959728) (xy 380.84581 -205.926525) (xy 380.792615 -205.886002) (xy 380.74519 -205.838858)
			(xy 380.704352 -205.785905) (xy 380.670805 -205.728057) (xy 380.645129 -205.666312) (xy 380.627766 -205.601734)
			(xy 380.619016 -205.535438) (xy 380.618492 -205.502002) (xy 380.618994 -205.470041) (xy 380.627005 -205.406623)
			(xy 380.642902 -205.344709) (xy 380.666434 -205.285276) (xy 380.697228 -205.229261) (xy 380.734801 -205.177546)
			(xy 380.778558 -205.130949) (xy 380.827811 -205.090204) (xy 380.881782 -205.055953) (xy 380.939621 -205.028736)
			(xy 381.000414 -205.008983) (xy 381.063204 -204.997005) (xy 381.127 -204.992992) (xy 381.190796 -204.997005)
			(xy 381.253586 -205.008983) (xy 381.314379 -205.028736) (xy 381.372218 -205.055953) (xy 381.426189 -205.090204)
			(xy 381.427135 -205.090987) (xy 390.644882 -205.090987) (xy 390.644882 -205.027065) (xy 390.652893 -204.963647)
			(xy 390.66879 -204.901733) (xy 390.692322 -204.8423) (xy 390.723116 -204.786285) (xy 390.760689 -204.73457)
			(xy 390.804446 -204.687973) (xy 390.853699 -204.647228) (xy 390.90767 -204.612977) (xy 390.965509 -204.58576)
			(xy 391.026302 -204.566007) (xy 391.089092 -204.554029) (xy 391.152888 -204.550016) (xy 391.216684 -204.554029)
			(xy 391.279474 -204.566007) (xy 391.340267 -204.58576) (xy 391.398106 -204.612977) (xy 391.452077 -204.647228)
			(xy 391.50133 -204.687973) (xy 391.545087 -204.73457) (xy 391.58266 -204.786285) (xy 391.613454 -204.8423)
			(xy 391.636986 -204.901733) (xy 391.652883 -204.963647) (xy 391.660894 -205.027065) (xy 391.661196 -205.0463)
			(xy 392.571515 -205.0463) (xy 392.575529 -204.982508) (xy 392.587506 -204.919722) (xy 392.607258 -204.858932)
			(xy 392.634473 -204.801097) (xy 392.668721 -204.747128) (xy 392.709464 -204.697878) (xy 392.756058 -204.654123)
			(xy 392.807769 -204.616552) (xy 392.863781 -204.585759) (xy 392.923211 -204.562228) (xy 392.985121 -204.546332)
			(xy 393.048535 -204.53832) (xy 393.080494 -204.537818) (xy 393.113214 -204.538283) (xy 393.178112 -204.546685)
			(xy 393.241398 -204.563338) (xy 393.302027 -204.587967) (xy 393.358997 -204.620165) (xy 393.41137 -204.659402)
			(xy 393.458279 -204.70503) (xy 393.498952 -204.756295) (xy 393.532717 -204.812352) (xy 393.54633 -204.84211)
			(xy 393.552426 -204.85608) (xy 393.577572 -204.87259) (xy 393.701016 -204.87259) (xy 393.726162 -204.85608)
			(xy 393.732258 -204.84211) (xy 393.745871 -204.812354) (xy 393.779637 -204.756303) (xy 393.820311 -204.705043)
			(xy 393.867222 -204.659422) (xy 393.919596 -204.620193) (xy 393.976567 -204.588003) (xy 394.037195 -204.563384)
			(xy 394.10048 -204.546742) (xy 394.165376 -204.538351) (xy 394.230812 -204.538351) (xy 394.295708 -204.546742)
			(xy 394.358993 -204.563384) (xy 394.419621 -204.588003) (xy 394.476592 -204.620193) (xy 394.528966 -204.659422)
			(xy 394.575877 -204.705043) (xy 394.616551 -204.756303) (xy 394.650317 -204.812354) (xy 394.66393 -204.84211)
			(xy 394.670026 -204.85608) (xy 394.695172 -204.87259) (xy 394.818616 -204.87259) (xy 394.843762 -204.85608)
			(xy 394.849858 -204.84211) (xy 394.863492 -204.812363) (xy 394.897251 -204.756306) (xy 394.937919 -204.705041)
			(xy 394.984826 -204.659415) (xy 395.037197 -204.62018) (xy 395.094166 -204.587986) (xy 395.154794 -204.563362)
			(xy 395.218079 -204.546717) (xy 395.282975 -204.538325) (xy 395.315694 -204.537818) (xy 395.347658 -204.538247)
			(xy 395.411083 -204.546258) (xy 395.473003 -204.562156) (xy 395.532442 -204.585689) (xy 395.588463 -204.616486)
			(xy 395.640183 -204.654062) (xy 395.686785 -204.697824) (xy 395.727535 -204.747082) (xy 395.76179 -204.801058)
			(xy 395.789009 -204.858902) (xy 395.808764 -204.919702) (xy 395.820743 -204.982498) (xy 395.824758 -205.0463)
			(xy 395.820743 -205.110102) (xy 395.808764 -205.172898) (xy 395.789009 -205.233698) (xy 395.76179 -205.291542)
			(xy 395.727535 -205.345518) (xy 395.686785 -205.394776) (xy 395.640183 -205.438538) (xy 395.588463 -205.476114)
			(xy 395.532442 -205.506911) (xy 395.473003 -205.530444) (xy 395.411083 -205.546342) (xy 395.347658 -205.554353)
			(xy 395.315694 -205.554834) (xy 395.282975 -205.554348) (xy 395.218079 -205.545946) (xy 395.154795 -205.529294)
			(xy 395.094168 -205.504666) (xy 395.037198 -205.47247) (xy 394.984826 -205.433236) (xy 394.937915 -205.387612)
			(xy 394.897241 -205.336351) (xy 394.863473 -205.280298) (xy 394.849858 -205.250542) (xy 394.843762 -205.236572)
			(xy 394.818616 -205.220062) (xy 394.695172 -205.220062) (xy 394.670026 -205.236572) (xy 394.66393 -205.250542)
			(xy 394.650317 -205.280298) (xy 394.616551 -205.336349) (xy 394.575877 -205.387609) (xy 394.528966 -205.43323)
			(xy 394.476592 -205.472459) (xy 394.419621 -205.504649) (xy 394.358993 -205.529268) (xy 394.295708 -205.54591)
			(xy 394.230812 -205.554301) (xy 394.165376 -205.554301) (xy 394.10048 -205.54591) (xy 394.037195 -205.529268)
			(xy 393.976567 -205.504649) (xy 393.919596 -205.472459) (xy 393.867222 -205.43323) (xy 393.820311 -205.387609)
			(xy 393.779637 -205.336349) (xy 393.745871 -205.280298) (xy 393.732258 -205.250542) (xy 393.726162 -205.236572)
			(xy 393.701016 -205.220062) (xy 393.577572 -205.220062) (xy 393.552426 -205.236572) (xy 393.54633 -205.250542)
			(xy 393.532682 -205.280283) (xy 393.498927 -205.336342) (xy 393.458262 -205.387608) (xy 393.411357 -205.433236)
			(xy 393.358988 -205.472472) (xy 393.30202 -205.504668) (xy 393.241393 -205.529291) (xy 393.178109 -205.545936)
			(xy 393.113212 -205.554328) (xy 393.080494 -205.554834) (xy 393.048535 -205.55428) (xy 392.985121 -205.546268)
			(xy 392.923211 -205.530372) (xy 392.863781 -205.506841) (xy 392.807769 -205.476048) (xy 392.756058 -205.438477)
			(xy 392.709464 -205.394722) (xy 392.668721 -205.345472) (xy 392.634473 -205.291503) (xy 392.607258 -205.233668)
			(xy 392.587506 -205.172878) (xy 392.575529 -205.110092) (xy 392.571515 -205.0463) (xy 391.661196 -205.0463)
			(xy 391.661396 -205.059026) (xy 391.660894 -205.090987) (xy 391.652883 -205.154405) (xy 391.636986 -205.216319)
			(xy 391.613454 -205.275752) (xy 391.58266 -205.331767) (xy 391.545087 -205.383482) (xy 391.50133 -205.430079)
			(xy 391.452077 -205.470824) (xy 391.398106 -205.505075) (xy 391.340267 -205.532292) (xy 391.279474 -205.552045)
			(xy 391.216684 -205.564023) (xy 391.152888 -205.568037) (xy 391.089092 -205.564023) (xy 391.026302 -205.552045)
			(xy 390.965509 -205.532292) (xy 390.90767 -205.505075) (xy 390.853699 -205.470824) (xy 390.804446 -205.430079)
			(xy 390.760689 -205.383482) (xy 390.723116 -205.331767) (xy 390.692322 -205.275752) (xy 390.66879 -205.216319)
			(xy 390.652893 -205.154405) (xy 390.644882 -205.090987) (xy 381.427135 -205.090987) (xy 381.475442 -205.130949)
			(xy 381.519199 -205.177546) (xy 381.556772 -205.229261) (xy 381.587566 -205.285276) (xy 381.611098 -205.344709)
			(xy 381.626995 -205.406623) (xy 381.635006 -205.470041) (xy 381.635508 -205.502002) (xy 381.635008 -205.533083)
			(xy 381.627396 -205.594778) (xy 381.612323 -205.655086) (xy 381.590013 -205.713108) (xy 381.575818 -205.740762)
			(xy 381.571246 -205.749906) (xy 381.569214 -205.769972) (xy 381.596138 -205.85811) (xy 381.609092 -205.873604)
			(xy 381.617982 -205.87843) (xy 381.643841 -205.892728) (xy 381.691171 -205.9281) (xy 381.732481 -205.970348)
			(xy 381.766781 -206.01846) (xy 381.793251 -206.071287) (xy 381.811259 -206.127564) (xy 381.820372 -206.185944)
			(xy 381.820928 -206.215488) (xy 381.820382 -206.244589) (xy 381.811548 -206.302118) (xy 381.794084 -206.357639)
			(xy 381.768393 -206.409865) (xy 381.735072 -206.457585) (xy 381.694893 -206.499695) (xy 381.648787 -206.535217)
			(xy 381.62357 -206.549752) (xy 381.616035 -206.554286) (xy 381.604338 -206.567396) (xy 381.60071 -206.575406)
			(xy 381.589788 -206.6036) (xy 381.586757 -206.612066) (xy 381.586234 -206.630026) (xy 381.588772 -206.638652)
			(xy 381.597316 -206.664979) (xy 381.609282 -206.719022) (xy 381.615316 -206.774044) (xy 381.615696 -206.80172)
			(xy 381.61533 -206.828662) (xy 381.609601 -206.882242) (xy 381.604266 -206.908654) (xy 381.603744 -206.9112)
			(xy 383.097283 -206.9112) (xy 383.101297 -206.847404) (xy 383.113275 -206.784614) (xy 383.133028 -206.72382)
			(xy 383.160245 -206.665981) (xy 383.194496 -206.61201) (xy 383.235241 -206.562756) (xy 383.281838 -206.518998)
			(xy 383.333552 -206.481425) (xy 383.389567 -206.45063) (xy 383.449001 -206.427098) (xy 383.510915 -206.411201)
			(xy 383.574333 -206.403188) (xy 383.606294 -206.402686) (xy 383.637536 -206.403702) (xy 383.646471 -206.403878)
			(xy 383.663587 -206.398778) (xy 383.677918 -206.388121) (xy 383.68773 -206.373198) (xy 383.690114 -206.364586)
			(xy 383.697941 -206.333563) (xy 383.720389 -206.273648) (xy 383.750182 -206.217025) (xy 383.786849 -206.164591)
			(xy 383.80797 -206.140558) (xy 383.81432 -206.133446) (xy 383.821178 -206.115666) (xy 383.82067 -206.028036)
			(xy 383.813558 -206.01051) (xy 383.807208 -206.003398) (xy 383.786116 -205.979861) (xy 383.749329 -205.928467)
			(xy 383.719197 -205.872909) (xy 383.696182 -205.814046) (xy 383.68064 -205.752784) (xy 383.672811 -205.690067)
			(xy 383.672334 -205.658466) (xy 383.672836 -205.626505) (xy 383.680847 -205.563087) (xy 383.696744 -205.501173)
			(xy 383.720276 -205.44174) (xy 383.75107 -205.385725) (xy 383.788643 -205.33401) (xy 383.8324 -205.287413)
			(xy 383.881653 -205.246668) (xy 383.935624 -205.212417) (xy 383.993463 -205.1852) (xy 384.054256 -205.165447)
			(xy 384.117046 -205.153469) (xy 384.180842 -205.149456) (xy 384.244638 -205.153469) (xy 384.307428 -205.165447)
			(xy 384.368221 -205.1852) (xy 384.42606 -205.212417) (xy 384.480031 -205.246668) (xy 384.529284 -205.287413)
			(xy 384.573041 -205.33401) (xy 384.610614 -205.385725) (xy 384.641408 -205.44174) (xy 384.66494 -205.501173)
			(xy 384.680837 -205.563087) (xy 384.688848 -205.626505) (xy 384.68935 -205.658466) (xy 384.688851 -205.689642)
			(xy 384.681215 -205.751524) (xy 384.666065 -205.812008) (xy 384.643631 -205.870183) (xy 384.614247 -205.925178)
			(xy 384.578357 -205.976164) (xy 384.557778 -205.999588) (xy 384.551428 -206.0067) (xy 384.54457 -206.02448)
			(xy 384.545078 -206.11211) (xy 384.55219 -206.129636) (xy 384.55854 -206.136748) (xy 384.581185 -206.162077)
			(xy 384.620232 -206.217678) (xy 384.651535 -206.277979) (xy 384.674539 -206.341908) (xy 384.682238 -206.375)
			(xy 384.68427 -206.384652) (xy 384.694938 -206.400908) (xy 384.769106 -206.451454) (xy 384.787902 -206.455772)
			(xy 384.797808 -206.453994) (xy 384.812944 -206.451714) (xy 384.843461 -206.449299) (xy 384.858768 -206.449168)
			(xy 384.86334 -206.449168) (xy 384.876294 -206.449422) (xy 384.8989 -206.437484) (xy 384.960876 -206.34579)
			(xy 384.963162 -206.32039) (xy 384.958336 -206.308452) (xy 384.945861 -206.277285) (xy 384.928332 -206.212481)
			(xy 384.919499 -206.145931) (xy 384.918966 -206.112364) (xy 384.919506 -206.080825) (xy 384.927312 -206.018233)
			(xy 384.942801 -205.957087) (xy 384.965734 -205.898326) (xy 384.99576 -205.842853) (xy 385.032416 -205.79152)
			(xy 385.07514 -205.745116) (xy 385.123276 -205.704352) (xy 385.176085 -205.669856) (xy 385.232755 -205.642156)
			(xy 385.292416 -205.621679) (xy 385.354152 -205.608738) (xy 385.417014 -205.603534) (xy 385.480037 -205.606144)
			(xy 385.542254 -205.61653) (xy 385.602707 -205.634532) (xy 385.66047 -205.659874) (xy 385.714655 -205.692166)
			(xy 385.76443 -205.730912) (xy 385.809029 -205.775517) (xy 385.847769 -205.825296) (xy 385.880054 -205.879485)
			(xy 385.905389 -205.937251) (xy 385.923384 -205.997707) (xy 385.933762 -206.059925) (xy 385.936365 -206.122948)
			(xy 385.931153 -206.18581) (xy 385.918205 -206.247544) (xy 385.89772 -206.307202) (xy 385.870014 -206.363869)
			(xy 385.835511 -206.416673) (xy 385.794741 -206.464804) (xy 385.748331 -206.507523) (xy 385.696994 -206.544173)
			(xy 385.641518 -206.574192) (xy 385.582754 -206.597118) (xy 385.521606 -206.612599) (xy 385.459013 -206.620398)
			(xy 385.427474 -206.620872) (xy 385.406549 -206.620661) (xy 385.364839 -206.617231) (xy 385.344162 -206.614014)
			(xy 385.331462 -206.611982) (xy 385.307332 -206.62011) (xy 385.232148 -206.70139) (xy 385.225798 -206.726282)
			(xy 385.2291 -206.738728) (xy 385.234334 -206.761354) (xy 385.239944 -206.807455) (xy 385.240276 -206.830676)
			(xy 385.239822 -206.85793) (xy 385.232068 -206.911883) (xy 385.216713 -206.964183) (xy 385.194071 -207.013765)
			(xy 385.164603 -207.05962) (xy 385.128908 -207.100813) (xy 385.087713 -207.136507) (xy 385.041858 -207.165975)
			(xy 384.992275 -207.188616) (xy 384.939975 -207.203969) (xy 384.886022 -207.211723) (xy 384.858768 -207.212184)
			(xy 384.832126 -207.211737) (xy 384.779358 -207.204343) (xy 384.728133 -207.189676) (xy 384.679448 -207.168021)
			(xy 384.634252 -207.139801) (xy 384.593424 -207.105563) (xy 384.557759 -207.065976) (xy 384.527951 -207.02181)
			(xy 384.515868 -206.998062) (xy 384.51155 -206.989172) (xy 384.497326 -206.976218) (xy 384.413252 -206.944976)
			(xy 384.393948 -206.945484) (xy 384.384804 -206.949294) (xy 384.353082 -206.962225) (xy 384.287042 -206.980432)
			(xy 384.219158 -206.989625) (xy 384.184906 -206.990188) (xy 384.153664 -206.989172) (xy 384.14473 -206.989016)
			(xy 384.127618 -206.994113) (xy 384.113288 -207.004763) (xy 384.103474 -207.019679) (xy 384.101086 -207.028288)
			(xy 384.093494 -207.058291) (xy 384.072047 -207.116346) (xy 384.043711 -207.171368) (xy 384.008906 -207.222544)
			(xy 383.968145 -207.269116) (xy 383.922033 -207.310395) (xy 383.87125 -207.345771) (xy 383.816548 -207.374722)
			(xy 383.758737 -207.396817) (xy 383.698671 -207.411731) (xy 383.637239 -207.419244) (xy 383.606294 -207.419702)
			(xy 383.574333 -207.419212) (xy 383.510915 -207.411199) (xy 383.449001 -207.395302) (xy 383.389567 -207.37177)
			(xy 383.333552 -207.340975) (xy 383.281838 -207.303402) (xy 383.235241 -207.259644) (xy 383.194496 -207.21039)
			(xy 383.160245 -207.156419) (xy 383.133028 -207.09858) (xy 383.113275 -207.037786) (xy 383.101297 -206.974996)
			(xy 383.097283 -206.9112) (xy 381.603744 -206.9112) (xy 381.602234 -206.91856) (xy 381.605536 -206.93761)
			(xy 381.653288 -207.014572) (xy 381.668782 -207.026002) (xy 381.678434 -207.028542) (xy 381.708198 -207.03657)
			(xy 381.765656 -207.05891) (xy 381.819989 -207.088039) (xy 381.870397 -207.123529) (xy 381.893572 -207.143858)
			(xy 381.900452 -207.149559) (xy 381.917042 -207.156169) (xy 381.934893 -207.156709) (xy 381.951852 -207.151114)
			(xy 381.959104 -207.14589) (xy 381.986148 -207.125317) (xy 382.044634 -207.090723) (xy 382.107203 -207.064223)
			(xy 382.172744 -207.046288) (xy 382.240089 -207.037237) (xy 382.274064 -207.03667) (xy 382.306026 -207.037193)
			(xy 382.369448 -207.045201) (xy 382.431365 -207.061094) (xy 382.490802 -207.084623) (xy 382.546821 -207.115417)
			(xy 382.598539 -207.152989) (xy 382.64514 -207.196746) (xy 382.685889 -207.246) (xy 382.720143 -207.299973)
			(xy 382.747362 -207.357813) (xy 382.767117 -207.418609) (xy 382.779095 -207.481401) (xy 382.78311 -207.5452)
			(xy 382.779095 -207.608999) (xy 382.767117 -207.671791) (xy 382.747362 -207.732587) (xy 382.720143 -207.790427)
			(xy 382.685889 -207.8444) (xy 382.64514 -207.893654) (xy 382.598539 -207.937411) (xy 382.546821 -207.974983)
			(xy 382.490802 -208.005777) (xy 382.431365 -208.029306) (xy 382.369448 -208.045199) (xy 382.306026 -208.053207)
			(xy 382.274064 -208.053686) (xy 382.242948 -208.053213) (xy 382.181187 -208.045576) (xy 382.120817 -208.030469)
			(xy 382.062737 -208.008117) (xy 382.007815 -207.978854) (xy 381.956868 -207.943116) (xy 381.93345 -207.922622)
			(xy 381.926581 -207.916896) (xy 381.909983 -207.910266) (xy 381.892117 -207.909719) (xy 381.875144 -207.915321)
			(xy 381.867918 -207.92059) (xy 381.840897 -207.941196) (xy 381.782406 -207.975785) (xy 381.71983 -208.002279)
			(xy 381.654284 -208.020206) (xy 381.586935 -208.029248) (xy 381.552958 -208.02981) (xy 381.522226 -208.029384)
			(xy 381.461211 -208.021971) (xy 381.401534 -208.007257) (xy 381.344066 -207.985458) (xy 381.289644 -207.956892)
			(xy 381.239062 -207.921974) (xy 381.193058 -207.881214) (xy 381.152302 -207.835206) (xy 381.117388 -207.784621)
			(xy 381.088825 -207.730197) (xy 381.067031 -207.672727) (xy 381.052322 -207.613049) (xy 381.044914 -207.552034)
			(xy 381.04445 -207.521302) (xy 381.044821 -207.49436) (xy 381.050547 -207.44078) (xy 381.05588 -207.414368)
			(xy 381.057912 -207.404462) (xy 381.05461 -207.385412) (xy 381.006858 -207.30845) (xy 380.991364 -207.29702)
			(xy 380.981712 -207.29448) (xy 380.941326 -207.282542) (xy 380.931694 -207.27984) (xy 380.911759 -207.281102)
			(xy 380.893822 -207.289895) (xy 380.880614 -207.30488) (xy 380.874143 -207.323779) (xy 380.875395 -207.343716)
			(xy 380.87935 -207.3529) (xy 380.89168 -207.379243) (xy 380.909098 -207.434734) (xy 380.917916 -207.492222)
			(xy 380.918466 -207.521302) (xy 380.91802 -207.548552) (xy 380.910264 -207.602499) (xy 380.894909 -207.654792)
			(xy 380.872269 -207.704368) (xy 380.842804 -207.750217) (xy 380.807114 -207.791406) (xy 380.765926 -207.827098)
			(xy 380.720077 -207.856564) (xy 380.670502 -207.879205) (xy 380.618209 -207.894561) (xy 380.564263 -207.902319)
			(xy 380.509762 -207.902321) (xy 380.455816 -207.894567) (xy 380.403522 -207.879214) (xy 380.353945 -207.856576)
			(xy 380.308095 -207.827113) (xy 380.266904 -207.791424) (xy 380.231211 -207.750237) (xy 380.201743 -207.70439)
			(xy 380.1791 -207.654816) (xy 380.163742 -207.602523) (xy 380.155982 -207.548578) (xy 380.155978 -207.494077)
			(xy 378.440128 -207.494077) (xy 378.432437 -207.554959) (xy 378.41654 -207.616873) (xy 378.393008 -207.676306)
			(xy 378.362214 -207.732321) (xy 378.324641 -207.784036) (xy 378.280884 -207.830633) (xy 378.231631 -207.871378)
			(xy 378.17766 -207.905629) (xy 378.119821 -207.932846) (xy 378.059028 -207.952599) (xy 377.996238 -207.964577)
			(xy 377.932442 -207.968591) (xy 377.868646 -207.964577) (xy 377.805856 -207.952599) (xy 377.745063 -207.932846)
			(xy 377.687224 -207.905629) (xy 377.633253 -207.871378) (xy 377.584 -207.830633) (xy 377.540243 -207.784036)
			(xy 377.50267 -207.732321) (xy 377.471876 -207.676306) (xy 377.448344 -207.616873) (xy 377.432447 -207.554959)
			(xy 377.424436 -207.491541) (xy 377.423934 -207.45958) (xy 375.832978 -207.45958) (xy 375.837957 -207.493416)
			(xy 375.838466 -207.521302) (xy 375.837957 -207.549188) (xy 375.829837 -207.604364) (xy 375.813769 -207.657771)
			(xy 375.790097 -207.708268) (xy 375.759324 -207.754781) (xy 375.722107 -207.796318) (xy 375.679239 -207.831993)
			(xy 375.631633 -207.861047) (xy 375.580304 -207.882859) (xy 375.526347 -207.896965) (xy 375.47091 -207.903065)
			(xy 375.415176 -207.901028) (xy 375.360333 -207.890898) (xy 375.307549 -207.872891) (xy 375.257949 -207.84739)
			(xy 375.212591 -207.814939) (xy 375.172442 -207.77623) (xy 375.138356 -207.732087) (xy 375.11106 -207.683452)
			(xy 375.091137 -207.631361) (xy 375.079011 -207.576924) (xy 375.07494 -207.521302) (xy 374.948575 -207.521302)
			(xy 374.94031 -207.584306) (xy 374.923234 -207.648321) (xy 374.897988 -207.709576) (xy 374.864999 -207.767033)
			(xy 374.824828 -207.819719) (xy 374.801892 -207.843628) (xy 374.79478 -207.850994) (xy 374.78716 -207.869282)
			(xy 374.78716 -207.938878) (xy 374.787599 -207.948941) (xy 374.79534 -207.967519) (xy 374.802146 -207.974946)
			(xy 376.7021 -209.8749) (xy 377.128255 -209.8749) (xy 377.132269 -209.8111) (xy 377.144248 -209.748307)
			(xy 377.164002 -209.68751) (xy 377.19122 -209.629668) (xy 377.225473 -209.575693) (xy 377.266221 -209.526437)
			(xy 377.31282 -209.482677) (xy 377.364537 -209.445102) (xy 377.420555 -209.414305) (xy 377.479992 -209.390771)
			(xy 377.541909 -209.374873) (xy 377.605331 -209.36686) (xy 377.637294 -209.366358) (xy 377.670969 -209.366922)
			(xy 377.737731 -209.375812) (xy 377.802735 -209.393437) (xy 377.864843 -209.419489) (xy 377.922969 -209.453511)
			(xy 377.976095 -209.494909) (xy 378.023291 -209.542957) (xy 378.043948 -209.569558) (xy 378.052584 -209.580988)
			(xy 378.078746 -209.591402) (xy 378.196348 -209.571336) (xy 378.217684 -209.552794) (xy 378.222002 -209.539078)
			(xy 378.232085 -209.508481) (xy 378.259005 -209.449949) (xy 378.293103 -209.395287) (xy 378.333832 -209.345369)
			(xy 378.38054 -209.300995) (xy 378.432478 -209.262876) (xy 378.488815 -209.231623) (xy 378.548648 -209.207735)
			(xy 378.611019 -209.191596) (xy 378.674929 -209.183464) (xy 378.707142 -209.18297) (xy 378.737873 -209.183416)
			(xy 378.798887 -209.190829) (xy 378.858562 -209.205542) (xy 378.916029 -209.227339) (xy 378.97045 -209.255905)
			(xy 379.021031 -209.290821) (xy 379.067035 -209.331579) (xy 379.107791 -209.377585) (xy 379.142706 -209.428167)
			(xy 379.171269 -209.482589) (xy 379.193064 -209.540057) (xy 379.207775 -209.599733) (xy 379.215185 -209.660747)
			(xy 379.21565 -209.691478) (xy 379.215218 -209.721839) (xy 379.207985 -209.782129) (xy 379.193617 -209.841128)
			(xy 379.172322 -209.897993) (xy 379.158754 -209.925158) (xy 379.15342 -209.935826) (xy 379.152658 -209.95894)
			(xy 379.196346 -210.053428) (xy 379.21438 -210.06816) (xy 379.22581 -210.0707) (xy 379.238939 -210.073889)
			(xy 379.264743 -210.081901) (xy 379.277372 -210.086702) (xy 379.290834 -210.092036) (xy 379.319282 -210.086702)
			(xy 379.407928 -210.005676) (xy 379.415802 -209.977736) (xy 379.411738 -209.963766) (xy 379.402382 -209.929211)
			(xy 379.392304 -209.858336) (xy 379.391672 -209.822542) (xy 379.392174 -209.790581) (xy 379.400185 -209.727163)
			(xy 379.416082 -209.665249) (xy 379.439614 -209.605816) (xy 379.470408 -209.549801) (xy 379.507981 -209.498086)
			(xy 379.551738 -209.451489) (xy 379.600991 -209.410744) (xy 379.654962 -209.376493) (xy 379.712801 -209.349276)
			(xy 379.773594 -209.329523) (xy 379.836384 -209.317545) (xy 379.90018 -209.313532) (xy 379.963976 -209.317545)
			(xy 380.026766 -209.329523) (xy 380.087559 -209.349276) (xy 380.145398 -209.376493) (xy 380.199369 -209.410744)
			(xy 380.248622 -209.451489) (xy 380.292379 -209.498086) (xy 380.329952 -209.549801) (xy 380.360746 -209.605816)
			(xy 380.384278 -209.665249) (xy 380.400175 -209.727163) (xy 380.408186 -209.790581) (xy 380.408688 -209.822542)
			(xy 380.408138 -209.855097) (xy 380.399804 -209.919673) (xy 380.383315 -209.982661) (xy 380.371604 -210.013042)
			(xy 380.366524 -210.025996) (xy 380.37008 -210.052158) (xy 380.439676 -210.143344) (xy 380.46406 -210.153758)
			(xy 380.477522 -210.152234) (xy 380.492326 -210.15058) (xy 380.522063 -210.1488) (xy 380.536958 -210.148678)
			(xy 380.570355 -210.149195) (xy 380.636575 -210.157942) (xy 380.701081 -210.175278) (xy 380.762764 -210.200906)
			(xy 380.820564 -210.234383) (xy 380.847346 -210.254342) (xy 380.855728 -210.260692) (xy 380.876048 -210.265772)
			(xy 380.970028 -210.250532) (xy 380.987554 -210.239356) (xy 380.99365 -210.230466) (xy 381.013628 -210.201812)
			(xy 381.060151 -210.149705) (xy 381.113357 -210.104445) (xy 381.142494 -210.085178) (xy 381.15367 -210.078066)
			(xy 381.166116 -210.055206) (xy 381.1651 -209.94243) (xy 381.152146 -209.919824) (xy 381.14097 -209.912966)
			(xy 381.117432 -209.89802) (xy 381.074601 -209.862324) (xy 381.037418 -209.820777) (xy 381.006675 -209.774263)
			(xy 380.983024 -209.723772) (xy 380.96697 -209.670378) (xy 380.958854 -209.615216) (xy 380.958344 -209.587338)
			(xy 380.95883 -209.560087) (xy 380.966586 -209.506139) (xy 380.981941 -209.453844) (xy 381.004583 -209.404267)
			(xy 381.034049 -209.358417) (xy 381.06974 -209.317226) (xy 381.110931 -209.281535) (xy 381.156781 -209.252069)
			(xy 381.206358 -209.229427) (xy 381.258653 -209.214072) (xy 381.312601 -209.206316) (xy 381.367103 -209.206316)
			(xy 381.421051 -209.214072) (xy 381.473346 -209.229427) (xy 381.522923 -209.252069) (xy 381.568773 -209.281535)
			(xy 381.609964 -209.317226) (xy 381.645655 -209.358417) (xy 381.675121 -209.404267) (xy 381.697763 -209.453844)
			(xy 381.713118 -209.506139) (xy 381.720874 -209.560087) (xy 381.72136 -209.587338) (xy 381.720895 -209.614657)
			(xy 381.713102 -209.668737) (xy 381.697668 -209.721149) (xy 381.674907 -209.770821) (xy 381.645287 -209.816734)
			(xy 381.609415 -209.857947) (xy 381.589026 -209.876136) (xy 381.57912 -209.884772) (xy 381.569976 -209.90941)
			(xy 381.587248 -210.020662) (xy 381.60325 -210.04149) (xy 381.615442 -210.04657) (xy 381.645568 -210.059992)
			(xy 381.702345 -210.093552) (xy 381.754308 -210.134169) (xy 381.800585 -210.181162) (xy 381.840401 -210.233742)
			(xy 381.873086 -210.291028) (xy 381.898092 -210.352057) (xy 381.915001 -210.415807) (xy 381.923528 -210.481207)
			(xy 381.924052 -210.514184) (xy 381.923529 -210.544913) (xy 381.916123 -210.605923) (xy 381.901418 -210.665596)
			(xy 381.879627 -210.723061) (xy 381.851069 -210.77748) (xy 381.816159 -210.828061) (xy 381.775408 -210.874065)
			(xy 381.729408 -210.914822) (xy 381.678832 -210.949738) (xy 381.624416 -210.978302) (xy 381.566953 -211.0001)
			(xy 381.507282 -211.014812) (xy 381.446273 -211.022225) (xy 381.415544 -211.022692) (xy 381.382146 -211.02218)
			(xy 381.315926 -211.013432) (xy 381.25142 -210.996096) (xy 381.189737 -210.970467) (xy 381.131938 -210.936988)
			(xy 381.105156 -210.917028) (xy 381.096774 -210.910678) (xy 381.076454 -210.905598) (xy 380.982474 -210.920838)
			(xy 380.964948 -210.932014) (xy 380.958852 -210.940904) (xy 380.941098 -210.96646) (xy 380.90034 -211.013485)
			(xy 380.854147 -211.055182) (xy 380.803209 -211.09093) (xy 380.74829 -211.120193) (xy 380.690209 -211.142534)
			(xy 380.629836 -211.157619) (xy 380.568073 -211.165221) (xy 380.536958 -211.165694) (xy 380.506226 -211.165284)
			(xy 380.445209 -211.15787) (xy 380.385531 -211.143156) (xy 380.328062 -211.121357) (xy 380.27364 -211.092789)
			(xy 380.223057 -211.05787) (xy 380.177052 -211.017108) (xy 380.136296 -210.971099) (xy 380.101382 -210.920512)
			(xy 380.07282 -210.866087) (xy 380.051027 -210.808615) (xy 380.03632 -210.748936) (xy 380.028913 -210.687918)
			(xy 380.02845 -210.657186) (xy 380.028975 -210.62463) (xy 380.037319 -210.560054) (xy 380.053818 -210.497066)
			(xy 380.065534 -210.466686) (xy 380.070614 -210.453732) (xy 380.067058 -210.42757) (xy 379.997462 -210.336384)
			(xy 379.973078 -210.32597) (xy 379.959616 -210.327494) (xy 379.944813 -210.329153) (xy 379.915075 -210.33093)
			(xy 379.90018 -210.33105) (xy 379.869282 -210.330574) (xy 379.807943 -210.323058) (xy 379.747964 -210.308177)
			(xy 379.690226 -210.286148) (xy 379.66269 -210.272122) (xy 379.64999 -210.265518) (xy 379.621034 -210.26755)
			(xy 379.523752 -210.337908) (xy 379.51283 -210.364578) (xy 379.515116 -210.379056) (xy 379.517603 -210.394749)
			(xy 379.520276 -210.426414) (xy 379.52045 -210.442302) (xy 379.519964 -210.469553) (xy 379.512208 -210.523501)
			(xy 379.496853 -210.575796) (xy 379.474211 -210.625373) (xy 379.444745 -210.671223) (xy 379.409054 -210.712414)
			(xy 379.367863 -210.748105) (xy 379.322013 -210.777571) (xy 379.272436 -210.800213) (xy 379.220141 -210.815568)
			(xy 379.166193 -210.823324) (xy 379.111691 -210.823324) (xy 379.057743 -210.815568) (xy 379.005448 -210.800213)
			(xy 378.955871 -210.777571) (xy 378.910021 -210.748105) (xy 378.86883 -210.712414) (xy 378.833139 -210.671223)
			(xy 378.803673 -210.625373) (xy 378.781031 -210.575796) (xy 378.765676 -210.523501) (xy 378.75792 -210.469553)
			(xy 378.757434 -210.442302) (xy 378.757961 -210.413932) (xy 378.766383 -210.35782) (xy 378.774198 -210.330542)
			(xy 378.777754 -210.319112) (xy 378.773944 -210.296252) (xy 378.714254 -210.211162) (xy 378.693934 -210.199986)
			(xy 378.681996 -210.199478) (xy 378.650185 -210.197351) (xy 378.587408 -210.186232) (xy 378.52651 -210.16736)
			(xy 378.468445 -210.141033) (xy 378.414122 -210.107661) (xy 378.364391 -210.067767) (xy 378.320031 -210.021975)
			(xy 378.300488 -209.996786) (xy 378.291852 -209.985356) (xy 378.26569 -209.974942) (xy 378.148088 -209.995008)
			(xy 378.126752 -210.01355) (xy 378.122434 -210.027266) (xy 378.112346 -210.057861) (xy 378.085423 -210.11639)
			(xy 378.051324 -210.17105) (xy 378.010595 -210.220966) (xy 377.963888 -210.265339) (xy 377.911951 -210.303458)
			(xy 377.855615 -210.334712) (xy 377.795784 -210.358601) (xy 377.733415 -210.374742) (xy 377.669506 -210.382878)
			(xy 377.637294 -210.383374) (xy 377.605331 -210.38294) (xy 377.541909 -210.374927) (xy 377.479992 -210.359029)
			(xy 377.420555 -210.335495) (xy 377.364537 -210.304698) (xy 377.31282 -210.267123) (xy 377.266221 -210.223363)
			(xy 377.225473 -210.174107) (xy 377.19122 -210.120132) (xy 377.164002 -210.06229) (xy 377.144248 -210.001493)
			(xy 377.132269 -209.9387) (xy 377.128255 -209.8749) (xy 376.7021 -209.8749) (xy 378.318014 -211.490814)
			(xy 378.324868 -211.498209) (xy 378.33261 -211.516808) (xy 378.333 -211.526882) (xy 378.333 -219.283788)
			(xy 380.102618 -219.283788) (xy 380.103086 -219.246611) (xy 380.11033 -219.172611) (xy 380.124748 -219.099668)
			(xy 380.146202 -219.028477) (xy 380.174488 -218.959714) (xy 380.191518 -218.926664) (xy 380.196838 -218.915311)
			(xy 380.196833 -218.890268) (xy 380.191518 -218.878912) (xy 380.174481 -218.845866) (xy 380.146209 -218.777097)
			(xy 380.12476 -218.705904) (xy 380.110338 -218.632963) (xy 380.103078 -218.558965) (xy 380.102618 -218.521788)
			(xy 380.103107 -218.483143) (xy 380.110927 -218.406249) (xy 380.126485 -218.330541) (xy 380.149623 -218.256795)
			(xy 380.180103 -218.185768) (xy 380.217612 -218.11819) (xy 380.261766 -218.054752) (xy 380.312111 -217.996108)
			(xy 380.36813 -217.942857) (xy 380.429249 -217.895547) (xy 380.494842 -217.854663) (xy 380.564233 -217.820625)
			(xy 380.636713 -217.793782) (xy 380.711536 -217.774409) (xy 380.787935 -217.762705) (xy 380.865126 -217.75879)
			(xy 380.942317 -217.762705) (xy 381.018716 -217.774409) (xy 381.093539 -217.793782) (xy 381.166019 -217.820625)
			(xy 381.23541 -217.854663) (xy 381.301003 -217.895547) (xy 381.362122 -217.942857) (xy 381.418141 -217.996108)
			(xy 381.468486 -218.054752) (xy 381.51264 -218.11819) (xy 381.550149 -218.185768) (xy 381.580629 -218.256795)
			(xy 381.603767 -218.330541) (xy 381.619325 -218.406249) (xy 381.627145 -218.483143) (xy 381.627634 -218.521788)
			(xy 381.627191 -218.558965) (xy 381.619941 -218.632966) (xy 381.605517 -218.705909) (xy 381.584058 -218.7771)
			(xy 381.555766 -218.845862) (xy 381.538734 -218.878912) (xy 381.533434 -218.890271) (xy 381.533429 -218.915308)
			(xy 381.538734 -218.926664) (xy 381.555757 -218.959717) (xy 381.584033 -219.028483) (xy 381.605485 -219.099674)
			(xy 381.619911 -219.172614) (xy 381.627173 -219.246612) (xy 381.627634 -219.283788) (xy 381.627145 -219.322433)
			(xy 381.619325 -219.399327) (xy 381.603767 -219.475035) (xy 381.580629 -219.548781) (xy 381.550149 -219.619808)
			(xy 381.51264 -219.687386) (xy 381.468486 -219.750824) (xy 381.418141 -219.809468) (xy 381.362122 -219.862719)
			(xy 381.301003 -219.910029) (xy 381.23541 -219.950913) (xy 381.166019 -219.984951) (xy 381.093539 -220.011794)
			(xy 381.018716 -220.031167) (xy 380.942317 -220.042871) (xy 380.865126 -220.046786) (xy 380.787935 -220.042871)
			(xy 380.711536 -220.031167) (xy 380.636713 -220.011794) (xy 380.564233 -219.984951) (xy 380.494842 -219.950913)
			(xy 380.429249 -219.910029) (xy 380.36813 -219.862719) (xy 380.312111 -219.809468) (xy 380.261766 -219.750824)
			(xy 380.217612 -219.687386) (xy 380.180103 -219.619808) (xy 380.149623 -219.548781) (xy 380.126485 -219.475035)
			(xy 380.110927 -219.399327) (xy 380.103107 -219.322433) (xy 380.102618 -219.283788) (xy 378.333 -219.283788)
			(xy 378.333 -221.187518) (xy 378.332573 -221.197587) (xy 378.324854 -221.216186) (xy 378.318014 -221.223586)
			(xy 377.787662 -221.753938) (xy 377.783598 -221.76359) (xy 377.772676 -221.78899) (xy 377.770644 -221.793816)
			(xy 377.768171 -221.80423) (xy 381.028968 -221.80423) (xy 381.032928 -221.755176) (xy 381.044705 -221.707392)
			(xy 381.063996 -221.662116) (xy 381.090299 -221.62052) (xy 381.122934 -221.583683) (xy 381.161055 -221.552558)
			(xy 381.203676 -221.527951) (xy 381.249692 -221.510499) (xy 381.297911 -221.500655) (xy 381.347086 -221.498674)
			(xy 381.395941 -221.504606) (xy 381.443212 -221.518298) (xy 381.487674 -221.539396) (xy 381.528177 -221.567352)
			(xy 381.56367 -221.601444) (xy 381.593235 -221.640788) (xy 381.616106 -221.684365) (xy 381.63169 -221.731046)
			(xy 381.639585 -221.779623) (xy 381.64008 -221.80423) (xy 381.639585 -221.828837) (xy 381.63169 -221.877414)
			(xy 381.616106 -221.924095) (xy 381.593235 -221.967672) (xy 381.56367 -222.007016) (xy 381.528177 -222.041108)
			(xy 381.487674 -222.069064) (xy 381.443212 -222.090162) (xy 381.395941 -222.103854) (xy 381.347086 -222.109786)
			(xy 381.297911 -222.107805) (xy 381.249692 -222.097961) (xy 381.203676 -222.080509) (xy 381.161055 -222.055902)
			(xy 381.122934 -222.024777) (xy 381.090299 -221.98794) (xy 381.063996 -221.946344) (xy 381.044705 -221.901068)
			(xy 381.032928 -221.853284) (xy 381.028968 -221.80423) (xy 377.768171 -221.80423) (xy 377.765818 -221.814136)
			(xy 377.765818 -221.819724) (xy 377.764681 -221.866996) (xy 377.755496 -221.961116) (xy 377.73848 -222.05414)
			(xy 377.713753 -222.145417) (xy 377.681487 -222.23431) (xy 377.641907 -222.320196) (xy 377.595292 -222.402475)
			(xy 377.541965 -222.480573) (xy 377.482301 -222.553943) (xy 377.449842 -222.588328) (xy 377.442984 -222.59544)
			(xy 377.435872 -222.612966) (xy 377.43585 -222.614236) (xy 378.67896 -222.614236) (xy 378.68292 -222.565182)
			(xy 378.694697 -222.517398) (xy 378.713988 -222.472122) (xy 378.740291 -222.430526) (xy 378.772926 -222.393689)
			(xy 378.811047 -222.362564) (xy 378.853668 -222.337957) (xy 378.899684 -222.320505) (xy 378.947903 -222.310661)
			(xy 378.997078 -222.30868) (xy 379.045933 -222.314612) (xy 379.093204 -222.328304) (xy 379.137666 -222.349402)
			(xy 379.178169 -222.377358) (xy 379.213662 -222.41145) (xy 379.243227 -222.450794) (xy 379.266098 -222.494371)
			(xy 379.281682 -222.541052) (xy 379.289577 -222.589629) (xy 379.290072 -222.614236) (xy 382.438922 -222.614236)
			(xy 382.442882 -222.565182) (xy 382.454659 -222.517398) (xy 382.47395 -222.472122) (xy 382.500253 -222.430526)
			(xy 382.532888 -222.393689) (xy 382.571009 -222.362564) (xy 382.61363 -222.337957) (xy 382.659646 -222.320505)
			(xy 382.707865 -222.310661) (xy 382.75704 -222.30868) (xy 382.805895 -222.314612) (xy 382.853166 -222.328304)
			(xy 382.897628 -222.349402) (xy 382.938131 -222.377358) (xy 382.973624 -222.41145) (xy 383.003189 -222.450794)
			(xy 383.02606 -222.494371) (xy 383.041644 -222.541052) (xy 383.049539 -222.589629) (xy 383.050034 -222.614236)
			(xy 383.378976 -222.614236) (xy 383.382936 -222.565182) (xy 383.394713 -222.517398) (xy 383.414004 -222.472122)
			(xy 383.440307 -222.430526) (xy 383.472942 -222.393689) (xy 383.511063 -222.362564) (xy 383.553684 -222.337957)
			(xy 383.5997 -222.320505) (xy 383.647919 -222.310661) (xy 383.697094 -222.30868) (xy 383.745949 -222.314612)
			(xy 383.79322 -222.328304) (xy 383.837682 -222.349402) (xy 383.878185 -222.377358) (xy 383.913678 -222.41145)
			(xy 383.943243 -222.450794) (xy 383.966114 -222.494371) (xy 383.981698 -222.541052) (xy 383.989593 -222.589629)
			(xy 383.990088 -222.614236) (xy 383.989593 -222.638843) (xy 383.981698 -222.68742) (xy 383.966114 -222.734101)
			(xy 383.943243 -222.777678) (xy 383.913678 -222.817022) (xy 383.878185 -222.851114) (xy 383.837682 -222.87907)
			(xy 383.79322 -222.900168) (xy 383.745949 -222.91386) (xy 383.697094 -222.919792) (xy 383.647919 -222.917811)
			(xy 383.5997 -222.907967) (xy 383.553684 -222.890515) (xy 383.511063 -222.865908) (xy 383.472942 -222.834783)
			(xy 383.440307 -222.797946) (xy 383.414004 -222.75635) (xy 383.394713 -222.711074) (xy 383.382936 -222.66329)
			(xy 383.378976 -222.614236) (xy 383.050034 -222.614236) (xy 383.049539 -222.638843) (xy 383.041644 -222.68742)
			(xy 383.02606 -222.734101) (xy 383.003189 -222.777678) (xy 382.973624 -222.817022) (xy 382.938131 -222.851114)
			(xy 382.897628 -222.87907) (xy 382.853166 -222.900168) (xy 382.805895 -222.91386) (xy 382.75704 -222.919792)
			(xy 382.707865 -222.917811) (xy 382.659646 -222.907967) (xy 382.61363 -222.890515) (xy 382.571009 -222.865908)
			(xy 382.532888 -222.834783) (xy 382.500253 -222.797946) (xy 382.47395 -222.75635) (xy 382.454659 -222.711074)
			(xy 382.442882 -222.66329) (xy 382.438922 -222.614236) (xy 379.290072 -222.614236) (xy 379.289577 -222.638843)
			(xy 379.281682 -222.68742) (xy 379.266098 -222.734101) (xy 379.243227 -222.777678) (xy 379.213662 -222.817022)
			(xy 379.178169 -222.851114) (xy 379.137666 -222.87907) (xy 379.093204 -222.900168) (xy 379.045933 -222.91386)
			(xy 378.997078 -222.919792) (xy 378.947903 -222.917811) (xy 378.899684 -222.907967) (xy 378.853668 -222.890515)
			(xy 378.811047 -222.865908) (xy 378.772926 -222.834783) (xy 378.740291 -222.797946) (xy 378.713988 -222.75635)
			(xy 378.694697 -222.711074) (xy 378.68292 -222.66329) (xy 378.67896 -222.614236) (xy 377.43585 -222.614236)
			(xy 377.435618 -222.627698) (xy 377.434856 -222.638112) (xy 377.432429 -222.6645) (xy 377.420233 -222.716066)
			(xy 377.399958 -222.765022) (xy 377.372125 -222.810113) (xy 377.337449 -222.85018) (xy 377.29682 -222.884195)
			(xy 377.274328 -222.898208) (xy 377.266237 -222.903474) (xy 377.254462 -222.91875) (xy 377.251468 -222.927926)
			(xy 377.237982 -222.972839) (xy 377.204539 -223.060457) (xy 377.184666 -223.102932) (xy 377.165022 -223.142902)
			(xy 377.12031 -223.219933) (xy 377.069676 -223.293208) (xy 377.013434 -223.362272) (xy 376.98299 -223.394778)
			(xy 376.976607 -223.402099) (xy 376.969415 -223.420125) (xy 376.969247 -223.424242) (xy 377.269006 -223.424242)
			(xy 377.272966 -223.375188) (xy 377.284743 -223.327404) (xy 377.304034 -223.282128) (xy 377.330337 -223.240532)
			(xy 377.362972 -223.203695) (xy 377.401093 -223.17257) (xy 377.443714 -223.147963) (xy 377.48973 -223.130511)
			(xy 377.537949 -223.120667) (xy 377.587124 -223.118686) (xy 377.635979 -223.124618) (xy 377.68325 -223.13831)
			(xy 377.727712 -223.159408) (xy 377.768215 -223.187364) (xy 377.803708 -223.221456) (xy 377.833273 -223.2608)
			(xy 377.856144 -223.304377) (xy 377.871728 -223.351058) (xy 377.879623 -223.399635) (xy 377.880118 -223.424242)
			(xy 378.20906 -223.424242) (xy 378.21302 -223.375188) (xy 378.224797 -223.327404) (xy 378.244088 -223.282128)
			(xy 378.270391 -223.240532) (xy 378.303026 -223.203695) (xy 378.341147 -223.17257) (xy 378.383768 -223.147963)
			(xy 378.429784 -223.130511) (xy 378.478003 -223.120667) (xy 378.527178 -223.118686) (xy 378.576033 -223.124618)
			(xy 378.623304 -223.13831) (xy 378.667766 -223.159408) (xy 378.708269 -223.187364) (xy 378.743762 -223.221456)
			(xy 378.773327 -223.2608) (xy 378.796198 -223.304377) (xy 378.811782 -223.351058) (xy 378.819677 -223.399635)
			(xy 378.820172 -223.424242) (xy 381.028968 -223.424242) (xy 381.032928 -223.375188) (xy 381.044705 -223.327404)
			(xy 381.063996 -223.282128) (xy 381.090299 -223.240532) (xy 381.122934 -223.203695) (xy 381.161055 -223.17257)
			(xy 381.203676 -223.147963) (xy 381.249692 -223.130511) (xy 381.297911 -223.120667) (xy 381.347086 -223.118686)
			(xy 381.395941 -223.124618) (xy 381.443212 -223.13831) (xy 381.487674 -223.159408) (xy 381.528177 -223.187364)
			(xy 381.56367 -223.221456) (xy 381.593235 -223.2608) (xy 381.616106 -223.304377) (xy 381.63169 -223.351058)
			(xy 381.639585 -223.399635) (xy 381.64008 -223.424242) (xy 381.969022 -223.424242) (xy 381.972982 -223.375188)
			(xy 381.984759 -223.327404) (xy 382.00405 -223.282128) (xy 382.030353 -223.240532) (xy 382.062988 -223.203695)
			(xy 382.101109 -223.17257) (xy 382.14373 -223.147963) (xy 382.189746 -223.130511) (xy 382.237965 -223.120667)
			(xy 382.28714 -223.118686) (xy 382.335995 -223.124618) (xy 382.383266 -223.13831) (xy 382.427728 -223.159408)
			(xy 382.468231 -223.187364) (xy 382.503724 -223.221456) (xy 382.533289 -223.2608) (xy 382.55616 -223.304377)
			(xy 382.571744 -223.351058) (xy 382.579639 -223.399635) (xy 382.580134 -223.424242) (xy 382.909076 -223.424242)
			(xy 382.913036 -223.375188) (xy 382.924813 -223.327404) (xy 382.944104 -223.282128) (xy 382.970407 -223.240532)
			(xy 383.003042 -223.203695) (xy 383.041163 -223.17257) (xy 383.083784 -223.147963) (xy 383.1298 -223.130511)
			(xy 383.178019 -223.120667) (xy 383.227194 -223.118686) (xy 383.276049 -223.124618) (xy 383.32332 -223.13831)
			(xy 383.367782 -223.159408) (xy 383.408285 -223.187364) (xy 383.443778 -223.221456) (xy 383.473343 -223.2608)
			(xy 383.496214 -223.304377) (xy 383.511798 -223.351058) (xy 383.519693 -223.399635) (xy 383.520188 -223.424242)
			(xy 383.519693 -223.448849) (xy 383.511798 -223.497426) (xy 383.496214 -223.544107) (xy 383.473343 -223.587684)
			(xy 383.443778 -223.627028) (xy 383.408285 -223.66112) (xy 383.367782 -223.689076) (xy 383.32332 -223.710174)
			(xy 383.276049 -223.723866) (xy 383.227194 -223.729798) (xy 383.178019 -223.727817) (xy 383.1298 -223.717973)
			(xy 383.083784 -223.700521) (xy 383.041163 -223.675914) (xy 383.003042 -223.644789) (xy 382.970407 -223.607952)
			(xy 382.944104 -223.566356) (xy 382.924813 -223.52108) (xy 382.913036 -223.473296) (xy 382.909076 -223.424242)
			(xy 382.580134 -223.424242) (xy 382.579639 -223.448849) (xy 382.571744 -223.497426) (xy 382.55616 -223.544107)
			(xy 382.533289 -223.587684) (xy 382.503724 -223.627028) (xy 382.468231 -223.66112) (xy 382.427728 -223.689076)
			(xy 382.383266 -223.710174) (xy 382.335995 -223.723866) (xy 382.28714 -223.729798) (xy 382.237965 -223.727817)
			(xy 382.189746 -223.717973) (xy 382.14373 -223.700521) (xy 382.101109 -223.675914) (xy 382.062988 -223.644789)
			(xy 382.030353 -223.607952) (xy 382.00405 -223.566356) (xy 381.984759 -223.52108) (xy 381.972982 -223.473296)
			(xy 381.969022 -223.424242) (xy 381.64008 -223.424242) (xy 381.639585 -223.448849) (xy 381.63169 -223.497426)
			(xy 381.616106 -223.544107) (xy 381.593235 -223.587684) (xy 381.56367 -223.627028) (xy 381.528177 -223.66112)
			(xy 381.487674 -223.689076) (xy 381.443212 -223.710174) (xy 381.395941 -223.723866) (xy 381.347086 -223.729798)
			(xy 381.297911 -223.727817) (xy 381.249692 -223.717973) (xy 381.203676 -223.700521) (xy 381.161055 -223.675914)
			(xy 381.122934 -223.644789) (xy 381.090299 -223.607952) (xy 381.063996 -223.566356) (xy 381.044705 -223.52108)
			(xy 381.032928 -223.473296) (xy 381.028968 -223.424242) (xy 378.820172 -223.424242) (xy 378.819677 -223.448849)
			(xy 378.811782 -223.497426) (xy 378.796198 -223.544107) (xy 378.773327 -223.587684) (xy 378.743762 -223.627028)
			(xy 378.708269 -223.66112) (xy 378.667766 -223.689076) (xy 378.623304 -223.710174) (xy 378.576033 -223.723866)
			(xy 378.527178 -223.729798) (xy 378.478003 -223.727817) (xy 378.429784 -223.717973) (xy 378.383768 -223.700521)
			(xy 378.341147 -223.675914) (xy 378.303026 -223.644789) (xy 378.270391 -223.607952) (xy 378.244088 -223.566356)
			(xy 378.224797 -223.52108) (xy 378.21302 -223.473296) (xy 378.20906 -223.424242) (xy 377.880118 -223.424242)
			(xy 377.879623 -223.448849) (xy 377.871728 -223.497426) (xy 377.856144 -223.544107) (xy 377.833273 -223.587684)
			(xy 377.803708 -223.627028) (xy 377.768215 -223.66112) (xy 377.727712 -223.689076) (xy 377.68325 -223.710174)
			(xy 377.635979 -223.723866) (xy 377.587124 -223.729798) (xy 377.537949 -223.727817) (xy 377.48973 -223.717973)
			(xy 377.443714 -223.700521) (xy 377.401093 -223.675914) (xy 377.362972 -223.644789) (xy 377.330337 -223.607952)
			(xy 377.304034 -223.566356) (xy 377.284743 -223.52108) (xy 377.272966 -223.473296) (xy 377.269006 -223.424242)
			(xy 376.969247 -223.424242) (xy 376.96902 -223.42983) (xy 376.96902 -223.82861) (xy 376.96955 -223.83912)
			(xy 376.977953 -223.858389) (xy 376.985276 -223.865948) (xy 377.048268 -223.924114) (xy 377.068588 -223.930972)
			(xy 377.079256 -223.929956) (xy 377.10491 -223.92894) (xy 377.130161 -223.929462) (xy 377.179973 -223.937776)
			(xy 377.227738 -223.954175) (xy 377.272153 -223.978212) (xy 377.312005 -224.009232) (xy 377.346208 -224.046388)
			(xy 377.37383 -224.088666) (xy 377.394116 -224.134914) (xy 377.406513 -224.183871) (xy 377.410683 -224.2342)
			(xy 377.410679 -224.234248) (xy 377.738906 -224.234248) (xy 377.742866 -224.185194) (xy 377.754643 -224.13741)
			(xy 377.773934 -224.092134) (xy 377.800237 -224.050538) (xy 377.832872 -224.013701) (xy 377.870993 -223.982576)
			(xy 377.913614 -223.957969) (xy 377.95963 -223.940517) (xy 378.007849 -223.930673) (xy 378.057024 -223.928692)
			(xy 378.105879 -223.934624) (xy 378.15315 -223.948316) (xy 378.197612 -223.969414) (xy 378.238115 -223.99737)
			(xy 378.273608 -224.031462) (xy 378.303173 -224.070806) (xy 378.326044 -224.114383) (xy 378.341628 -224.161064)
			(xy 378.349523 -224.209641) (xy 378.350018 -224.234248) (xy 378.67896 -224.234248) (xy 378.68292 -224.185194)
			(xy 378.694697 -224.13741) (xy 378.713988 -224.092134) (xy 378.740291 -224.050538) (xy 378.772926 -224.013701)
			(xy 378.811047 -223.982576) (xy 378.853668 -223.957969) (xy 378.899684 -223.940517) (xy 378.947903 -223.930673)
			(xy 378.997078 -223.928692) (xy 379.045933 -223.934624) (xy 379.093204 -223.948316) (xy 379.137666 -223.969414)
			(xy 379.178169 -223.99737) (xy 379.213662 -224.031462) (xy 379.243227 -224.070806) (xy 379.266098 -224.114383)
			(xy 379.281682 -224.161064) (xy 379.289577 -224.209641) (xy 379.290072 -224.234248) (xy 379.289577 -224.258855)
			(xy 379.281682 -224.307432) (xy 379.266098 -224.354113) (xy 379.243227 -224.39769) (xy 379.213662 -224.437034)
			(xy 379.178169 -224.471126) (xy 379.137666 -224.499082) (xy 379.093204 -224.52018) (xy 379.045933 -224.533872)
			(xy 378.997078 -224.539804) (xy 378.947903 -224.537823) (xy 378.899684 -224.527979) (xy 378.853668 -224.510527)
			(xy 378.811047 -224.48592) (xy 378.772926 -224.454795) (xy 378.740291 -224.417958) (xy 378.713988 -224.376362)
			(xy 378.694697 -224.331086) (xy 378.68292 -224.283302) (xy 378.67896 -224.234248) (xy 378.350018 -224.234248)
			(xy 378.349523 -224.258855) (xy 378.341628 -224.307432) (xy 378.326044 -224.354113) (xy 378.303173 -224.39769)
			(xy 378.273608 -224.437034) (xy 378.238115 -224.471126) (xy 378.197612 -224.499082) (xy 378.15315 -224.52018)
			(xy 378.105879 -224.533872) (xy 378.057024 -224.539804) (xy 378.007849 -224.537823) (xy 377.95963 -224.527979)
			(xy 377.913614 -224.510527) (xy 377.870993 -224.48592) (xy 377.832872 -224.454795) (xy 377.800237 -224.417958)
			(xy 377.773934 -224.376362) (xy 377.754643 -224.331086) (xy 377.742866 -224.283302) (xy 377.738906 -224.234248)
			(xy 377.410679 -224.234248) (xy 377.406513 -224.284529) (xy 377.394116 -224.333486) (xy 377.37383 -224.379734)
			(xy 377.346208 -224.422012) (xy 377.312005 -224.459168) (xy 377.272153 -224.490188) (xy 377.227738 -224.514225)
			(xy 377.179973 -224.530624) (xy 377.130161 -224.538938) (xy 377.10491 -224.539556) (xy 377.082392 -224.539155)
			(xy 377.037844 -224.532544) (xy 376.994749 -224.519463) (xy 376.954043 -224.500197) (xy 376.916606 -224.475162)
			(xy 376.899678 -224.460308) (xy 376.892312 -224.453704) (xy 376.874278 -224.446846) (xy 376.784362 -224.448878)
			(xy 376.766582 -224.456498) (xy 376.75947 -224.46361) (xy 376.648472 -224.574608) (xy 376.642339 -224.581289)
			(xy 376.634828 -224.597781) (xy 376.633539 -224.615858) (xy 376.635772 -224.624646) (xy 376.635772 -224.6249)
			(xy 376.664982 -224.72396) (xy 376.685048 -224.742756) (xy 376.699018 -224.745804) (xy 376.72426 -224.751805)
			(xy 376.7724 -224.771147) (xy 376.816579 -224.798345) (xy 376.855527 -224.832617) (xy 376.888123 -224.872978)
			(xy 376.913429 -224.918267) (xy 376.930718 -224.967182) (xy 376.939493 -225.018314) (xy 376.940064 -225.044254)
			(xy 377.258575 -225.044254) (xy 377.26267 -224.993526) (xy 377.274849 -224.944112) (xy 377.294797 -224.897292)
			(xy 377.321998 -224.854278) (xy 377.355746 -224.816184) (xy 377.395168 -224.783997) (xy 377.439242 -224.758551)
			(xy 377.486828 -224.740504) (xy 377.536692 -224.730324) (xy 377.587544 -224.728275) (xy 377.638065 -224.734409)
			(xy 377.686949 -224.748569) (xy 377.732928 -224.770386) (xy 377.774812 -224.799296) (xy 377.811516 -224.834551)
			(xy 377.842089 -224.875237) (xy 377.86574 -224.9203) (xy 377.881856 -224.968574) (xy 377.89002 -225.018808)
			(xy 377.890532 -225.044254) (xy 377.89002 -225.0697) (xy 377.881856 -225.119934) (xy 377.86574 -225.168208)
			(xy 377.842089 -225.213271) (xy 377.811516 -225.253957) (xy 377.774812 -225.289212) (xy 377.732928 -225.318122)
			(xy 377.686949 -225.339939) (xy 377.638065 -225.354099) (xy 377.587544 -225.360233) (xy 377.536692 -225.358184)
			(xy 377.486828 -225.348004) (xy 377.439242 -225.329957) (xy 377.395168 -225.304511) (xy 377.355746 -225.272324)
			(xy 377.321998 -225.23423) (xy 377.294797 -225.191216) (xy 377.274849 -225.144396) (xy 377.26267 -225.094982)
			(xy 377.258575 -225.044254) (xy 376.940064 -225.044254) (xy 376.939621 -225.068248) (xy 376.93212 -225.115647)
			(xy 376.917295 -225.161288) (xy 376.895511 -225.204047) (xy 376.867306 -225.242871) (xy 376.833373 -225.276804)
			(xy 376.794549 -225.30501) (xy 376.75179 -225.326794) (xy 376.706149 -225.341619) (xy 376.65875 -225.349121)
			(xy 376.634756 -225.349562) (xy 376.608809 -225.349047) (xy 376.557661 -225.340283) (xy 376.508731 -225.322999)
			(xy 376.463428 -225.297691) (xy 376.423055 -225.265088) (xy 376.388775 -225.226129) (xy 376.361575 -225.181936)
			(xy 376.342237 -225.13378) (xy 376.336306 -225.108516) (xy 376.333258 -225.094546) (xy 376.314462 -225.07448)
			(xy 376.215402 -225.04527) (xy 376.20194 -225.041206) (xy 376.175016 -225.048064) (xy 375.927366 -225.295714)
			(xy 375.920515 -225.30311) (xy 375.912775 -225.321709) (xy 375.91238 -225.331782) (xy 375.91238 -225.472244)
			(xy 375.91492 -225.483928) (xy 375.917378 -225.493313) (xy 375.928214 -225.509386) (xy 375.936002 -225.51517)
			(xy 376.008646 -225.564446) (xy 376.033538 -225.566986) (xy 376.045476 -225.56216) (xy 376.074111 -225.551265)
			(xy 376.134227 -225.539497) (xy 376.164856 -225.538792) (xy 376.189653 -225.53925) (xy 376.238637 -225.547002)
			(xy 376.285805 -225.562322) (xy 376.329996 -225.584833) (xy 376.370121 -225.61398) (xy 376.405191 -225.649046)
			(xy 376.434344 -225.689166) (xy 376.456861 -225.733354) (xy 376.472188 -225.78052) (xy 376.479947 -225.829503)
			(xy 376.479947 -225.85426) (xy 376.788675 -225.85426) (xy 376.79277 -225.803532) (xy 376.804949 -225.754118)
			(xy 376.824897 -225.707298) (xy 376.852098 -225.664284) (xy 376.885846 -225.62619) (xy 376.925268 -225.594003)
			(xy 376.969342 -225.568557) (xy 377.016928 -225.55051) (xy 377.066792 -225.54033) (xy 377.117644 -225.538281)
			(xy 377.168165 -225.544415) (xy 377.217049 -225.558575) (xy 377.263028 -225.580392) (xy 377.304912 -225.609302)
			(xy 377.341616 -225.644557) (xy 377.372189 -225.685243) (xy 377.39584 -225.730306) (xy 377.411956 -225.77858)
			(xy 377.42012 -225.828814) (xy 377.420632 -225.85426) (xy 377.42012 -225.879706) (xy 377.411956 -225.92994)
			(xy 377.39584 -225.978214) (xy 377.372189 -226.023277) (xy 377.341616 -226.063963) (xy 377.304912 -226.099218)
			(xy 377.263028 -226.128128) (xy 377.217049 -226.149945) (xy 377.168165 -226.164105) (xy 377.117644 -226.170239)
			(xy 377.066792 -226.16819) (xy 377.016928 -226.15801) (xy 376.969342 -226.139963) (xy 376.925268 -226.114517)
			(xy 376.885846 -226.08233) (xy 376.852098 -226.044236) (xy 376.824897 -226.001222) (xy 376.804949 -225.954402)
			(xy 376.79277 -225.904988) (xy 376.788675 -225.85426) (xy 376.479947 -225.85426) (xy 376.479947 -225.879097)
			(xy 376.472188 -225.92808) (xy 376.456861 -225.975246) (xy 376.434344 -226.019434) (xy 376.405191 -226.059554)
			(xy 376.370121 -226.09462) (xy 376.329996 -226.123767) (xy 376.285805 -226.146278) (xy 376.238637 -226.161598)
			(xy 376.189653 -226.16935) (xy 376.164856 -226.169728) (xy 376.141199 -226.169325) (xy 376.094408 -226.162303)
			(xy 376.04919 -226.148378) (xy 376.027696 -226.138486) (xy 376.014742 -226.139756) (xy 375.934732 -226.194112)
			(xy 375.933462 -226.194874) (xy 375.924023 -226.202528) (xy 375.91299 -226.224142) (xy 375.91238 -226.236276)
			(xy 375.91238 -226.414838) (xy 375.912842 -226.424345) (xy 375.919757 -226.442061) (xy 375.925842 -226.449382)
			(xy 375.941651 -226.466983) (xy 375.968355 -226.506035) (xy 375.988926 -226.548637) (xy 376.002905 -226.593834)
			(xy 376.009975 -226.640612) (xy 376.010424 -226.664266) (xy 376.328952 -226.664266) (xy 376.332912 -226.615212)
			(xy 376.344689 -226.567428) (xy 376.36398 -226.522152) (xy 376.390283 -226.480556) (xy 376.422918 -226.443719)
			(xy 376.461039 -226.412594) (xy 376.50366 -226.387987) (xy 376.549676 -226.370535) (xy 376.597895 -226.360691)
			(xy 376.64707 -226.35871) (xy 376.695925 -226.364642) (xy 376.743196 -226.378334) (xy 376.787658 -226.399432)
			(xy 376.828161 -226.427388) (xy 376.863654 -226.46148) (xy 376.893219 -226.500824) (xy 376.91609 -226.544401)
			(xy 376.931674 -226.591082) (xy 376.939569 -226.639659) (xy 376.940064 -226.664266) (xy 376.939569 -226.688873)
			(xy 376.931674 -226.73745) (xy 376.91609 -226.784131) (xy 376.893219 -226.827708) (xy 376.863654 -226.867052)
			(xy 376.828161 -226.901144) (xy 376.787658 -226.9291) (xy 376.743196 -226.950198) (xy 376.695925 -226.96389)
			(xy 376.64707 -226.969822) (xy 376.597895 -226.967841) (xy 376.549676 -226.957997) (xy 376.50366 -226.940545)
			(xy 376.461039 -226.915938) (xy 376.422918 -226.884813) (xy 376.390283 -226.847976) (xy 376.36398 -226.80638)
			(xy 376.344689 -226.761104) (xy 376.332912 -226.71332) (xy 376.328952 -226.664266) (xy 376.010424 -226.664266)
			(xy 376.009977 -226.687917) (xy 376.002872 -226.734684) (xy 375.988877 -226.779869) (xy 375.968303 -226.822464)
			(xy 375.941611 -226.861516) (xy 375.925842 -226.87915) (xy 375.919666 -226.886412) (xy 375.912763 -226.904167)
			(xy 375.91238 -226.913694) (xy 375.91238 -227.092256) (xy 375.91492 -227.10394) (xy 375.917379 -227.113324)
			(xy 375.928217 -227.129394) (xy 375.936002 -227.135182) (xy 376.008646 -227.184458) (xy 376.033538 -227.186998)
			(xy 376.045476 -227.182172) (xy 376.07411 -227.171276) (xy 376.134227 -227.159508) (xy 376.164856 -227.158804)
			(xy 376.189652 -227.159262) (xy 376.238634 -227.167014) (xy 376.285801 -227.182333) (xy 376.32999 -227.204843)
			(xy 376.370113 -227.233989) (xy 376.405182 -227.269053) (xy 376.434334 -227.309173) (xy 376.45685 -227.353358)
			(xy 376.472176 -227.400523) (xy 376.479935 -227.449504) (xy 376.479935 -227.474272) (xy 376.788675 -227.474272)
			(xy 376.79277 -227.423544) (xy 376.804949 -227.37413) (xy 376.824897 -227.32731) (xy 376.852098 -227.284296)
			(xy 376.885846 -227.246202) (xy 376.925268 -227.214015) (xy 376.969342 -227.188569) (xy 377.016928 -227.170522)
			(xy 377.066792 -227.160342) (xy 377.117644 -227.158293) (xy 377.168165 -227.164427) (xy 377.217049 -227.178587)
			(xy 377.263028 -227.200404) (xy 377.304912 -227.229314) (xy 377.341616 -227.264569) (xy 377.372189 -227.305255)
			(xy 377.39584 -227.350318) (xy 377.411956 -227.398592) (xy 377.42012 -227.448826) (xy 377.420632 -227.474272)
			(xy 377.42012 -227.499718) (xy 377.411956 -227.549952) (xy 377.39584 -227.598226) (xy 377.372189 -227.643289)
			(xy 377.341616 -227.683975) (xy 377.304912 -227.71923) (xy 377.263028 -227.74814) (xy 377.217049 -227.769957)
			(xy 377.168165 -227.784117) (xy 377.117644 -227.790251) (xy 377.066792 -227.788202) (xy 377.016928 -227.778022)
			(xy 376.969342 -227.759975) (xy 376.925268 -227.734529) (xy 376.885846 -227.702342) (xy 376.852098 -227.664248)
			(xy 376.824897 -227.621234) (xy 376.804949 -227.574414) (xy 376.79277 -227.525) (xy 376.788675 -227.474272)
			(xy 376.479935 -227.474272) (xy 376.479935 -227.499096) (xy 376.472176 -227.548077) (xy 376.45685 -227.595242)
			(xy 376.434334 -227.639427) (xy 376.405182 -227.679547) (xy 376.370113 -227.714611) (xy 376.32999 -227.743757)
			(xy 376.285801 -227.766267) (xy 376.238634 -227.781586) (xy 376.189652 -227.789338) (xy 376.164856 -227.78974)
			(xy 376.141199 -227.789337) (xy 376.094408 -227.782316) (xy 376.049189 -227.76839) (xy 376.027696 -227.758498)
			(xy 376.014742 -227.759768) (xy 375.934732 -227.814124) (xy 375.933462 -227.814886) (xy 375.924025 -227.822541)
			(xy 375.912997 -227.844155) (xy 375.91238 -227.856288) (xy 375.91238 -228.03485) (xy 375.91277 -228.044375)
			(xy 375.91967 -228.062131) (xy 375.925842 -228.069394) (xy 375.94165 -228.086995) (xy 375.968353 -228.126047)
			(xy 375.988923 -228.16865) (xy 376.002899 -228.213847) (xy 376.009968 -228.260624) (xy 376.010424 -228.284278)
			(xy 376.328952 -228.284278) (xy 376.332912 -228.235224) (xy 376.344689 -228.18744) (xy 376.36398 -228.142164)
			(xy 376.390283 -228.100568) (xy 376.422918 -228.063731) (xy 376.461039 -228.032606) (xy 376.50366 -228.007999)
			(xy 376.549676 -227.990547) (xy 376.597895 -227.980703) (xy 376.64707 -227.978722) (xy 376.695925 -227.984654)
			(xy 376.743196 -227.998346) (xy 376.787658 -228.019444) (xy 376.828161 -228.0474) (xy 376.863654 -228.081492)
			(xy 376.893219 -228.120836) (xy 376.91609 -228.164413) (xy 376.931674 -228.211094) (xy 376.939569 -228.259671)
			(xy 376.940064 -228.284278) (xy 376.939569 -228.308885) (xy 376.931674 -228.357462) (xy 376.91609 -228.404143)
			(xy 376.893219 -228.44772) (xy 376.863654 -228.487064) (xy 376.828161 -228.521156) (xy 376.787658 -228.549112)
			(xy 376.743196 -228.57021) (xy 376.695925 -228.583902) (xy 376.64707 -228.589834) (xy 376.597895 -228.587853)
			(xy 376.549676 -228.578009) (xy 376.50366 -228.560557) (xy 376.461039 -228.53595) (xy 376.422918 -228.504825)
			(xy 376.390283 -228.467988) (xy 376.36398 -228.426392) (xy 376.344689 -228.381116) (xy 376.332912 -228.333332)
			(xy 376.328952 -228.284278) (xy 376.010424 -228.284278) (xy 376.009983 -228.307932) (xy 376.00289 -228.354705)
			(xy 375.988905 -228.399898) (xy 375.968339 -228.442502) (xy 375.941653 -228.481564) (xy 375.925842 -228.499162)
			(xy 375.919667 -228.506425) (xy 375.912769 -228.524179) (xy 375.91238 -228.533706) (xy 375.91238 -228.712268)
			(xy 375.91492 -228.723952) (xy 375.917381 -228.733335) (xy 375.928221 -228.749401) (xy 375.936002 -228.755194)
			(xy 376.008646 -228.80447) (xy 376.033538 -228.80701) (xy 376.045476 -228.802184) (xy 376.07411 -228.791288)
			(xy 376.134227 -228.779519) (xy 376.164856 -228.778816) (xy 376.189651 -228.779274) (xy 376.238632 -228.787025)
			(xy 376.285796 -228.802344) (xy 376.329984 -228.824853) (xy 376.370105 -228.853998) (xy 376.405173 -228.889061)
			(xy 376.434324 -228.929179) (xy 376.456839 -228.973363) (xy 376.472164 -229.020526) (xy 376.479923 -229.069505)
			(xy 376.479923 -229.094284) (xy 376.788675 -229.094284) (xy 376.79277 -229.043556) (xy 376.804949 -228.994142)
			(xy 376.824897 -228.947322) (xy 376.852098 -228.904308) (xy 376.885846 -228.866214) (xy 376.925268 -228.834027)
			(xy 376.969342 -228.808581) (xy 377.016928 -228.790534) (xy 377.066792 -228.780354) (xy 377.117644 -228.778305)
			(xy 377.168165 -228.784439) (xy 377.217049 -228.798599) (xy 377.263028 -228.820416) (xy 377.304912 -228.849326)
			(xy 377.341616 -228.884581) (xy 377.372189 -228.925267) (xy 377.39584 -228.97033) (xy 377.411956 -229.018604)
			(xy 377.42012 -229.068838) (xy 377.420632 -229.094284) (xy 377.42012 -229.11973) (xy 377.411956 -229.169964)
			(xy 377.39584 -229.218238) (xy 377.372189 -229.263301) (xy 377.341616 -229.303987) (xy 377.304912 -229.339242)
			(xy 377.263028 -229.368152) (xy 377.217049 -229.389969) (xy 377.168165 -229.404129) (xy 377.117644 -229.410263)
			(xy 377.066792 -229.408214) (xy 377.016928 -229.398034) (xy 376.969342 -229.379987) (xy 376.925268 -229.354541)
			(xy 376.885846 -229.322354) (xy 376.852098 -229.28426) (xy 376.824897 -229.241246) (xy 376.804949 -229.194426)
			(xy 376.79277 -229.145012) (xy 376.788675 -229.094284) (xy 376.479923 -229.094284) (xy 376.479923 -229.119095)
			(xy 376.472164 -229.168074) (xy 376.456839 -229.215237) (xy 376.434324 -229.259421) (xy 376.405173 -229.299539)
			(xy 376.370105 -229.334602) (xy 376.329984 -229.363747) (xy 376.285796 -229.386256) (xy 376.238632 -229.401575)
			(xy 376.189651 -229.409326) (xy 376.164856 -229.409752) (xy 376.141199 -229.409349) (xy 376.094409 -229.402325)
			(xy 376.049192 -229.388397) (xy 376.027696 -229.37851) (xy 376.014742 -229.37978) (xy 375.934732 -229.434136)
			(xy 375.933462 -229.434898) (xy 375.924027 -229.442554) (xy 375.913004 -229.464168) (xy 375.91238 -229.4763)
			(xy 375.91238 -229.654608) (xy 375.912837 -229.664118) (xy 375.919744 -229.68184) (xy 375.925842 -229.689152)
			(xy 375.941653 -229.706752) (xy 375.96836 -229.745803) (xy 375.988936 -229.788405) (xy 376.002918 -229.833602)
			(xy 376.009994 -229.880381) (xy 376.010424 -229.904036) (xy 376.328952 -229.904036) (xy 376.332912 -229.854982)
			(xy 376.344689 -229.807198) (xy 376.36398 -229.761922) (xy 376.390283 -229.720326) (xy 376.422918 -229.683489)
			(xy 376.461039 -229.652364) (xy 376.50366 -229.627757) (xy 376.549676 -229.610305) (xy 376.597895 -229.600461)
			(xy 376.64707 -229.59848) (xy 376.695925 -229.604412) (xy 376.743196 -229.618104) (xy 376.787658 -229.639202)
			(xy 376.828161 -229.667158) (xy 376.863654 -229.70125) (xy 376.893219 -229.740594) (xy 376.91609 -229.784171)
			(xy 376.931674 -229.830852) (xy 376.939569 -229.879429) (xy 376.940064 -229.904036) (xy 376.939569 -229.928643)
			(xy 376.931674 -229.97722) (xy 376.91609 -230.023901) (xy 376.893219 -230.067478) (xy 376.863654 -230.106822)
			(xy 376.828161 -230.140914) (xy 376.787658 -230.16887) (xy 376.743196 -230.189968) (xy 376.695925 -230.20366)
			(xy 376.64707 -230.209592) (xy 376.597895 -230.207611) (xy 376.549676 -230.197767) (xy 376.50366 -230.180315)
			(xy 376.461039 -230.155708) (xy 376.422918 -230.124583) (xy 376.390283 -230.087746) (xy 376.36398 -230.04615)
			(xy 376.344689 -230.000874) (xy 376.332912 -229.95309) (xy 376.328952 -229.904036) (xy 376.010424 -229.904036)
			(xy 376.009979 -229.927688) (xy 376.002878 -229.974457) (xy 375.988886 -230.019645) (xy 375.968315 -230.062243)
			(xy 375.941625 -230.101298) (xy 375.925842 -230.11892) (xy 375.919661 -230.12618) (xy 375.912748 -230.143935)
			(xy 375.91238 -230.153464) (xy 375.91238 -230.33228) (xy 375.91492 -230.343964) (xy 375.917383 -230.353346)
			(xy 375.928225 -230.369409) (xy 375.936002 -230.375206) (xy 376.008646 -230.424482) (xy 376.033538 -230.427022)
			(xy 376.045476 -230.422196) (xy 376.07411 -230.4113) (xy 376.134227 -230.39953) (xy 376.164856 -230.398828)
			(xy 376.18965 -230.399286) (xy 376.238629 -230.407037) (xy 376.285792 -230.422355) (xy 376.329977 -230.444864)
			(xy 376.370097 -230.474007) (xy 376.405164 -230.509069) (xy 376.434313 -230.549185) (xy 376.456828 -230.593368)
			(xy 376.472153 -230.640528) (xy 376.479911 -230.689506) (xy 376.479911 -230.714296) (xy 376.788675 -230.714296)
			(xy 376.79277 -230.663568) (xy 376.804949 -230.614154) (xy 376.824897 -230.567334) (xy 376.852098 -230.52432)
			(xy 376.885846 -230.486226) (xy 376.925268 -230.454039) (xy 376.969342 -230.428593) (xy 377.016928 -230.410546)
			(xy 377.066792 -230.400366) (xy 377.117644 -230.398317) (xy 377.168165 -230.404451) (xy 377.217049 -230.418611)
			(xy 377.263028 -230.440428) (xy 377.304912 -230.469338) (xy 377.341616 -230.504593) (xy 377.372189 -230.545279)
			(xy 377.39584 -230.590342) (xy 377.411956 -230.638616) (xy 377.42012 -230.68885) (xy 377.420632 -230.714296)
			(xy 377.42012 -230.739742) (xy 377.411956 -230.789976) (xy 377.39584 -230.83825) (xy 377.372189 -230.883313)
			(xy 377.341616 -230.923999) (xy 377.304912 -230.959254) (xy 377.263028 -230.988164) (xy 377.217049 -231.009981)
			(xy 377.168165 -231.024141) (xy 377.117644 -231.030275) (xy 377.066792 -231.028226) (xy 377.016928 -231.018046)
			(xy 376.969342 -230.999999) (xy 376.925268 -230.974553) (xy 376.885846 -230.942366) (xy 376.852098 -230.904272)
			(xy 376.824897 -230.861258) (xy 376.804949 -230.814438) (xy 376.79277 -230.765024) (xy 376.788675 -230.714296)
			(xy 376.479911 -230.714296) (xy 376.479911 -230.739094) (xy 376.472153 -230.788072) (xy 376.456828 -230.835232)
			(xy 376.434313 -230.879415) (xy 376.405164 -230.919531) (xy 376.370097 -230.954593) (xy 376.329977 -230.983736)
			(xy 376.285792 -231.006245) (xy 376.238629 -231.021563) (xy 376.18965 -231.029314) (xy 376.164856 -231.029764)
			(xy 376.141199 -231.029361) (xy 376.094409 -231.022338) (xy 376.049192 -231.00841) (xy 376.027696 -230.998522)
			(xy 376.014742 -230.999792) (xy 375.934732 -231.054148) (xy 375.933462 -231.05491) (xy 375.924029 -231.062566)
			(xy 375.913011 -231.08418) (xy 375.91238 -231.096312) (xy 375.91238 -231.27462) (xy 375.912839 -231.284129)
			(xy 375.91975 -231.301848) (xy 375.925842 -231.309164) (xy 375.941652 -231.326765) (xy 375.968358 -231.365816)
			(xy 375.988932 -231.408418) (xy 376.002913 -231.453615) (xy 376.009986 -231.500393) (xy 376.010424 -231.524048)
			(xy 376.328952 -231.524048) (xy 376.332912 -231.474994) (xy 376.344689 -231.42721) (xy 376.36398 -231.381934)
			(xy 376.390283 -231.340338) (xy 376.422918 -231.303501) (xy 376.461039 -231.272376) (xy 376.50366 -231.247769)
			(xy 376.549676 -231.230317) (xy 376.597895 -231.220473) (xy 376.64707 -231.218492) (xy 376.695925 -231.224424)
			(xy 376.743196 -231.238116) (xy 376.787658 -231.259214) (xy 376.828161 -231.28717) (xy 376.863654 -231.321262)
			(xy 376.893219 -231.360606) (xy 376.91609 -231.404183) (xy 376.931674 -231.450864) (xy 376.939569 -231.499441)
			(xy 376.940064 -231.524048) (xy 376.939569 -231.548655) (xy 376.931674 -231.597232) (xy 376.91609 -231.643913)
			(xy 376.893219 -231.68749) (xy 376.863654 -231.726834) (xy 376.828161 -231.760926) (xy 376.787658 -231.788882)
			(xy 376.743196 -231.80998) (xy 376.695925 -231.823672) (xy 376.64707 -231.829604) (xy 376.597895 -231.827623)
			(xy 376.549676 -231.817779) (xy 376.50366 -231.800327) (xy 376.461039 -231.77572) (xy 376.422918 -231.744595)
			(xy 376.390283 -231.707758) (xy 376.36398 -231.666162) (xy 376.344689 -231.620886) (xy 376.332912 -231.573102)
			(xy 376.328952 -231.524048) (xy 376.010424 -231.524048) (xy 376.009978 -231.5477) (xy 376.002876 -231.594467)
			(xy 375.988883 -231.639654) (xy 375.968311 -231.682251) (xy 375.941619 -231.721306) (xy 375.925842 -231.738932)
			(xy 375.919663 -231.746193) (xy 375.912754 -231.763948) (xy 375.91238 -231.773476) (xy 375.91238 -231.952038)
			(xy 375.91492 -231.963722) (xy 375.917377 -231.973108) (xy 375.928212 -231.989182) (xy 375.936002 -231.994964)
			(xy 376.008646 -232.04424) (xy 376.033538 -232.04678) (xy 376.045476 -232.041954) (xy 376.074096 -232.030983)
			(xy 376.134214 -232.019082) (xy 376.164856 -232.018332) (xy 376.189673 -232.01879) (xy 376.238698 -232.026549)
			(xy 376.285905 -232.041881) (xy 376.330132 -232.064411) (xy 376.37029 -232.093582) (xy 376.405389 -232.128677)
			(xy 376.434566 -232.16883) (xy 376.457102 -232.213054) (xy 376.472441 -232.260259) (xy 376.480206 -232.309283)
			(xy 376.480206 -232.334054) (xy 376.788675 -232.334054) (xy 376.79277 -232.283326) (xy 376.804949 -232.233912)
			(xy 376.824897 -232.187092) (xy 376.852098 -232.144078) (xy 376.885846 -232.105984) (xy 376.925268 -232.073797)
			(xy 376.969342 -232.048351) (xy 377.016928 -232.030304) (xy 377.066792 -232.020124) (xy 377.117644 -232.018075)
			(xy 377.168165 -232.024209) (xy 377.217049 -232.038369) (xy 377.263028 -232.060186) (xy 377.304912 -232.089096)
			(xy 377.341616 -232.124351) (xy 377.372189 -232.165037) (xy 377.39584 -232.2101) (xy 377.411956 -232.258374)
			(xy 377.42012 -232.308608) (xy 377.420632 -232.334054) (xy 377.42012 -232.3595) (xy 377.411956 -232.409734)
			(xy 377.39584 -232.458008) (xy 377.372189 -232.503071) (xy 377.341616 -232.543757) (xy 377.304912 -232.579012)
			(xy 377.263028 -232.607922) (xy 377.217049 -232.629739) (xy 377.168165 -232.643899) (xy 377.117644 -232.650033)
			(xy 377.066792 -232.647984) (xy 377.016928 -232.637804) (xy 376.969342 -232.619757) (xy 376.925268 -232.594311)
			(xy 376.885846 -232.562124) (xy 376.852098 -232.52403) (xy 376.824897 -232.481016) (xy 376.804949 -232.434196)
			(xy 376.79277 -232.384782) (xy 376.788675 -232.334054) (xy 376.480206 -232.334054) (xy 376.480206 -232.358917)
			(xy 376.472441 -232.407941) (xy 376.457102 -232.455146) (xy 376.434566 -232.49937) (xy 376.405389 -232.539523)
			(xy 376.37029 -232.574618) (xy 376.330132 -232.603789) (xy 376.285905 -232.626319) (xy 376.238698 -232.641651)
			(xy 376.189673 -232.64941) (xy 376.164856 -232.649776) (xy 376.14119 -232.649333) (xy 376.094396 -232.642222)
			(xy 376.04919 -232.628195) (xy 376.027696 -232.61828) (xy 376.014742 -232.61955) (xy 375.934732 -232.673906)
			(xy 375.933462 -232.674668) (xy 375.924039 -232.682328) (xy 375.913046 -232.703943) (xy 375.91238 -232.71607)
			(xy 375.91238 -232.894632) (xy 375.912841 -232.90414) (xy 375.919755 -232.921857) (xy 375.925842 -232.929176)
			(xy 375.941651 -232.946777) (xy 375.968356 -232.985829) (xy 375.988928 -233.028431) (xy 376.002907 -233.073628)
			(xy 376.009979 -233.120405) (xy 376.010424 -233.14406) (xy 376.328952 -233.14406) (xy 376.332912 -233.095006)
			(xy 376.344689 -233.047222) (xy 376.36398 -233.001946) (xy 376.390283 -232.96035) (xy 376.422918 -232.923513)
			(xy 376.461039 -232.892388) (xy 376.50366 -232.867781) (xy 376.549676 -232.850329) (xy 376.597895 -232.840485)
			(xy 376.64707 -232.838504) (xy 376.695925 -232.844436) (xy 376.743196 -232.858128) (xy 376.787658 -232.879226)
			(xy 376.828161 -232.907182) (xy 376.863654 -232.941274) (xy 376.893219 -232.980618) (xy 376.91609 -233.024195)
			(xy 376.931674 -233.070876) (xy 376.939569 -233.119453) (xy 376.940064 -233.14406) (xy 376.939569 -233.168667)
			(xy 376.931674 -233.217244) (xy 376.91609 -233.263925) (xy 376.893219 -233.307502) (xy 376.863654 -233.346846)
			(xy 376.828161 -233.380938) (xy 376.787658 -233.408894) (xy 376.743196 -233.429992) (xy 376.695925 -233.443684)
			(xy 376.64707 -233.449616) (xy 376.597895 -233.447635) (xy 376.549676 -233.437791) (xy 376.50366 -233.420339)
			(xy 376.461039 -233.395732) (xy 376.422918 -233.364607) (xy 376.390283 -233.32777) (xy 376.36398 -233.286174)
			(xy 376.344689 -233.240898) (xy 376.332912 -233.193114) (xy 376.328952 -233.14406) (xy 376.010424 -233.14406)
			(xy 376.009977 -233.167711) (xy 376.002873 -233.214478) (xy 375.988879 -233.259664) (xy 375.968306 -233.302259)
			(xy 375.941614 -233.341313) (xy 375.925842 -233.358944) (xy 375.919665 -233.366206) (xy 375.91276 -233.383961)
			(xy 375.91238 -233.393488) (xy 375.91238 -233.57205) (xy 375.91492 -233.583734) (xy 375.917379 -233.593119)
			(xy 375.928216 -233.60919) (xy 375.936002 -233.614976) (xy 376.008646 -233.664252) (xy 376.033538 -233.666792)
			(xy 376.045476 -233.661966) (xy 376.074097 -233.650998) (xy 376.134215 -233.639101) (xy 376.164856 -233.638344)
			(xy 376.189672 -233.638802) (xy 376.238695 -233.64656) (xy 376.285901 -233.661892) (xy 376.330126 -233.684421)
			(xy 376.370282 -233.713591) (xy 376.40538 -233.748684) (xy 376.434556 -233.788836) (xy 376.457091 -233.833059)
			(xy 376.472429 -233.880262) (xy 376.480194 -233.929284) (xy 376.480194 -233.954066) (xy 376.788675 -233.954066)
			(xy 376.79277 -233.903338) (xy 376.804949 -233.853924) (xy 376.824897 -233.807104) (xy 376.852098 -233.76409)
			(xy 376.885846 -233.725996) (xy 376.925268 -233.693809) (xy 376.969342 -233.668363) (xy 377.016928 -233.650316)
			(xy 377.066792 -233.640136) (xy 377.117644 -233.638087) (xy 377.168165 -233.644221) (xy 377.217049 -233.658381)
			(xy 377.263028 -233.680198) (xy 377.304912 -233.709108) (xy 377.341616 -233.744363) (xy 377.372189 -233.785049)
			(xy 377.39584 -233.830112) (xy 377.411956 -233.878386) (xy 377.42012 -233.92862) (xy 377.420632 -233.954066)
			(xy 377.42012 -233.979512) (xy 377.411956 -234.029746) (xy 377.39584 -234.07802) (xy 377.372189 -234.123083)
			(xy 377.341616 -234.163769) (xy 377.304912 -234.199024) (xy 377.263028 -234.227934) (xy 377.217049 -234.249751)
			(xy 377.168165 -234.263911) (xy 377.117644 -234.270045) (xy 377.066792 -234.267996) (xy 377.016928 -234.257816)
			(xy 376.969342 -234.239769) (xy 376.925268 -234.214323) (xy 376.885846 -234.182136) (xy 376.852098 -234.144042)
			(xy 376.824897 -234.101028) (xy 376.804949 -234.054208) (xy 376.79277 -234.004794) (xy 376.788675 -233.954066)
			(xy 376.480194 -233.954066) (xy 376.480194 -233.978916) (xy 376.472429 -234.027938) (xy 376.457091 -234.075141)
			(xy 376.434556 -234.119364) (xy 376.40538 -234.159516) (xy 376.370282 -234.194609) (xy 376.330126 -234.223779)
			(xy 376.285901 -234.246308) (xy 376.238695 -234.26164) (xy 376.189672 -234.269398) (xy 376.164856 -234.269788)
			(xy 376.14119 -234.269346) (xy 376.094395 -234.262234) (xy 376.049189 -234.248207) (xy 376.027696 -234.238292)
			(xy 376.014742 -234.239562) (xy 375.934732 -234.293918) (xy 375.933462 -234.29468) (xy 375.924024 -234.302335)
			(xy 375.912994 -234.323948) (xy 375.91238 -234.336082) (xy 375.91238 -234.514644) (xy 375.912769 -234.524169)
			(xy 375.919668 -234.541927) (xy 375.925842 -234.549188) (xy 375.941651 -234.566789) (xy 375.968354 -234.605841)
			(xy 375.988925 -234.648443) (xy 376.002902 -234.69364) (xy 376.009972 -234.740418) (xy 376.010424 -234.764072)
			(xy 376.328952 -234.764072) (xy 376.332912 -234.715018) (xy 376.344689 -234.667234) (xy 376.36398 -234.621958)
			(xy 376.390283 -234.580362) (xy 376.422918 -234.543525) (xy 376.461039 -234.5124) (xy 376.50366 -234.487793)
			(xy 376.549676 -234.470341) (xy 376.597895 -234.460497) (xy 376.64707 -234.458516) (xy 376.695925 -234.464448)
			(xy 376.743196 -234.47814) (xy 376.787658 -234.499238) (xy 376.828161 -234.527194) (xy 376.863654 -234.561286)
			(xy 376.893219 -234.60063) (xy 376.91609 -234.644207) (xy 376.931674 -234.690888) (xy 376.939569 -234.739465)
			(xy 376.940064 -234.764072) (xy 376.939569 -234.788679) (xy 376.931674 -234.837256) (xy 376.91609 -234.883937)
			(xy 376.893219 -234.927514) (xy 376.863654 -234.966858) (xy 376.828161 -235.00095) (xy 376.787658 -235.028906)
			(xy 376.743196 -235.050004) (xy 376.695925 -235.063696) (xy 376.64707 -235.069628) (xy 376.597895 -235.067647)
			(xy 376.549676 -235.057803) (xy 376.50366 -235.040351) (xy 376.461039 -235.015744) (xy 376.422918 -234.984619)
			(xy 376.390283 -234.947782) (xy 376.36398 -234.906186) (xy 376.344689 -234.86091) (xy 376.332912 -234.813126)
			(xy 376.328952 -234.764072) (xy 376.010424 -234.764072) (xy 376.009983 -234.787726) (xy 376.002891 -234.834499)
			(xy 375.988907 -234.879693) (xy 375.968341 -234.922297) (xy 375.941655 -234.96136) (xy 375.925842 -234.978956)
			(xy 375.919666 -234.986218) (xy 375.912766 -235.003973) (xy 375.91238 -235.0135) (xy 375.91238 -235.192062)
			(xy 375.91492 -235.203746) (xy 375.91738 -235.21313) (xy 375.928219 -235.229197) (xy 375.936002 -235.234988)
			(xy 376.008646 -235.284264) (xy 376.033538 -235.286804) (xy 376.045476 -235.281978) (xy 376.074097 -235.27101)
			(xy 376.134215 -235.259112) (xy 376.164856 -235.258356) (xy 376.189672 -235.258814) (xy 376.238692 -235.266572)
			(xy 376.285896 -235.281904) (xy 376.33012 -235.304431) (xy 376.370274 -235.3336) (xy 376.405371 -235.368692)
			(xy 376.434546 -235.408843) (xy 376.45708 -235.453063) (xy 376.472418 -235.500265) (xy 376.480182 -235.549285)
			(xy 376.480182 -235.574078) (xy 376.788675 -235.574078) (xy 376.79277 -235.52335) (xy 376.804949 -235.473936)
			(xy 376.824897 -235.427116) (xy 376.852098 -235.384102) (xy 376.885846 -235.346008) (xy 376.925268 -235.313821)
			(xy 376.969342 -235.288375) (xy 377.016928 -235.270328) (xy 377.066792 -235.260148) (xy 377.117644 -235.258099)
			(xy 377.168165 -235.264233) (xy 377.217049 -235.278393) (xy 377.263028 -235.30021) (xy 377.304912 -235.32912)
			(xy 377.341616 -235.364375) (xy 377.372189 -235.405061) (xy 377.39584 -235.450124) (xy 377.411956 -235.498398)
			(xy 377.42012 -235.548632) (xy 377.420632 -235.574078) (xy 377.42012 -235.599524) (xy 377.411956 -235.649758)
			(xy 377.39584 -235.698032) (xy 377.372189 -235.743095) (xy 377.341616 -235.783781) (xy 377.304912 -235.819036)
			(xy 377.263028 -235.847946) (xy 377.217049 -235.869763) (xy 377.168165 -235.883923) (xy 377.117644 -235.890057)
			(xy 377.066792 -235.888008) (xy 377.016928 -235.877828) (xy 376.969342 -235.859781) (xy 376.925268 -235.834335)
			(xy 376.885846 -235.802148) (xy 376.852098 -235.764054) (xy 376.824897 -235.72104) (xy 376.804949 -235.67422)
			(xy 376.79277 -235.624806) (xy 376.788675 -235.574078) (xy 376.480182 -235.574078) (xy 376.480182 -235.598915)
			(xy 376.472418 -235.647935) (xy 376.45708 -235.695137) (xy 376.434546 -235.739357) (xy 376.405371 -235.779508)
			(xy 376.370274 -235.8146) (xy 376.33012 -235.843769) (xy 376.285896 -235.866296) (xy 376.238692 -235.881628)
			(xy 376.189672 -235.889386) (xy 376.164856 -235.8898) (xy 376.14119 -235.889358) (xy 376.094395 -235.882246)
			(xy 376.049189 -235.86822) (xy 376.027696 -235.858304) (xy 376.014742 -235.859574) (xy 375.934732 -235.91393)
			(xy 375.933462 -235.914692) (xy 375.924026 -235.922347) (xy 375.913001 -235.943961) (xy 375.91238 -235.956094)
			(xy 375.91238 -236.134656) (xy 375.912771 -236.14418) (xy 375.919673 -236.161935) (xy 375.925842 -236.1692)
			(xy 375.941656 -236.186799) (xy 375.96837 -236.225849) (xy 375.988952 -236.26845) (xy 376.002942 -236.313648)
			(xy 376.010025 -236.360428) (xy 376.010424 -236.384084) (xy 376.328952 -236.384084) (xy 376.332912 -236.33503)
			(xy 376.344689 -236.287246) (xy 376.36398 -236.24197) (xy 376.390283 -236.200374) (xy 376.422918 -236.163537)
			(xy 376.461039 -236.132412) (xy 376.50366 -236.107805) (xy 376.549676 -236.090353) (xy 376.597895 -236.080509)
			(xy 376.64707 -236.078528) (xy 376.695925 -236.08446) (xy 376.743196 -236.098152) (xy 376.787658 -236.11925)
			(xy 376.828161 -236.147206) (xy 376.863654 -236.181298) (xy 376.893219 -236.220642) (xy 376.91609 -236.264219)
			(xy 376.931674 -236.3109) (xy 376.939569 -236.359477) (xy 376.940064 -236.384084) (xy 376.939569 -236.408691)
			(xy 376.931674 -236.457268) (xy 376.91609 -236.503949) (xy 376.893219 -236.547526) (xy 376.863654 -236.58687)
			(xy 376.828161 -236.620962) (xy 376.787658 -236.648918) (xy 376.743196 -236.670016) (xy 376.695925 -236.683708)
			(xy 376.64707 -236.68964) (xy 376.597895 -236.687659) (xy 376.549676 -236.677815) (xy 376.50366 -236.660363)
			(xy 376.461039 -236.635756) (xy 376.422918 -236.604631) (xy 376.390283 -236.567794) (xy 376.36398 -236.526198)
			(xy 376.344689 -236.480922) (xy 376.332912 -236.433138) (xy 376.328952 -236.384084) (xy 376.010424 -236.384084)
			(xy 376.009963 -236.408888) (xy 376.0022 -236.457884) (xy 375.986864 -236.505062) (xy 375.964331 -236.549257)
			(xy 375.935159 -236.58938) (xy 375.900065 -236.624442) (xy 375.859916 -236.653579) (xy 375.815701 -236.676072)
			(xy 375.76851 -236.691366) (xy 375.719506 -236.699085) (xy 375.694702 -236.699552) (xy 375.666318 -236.698975)
			(xy 375.610461 -236.688857) (xy 375.557321 -236.668894) (xy 375.53265 -236.654848) (xy 375.525197 -236.650799)
			(xy 375.508583 -236.647438) (xy 375.500138 -236.648244) (xy 375.493534 -236.649006) (xy 375.366534 -236.776006)
			(xy 375.3589 -236.784642) (xy 375.351405 -236.806405) (xy 375.352056 -236.817916) (xy 375.360184 -236.885734)
			(xy 375.360979 -236.891315) (xy 375.364692 -236.901957) (xy 375.36755 -236.906816) (xy 375.384568 -236.933486)
			(xy 375.393712 -236.939582) (xy 375.414322 -236.953881) (xy 375.451006 -236.988089) (xy 375.481607 -237.027831)
			(xy 375.505305 -237.072038) (xy 375.521461 -237.119524) (xy 375.529641 -237.169011) (xy 375.53011 -237.19409)
			(xy 375.848621 -237.19409) (xy 375.852716 -237.143362) (xy 375.864895 -237.093948) (xy 375.884843 -237.047128)
			(xy 375.912044 -237.004114) (xy 375.945792 -236.96602) (xy 375.985214 -236.933833) (xy 376.029288 -236.908387)
			(xy 376.076874 -236.89034) (xy 376.126738 -236.88016) (xy 376.17759 -236.878111) (xy 376.228111 -236.884245)
			(xy 376.276995 -236.898405) (xy 376.322974 -236.920222) (xy 376.364858 -236.949132) (xy 376.401562 -236.984387)
			(xy 376.432135 -237.025073) (xy 376.455786 -237.070136) (xy 376.471902 -237.11841) (xy 376.480066 -237.168644)
			(xy 376.480578 -237.19409) (xy 376.788675 -237.19409) (xy 376.79277 -237.143362) (xy 376.804949 -237.093948)
			(xy 376.824897 -237.047128) (xy 376.852098 -237.004114) (xy 376.885846 -236.96602) (xy 376.925268 -236.933833)
			(xy 376.969342 -236.908387) (xy 377.016928 -236.89034) (xy 377.066792 -236.88016) (xy 377.117644 -236.878111)
			(xy 377.168165 -236.884245) (xy 377.217049 -236.898405) (xy 377.263028 -236.920222) (xy 377.304912 -236.949132)
			(xy 377.341616 -236.984387) (xy 377.372189 -237.025073) (xy 377.39584 -237.070136) (xy 377.411956 -237.11841)
			(xy 377.42012 -237.168644) (xy 377.420632 -237.19409) (xy 377.42012 -237.219536) (xy 377.411956 -237.26977)
			(xy 377.39584 -237.318044) (xy 377.372189 -237.363107) (xy 377.341616 -237.403793) (xy 377.304912 -237.439048)
			(xy 377.263028 -237.467958) (xy 377.217049 -237.489775) (xy 377.168165 -237.503935) (xy 377.117644 -237.510069)
			(xy 377.066792 -237.50802) (xy 377.016928 -237.49784) (xy 376.969342 -237.479793) (xy 376.925268 -237.454347)
			(xy 376.885846 -237.42216) (xy 376.852098 -237.384066) (xy 376.824897 -237.341052) (xy 376.804949 -237.294232)
			(xy 376.79277 -237.244818) (xy 376.788675 -237.19409) (xy 376.480578 -237.19409) (xy 376.480066 -237.219536)
			(xy 376.471902 -237.26977) (xy 376.455786 -237.318044) (xy 376.432135 -237.363107) (xy 376.401562 -237.403793)
			(xy 376.364858 -237.439048) (xy 376.322974 -237.467958) (xy 376.276995 -237.489775) (xy 376.228111 -237.503935)
			(xy 376.17759 -237.510069) (xy 376.126738 -237.50802) (xy 376.076874 -237.49784) (xy 376.029288 -237.479793)
			(xy 375.985214 -237.454347) (xy 375.945792 -237.42216) (xy 375.912044 -237.384066) (xy 375.884843 -237.341052)
			(xy 375.864895 -237.294232) (xy 375.852716 -237.244818) (xy 375.848621 -237.19409) (xy 375.53011 -237.19409)
			(xy 375.529588 -237.219345) (xy 375.521275 -237.269167) (xy 375.504874 -237.316941) (xy 375.480833 -237.361364)
			(xy 375.449809 -237.401224) (xy 375.412647 -237.435434) (xy 375.370361 -237.46306) (xy 375.324105 -237.48335)
			(xy 375.27514 -237.49575) (xy 375.224802 -237.499921) (xy 375.174464 -237.49575) (xy 375.125499 -237.48335)
			(xy 375.079243 -237.46306) (xy 375.036957 -237.435434) (xy 374.999795 -237.401224) (xy 374.968771 -237.361364)
			(xy 374.94473 -237.316941) (xy 374.928329 -237.269167) (xy 374.920016 -237.219345) (xy 374.919494 -237.19409)
			(xy 374.919914 -237.171361) (xy 374.926663 -237.126405) (xy 374.940009 -237.08295) (xy 374.959657 -237.041956)
			(xy 374.985172 -237.004333) (xy 375.000266 -236.987334) (xy 375.010426 -236.976158) (xy 375.015506 -236.94644)
			(xy 374.971818 -236.84738) (xy 374.969278 -236.842046) (xy 374.964541 -236.834654) (xy 374.951089 -236.823391)
			(xy 374.934614 -236.81736) (xy 374.925844 -236.8169) (xy 374.584214 -236.8169) (xy 374.583706 -236.8169)
			(xy 374.574943 -236.81736) (xy 374.558494 -236.823435) (xy 374.545037 -236.834677) (xy 374.540272 -236.842046)
			(xy 374.537732 -236.84738) (xy 374.494044 -236.94644) (xy 374.499124 -236.976158) (xy 374.509284 -236.987334)
			(xy 374.524378 -237.004332) (xy 374.549881 -237.041959) (xy 374.56952 -237.082954) (xy 374.582859 -237.126409)
			(xy 374.589604 -237.171362) (xy 374.590056 -237.19409) (xy 374.589534 -237.219345) (xy 374.581221 -237.269167)
			(xy 374.56482 -237.316941) (xy 374.540779 -237.361364) (xy 374.509755 -237.401224) (xy 374.472593 -237.435434)
			(xy 374.430307 -237.46306) (xy 374.384051 -237.48335) (xy 374.335086 -237.49575) (xy 374.284748 -237.499921)
			(xy 374.23441 -237.49575) (xy 374.185445 -237.48335) (xy 374.139189 -237.46306) (xy 374.096903 -237.435434)
			(xy 374.059741 -237.401224) (xy 374.028717 -237.361364) (xy 374.004676 -237.316941) (xy 373.988275 -237.269167)
			(xy 373.979962 -237.219345) (xy 373.97944 -237.19409) (xy 373.980107 -237.165454) (xy 373.990843 -237.109196)
			(xy 374.000776 -237.08233) (xy 374.005602 -237.06963) (xy 374.001792 -237.04296) (xy 373.939562 -236.963712)
			(xy 373.93199 -236.954986) (xy 373.911224 -236.944911) (xy 373.899684 -236.944408) (xy 373.892318 -236.944408)
			(xy 373.88927 -236.944916) (xy 373.854218 -236.948218) (xy 373.814848 -236.949488) (xy 373.72544 -236.949488)
			(xy 373.713017 -236.950097) (xy 373.691031 -236.961667) (xy 373.68353 -236.971586) (xy 373.639334 -237.035848)
			(xy 373.635197 -237.042358) (xy 373.630666 -237.057094) (xy 373.630444 -237.064804) (xy 373.630444 -237.08614)
			(xy 373.633238 -237.094268) (xy 373.641072 -237.118476) (xy 373.649502 -237.168651) (xy 373.650002 -237.19409)
			(xy 373.64948 -237.219345) (xy 373.641167 -237.269167) (xy 373.624766 -237.316941) (xy 373.600725 -237.361364)
			(xy 373.569701 -237.401224) (xy 373.532539 -237.435434) (xy 373.490253 -237.46306) (xy 373.443997 -237.48335)
			(xy 373.395032 -237.49575) (xy 373.344694 -237.499921) (xy 373.294356 -237.49575) (xy 373.245391 -237.48335)
			(xy 373.199135 -237.46306) (xy 373.156849 -237.435434) (xy 373.119687 -237.401224) (xy 373.088663 -237.361364)
			(xy 373.064622 -237.316941) (xy 373.048221 -237.269167) (xy 373.039908 -237.219345) (xy 373.039386 -237.19409)
			(xy 373.039975 -237.166697) (xy 373.049681 -237.112778) (xy 373.05869 -237.086902) (xy 373.063262 -237.075218)
			(xy 373.060214 -237.050834) (xy 373.005858 -236.971586) (xy 372.998335 -236.961684) (xy 372.976368 -236.950085)
			(xy 372.963948 -236.949488) (xy 372.874794 -236.949488) (xy 372.835424 -236.948218) (xy 372.797324 -236.944408)
			(xy 372.783862 -236.94263) (xy 372.75897 -236.95279) (xy 372.68785 -237.04296) (xy 372.68404 -237.06963)
			(xy 372.688866 -237.08233) (xy 372.698768 -237.109205) (xy 372.709509 -237.165457) (xy 372.710202 -237.19409)
			(xy 372.70968 -237.219345) (xy 372.701367 -237.269167) (xy 372.684966 -237.316941) (xy 372.660925 -237.361364)
			(xy 372.629901 -237.401224) (xy 372.592739 -237.435434) (xy 372.550453 -237.46306) (xy 372.504197 -237.48335)
			(xy 372.455232 -237.49575) (xy 372.404894 -237.499921) (xy 372.354556 -237.49575) (xy 372.305591 -237.48335)
			(xy 372.259335 -237.46306) (xy 372.217049 -237.435434) (xy 372.179887 -237.401224) (xy 372.148863 -237.361364)
			(xy 372.124822 -237.316941) (xy 372.108421 -237.269167) (xy 372.100108 -237.219345) (xy 372.099586 -237.19409)
			(xy 372.100006 -237.171361) (xy 372.106757 -237.126408) (xy 372.120106 -237.082954) (xy 372.139758 -237.041964)
			(xy 372.165279 -237.004346) (xy 372.180358 -236.987334) (xy 372.190518 -236.976158) (xy 372.195598 -236.94644)
			(xy 372.15191 -236.84738) (xy 372.14937 -236.842046) (xy 372.144632 -236.834655) (xy 372.13118 -236.823394)
			(xy 372.114705 -236.817366) (xy 372.105936 -236.8169) (xy 371.764306 -236.8169) (xy 371.763798 -236.8169)
			(xy 371.755036 -236.817361) (xy 371.738589 -236.823438) (xy 371.725134 -236.834681) (xy 371.720364 -236.842046)
			(xy 371.717824 -236.84738) (xy 371.674136 -236.94644) (xy 371.679216 -236.976158) (xy 371.689376 -236.987334)
			(xy 371.70447 -237.004331) (xy 371.729974 -237.041959) (xy 371.749613 -237.082954) (xy 371.762953 -237.126409)
			(xy 371.769698 -237.171362) (xy 371.770148 -237.19409) (xy 371.769626 -237.219345) (xy 371.761313 -237.269167)
			(xy 371.744912 -237.316941) (xy 371.720871 -237.361364) (xy 371.689847 -237.401224) (xy 371.652685 -237.435434)
			(xy 371.610399 -237.46306) (xy 371.564143 -237.48335) (xy 371.515178 -237.49575) (xy 371.46484 -237.499921)
			(xy 371.414502 -237.49575) (xy 371.365537 -237.48335) (xy 371.319281 -237.46306) (xy 371.276995 -237.435434)
			(xy 371.239833 -237.401224) (xy 371.208809 -237.361364) (xy 371.184768 -237.316941) (xy 371.168367 -237.269167)
			(xy 371.160054 -237.219345) (xy 371.159532 -237.19409) (xy 371.160186 -237.165391) (xy 371.170932 -237.109008)
			(xy 371.180868 -237.082076) (xy 371.185948 -237.069376) (xy 371.181884 -237.042706) (xy 371.110764 -236.952536)
			(xy 371.085618 -236.942376) (xy 371.072156 -236.944154) (xy 371.052886 -236.946655) (xy 371.014117 -236.949325)
			(xy 370.994686 -236.949488) (xy 370.905532 -236.949488) (xy 370.89311 -236.950098) (xy 370.871127 -236.961671)
			(xy 370.863622 -236.971586) (xy 370.819426 -237.035848) (xy 370.81529 -237.042358) (xy 370.810759 -237.057095)
			(xy 370.810536 -237.064804) (xy 370.810536 -237.08614) (xy 370.81333 -237.094268) (xy 370.821164 -237.118476)
			(xy 370.829595 -237.168651) (xy 370.830094 -237.19409) (xy 370.829572 -237.219345) (xy 370.821259 -237.269167)
			(xy 370.804858 -237.316941) (xy 370.780817 -237.361364) (xy 370.749793 -237.401224) (xy 370.712631 -237.435434)
			(xy 370.670345 -237.46306) (xy 370.624089 -237.48335) (xy 370.575124 -237.49575) (xy 370.524786 -237.499921)
			(xy 370.474448 -237.49575) (xy 370.425483 -237.48335) (xy 370.379227 -237.46306) (xy 370.336941 -237.435434)
			(xy 370.299779 -237.401224) (xy 370.268755 -237.361364) (xy 370.244714 -237.316941) (xy 370.228313 -237.269167)
			(xy 370.22 -237.219345) (xy 370.219478 -237.19409) (xy 370.220067 -237.166697) (xy 370.229773 -237.112778)
			(xy 370.238782 -237.086902) (xy 370.243354 -237.075218) (xy 370.240306 -237.050834) (xy 370.18595 -236.971586)
			(xy 370.178426 -236.961685) (xy 370.156459 -236.95009) (xy 370.14404 -236.949488) (xy 370.054886 -236.949488)
			(xy 370.035455 -236.949322) (xy 369.996686 -236.946651) (xy 369.977416 -236.944154) (xy 369.963954 -236.942376)
			(xy 369.938808 -236.952536) (xy 369.867688 -237.042706) (xy 369.863624 -237.069376) (xy 369.868704 -237.082076)
			(xy 369.878621 -237.109013) (xy 369.889357 -237.165394) (xy 369.89004 -237.19409) (xy 369.889518 -237.219345)
			(xy 369.881205 -237.269167) (xy 369.864804 -237.316941) (xy 369.840763 -237.361364) (xy 369.809739 -237.401224)
			(xy 369.772577 -237.435434) (xy 369.730291 -237.46306) (xy 369.684035 -237.48335) (xy 369.63507 -237.49575)
			(xy 369.584732 -237.499921) (xy 369.534394 -237.49575) (xy 369.485429 -237.48335) (xy 369.439173 -237.46306)
			(xy 369.396887 -237.435434) (xy 369.359725 -237.401224) (xy 369.328701 -237.361364) (xy 369.30466 -237.316941)
			(xy 369.288259 -237.269167) (xy 369.279946 -237.219345) (xy 369.279424 -237.19409) (xy 369.279964 -237.167915)
			(xy 369.288896 -237.116334) (xy 369.306495 -237.067032) (xy 369.332247 -237.021454) (xy 369.365396 -236.980938)
			(xy 369.40497 -236.94667) (xy 369.44981 -236.919655) (xy 369.473988 -236.90961) (xy 369.48618 -236.904784)
			(xy 369.50269 -236.88548) (xy 369.522756 -236.789468) (xy 369.524701 -236.77694) (xy 369.51752 -236.752661)
			(xy 369.50904 -236.74324) (xy 369.383564 -236.617764) (xy 369.376562 -236.611337) (xy 369.359158 -236.603732)
			(xy 369.340181 -236.602955) (xy 369.322213 -236.609113) (xy 369.31473 -236.61497) (xy 369.314222 -236.615224)
			(xy 369.314222 -236.615478) (xy 369.293241 -236.632748) (xy 369.246434 -236.660343) (xy 369.195485 -236.679226)
			(xy 369.142 -236.688804) (xy 369.114832 -236.689392) (xy 369.10264 -236.689138) (xy 369.077375 -236.687634)
			(xy 369.02783 -236.677306) (xy 368.980666 -236.658948) (xy 368.937176 -236.633064) (xy 368.89855 -236.600362)
			(xy 368.865846 -236.561738) (xy 368.839959 -236.518249) (xy 368.821599 -236.471086) (xy 368.811268 -236.421542)
			(xy 368.809778 -236.396276) (xy 368.809524 -236.390434) (xy 368.809524 -236.384084) (xy 368.810092 -236.356914)
			(xy 368.819663 -236.303425) (xy 368.838553 -236.252475) (xy 368.866166 -236.205675) (xy 368.883438 -236.184694)
			(xy 368.883692 -236.184694) (xy 368.883946 -236.184186) (xy 368.889833 -236.176709) (xy 368.896065 -236.158744)
			(xy 368.895285 -236.139745) (xy 368.887602 -236.122351) (xy 368.881152 -236.115352) (xy 368.878866 -236.113066)
			(xy 368.871469 -236.106218) (xy 368.85287 -236.098485) (xy 368.842798 -236.09808) (xy 366.663224 -236.09808)
			(xy 366.651794 -236.09935) (xy 366.644936 -236.100874) (xy 366.635179 -236.103626) (xy 366.618807 -236.115551)
			(xy 366.613186 -236.123988) (xy 366.574578 -236.18698) (xy 366.569244 -236.198156) (xy 366.566958 -236.21111)
			(xy 366.566958 -236.245146) (xy 366.571784 -236.255306) (xy 366.580772 -236.275571) (xy 366.593448 -236.31805)
			(xy 366.599833 -236.361918) (xy 366.600232 -236.384084) (xy 366.59971 -236.409339) (xy 366.591397 -236.459161)
			(xy 366.574996 -236.506935) (xy 366.550955 -236.551358) (xy 366.519931 -236.591218) (xy 366.482769 -236.625428)
			(xy 366.440483 -236.653054) (xy 366.394227 -236.673344) (xy 366.345262 -236.685744) (xy 366.294924 -236.689915)
			(xy 366.244586 -236.685744) (xy 366.195621 -236.673344) (xy 366.149365 -236.653054) (xy 366.107079 -236.625428)
			(xy 366.069917 -236.591218) (xy 366.038893 -236.551358) (xy 366.014852 -236.506935) (xy 365.998451 -236.459161)
			(xy 365.990138 -236.409339) (xy 365.989616 -236.384084) (xy 365.990106 -236.360123) (xy 365.997626 -236.312795)
			(xy 366.012432 -236.267217) (xy 366.02289 -236.245654) (xy 366.028986 -236.233716) (xy 366.027716 -236.207554)
			(xy 365.975646 -236.122464) (xy 365.971655 -236.116401) (xy 365.960954 -236.106604) (xy 365.954564 -236.10316)
			(xy 365.949285 -236.100782) (xy 365.938 -236.098212) (xy 365.932212 -236.09808) (xy 363.843062 -236.09808)
			(xy 363.831632 -236.09935) (xy 363.824774 -236.100874) (xy 363.815013 -236.103621) (xy 363.79863 -236.11554)
			(xy 363.793024 -236.123988) (xy 363.754416 -236.18698) (xy 363.749082 -236.198156) (xy 363.746796 -236.21111)
			(xy 363.746796 -236.245146) (xy 363.751622 -236.255306) (xy 363.760612 -236.27557) (xy 363.773291 -236.31805)
			(xy 363.779677 -236.361918) (xy 363.78007 -236.384084) (xy 363.779548 -236.409339) (xy 363.771235 -236.459161)
			(xy 363.754834 -236.506935) (xy 363.730793 -236.551358) (xy 363.699769 -236.591218) (xy 363.662607 -236.625428)
			(xy 363.620321 -236.653054) (xy 363.574065 -236.673344) (xy 363.5251 -236.685744) (xy 363.474762 -236.689915)
			(xy 363.424424 -236.685744) (xy 363.375459 -236.673344) (xy 363.329203 -236.653054) (xy 363.286917 -236.625428)
			(xy 363.249755 -236.591218) (xy 363.218731 -236.551358) (xy 363.19469 -236.506935) (xy 363.178289 -236.459161)
			(xy 363.169976 -236.409339) (xy 363.169454 -236.384084) (xy 363.170121 -236.355448) (xy 363.180856 -236.29919)
			(xy 363.19079 -236.272324) (xy 363.195616 -236.259624) (xy 363.191806 -236.232954) (xy 363.129576 -236.153706)
			(xy 363.121998 -236.144995) (xy 363.101232 -236.134956) (xy 363.089698 -236.134402) (xy 363.082332 -236.134402)
			(xy 363.07903 -236.13491) (xy 363.060572 -236.137181) (xy 363.023458 -236.139593) (xy 363.004862 -236.139736)
			(xy 362.915454 -236.139736) (xy 362.903131 -236.140333) (xy 362.881311 -236.151792) (xy 362.873798 -236.16158)
			(xy 362.829602 -236.225588) (xy 362.825393 -236.232146) (xy 362.820739 -236.24701) (xy 362.820458 -236.254798)
			(xy 362.820458 -236.276134) (xy 362.823252 -236.284262) (xy 362.831086 -236.30847) (xy 362.839517 -236.358645)
			(xy 362.840016 -236.384084) (xy 362.839494 -236.409339) (xy 362.831181 -236.459161) (xy 362.81478 -236.506935)
			(xy 362.790739 -236.551358) (xy 362.759715 -236.591218) (xy 362.722553 -236.625428) (xy 362.680267 -236.653054)
			(xy 362.634011 -236.673344) (xy 362.585046 -236.685744) (xy 362.534708 -236.689915) (xy 362.48437 -236.685744)
			(xy 362.435405 -236.673344) (xy 362.389149 -236.653054) (xy 362.346863 -236.625428) (xy 362.309701 -236.591218)
			(xy 362.278677 -236.551358) (xy 362.254636 -236.506935) (xy 362.238235 -236.459161) (xy 362.229922 -236.409339)
			(xy 362.2294 -236.384084) (xy 362.229989 -236.356691) (xy 362.239697 -236.302773) (xy 362.248704 -236.276896)
			(xy 362.253276 -236.265212) (xy 362.250228 -236.240574) (xy 362.195618 -236.16158) (xy 362.188 -236.151923)
			(xy 362.166239 -236.140538) (xy 362.153962 -236.139736) (xy 362.064808 -236.139736) (xy 362.045377 -236.139571)
			(xy 362.006608 -236.136899) (xy 361.987338 -236.134402) (xy 361.973876 -236.132624) (xy 361.948984 -236.14253)
			(xy 361.877864 -236.232954) (xy 361.874054 -236.259624) (xy 361.87888 -236.272324) (xy 361.888782 -236.299199)
			(xy 361.899524 -236.355451) (xy 361.900216 -236.384084) (xy 361.899694 -236.409339) (xy 361.891381 -236.459161)
			(xy 361.87498 -236.506935) (xy 361.850939 -236.551358) (xy 361.819915 -236.591218) (xy 361.782753 -236.625428)
			(xy 361.740467 -236.653054) (xy 361.694211 -236.673344) (xy 361.645246 -236.685744) (xy 361.594908 -236.689915)
			(xy 361.54457 -236.685744) (xy 361.495605 -236.673344) (xy 361.449349 -236.653054) (xy 361.407063 -236.625428)
			(xy 361.369901 -236.591218) (xy 361.338877 -236.551358) (xy 361.314836 -236.506935) (xy 361.298435 -236.459161)
			(xy 361.290122 -236.409339) (xy 361.2896 -236.384084) (xy 361.29009 -236.358792) (xy 361.298419 -236.308899)
			(xy 361.314862 -236.261062) (xy 361.33897 -236.216593) (xy 361.370082 -236.176709) (xy 361.407346 -236.142502)
			(xy 361.428284 -236.128306) (xy 361.43311 -236.125004) (xy 361.44073 -236.117384) (xy 361.444032 -236.11205)
			(xy 361.446867 -236.107127) (xy 361.45047 -236.096355) (xy 361.451144 -236.090714) (xy 361.459272 -236.012482)
			(xy 361.459867 -236.001154) (xy 361.452368 -235.979776) (xy 361.444794 -235.971334) (xy 361.314746 -235.841286)
			(xy 361.28198 -235.836206) (xy 361.266994 -235.84408) (xy 361.244944 -235.855182) (xy 361.19815 -235.870904)
			(xy 361.149436 -235.878898) (xy 361.124754 -235.879386) (xy 361.100766 -235.878912) (xy 361.053381 -235.8714)
			(xy 361.007754 -235.856568) (xy 360.96501 -235.834782) (xy 360.926199 -235.806577) (xy 360.892278 -235.772649)
			(xy 360.864083 -235.733832) (xy 360.842306 -235.691083) (xy 360.827484 -235.645453) (xy 360.819983 -235.598066)
			(xy 360.819446 -235.574078) (xy 360.819829 -235.551207) (xy 360.826617 -235.505973) (xy 360.840099 -235.462264)
			(xy 360.849672 -235.44149) (xy 360.852212 -235.43641) (xy 360.854752 -235.425234) (xy 360.854752 -235.402374)
			(xy 360.854323 -235.392307) (xy 360.846596 -235.373714) (xy 360.839766 -235.366306) (xy 359.489756 -234.016296)
			(xy 359.482904 -234.0089) (xy 359.475162 -233.990301) (xy 359.47477 -233.980228) (xy 359.47477 -232.051352)
			(xy 359.474337 -232.041286) (xy 359.466607 -232.022697) (xy 359.459784 -232.015284) (xy 358.762046 -231.317546)
			(xy 358.754934 -231.31018) (xy 358.736138 -231.30256) (xy 357.884222 -231.30256) (xy 357.87562 -231.302898)
			(xy 357.859395 -231.308619) (xy 357.852472 -231.313736) (xy 357.823224 -231.336655) (xy 357.761053 -231.377361)
			(xy 357.695244 -231.411875) (xy 357.62641 -231.439877) (xy 357.555195 -231.461103) (xy 357.482264 -231.475357)
			(xy 357.408298 -231.482505) (xy 357.371142 -231.4829) (xy 357.0732 -231.4829) (xy 357.032504 -231.482408)
			(xy 356.951561 -231.473879) (xy 356.911656 -231.465882) (xy 356.906428 -231.464932) (xy 356.895802 -231.464932)
			(xy 356.890574 -231.465882) (xy 356.850668 -231.473874) (xy 356.769726 -231.482402) (xy 356.72903 -231.4829)
			(xy 356.431088 -231.4829) (xy 356.416279 -231.482894) (xy 356.38668 -231.481879) (xy 356.371906 -231.480868)
			(xy 356.362 -231.480106) (xy 356.343966 -231.48544) (xy 356.27437 -231.54132) (xy 356.264972 -231.55783)
			(xy 356.263702 -231.567482) (xy 356.259795 -231.591432) (xy 356.245399 -231.63777) (xy 356.223858 -231.68125)
			(xy 356.195715 -231.720778) (xy 356.161678 -231.755361) (xy 356.122602 -231.784128) (xy 356.07947 -231.806357)
			(xy 356.033366 -231.821488) (xy 355.98545 -231.82914) (xy 355.961188 -231.82961) (xy 355.937176 -231.829138)
			(xy 355.889744 -231.821625) (xy 355.84407 -231.806785) (xy 355.80128 -231.784983) (xy 355.762427 -231.756757)
			(xy 355.728467 -231.722801) (xy 355.700236 -231.683951) (xy 355.678429 -231.641163) (xy 355.663584 -231.595492)
			(xy 355.656065 -231.54806) (xy 355.655626 -231.524048) (xy 355.656053 -231.500556) (xy 355.66324 -231.454126)
			(xy 355.677451 -231.409343) (xy 355.698351 -231.367264) (xy 355.725448 -231.328881) (xy 355.741478 -231.311704)
			(xy 355.748039 -231.304253) (xy 355.755411 -231.28584) (xy 355.755263 -231.266007) (xy 355.747618 -231.247706)
			(xy 355.74097 -231.24033) (xy 355.535484 -231.034844) (xy 355.527815 -231.027828) (xy 355.508539 -231.020108)
			(xy 355.498146 -231.019858) (xy 355.491034 -231.019858) (xy 355.46676 -231.019394) (xy 355.418822 -231.011722)
			(xy 355.3727 -230.996567) (xy 355.329555 -230.97431) (xy 355.290472 -230.94551) (xy 355.256435 -230.910893)
			(xy 355.228299 -230.871329) (xy 355.206774 -230.827813) (xy 355.192401 -230.781442) (xy 355.18852 -230.757476)
			(xy 355.18725 -230.74757) (xy 355.177852 -230.731314) (xy 355.108002 -230.675434) (xy 355.089968 -230.669846)
			(xy 355.080062 -230.670608) (xy 355.065351 -230.671609) (xy 355.035879 -230.672627) (xy 355.021134 -230.67264)
			(xy 354.723192 -230.67264) (xy 354.682496 -230.672148) (xy 354.601554 -230.663617) (xy 354.561648 -230.655622)
			(xy 354.55642 -230.654672) (xy 354.545794 -230.654672) (xy 354.540566 -230.655622) (xy 354.50066 -230.663615)
			(xy 354.419718 -230.672142) (xy 354.379022 -230.67264) (xy 354.08108 -230.67264) (xy 354.043384 -230.672197)
			(xy 353.968353 -230.664847) (xy 353.894402 -230.65018) (xy 353.822245 -230.628339) (xy 353.752575 -230.599532)
			(xy 353.686062 -230.564038) (xy 353.623348 -230.522197) (xy 353.593908 -230.49865) (xy 353.586891 -230.493412)
			(xy 353.570399 -230.487558) (xy 353.56165 -230.48722) (xy 353.058476 -230.48722) (xy 353.058222 -230.48722)
			(xy 353.04455 -230.487699) (xy 353.018202 -230.495026) (xy 352.994742 -230.50908) (xy 352.975851 -230.528854)
			(xy 352.962883 -230.552931) (xy 352.956767 -230.579586) (xy 352.957941 -230.606908) (xy 352.961702 -230.620062)
			(xy 352.968664 -230.642997) (xy 352.976184 -230.690332) (xy 352.976688 -230.714296) (xy 352.976217 -230.738308)
			(xy 352.968706 -230.785741) (xy 352.953867 -230.831415) (xy 352.932066 -230.874206) (xy 352.903839 -230.91306)
			(xy 352.869883 -230.94702) (xy 352.831032 -230.97525) (xy 352.788243 -230.997055) (xy 352.742571 -231.011899)
			(xy 352.695138 -231.019415) (xy 352.671126 -231.019858) (xy 352.646852 -231.019393) (xy 352.598915 -231.011721)
			(xy 352.552794 -230.996565) (xy 352.50965 -230.974307) (xy 352.470568 -230.945507) (xy 352.436532 -230.91089)
			(xy 352.408398 -230.871326) (xy 352.386873 -230.827811) (xy 352.3725 -230.781441) (xy 352.368612 -230.757476)
			(xy 352.367342 -230.74757) (xy 352.357944 -230.731314) (xy 352.288094 -230.675434) (xy 352.27006 -230.669846)
			(xy 352.260154 -230.670608) (xy 352.245443 -230.671609) (xy 352.215971 -230.672626) (xy 352.201226 -230.67264)
			(xy 351.903284 -230.67264) (xy 351.862588 -230.672147) (xy 351.781646 -230.663616) (xy 351.74174 -230.655622)
			(xy 351.736512 -230.654672) (xy 351.725886 -230.654672) (xy 351.720658 -230.655622) (xy 351.680752 -230.663614)
			(xy 351.599809 -230.67214) (xy 351.559114 -230.67264) (xy 351.261172 -230.67264) (xy 351.223477 -230.672196)
			(xy 351.148445 -230.664846) (xy 351.074495 -230.650179) (xy 351.002338 -230.628336) (xy 350.932668 -230.599529)
			(xy 350.866156 -230.564034) (xy 350.803443 -230.522193) (xy 350.774 -230.49865) (xy 350.766982 -230.493413)
			(xy 350.750491 -230.487561) (xy 350.741742 -230.48722) (xy 350.238568 -230.48722) (xy 350.238314 -230.48722)
			(xy 350.224642 -230.4877) (xy 350.198297 -230.495028) (xy 350.174839 -230.509082) (xy 350.15595 -230.528856)
			(xy 350.142983 -230.552932) (xy 350.136867 -230.579585) (xy 350.138041 -230.606906) (xy 350.141794 -230.620062)
			(xy 350.148756 -230.642997) (xy 350.156276 -230.690332) (xy 350.15678 -230.714296) (xy 350.156309 -230.738308)
			(xy 350.148798 -230.785741) (xy 350.133959 -230.831414) (xy 350.112157 -230.874204) (xy 350.083931 -230.913057)
			(xy 350.049974 -230.947017) (xy 350.011123 -230.975246) (xy 349.968335 -230.99705) (xy 349.922662 -231.011893)
			(xy 349.87523 -231.019408) (xy 349.851218 -231.019858) (xy 349.826945 -231.019392) (xy 349.779009 -231.011719)
			(xy 349.732889 -230.996563) (xy 349.689746 -230.974304) (xy 349.650665 -230.945504) (xy 349.61663 -230.910887)
			(xy 349.588496 -230.871323) (xy 349.566972 -230.827809) (xy 349.5526 -230.781439) (xy 349.548704 -230.757476)
			(xy 349.547434 -230.74757) (xy 349.538036 -230.73106) (xy 349.468186 -230.67518) (xy 349.450152 -230.669592)
			(xy 349.440246 -230.670354) (xy 349.425474 -230.671423) (xy 349.395875 -230.672566) (xy 349.381064 -230.67264)
			(xy 349.083122 -230.67264) (xy 349.042426 -230.672149) (xy 348.961483 -230.663622) (xy 348.921578 -230.655622)
			(xy 348.91635 -230.654672) (xy 348.905724 -230.654672) (xy 348.900496 -230.655622) (xy 348.86059 -230.663616)
			(xy 348.779648 -230.672146) (xy 348.738952 -230.67264) (xy 348.44101 -230.67264) (xy 348.403316 -230.672193)
			(xy 348.328287 -230.664837) (xy 348.25434 -230.650165) (xy 348.182186 -230.628318) (xy 348.11252 -230.599507)
			(xy 348.046013 -230.564008) (xy 347.983303 -230.522164) (xy 347.953838 -230.49865) (xy 347.946818 -230.493422)
			(xy 347.930326 -230.48759) (xy 347.92158 -230.48722) (xy 347.418406 -230.48722) (xy 347.418152 -230.48722)
			(xy 347.404486 -230.487707) (xy 347.378155 -230.495045) (xy 347.354713 -230.509103) (xy 347.335837 -230.528873)
			(xy 347.322879 -230.552941) (xy 347.316767 -230.579584) (xy 347.317938 -230.606893) (xy 347.321632 -230.620062)
			(xy 347.328593 -230.642998) (xy 347.336112 -230.690332) (xy 347.336618 -230.714296) (xy 347.336045 -230.740898)
			(xy 347.32684 -230.793298) (xy 347.308706 -230.843315) (xy 347.28219 -230.88944) (xy 347.248093 -230.930281)
			(xy 347.207444 -230.964606) (xy 347.184726 -230.978456) (xy 347.173042 -230.985314) (xy 347.15958 -231.008682)
			(xy 347.15958 -231.032558) (xy 347.164914 -231.048052) (xy 347.170248 -231.05491) (xy 347.194352 -231.087078)
			(xy 347.236477 -231.155544) (xy 347.254322 -231.191562) (xy 347.25864 -231.200452) (xy 347.272864 -231.21366)
			(xy 347.356176 -231.245664) (xy 347.37548 -231.24541) (xy 347.384624 -231.2416) (xy 347.412566 -231.230852)
			(xy 347.471281 -231.21921) (xy 347.50121 -231.218486) (xy 347.526482 -231.219009) (xy 347.576336 -231.227329)
			(xy 347.624141 -231.243742) (xy 347.668592 -231.267799) (xy 347.708477 -231.298844) (xy 347.742709 -231.336031)
			(xy 347.770353 -231.378345) (xy 347.790656 -231.424632) (xy 347.803064 -231.473629) (xy 347.807238 -231.524)
			(xy 347.807234 -231.524048) (xy 348.135206 -231.524048) (xy 348.139166 -231.474994) (xy 348.150943 -231.42721)
			(xy 348.170234 -231.381934) (xy 348.196537 -231.340338) (xy 348.229172 -231.303501) (xy 348.267293 -231.272376)
			(xy 348.309914 -231.247769) (xy 348.35593 -231.230317) (xy 348.404149 -231.220473) (xy 348.453324 -231.218492)
			(xy 348.502179 -231.224424) (xy 348.54945 -231.238116) (xy 348.593912 -231.259214) (xy 348.634415 -231.28717)
			(xy 348.669908 -231.321262) (xy 348.699473 -231.360606) (xy 348.722344 -231.404183) (xy 348.737928 -231.450864)
			(xy 348.745823 -231.499441) (xy 348.746318 -231.524048) (xy 349.07526 -231.524048) (xy 349.07922 -231.474994)
			(xy 349.090997 -231.42721) (xy 349.110288 -231.381934) (xy 349.136591 -231.340338) (xy 349.169226 -231.303501)
			(xy 349.207347 -231.272376) (xy 349.249968 -231.247769) (xy 349.295984 -231.230317) (xy 349.344203 -231.220473)
			(xy 349.393378 -231.218492) (xy 349.442233 -231.224424) (xy 349.489504 -231.238116) (xy 349.533966 -231.259214)
			(xy 349.574469 -231.28717) (xy 349.609962 -231.321262) (xy 349.639527 -231.360606) (xy 349.662398 -231.404183)
			(xy 349.677982 -231.450864) (xy 349.685877 -231.499441) (xy 349.686372 -231.524048) (xy 350.015314 -231.524048)
			(xy 350.019274 -231.474994) (xy 350.031051 -231.42721) (xy 350.050342 -231.381934) (xy 350.076645 -231.340338)
			(xy 350.10928 -231.303501) (xy 350.147401 -231.272376) (xy 350.190022 -231.247769) (xy 350.236038 -231.230317)
			(xy 350.284257 -231.220473) (xy 350.333432 -231.218492) (xy 350.382287 -231.224424) (xy 350.429558 -231.238116)
			(xy 350.47402 -231.259214) (xy 350.514523 -231.28717) (xy 350.550016 -231.321262) (xy 350.579581 -231.360606)
			(xy 350.602452 -231.404183) (xy 350.618036 -231.450864) (xy 350.625931 -231.499441) (xy 350.626426 -231.524048)
			(xy 350.955368 -231.524048) (xy 350.959328 -231.474994) (xy 350.971105 -231.42721) (xy 350.990396 -231.381934)
			(xy 351.016699 -231.340338) (xy 351.049334 -231.303501) (xy 351.087455 -231.272376) (xy 351.130076 -231.247769)
			(xy 351.176092 -231.230317) (xy 351.224311 -231.220473) (xy 351.273486 -231.218492) (xy 351.322341 -231.224424)
			(xy 351.369612 -231.238116) (xy 351.414074 -231.259214) (xy 351.454577 -231.28717) (xy 351.49007 -231.321262)
			(xy 351.519635 -231.360606) (xy 351.542506 -231.404183) (xy 351.55809 -231.450864) (xy 351.565985 -231.499441)
			(xy 351.56648 -231.524048) (xy 351.895422 -231.524048) (xy 351.899382 -231.474994) (xy 351.911159 -231.42721)
			(xy 351.93045 -231.381934) (xy 351.956753 -231.340338) (xy 351.989388 -231.303501) (xy 352.027509 -231.272376)
			(xy 352.07013 -231.247769) (xy 352.116146 -231.230317) (xy 352.164365 -231.220473) (xy 352.21354 -231.218492)
			(xy 352.262395 -231.224424) (xy 352.309666 -231.238116) (xy 352.354128 -231.259214) (xy 352.394631 -231.28717)
			(xy 352.430124 -231.321262) (xy 352.459689 -231.360606) (xy 352.48256 -231.404183) (xy 352.498144 -231.450864)
			(xy 352.506039 -231.499441) (xy 352.506534 -231.524048) (xy 352.835222 -231.524048) (xy 352.839182 -231.474994)
			(xy 352.850959 -231.42721) (xy 352.87025 -231.381934) (xy 352.896553 -231.340338) (xy 352.929188 -231.303501)
			(xy 352.967309 -231.272376) (xy 353.00993 -231.247769) (xy 353.055946 -231.230317) (xy 353.104165 -231.220473)
			(xy 353.15334 -231.218492) (xy 353.202195 -231.224424) (xy 353.249466 -231.238116) (xy 353.293928 -231.259214)
			(xy 353.334431 -231.28717) (xy 353.369924 -231.321262) (xy 353.399489 -231.360606) (xy 353.42236 -231.404183)
			(xy 353.437944 -231.450864) (xy 353.445839 -231.499441) (xy 353.446334 -231.524048) (xy 353.775276 -231.524048)
			(xy 353.779236 -231.474994) (xy 353.791013 -231.42721) (xy 353.810304 -231.381934) (xy 353.836607 -231.340338)
			(xy 353.869242 -231.303501) (xy 353.907363 -231.272376) (xy 353.949984 -231.247769) (xy 353.996 -231.230317)
			(xy 354.044219 -231.220473) (xy 354.093394 -231.218492) (xy 354.142249 -231.224424) (xy 354.18952 -231.238116)
			(xy 354.233982 -231.259214) (xy 354.274485 -231.28717) (xy 354.309978 -231.321262) (xy 354.339543 -231.360606)
			(xy 354.362414 -231.404183) (xy 354.377998 -231.450864) (xy 354.385893 -231.499441) (xy 354.386388 -231.524048)
			(xy 354.71533 -231.524048) (xy 354.71929 -231.474994) (xy 354.731067 -231.42721) (xy 354.750358 -231.381934)
			(xy 354.776661 -231.340338) (xy 354.809296 -231.303501) (xy 354.847417 -231.272376) (xy 354.890038 -231.247769)
			(xy 354.936054 -231.230317) (xy 354.984273 -231.220473) (xy 355.033448 -231.218492) (xy 355.082303 -231.224424)
			(xy 355.129574 -231.238116) (xy 355.174036 -231.259214) (xy 355.214539 -231.28717) (xy 355.250032 -231.321262)
			(xy 355.279597 -231.360606) (xy 355.302468 -231.404183) (xy 355.318052 -231.450864) (xy 355.325947 -231.499441)
			(xy 355.326442 -231.524048) (xy 355.325947 -231.548655) (xy 355.318052 -231.597232) (xy 355.302468 -231.643913)
			(xy 355.279597 -231.68749) (xy 355.250032 -231.726834) (xy 355.214539 -231.760926) (xy 355.174036 -231.788882)
			(xy 355.129574 -231.80998) (xy 355.082303 -231.823672) (xy 355.033448 -231.829604) (xy 354.984273 -231.827623)
			(xy 354.936054 -231.817779) (xy 354.890038 -231.800327) (xy 354.847417 -231.77572) (xy 354.809296 -231.744595)
			(xy 354.776661 -231.707758) (xy 354.750358 -231.666162) (xy 354.731067 -231.620886) (xy 354.71929 -231.573102)
			(xy 354.71533 -231.524048) (xy 354.386388 -231.524048) (xy 354.385893 -231.548655) (xy 354.377998 -231.597232)
			(xy 354.362414 -231.643913) (xy 354.339543 -231.68749) (xy 354.309978 -231.726834) (xy 354.274485 -231.760926)
			(xy 354.233982 -231.788882) (xy 354.18952 -231.80998) (xy 354.142249 -231.823672) (xy 354.093394 -231.829604)
			(xy 354.044219 -231.827623) (xy 353.996 -231.817779) (xy 353.949984 -231.800327) (xy 353.907363 -231.77572)
			(xy 353.869242 -231.744595) (xy 353.836607 -231.707758) (xy 353.810304 -231.666162) (xy 353.791013 -231.620886)
			(xy 353.779236 -231.573102) (xy 353.775276 -231.524048) (xy 353.446334 -231.524048) (xy 353.445839 -231.548655)
			(xy 353.437944 -231.597232) (xy 353.42236 -231.643913) (xy 353.399489 -231.68749) (xy 353.369924 -231.726834)
			(xy 353.334431 -231.760926) (xy 353.293928 -231.788882) (xy 353.249466 -231.80998) (xy 353.202195 -231.823672)
			(xy 353.15334 -231.829604) (xy 353.104165 -231.827623) (xy 353.055946 -231.817779) (xy 353.00993 -231.800327)
			(xy 352.967309 -231.77572) (xy 352.929188 -231.744595) (xy 352.896553 -231.707758) (xy 352.87025 -231.666162)
			(xy 352.850959 -231.620886) (xy 352.839182 -231.573102) (xy 352.835222 -231.524048) (xy 352.506534 -231.524048)
			(xy 352.506039 -231.548655) (xy 352.498144 -231.597232) (xy 352.48256 -231.643913) (xy 352.459689 -231.68749)
			(xy 352.430124 -231.726834) (xy 352.394631 -231.760926) (xy 352.354128 -231.788882) (xy 352.309666 -231.80998)
			(xy 352.262395 -231.823672) (xy 352.21354 -231.829604) (xy 352.164365 -231.827623) (xy 352.116146 -231.817779)
			(xy 352.07013 -231.800327) (xy 352.027509 -231.77572) (xy 351.989388 -231.744595) (xy 351.956753 -231.707758)
			(xy 351.93045 -231.666162) (xy 351.911159 -231.620886) (xy 351.899382 -231.573102) (xy 351.895422 -231.524048)
			(xy 351.56648 -231.524048) (xy 351.565985 -231.548655) (xy 351.55809 -231.597232) (xy 351.542506 -231.643913)
			(xy 351.519635 -231.68749) (xy 351.49007 -231.726834) (xy 351.454577 -231.760926) (xy 351.414074 -231.788882)
			(xy 351.369612 -231.80998) (xy 351.322341 -231.823672) (xy 351.273486 -231.829604) (xy 351.224311 -231.827623)
			(xy 351.176092 -231.817779) (xy 351.130076 -231.800327) (xy 351.087455 -231.77572) (xy 351.049334 -231.744595)
			(xy 351.016699 -231.707758) (xy 350.990396 -231.666162) (xy 350.971105 -231.620886) (xy 350.959328 -231.573102)
			(xy 350.955368 -231.524048) (xy 350.626426 -231.524048) (xy 350.625931 -231.548655) (xy 350.618036 -231.597232)
			(xy 350.602452 -231.643913) (xy 350.579581 -231.68749) (xy 350.550016 -231.726834) (xy 350.514523 -231.760926)
			(xy 350.47402 -231.788882) (xy 350.429558 -231.80998) (xy 350.382287 -231.823672) (xy 350.333432 -231.829604)
			(xy 350.284257 -231.827623) (xy 350.236038 -231.817779) (xy 350.190022 -231.800327) (xy 350.147401 -231.77572)
			(xy 350.10928 -231.744595) (xy 350.076645 -231.707758) (xy 350.050342 -231.666162) (xy 350.031051 -231.620886)
			(xy 350.019274 -231.573102) (xy 350.015314 -231.524048) (xy 349.686372 -231.524048) (xy 349.685877 -231.548655)
			(xy 349.677982 -231.597232) (xy 349.662398 -231.643913) (xy 349.639527 -231.68749) (xy 349.609962 -231.726834)
			(xy 349.574469 -231.760926) (xy 349.533966 -231.788882) (xy 349.489504 -231.80998) (xy 349.442233 -231.823672)
			(xy 349.393378 -231.829604) (xy 349.344203 -231.827623) (xy 349.295984 -231.817779) (xy 349.249968 -231.800327)
			(xy 349.207347 -231.77572) (xy 349.169226 -231.744595) (xy 349.136591 -231.707758) (xy 349.110288 -231.666162)
			(xy 349.090997 -231.620886) (xy 349.07922 -231.573102) (xy 349.07526 -231.524048) (xy 348.746318 -231.524048)
			(xy 348.745823 -231.548655) (xy 348.737928 -231.597232) (xy 348.722344 -231.643913) (xy 348.699473 -231.68749)
			(xy 348.669908 -231.726834) (xy 348.634415 -231.760926) (xy 348.593912 -231.788882) (xy 348.54945 -231.80998)
			(xy 348.502179 -231.823672) (xy 348.453324 -231.829604) (xy 348.404149 -231.827623) (xy 348.35593 -231.817779)
			(xy 348.309914 -231.800327) (xy 348.267293 -231.77572) (xy 348.229172 -231.744595) (xy 348.196537 -231.707758)
			(xy 348.170234 -231.666162) (xy 348.150943 -231.620886) (xy 348.139166 -231.573102) (xy 348.135206 -231.524048)
			(xy 347.807234 -231.524048) (xy 347.803064 -231.574371) (xy 347.790656 -231.623368) (xy 347.770353 -231.669655)
			(xy 347.742709 -231.711969) (xy 347.708477 -231.749156) (xy 347.668592 -231.780201) (xy 347.624141 -231.804258)
			(xy 347.576336 -231.820671) (xy 347.526482 -231.828991) (xy 347.50121 -231.82961) (xy 347.471281 -231.828885)
			(xy 347.412565 -231.817247) (xy 347.384624 -231.806496) (xy 347.37548 -231.802686) (xy 347.356176 -231.802432)
			(xy 347.272864 -231.834436) (xy 347.25864 -231.847644) (xy 347.254322 -231.856534) (xy 347.241668 -231.882268)
			(xy 347.213061 -231.931976) (xy 347.197172 -231.955848) (xy 347.191584 -231.963976) (xy 347.18752 -231.982518)
			(xy 347.20149 -232.070656) (xy 347.210888 -232.086912) (xy 347.218762 -232.093008) (xy 347.236785 -232.107564)
			(xy 347.268641 -232.141198) (xy 347.295047 -232.179261) (xy 347.315395 -232.220879) (xy 347.329218 -232.265094)
			(xy 347.336198 -232.310891) (xy 347.336618 -232.334054) (xy 347.665306 -232.334054) (xy 347.669266 -232.285)
			(xy 347.681043 -232.237216) (xy 347.700334 -232.19194) (xy 347.726637 -232.150344) (xy 347.759272 -232.113507)
			(xy 347.797393 -232.082382) (xy 347.840014 -232.057775) (xy 347.88603 -232.040323) (xy 347.934249 -232.030479)
			(xy 347.983424 -232.028498) (xy 348.032279 -232.03443) (xy 348.07955 -232.048122) (xy 348.124012 -232.06922)
			(xy 348.164515 -232.097176) (xy 348.200008 -232.131268) (xy 348.229573 -232.170612) (xy 348.252444 -232.214189)
			(xy 348.268028 -232.26087) (xy 348.275923 -232.309447) (xy 348.276418 -232.334054) (xy 348.60536 -232.334054)
			(xy 348.60932 -232.285) (xy 348.621097 -232.237216) (xy 348.640388 -232.19194) (xy 348.666691 -232.150344)
			(xy 348.699326 -232.113507) (xy 348.737447 -232.082382) (xy 348.780068 -232.057775) (xy 348.826084 -232.040323)
			(xy 348.874303 -232.030479) (xy 348.923478 -232.028498) (xy 348.972333 -232.03443) (xy 349.019604 -232.048122)
			(xy 349.064066 -232.06922) (xy 349.104569 -232.097176) (xy 349.140062 -232.131268) (xy 349.169627 -232.170612)
			(xy 349.192498 -232.214189) (xy 349.208082 -232.26087) (xy 349.215977 -232.309447) (xy 349.216472 -232.334054)
			(xy 349.545414 -232.334054) (xy 349.549374 -232.285) (xy 349.561151 -232.237216) (xy 349.580442 -232.19194)
			(xy 349.606745 -232.150344) (xy 349.63938 -232.113507) (xy 349.677501 -232.082382) (xy 349.720122 -232.057775)
			(xy 349.766138 -232.040323) (xy 349.814357 -232.030479) (xy 349.863532 -232.028498) (xy 349.912387 -232.03443)
			(xy 349.959658 -232.048122) (xy 350.00412 -232.06922) (xy 350.044623 -232.097176) (xy 350.080116 -232.131268)
			(xy 350.109681 -232.170612) (xy 350.132552 -232.214189) (xy 350.148136 -232.26087) (xy 350.156031 -232.309447)
			(xy 350.156526 -232.334054) (xy 350.485214 -232.334054) (xy 350.489174 -232.285) (xy 350.500951 -232.237216)
			(xy 350.520242 -232.19194) (xy 350.546545 -232.150344) (xy 350.57918 -232.113507) (xy 350.617301 -232.082382)
			(xy 350.659922 -232.057775) (xy 350.705938 -232.040323) (xy 350.754157 -232.030479) (xy 350.803332 -232.028498)
			(xy 350.852187 -232.03443) (xy 350.899458 -232.048122) (xy 350.94392 -232.06922) (xy 350.984423 -232.097176)
			(xy 351.019916 -232.131268) (xy 351.049481 -232.170612) (xy 351.072352 -232.214189) (xy 351.087936 -232.26087)
			(xy 351.095831 -232.309447) (xy 351.096326 -232.334054) (xy 351.425268 -232.334054) (xy 351.429228 -232.285)
			(xy 351.441005 -232.237216) (xy 351.460296 -232.19194) (xy 351.486599 -232.150344) (xy 351.519234 -232.113507)
			(xy 351.557355 -232.082382) (xy 351.599976 -232.057775) (xy 351.645992 -232.040323) (xy 351.694211 -232.030479)
			(xy 351.743386 -232.028498) (xy 351.792241 -232.03443) (xy 351.839512 -232.048122) (xy 351.883974 -232.06922)
			(xy 351.924477 -232.097176) (xy 351.95997 -232.131268) (xy 351.989535 -232.170612) (xy 352.012406 -232.214189)
			(xy 352.02799 -232.26087) (xy 352.035885 -232.309447) (xy 352.03638 -232.334054) (xy 352.365322 -232.334054)
			(xy 352.369282 -232.285) (xy 352.381059 -232.237216) (xy 352.40035 -232.19194) (xy 352.426653 -232.150344)
			(xy 352.459288 -232.113507) (xy 352.497409 -232.082382) (xy 352.54003 -232.057775) (xy 352.586046 -232.040323)
			(xy 352.634265 -232.030479) (xy 352.68344 -232.028498) (xy 352.732295 -232.03443) (xy 352.779566 -232.048122)
			(xy 352.824028 -232.06922) (xy 352.864531 -232.097176) (xy 352.900024 -232.131268) (xy 352.929589 -232.170612)
			(xy 352.95246 -232.214189) (xy 352.968044 -232.26087) (xy 352.975939 -232.309447) (xy 352.976434 -232.334054)
			(xy 353.305376 -232.334054) (xy 353.309336 -232.285) (xy 353.321113 -232.237216) (xy 353.340404 -232.19194)
			(xy 353.366707 -232.150344) (xy 353.399342 -232.113507) (xy 353.437463 -232.082382) (xy 353.480084 -232.057775)
			(xy 353.5261 -232.040323) (xy 353.574319 -232.030479) (xy 353.623494 -232.028498) (xy 353.672349 -232.03443)
			(xy 353.71962 -232.048122) (xy 353.764082 -232.06922) (xy 353.804585 -232.097176) (xy 353.840078 -232.131268)
			(xy 353.869643 -232.170612) (xy 353.892514 -232.214189) (xy 353.908098 -232.26087) (xy 353.915993 -232.309447)
			(xy 353.916488 -232.334054) (xy 354.24543 -232.334054) (xy 354.24939 -232.285) (xy 354.261167 -232.237216)
			(xy 354.280458 -232.19194) (xy 354.306761 -232.150344) (xy 354.339396 -232.113507) (xy 354.377517 -232.082382)
			(xy 354.420138 -232.057775) (xy 354.466154 -232.040323) (xy 354.514373 -232.030479) (xy 354.563548 -232.028498)
			(xy 354.612403 -232.03443) (xy 354.659674 -232.048122) (xy 354.704136 -232.06922) (xy 354.744639 -232.097176)
			(xy 354.780132 -232.131268) (xy 354.809697 -232.170612) (xy 354.832568 -232.214189) (xy 354.848152 -232.26087)
			(xy 354.856047 -232.309447) (xy 354.856542 -232.334054) (xy 355.18523 -232.334054) (xy 355.18919 -232.285)
			(xy 355.200967 -232.237216) (xy 355.220258 -232.19194) (xy 355.246561 -232.150344) (xy 355.279196 -232.113507)
			(xy 355.317317 -232.082382) (xy 355.359938 -232.057775) (xy 355.405954 -232.040323) (xy 355.454173 -232.030479)
			(xy 355.503348 -232.028498) (xy 355.552203 -232.03443) (xy 355.599474 -232.048122) (xy 355.643936 -232.06922)
			(xy 355.684439 -232.097176) (xy 355.719932 -232.131268) (xy 355.749497 -232.170612) (xy 355.772368 -232.214189)
			(xy 355.787952 -232.26087) (xy 355.795847 -232.309447) (xy 355.796342 -232.334054) (xy 356.125284 -232.334054)
			(xy 356.129244 -232.285) (xy 356.141021 -232.237216) (xy 356.160312 -232.19194) (xy 356.186615 -232.150344)
			(xy 356.21925 -232.113507) (xy 356.257371 -232.082382) (xy 356.299992 -232.057775) (xy 356.346008 -232.040323)
			(xy 356.394227 -232.030479) (xy 356.443402 -232.028498) (xy 356.492257 -232.03443) (xy 356.539528 -232.048122)
			(xy 356.58399 -232.06922) (xy 356.624493 -232.097176) (xy 356.659986 -232.131268) (xy 356.689551 -232.170612)
			(xy 356.712422 -232.214189) (xy 356.728006 -232.26087) (xy 356.735901 -232.309447) (xy 356.736396 -232.334054)
			(xy 357.065338 -232.334054) (xy 357.069298 -232.285) (xy 357.081075 -232.237216) (xy 357.100366 -232.19194)
			(xy 357.126669 -232.150344) (xy 357.159304 -232.113507) (xy 357.197425 -232.082382) (xy 357.240046 -232.057775)
			(xy 357.286062 -232.040323) (xy 357.334281 -232.030479) (xy 357.383456 -232.028498) (xy 357.432311 -232.03443)
			(xy 357.479582 -232.048122) (xy 357.524044 -232.06922) (xy 357.564547 -232.097176) (xy 357.60004 -232.131268)
			(xy 357.629605 -232.170612) (xy 357.652476 -232.214189) (xy 357.66806 -232.26087) (xy 357.675955 -232.309447)
			(xy 357.67645 -232.334054) (xy 358.005392 -232.334054) (xy 358.009352 -232.285) (xy 358.021129 -232.237216)
			(xy 358.04042 -232.19194) (xy 358.066723 -232.150344) (xy 358.099358 -232.113507) (xy 358.137479 -232.082382)
			(xy 358.1801 -232.057775) (xy 358.226116 -232.040323) (xy 358.274335 -232.030479) (xy 358.32351 -232.028498)
			(xy 358.372365 -232.03443) (xy 358.419636 -232.048122) (xy 358.464098 -232.06922) (xy 358.504601 -232.097176)
			(xy 358.540094 -232.131268) (xy 358.569659 -232.170612) (xy 358.59253 -232.214189) (xy 358.608114 -232.26087)
			(xy 358.616009 -232.309447) (xy 358.616504 -232.334054) (xy 358.616009 -232.358661) (xy 358.608114 -232.407238)
			(xy 358.59253 -232.453919) (xy 358.569659 -232.497496) (xy 358.540094 -232.53684) (xy 358.504601 -232.570932)
			(xy 358.464098 -232.598888) (xy 358.419636 -232.619986) (xy 358.372365 -232.633678) (xy 358.32351 -232.63961)
			(xy 358.274335 -232.637629) (xy 358.226116 -232.627785) (xy 358.1801 -232.610333) (xy 358.137479 -232.585726)
			(xy 358.099358 -232.554601) (xy 358.066723 -232.517764) (xy 358.04042 -232.476168) (xy 358.021129 -232.430892)
			(xy 358.009352 -232.383108) (xy 358.005392 -232.334054) (xy 357.67645 -232.334054) (xy 357.675955 -232.358661)
			(xy 357.66806 -232.407238) (xy 357.652476 -232.453919) (xy 357.629605 -232.497496) (xy 357.60004 -232.53684)
			(xy 357.564547 -232.570932) (xy 357.524044 -232.598888) (xy 357.479582 -232.619986) (xy 357.432311 -232.633678)
			(xy 357.383456 -232.63961) (xy 357.334281 -232.637629) (xy 357.286062 -232.627785) (xy 357.240046 -232.610333)
			(xy 357.197425 -232.585726) (xy 357.159304 -232.554601) (xy 357.126669 -232.517764) (xy 357.100366 -232.476168)
			(xy 357.081075 -232.430892) (xy 357.069298 -232.383108) (xy 357.065338 -232.334054) (xy 356.736396 -232.334054)
			(xy 356.735901 -232.358661) (xy 356.728006 -232.407238) (xy 356.712422 -232.453919) (xy 356.689551 -232.497496)
			(xy 356.659986 -232.53684) (xy 356.624493 -232.570932) (xy 356.58399 -232.598888) (xy 356.539528 -232.619986)
			(xy 356.492257 -232.633678) (xy 356.443402 -232.63961) (xy 356.394227 -232.637629) (xy 356.346008 -232.627785)
			(xy 356.299992 -232.610333) (xy 356.257371 -232.585726) (xy 356.21925 -232.554601) (xy 356.186615 -232.517764)
			(xy 356.160312 -232.476168) (xy 356.141021 -232.430892) (xy 356.129244 -232.383108) (xy 356.125284 -232.334054)
			(xy 355.796342 -232.334054) (xy 355.795847 -232.358661) (xy 355.787952 -232.407238) (xy 355.772368 -232.453919)
			(xy 355.749497 -232.497496) (xy 355.719932 -232.53684) (xy 355.684439 -232.570932) (xy 355.643936 -232.598888)
			(xy 355.599474 -232.619986) (xy 355.552203 -232.633678) (xy 355.503348 -232.63961) (xy 355.454173 -232.637629)
			(xy 355.405954 -232.627785) (xy 355.359938 -232.610333) (xy 355.317317 -232.585726) (xy 355.279196 -232.554601)
			(xy 355.246561 -232.517764) (xy 355.220258 -232.476168) (xy 355.200967 -232.430892) (xy 355.18919 -232.383108)
			(xy 355.18523 -232.334054) (xy 354.856542 -232.334054) (xy 354.856047 -232.358661) (xy 354.848152 -232.407238)
			(xy 354.832568 -232.453919) (xy 354.809697 -232.497496) (xy 354.780132 -232.53684) (xy 354.744639 -232.570932)
			(xy 354.704136 -232.598888) (xy 354.659674 -232.619986) (xy 354.612403 -232.633678) (xy 354.563548 -232.63961)
			(xy 354.514373 -232.637629) (xy 354.466154 -232.627785) (xy 354.420138 -232.610333) (xy 354.377517 -232.585726)
			(xy 354.339396 -232.554601) (xy 354.306761 -232.517764) (xy 354.280458 -232.476168) (xy 354.261167 -232.430892)
			(xy 354.24939 -232.383108) (xy 354.24543 -232.334054) (xy 353.916488 -232.334054) (xy 353.915993 -232.358661)
			(xy 353.908098 -232.407238) (xy 353.892514 -232.453919) (xy 353.869643 -232.497496) (xy 353.840078 -232.53684)
			(xy 353.804585 -232.570932) (xy 353.764082 -232.598888) (xy 353.71962 -232.619986) (xy 353.672349 -232.633678)
			(xy 353.623494 -232.63961) (xy 353.574319 -232.637629) (xy 353.5261 -232.627785) (xy 353.480084 -232.610333)
			(xy 353.437463 -232.585726) (xy 353.399342 -232.554601) (xy 353.366707 -232.517764) (xy 353.340404 -232.476168)
			(xy 353.321113 -232.430892) (xy 353.309336 -232.383108) (xy 353.305376 -232.334054) (xy 352.976434 -232.334054)
			(xy 352.975939 -232.358661) (xy 352.968044 -232.407238) (xy 352.95246 -232.453919) (xy 352.929589 -232.497496)
			(xy 352.900024 -232.53684) (xy 352.864531 -232.570932) (xy 352.824028 -232.598888) (xy 352.779566 -232.619986)
			(xy 352.732295 -232.633678) (xy 352.68344 -232.63961) (xy 352.634265 -232.637629) (xy 352.586046 -232.627785)
			(xy 352.54003 -232.610333) (xy 352.497409 -232.585726) (xy 352.459288 -232.554601) (xy 352.426653 -232.517764)
			(xy 352.40035 -232.476168) (xy 352.381059 -232.430892) (xy 352.369282 -232.383108) (xy 352.365322 -232.334054)
			(xy 352.03638 -232.334054) (xy 352.035885 -232.358661) (xy 352.02799 -232.407238) (xy 352.012406 -232.453919)
			(xy 351.989535 -232.497496) (xy 351.95997 -232.53684) (xy 351.924477 -232.570932) (xy 351.883974 -232.598888)
			(xy 351.839512 -232.619986) (xy 351.792241 -232.633678) (xy 351.743386 -232.63961) (xy 351.694211 -232.637629)
			(xy 351.645992 -232.627785) (xy 351.599976 -232.610333) (xy 351.557355 -232.585726) (xy 351.519234 -232.554601)
			(xy 351.486599 -232.517764) (xy 351.460296 -232.476168) (xy 351.441005 -232.430892) (xy 351.429228 -232.383108)
			(xy 351.425268 -232.334054) (xy 351.096326 -232.334054) (xy 351.095831 -232.358661) (xy 351.087936 -232.407238)
			(xy 351.072352 -232.453919) (xy 351.049481 -232.497496) (xy 351.019916 -232.53684) (xy 350.984423 -232.570932)
			(xy 350.94392 -232.598888) (xy 350.899458 -232.619986) (xy 350.852187 -232.633678) (xy 350.803332 -232.63961)
			(xy 350.754157 -232.637629) (xy 350.705938 -232.627785) (xy 350.659922 -232.610333) (xy 350.617301 -232.585726)
			(xy 350.57918 -232.554601) (xy 350.546545 -232.517764) (xy 350.520242 -232.476168) (xy 350.500951 -232.430892)
			(xy 350.489174 -232.383108) (xy 350.485214 -232.334054) (xy 350.156526 -232.334054) (xy 350.156031 -232.358661)
			(xy 350.148136 -232.407238) (xy 350.132552 -232.453919) (xy 350.109681 -232.497496) (xy 350.080116 -232.53684)
			(xy 350.044623 -232.570932) (xy 350.00412 -232.598888) (xy 349.959658 -232.619986) (xy 349.912387 -232.633678)
			(xy 349.863532 -232.63961) (xy 349.814357 -232.637629) (xy 349.766138 -232.627785) (xy 349.720122 -232.610333)
			(xy 349.677501 -232.585726) (xy 349.63938 -232.554601) (xy 349.606745 -232.517764) (xy 349.580442 -232.476168)
			(xy 349.561151 -232.430892) (xy 349.549374 -232.383108) (xy 349.545414 -232.334054) (xy 349.216472 -232.334054)
			(xy 349.215977 -232.358661) (xy 349.208082 -232.407238) (xy 349.192498 -232.453919) (xy 349.169627 -232.497496)
			(xy 349.140062 -232.53684) (xy 349.104569 -232.570932) (xy 349.064066 -232.598888) (xy 349.019604 -232.619986)
			(xy 348.972333 -232.633678) (xy 348.923478 -232.63961) (xy 348.874303 -232.637629) (xy 348.826084 -232.627785)
			(xy 348.780068 -232.610333) (xy 348.737447 -232.585726) (xy 348.699326 -232.554601) (xy 348.666691 -232.517764)
			(xy 348.640388 -232.476168) (xy 348.621097 -232.430892) (xy 348.60932 -232.383108) (xy 348.60536 -232.334054)
			(xy 348.276418 -232.334054) (xy 348.275923 -232.358661) (xy 348.268028 -232.407238) (xy 348.252444 -232.453919)
			(xy 348.229573 -232.497496) (xy 348.200008 -232.53684) (xy 348.164515 -232.570932) (xy 348.124012 -232.598888)
			(xy 348.07955 -232.619986) (xy 348.032279 -232.633678) (xy 347.983424 -232.63961) (xy 347.934249 -232.637629)
			(xy 347.88603 -232.627785) (xy 347.840014 -232.610333) (xy 347.797393 -232.585726) (xy 347.759272 -232.554601)
			(xy 347.726637 -232.517764) (xy 347.700334 -232.476168) (xy 347.681043 -232.430892) (xy 347.669266 -232.383108)
			(xy 347.665306 -232.334054) (xy 347.336618 -232.334054) (xy 347.336175 -232.358068) (xy 347.328667 -232.405506)
			(xy 347.31383 -232.451185) (xy 347.292028 -232.49398) (xy 347.263799 -232.532837) (xy 347.229838 -232.566798)
			(xy 347.190982 -232.595027) (xy 347.148187 -232.616829) (xy 347.102508 -232.631667) (xy 347.05507 -232.639175)
			(xy 347.031056 -232.639616) (xy 347.006768 -232.639152) (xy 346.958803 -232.631474) (xy 346.912657 -232.616303)
			(xy 346.869492 -232.594022) (xy 346.830398 -232.56519) (xy 346.796358 -232.530536) (xy 346.768231 -232.490932)
			(xy 346.746725 -232.447377) (xy 346.732382 -232.400966) (xy 346.728542 -232.37698) (xy 346.727272 -232.367328)
			(xy 346.717874 -232.350818) (xy 346.64904 -232.295446) (xy 346.630752 -232.289604) (xy 346.620846 -232.290366)
			(xy 346.605947 -232.291443) (xy 346.576094 -232.292587) (xy 346.561156 -232.292652) (xy 346.44711 -232.292652)
			(xy 346.437223 -232.293113) (xy 346.418915 -232.300581) (xy 346.404787 -232.314414) (xy 346.396933 -232.33256)
			(xy 346.39631 -232.342436) (xy 346.39631 -232.342944) (xy 346.395086 -232.367705) (xy 346.38562 -232.416365)
			(xy 346.36842 -232.462857) (xy 346.343938 -232.505962) (xy 346.312817 -232.544548) (xy 346.275873 -232.577602)
			(xy 346.234076 -232.604256) (xy 346.188524 -232.623811) (xy 346.140411 -232.635753) (xy 346.091002 -232.639768)
			(xy 346.041593 -232.635753) (xy 345.99348 -232.623811) (xy 345.947928 -232.604256) (xy 345.906131 -232.577602)
			(xy 345.869187 -232.544548) (xy 345.838066 -232.505962) (xy 345.813584 -232.462857) (xy 345.796384 -232.416365)
			(xy 345.786918 -232.367705) (xy 345.785694 -232.342944) (xy 345.785694 -232.342436) (xy 345.785042 -232.332557)
			(xy 345.777213 -232.314393) (xy 345.763094 -232.300541) (xy 345.744784 -232.29306) (xy 345.734894 -232.292652)
			(xy 345.621102 -232.292652) (xy 345.606228 -232.292586) (xy 345.576501 -232.291443) (xy 345.561666 -232.290366)
			(xy 345.55176 -232.289604) (xy 345.533726 -232.295192) (xy 345.46413 -232.351072) (xy 345.454986 -232.367328)
			(xy 345.453462 -232.377234) (xy 345.449573 -232.401179) (xy 345.435214 -232.447513) (xy 345.413709 -232.490993)
			(xy 345.385599 -232.530526) (xy 345.351592 -232.565118) (xy 345.312544 -232.593897) (xy 345.269436 -232.61614)
			(xy 345.223354 -232.631287) (xy 345.175456 -232.638957) (xy 345.151202 -232.639362) (xy 345.12721 -232.638916)
			(xy 345.079817 -232.631409) (xy 345.034182 -232.61658) (xy 344.991429 -232.594794) (xy 344.952611 -232.566588)
			(xy 344.918684 -232.532656) (xy 344.890483 -232.493833) (xy 344.868703 -232.451077) (xy 344.853881 -232.40544)
			(xy 344.846381 -232.358046) (xy 344.845894 -232.334054) (xy 344.846289 -232.311984) (xy 344.852644 -232.268305)
			(xy 344.8652 -232.225989) (xy 344.874088 -232.205784) (xy 344.874596 -232.205022) (xy 344.875358 -232.20299)
			(xy 344.875358 -232.202736) (xy 344.878692 -232.194885) (xy 344.880481 -232.177932) (xy 344.876615 -232.16133)
			(xy 344.87231 -232.153968) (xy 344.865452 -232.143046) (xy 344.842592 -232.1306) (xy 344.836242 -232.1306)
			(xy 344.826177 -232.130166) (xy 344.807587 -232.122437) (xy 344.800174 -232.115614) (xy 344.215974 -231.531414)
			(xy 344.209218 -231.525142) (xy 344.19246 -231.5175) (xy 344.174078 -231.516332) (xy 344.165174 -231.518714)
			(xy 344.093038 -231.540812) (xy 344.086538 -231.543016) (xy 344.074939 -231.550347) (xy 344.070178 -231.55529)
			(xy 344.057478 -231.569514) (xy 344.051382 -231.581198) (xy 344.050112 -231.588056) (xy 344.044798 -231.611433)
			(xy 344.028057 -231.656354) (xy 344.004718 -231.698228) (xy 343.975317 -231.736092) (xy 343.94053 -231.769076)
			(xy 343.901155 -231.796422) (xy 343.858099 -231.817501) (xy 343.812351 -231.831828) (xy 343.764963 -231.839075)
			(xy 343.740994 -231.839516) (xy 343.716201 -231.839029) (xy 343.667225 -231.831272) (xy 343.620066 -231.815948)
			(xy 343.575885 -231.793436) (xy 343.535769 -231.764289) (xy 343.500707 -231.729226) (xy 343.471561 -231.68911)
			(xy 343.44905 -231.644928) (xy 343.433727 -231.597769) (xy 343.42597 -231.548793) (xy 343.42597 -231.499207)
			(xy 343.433727 -231.450231) (xy 343.44905 -231.403072) (xy 343.471561 -231.35889) (xy 343.500707 -231.318774)
			(xy 343.535769 -231.283711) (xy 343.575885 -231.254564) (xy 343.620066 -231.232052) (xy 343.667225 -231.216728)
			(xy 343.716201 -231.208971) (xy 343.740994 -231.20858) (xy 343.759282 -231.20858) (xy 343.784428 -231.193086)
			(xy 343.79916 -231.162352) (xy 343.803201 -231.152712) (xy 343.803941 -231.131845) (xy 343.7963 -231.112413)
			(xy 343.789254 -231.104694) (xy 343.773506 -231.088946) (xy 343.766667 -231.081545) (xy 343.758952 -231.062947)
			(xy 343.75852 -231.052878) (xy 343.75852 -230.282242) (xy 343.758129 -230.272718) (xy 343.751226 -230.254964)
			(xy 343.745058 -230.247698) (xy 343.7255 -230.226362) (xy 343.709752 -230.218234) (xy 343.700608 -230.216964)
			(xy 343.675562 -230.213249) (xy 343.627015 -230.198879) (xy 343.581385 -230.176941) (xy 343.539844 -230.147997)
			(xy 343.503458 -230.112792) (xy 343.473161 -230.072228) (xy 343.44973 -230.027346) (xy 343.433767 -229.979299)
			(xy 343.425681 -229.929319) (xy 343.425681 -229.87869) (xy 343.433765 -229.82871) (xy 343.449727 -229.780662)
			(xy 343.473156 -229.73578) (xy 343.503452 -229.695215) (xy 343.539837 -229.660008) (xy 343.581377 -229.631064)
			(xy 343.627006 -229.609125) (xy 343.675553 -229.594753) (xy 343.700608 -229.591108) (xy 343.709752 -229.589838)
			(xy 343.7255 -229.58171) (xy 343.745058 -229.560374) (xy 343.751238 -229.553113) (xy 343.758149 -229.535358)
			(xy 343.75852 -229.52583) (xy 343.75852 -228.662484) (xy 343.758062 -228.652975) (xy 343.751152 -228.635254)
			(xy 343.745058 -228.62794) (xy 343.7255 -228.606604) (xy 343.709752 -228.598476) (xy 343.700608 -228.597206)
			(xy 343.675567 -228.593491) (xy 343.627029 -228.579122) (xy 343.581408 -228.557187) (xy 343.539875 -228.528248)
			(xy 343.503496 -228.493048) (xy 343.473206 -228.452491) (xy 343.44978 -228.407617) (xy 343.433821 -228.359578)
			(xy 343.425738 -228.309607) (xy 343.425739 -228.258987) (xy 343.433822 -228.209016) (xy 343.449782 -228.160978)
			(xy 343.473209 -228.116104) (xy 343.5035 -228.075547) (xy 343.539879 -228.040348) (xy 343.581412 -228.01141)
			(xy 343.627034 -227.989476) (xy 343.675572 -227.975108) (xy 343.700608 -227.97135) (xy 343.709752 -227.97008)
			(xy 343.7255 -227.961952) (xy 343.745058 -227.940616) (xy 343.751245 -227.933357) (xy 343.75817 -227.915603)
			(xy 343.75852 -227.906072) (xy 343.75852 -227.042472) (xy 343.75806 -227.032964) (xy 343.751147 -227.015246)
			(xy 343.745058 -227.007928) (xy 343.7255 -226.986592) (xy 343.709752 -226.978464) (xy 343.700608 -226.977194)
			(xy 343.675568 -226.973479) (xy 343.627031 -226.959111) (xy 343.581412 -226.937176) (xy 343.539881 -226.908238)
			(xy 343.503504 -226.873039) (xy 343.473215 -226.832483) (xy 343.449791 -226.787611) (xy 343.433832 -226.739574)
			(xy 343.42575 -226.689605) (xy 343.425751 -226.638986) (xy 343.433834 -226.589018) (xy 343.449794 -226.540981)
			(xy 343.47322 -226.496109) (xy 343.50351 -226.455554) (xy 343.539888 -226.420356) (xy 343.58142 -226.39142)
			(xy 343.62704 -226.369486) (xy 343.675576 -226.355119) (xy 343.700608 -226.351338) (xy 343.709752 -226.350068)
			(xy 343.7255 -226.34194) (xy 343.745058 -226.320604) (xy 343.751243 -226.313345) (xy 343.758164 -226.29559)
			(xy 343.75852 -226.28606) (xy 343.75852 -225.41865) (xy 343.75813 -225.409125) (xy 343.75123 -225.391369)
			(xy 343.745058 -225.384106) (xy 343.730834 -225.368612) (xy 343.727881 -225.365513) (xy 343.721117 -225.36027)
			(xy 343.717372 -225.358198) (xy 343.695274 -225.34626) (xy 343.6874 -225.34499) (xy 343.66281 -225.340094)
			(xy 343.615552 -225.323353) (xy 343.571663 -225.299119) (xy 343.532321 -225.268042) (xy 343.498583 -225.230958)
			(xy 343.471353 -225.188862) (xy 343.451365 -225.142884) (xy 343.439153 -225.094259) (xy 343.435047 -225.044292)
			(xy 343.439156 -224.994325) (xy 343.45137 -224.945701) (xy 343.471361 -224.899724) (xy 343.498592 -224.857629)
			(xy 343.532333 -224.820546) (xy 343.571677 -224.789472) (xy 343.615567 -224.765241) (xy 343.662826 -224.748502)
			(xy 343.6874 -224.743518) (xy 343.695274 -224.742248) (xy 343.717372 -224.73031) (xy 343.721101 -224.728214)
			(xy 343.727865 -224.722976) (xy 343.730834 -224.719896) (xy 343.745058 -224.704402) (xy 343.751243 -224.697143)
			(xy 343.758163 -224.679388) (xy 343.75852 -224.669858) (xy 343.75852 -223.798638) (xy 343.758128 -223.789114)
			(xy 343.751224 -223.771361) (xy 343.745058 -223.764094) (xy 343.730834 -223.7486) (xy 343.727881 -223.745502)
			(xy 343.721116 -223.74026) (xy 343.717372 -223.738186) (xy 343.695274 -223.726248) (xy 343.6874 -223.724978)
			(xy 343.662803 -223.720081) (xy 343.615531 -223.703338) (xy 343.571628 -223.679099) (xy 343.532274 -223.648016)
			(xy 343.498523 -223.610923) (xy 343.471284 -223.568817) (xy 343.451287 -223.522826) (xy 343.43907 -223.474188)
			(xy 343.43496 -223.424207) (xy 343.439068 -223.374227) (xy 343.451283 -223.325588) (xy 343.471277 -223.279596)
			(xy 343.498514 -223.237488) (xy 343.532263 -223.200394) (xy 343.571616 -223.169309) (xy 343.615518 -223.145068)
			(xy 343.662789 -223.128322) (xy 343.6874 -223.123506) (xy 343.695274 -223.122236) (xy 343.717372 -223.110298)
			(xy 343.721101 -223.108201) (xy 343.727863 -223.102963) (xy 343.730834 -223.099884) (xy 343.745058 -223.08439)
			(xy 343.751241 -223.07713) (xy 343.758157 -223.059375) (xy 343.75852 -223.049846) (xy 343.75852 -221.262702)
			(xy 343.7509 -221.243906) (xy 343.743534 -221.236794) (xy 343.395046 -220.888306) (xy 343.387645 -220.881467)
			(xy 343.369047 -220.873752) (xy 343.358978 -220.87332) (xy 340.905338 -220.87332) (xy 340.895432 -220.877638)
			(xy 340.862997 -220.891273) (xy 340.795316 -220.910494) (xy 340.725633 -220.920215) (xy 340.690454 -220.920818)
			(xy 340.655274 -220.920223) (xy 340.585588 -220.910515) (xy 340.517909 -220.891278) (xy 340.485476 -220.877638)
			(xy 340.47557 -220.87332) (xy 340.086442 -220.87332) (xy 340.067646 -220.88094) (xy 340.060534 -220.888306)
			(xy 339.653626 -221.295214) (xy 339.646779 -221.302612) (xy 339.639046 -221.32121) (xy 339.63864 -221.331282)
			(xy 339.63864 -222.31985) (xy 339.652102 -222.342964) (xy 339.66404 -222.350076) (xy 339.685073 -222.362802)
			(xy 339.723139 -222.393905) (xy 339.755725 -222.430709) (xy 339.781987 -222.472263) (xy 339.801246 -222.51749)
			(xy 339.813003 -222.56522) (xy 339.816954 -222.614218) (xy 339.816953 -222.614236) (xy 340.145382 -222.614236)
			(xy 340.149342 -222.565182) (xy 340.161119 -222.517398) (xy 340.18041 -222.472122) (xy 340.206713 -222.430526)
			(xy 340.239348 -222.393689) (xy 340.277469 -222.362564) (xy 340.32009 -222.337957) (xy 340.366106 -222.320505)
			(xy 340.414325 -222.310661) (xy 340.4635 -222.30868) (xy 340.512355 -222.314612) (xy 340.559626 -222.328304)
			(xy 340.604088 -222.349402) (xy 340.644591 -222.377358) (xy 340.680084 -222.41145) (xy 340.709649 -222.450794)
			(xy 340.73252 -222.494371) (xy 340.748104 -222.541052) (xy 340.755999 -222.589629) (xy 340.756494 -222.614236)
			(xy 342.96529 -222.614236) (xy 342.96925 -222.565182) (xy 342.981027 -222.517398) (xy 343.000318 -222.472122)
			(xy 343.026621 -222.430526) (xy 343.059256 -222.393689) (xy 343.097377 -222.362564) (xy 343.139998 -222.337957)
			(xy 343.186014 -222.320505) (xy 343.234233 -222.310661) (xy 343.283408 -222.30868) (xy 343.332263 -222.314612)
			(xy 343.379534 -222.328304) (xy 343.423996 -222.349402) (xy 343.464499 -222.377358) (xy 343.499992 -222.41145)
			(xy 343.529557 -222.450794) (xy 343.552428 -222.494371) (xy 343.568012 -222.541052) (xy 343.575907 -222.589629)
			(xy 343.576402 -222.614236) (xy 343.575907 -222.638843) (xy 343.568012 -222.68742) (xy 343.552428 -222.734101)
			(xy 343.529557 -222.777678) (xy 343.499992 -222.817022) (xy 343.464499 -222.851114) (xy 343.423996 -222.87907)
			(xy 343.379534 -222.900168) (xy 343.332263 -222.91386) (xy 343.283408 -222.919792) (xy 343.234233 -222.917811)
			(xy 343.186014 -222.907967) (xy 343.139998 -222.890515) (xy 343.097377 -222.865908) (xy 343.059256 -222.834783)
			(xy 343.026621 -222.797946) (xy 343.000318 -222.75635) (xy 342.981027 -222.711074) (xy 342.96925 -222.66329)
			(xy 342.96529 -222.614236) (xy 340.756494 -222.614236) (xy 340.755999 -222.638843) (xy 340.748104 -222.68742)
			(xy 340.73252 -222.734101) (xy 340.709649 -222.777678) (xy 340.680084 -222.817022) (xy 340.644591 -222.851114)
			(xy 340.604088 -222.87907) (xy 340.559626 -222.900168) (xy 340.512355 -222.91386) (xy 340.4635 -222.919792)
			(xy 340.414325 -222.917811) (xy 340.366106 -222.907967) (xy 340.32009 -222.890515) (xy 340.277469 -222.865908)
			(xy 340.239348 -222.834783) (xy 340.206713 -222.797946) (xy 340.18041 -222.75635) (xy 340.161119 -222.711074)
			(xy 340.149342 -222.66329) (xy 340.145382 -222.614236) (xy 339.816953 -222.614236) (xy 339.812997 -222.663215)
			(xy 339.801234 -222.710944) (xy 339.78197 -222.756169) (xy 339.755703 -222.797719) (xy 339.723113 -222.83452)
			(xy 339.685043 -222.865619) (xy 339.66404 -222.878396) (xy 339.652102 -222.885508) (xy 339.63864 -222.908622)
			(xy 339.63864 -223.424242) (xy 341.555336 -223.424242) (xy 341.559296 -223.375188) (xy 341.571073 -223.327404)
			(xy 341.590364 -223.282128) (xy 341.616667 -223.240532) (xy 341.649302 -223.203695) (xy 341.687423 -223.17257)
			(xy 341.730044 -223.147963) (xy 341.77606 -223.130511) (xy 341.824279 -223.120667) (xy 341.873454 -223.118686)
			(xy 341.922309 -223.124618) (xy 341.96958 -223.13831) (xy 342.014042 -223.159408) (xy 342.054545 -223.187364)
			(xy 342.090038 -223.221456) (xy 342.119603 -223.2608) (xy 342.142474 -223.304377) (xy 342.158058 -223.351058)
			(xy 342.165953 -223.399635) (xy 342.166448 -223.424242) (xy 342.49539 -223.424242) (xy 342.49935 -223.375188)
			(xy 342.511127 -223.327404) (xy 342.530418 -223.282128) (xy 342.556721 -223.240532) (xy 342.589356 -223.203695)
			(xy 342.627477 -223.17257) (xy 342.670098 -223.147963) (xy 342.716114 -223.130511) (xy 342.764333 -223.120667)
			(xy 342.813508 -223.118686) (xy 342.862363 -223.124618) (xy 342.909634 -223.13831) (xy 342.954096 -223.159408)
			(xy 342.994599 -223.187364) (xy 343.030092 -223.221456) (xy 343.059657 -223.2608) (xy 343.082528 -223.304377)
			(xy 343.098112 -223.351058) (xy 343.106007 -223.399635) (xy 343.106502 -223.424242) (xy 343.106007 -223.448849)
			(xy 343.098112 -223.497426) (xy 343.082528 -223.544107) (xy 343.059657 -223.587684) (xy 343.030092 -223.627028)
			(xy 342.994599 -223.66112) (xy 342.954096 -223.689076) (xy 342.909634 -223.710174) (xy 342.862363 -223.723866)
			(xy 342.813508 -223.729798) (xy 342.764333 -223.727817) (xy 342.716114 -223.717973) (xy 342.670098 -223.700521)
			(xy 342.627477 -223.675914) (xy 342.589356 -223.644789) (xy 342.556721 -223.607952) (xy 342.530418 -223.566356)
			(xy 342.511127 -223.52108) (xy 342.49935 -223.473296) (xy 342.49539 -223.424242) (xy 342.166448 -223.424242)
			(xy 342.165953 -223.448849) (xy 342.158058 -223.497426) (xy 342.142474 -223.544107) (xy 342.119603 -223.587684)
			(xy 342.090038 -223.627028) (xy 342.054545 -223.66112) (xy 342.014042 -223.689076) (xy 341.96958 -223.710174)
			(xy 341.922309 -223.723866) (xy 341.873454 -223.729798) (xy 341.824279 -223.727817) (xy 341.77606 -223.717973)
			(xy 341.730044 -223.700521) (xy 341.687423 -223.675914) (xy 341.649302 -223.644789) (xy 341.616667 -223.607952)
			(xy 341.590364 -223.566356) (xy 341.571073 -223.52108) (xy 341.559296 -223.473296) (xy 341.555336 -223.424242)
			(xy 339.63864 -223.424242) (xy 339.63864 -223.939862) (xy 339.652102 -223.962976) (xy 339.66404 -223.970088)
			(xy 339.686827 -223.983885) (xy 339.727618 -224.018138) (xy 339.761841 -224.058954) (xy 339.788455 -224.105094)
			(xy 339.806652 -224.155155) (xy 339.815877 -224.207615) (xy 339.81644 -224.234248) (xy 341.085182 -224.234248)
			(xy 341.089142 -224.185194) (xy 341.100919 -224.13741) (xy 341.12021 -224.092134) (xy 341.146513 -224.050538)
			(xy 341.179148 -224.013701) (xy 341.217269 -223.982576) (xy 341.25989 -223.957969) (xy 341.305906 -223.940517)
			(xy 341.354125 -223.930673) (xy 341.4033 -223.928692) (xy 341.452155 -223.934624) (xy 341.499426 -223.948316)
			(xy 341.543888 -223.969414) (xy 341.584391 -223.99737) (xy 341.619884 -224.031462) (xy 341.649449 -224.070806)
			(xy 341.67232 -224.114383) (xy 341.687904 -224.161064) (xy 341.695799 -224.209641) (xy 341.696294 -224.234248)
			(xy 341.695799 -224.258855) (xy 341.687904 -224.307432) (xy 341.67232 -224.354113) (xy 341.649449 -224.39769)
			(xy 341.619884 -224.437034) (xy 341.584391 -224.471126) (xy 341.543888 -224.499082) (xy 341.499426 -224.52018)
			(xy 341.452155 -224.533872) (xy 341.4033 -224.539804) (xy 341.354125 -224.537823) (xy 341.305906 -224.527979)
			(xy 341.25989 -224.510527) (xy 341.217269 -224.48592) (xy 341.179148 -224.454795) (xy 341.146513 -224.417958)
			(xy 341.12021 -224.376362) (xy 341.100919 -224.331086) (xy 341.089142 -224.283302) (xy 341.085182 -224.234248)
			(xy 339.81644 -224.234248) (xy 339.816394 -224.243285) (xy 339.815379 -224.261331) (xy 339.814408 -224.270316)
			(xy 339.814408 -224.270824) (xy 339.813778 -224.28221) (xy 339.821308 -224.303702) (xy 339.828886 -224.312226)
			(xy 340.4743 -224.95764) (xy 340.483593 -224.966095) (xy 340.507589 -224.973431) (xy 340.52002 -224.97161)
			(xy 340.615524 -224.952814) (xy 340.635082 -224.937066) (xy 340.639908 -224.925128) (xy 340.650341 -224.901814)
			(xy 340.677806 -224.858754) (xy 340.712058 -224.820868) (xy 340.752139 -224.789213) (xy 340.796931 -224.764673)
			(xy 340.845183 -224.747933) (xy 340.895549 -224.739461) (xy 340.921086 -224.738946) (xy 340.945079 -224.739416)
			(xy 340.992475 -224.74692) (xy 341.038114 -224.761745) (xy 341.080872 -224.783527) (xy 341.119696 -224.81173)
			(xy 341.153631 -224.845658) (xy 341.181841 -224.884477) (xy 341.203632 -224.92723) (xy 341.218466 -224.972866)
			(xy 341.22598 -225.020261) (xy 341.226394 -225.044254) (xy 341.544905 -225.044254) (xy 341.549 -224.993526)
			(xy 341.561179 -224.944112) (xy 341.581127 -224.897292) (xy 341.608328 -224.854278) (xy 341.642076 -224.816184)
			(xy 341.681498 -224.783997) (xy 341.725572 -224.758551) (xy 341.773158 -224.740504) (xy 341.823022 -224.730324)
			(xy 341.873874 -224.728275) (xy 341.924395 -224.734409) (xy 341.973279 -224.748569) (xy 342.019258 -224.770386)
			(xy 342.061142 -224.799296) (xy 342.097846 -224.834551) (xy 342.128419 -224.875237) (xy 342.15207 -224.9203)
			(xy 342.168186 -224.968574) (xy 342.17635 -225.018808) (xy 342.176862 -225.044254) (xy 342.49539 -225.044254)
			(xy 342.49935 -224.9952) (xy 342.511127 -224.947416) (xy 342.530418 -224.90214) (xy 342.556721 -224.860544)
			(xy 342.589356 -224.823707) (xy 342.627477 -224.792582) (xy 342.670098 -224.767975) (xy 342.716114 -224.750523)
			(xy 342.764333 -224.740679) (xy 342.813508 -224.738698) (xy 342.862363 -224.74463) (xy 342.909634 -224.758322)
			(xy 342.954096 -224.77942) (xy 342.994599 -224.807376) (xy 343.030092 -224.841468) (xy 343.059657 -224.880812)
			(xy 343.082528 -224.924389) (xy 343.098112 -224.97107) (xy 343.106007 -225.019647) (xy 343.106502 -225.044254)
			(xy 343.106007 -225.068861) (xy 343.098112 -225.117438) (xy 343.082528 -225.164119) (xy 343.059657 -225.207696)
			(xy 343.030092 -225.24704) (xy 342.994599 -225.281132) (xy 342.954096 -225.309088) (xy 342.909634 -225.330186)
			(xy 342.862363 -225.343878) (xy 342.813508 -225.34981) (xy 342.764333 -225.347829) (xy 342.716114 -225.337985)
			(xy 342.670098 -225.320533) (xy 342.627477 -225.295926) (xy 342.589356 -225.264801) (xy 342.556721 -225.227964)
			(xy 342.530418 -225.186368) (xy 342.511127 -225.141092) (xy 342.49935 -225.093308) (xy 342.49539 -225.044254)
			(xy 342.176862 -225.044254) (xy 342.17635 -225.0697) (xy 342.168186 -225.119934) (xy 342.15207 -225.168208)
			(xy 342.128419 -225.213271) (xy 342.097846 -225.253957) (xy 342.061142 -225.289212) (xy 342.019258 -225.318122)
			(xy 341.973279 -225.339939) (xy 341.924395 -225.354099) (xy 341.873874 -225.360233) (xy 341.823022 -225.358184)
			(xy 341.773158 -225.348004) (xy 341.725572 -225.329957) (xy 341.681498 -225.304511) (xy 341.642076 -225.272324)
			(xy 341.608328 -225.23423) (xy 341.581127 -225.191216) (xy 341.561179 -225.144396) (xy 341.549 -225.094982)
			(xy 341.544905 -225.044254) (xy 341.226394 -225.044254) (xy 341.225875 -225.069788) (xy 341.217375 -225.120142)
			(xy 341.20062 -225.168383) (xy 341.176077 -225.213166) (xy 341.144429 -225.253244) (xy 341.106557 -225.287502)
			(xy 341.063517 -225.314986) (xy 341.040212 -225.325432) (xy 341.028274 -225.330258) (xy 341.012526 -225.349816)
			(xy 340.99373 -225.44532) (xy 340.992 -225.45774) (xy 340.999341 -225.481689) (xy 341.0077 -225.49104)
			(xy 341.144352 -225.627692) (xy 341.183214 -225.629724) (xy 341.198454 -225.617278) (xy 341.219011 -225.601255)
			(xy 341.264451 -225.575735) (xy 341.313566 -225.558303) (xy 341.364928 -225.549466) (xy 341.390986 -225.548952)
			(xy 341.416248 -225.549444) (xy 341.466083 -225.557758) (xy 341.513869 -225.574161) (xy 341.558304 -225.598206)
			(xy 341.598175 -225.629237) (xy 341.632394 -225.666408) (xy 341.660029 -225.708704) (xy 341.680325 -225.754972)
			(xy 341.692728 -225.803949) (xy 341.696897 -225.85426) (xy 342.014805 -225.85426) (xy 342.0189 -225.803532)
			(xy 342.031079 -225.754118) (xy 342.051027 -225.707298) (xy 342.078228 -225.664284) (xy 342.111976 -225.62619)
			(xy 342.151398 -225.594003) (xy 342.195472 -225.568557) (xy 342.243058 -225.55051) (xy 342.292922 -225.54033)
			(xy 342.343774 -225.538281) (xy 342.394295 -225.544415) (xy 342.443179 -225.558575) (xy 342.489158 -225.580392)
			(xy 342.531042 -225.609302) (xy 342.567746 -225.644557) (xy 342.598319 -225.685243) (xy 342.62197 -225.730306)
			(xy 342.638086 -225.77858) (xy 342.64625 -225.828814) (xy 342.646762 -225.85426) (xy 342.954859 -225.85426)
			(xy 342.958954 -225.803532) (xy 342.971133 -225.754118) (xy 342.991081 -225.707298) (xy 343.018282 -225.664284)
			(xy 343.05203 -225.62619) (xy 343.091452 -225.594003) (xy 343.135526 -225.568557) (xy 343.183112 -225.55051)
			(xy 343.232976 -225.54033) (xy 343.283828 -225.538281) (xy 343.334349 -225.544415) (xy 343.383233 -225.558575)
			(xy 343.429212 -225.580392) (xy 343.471096 -225.609302) (xy 343.5078 -225.644557) (xy 343.538373 -225.685243)
			(xy 343.562024 -225.730306) (xy 343.57814 -225.77858) (xy 343.586304 -225.828814) (xy 343.586816 -225.85426)
			(xy 343.586304 -225.879706) (xy 343.57814 -225.92994) (xy 343.562024 -225.978214) (xy 343.538373 -226.023277)
			(xy 343.5078 -226.063963) (xy 343.471096 -226.099218) (xy 343.429212 -226.128128) (xy 343.383233 -226.149945)
			(xy 343.334349 -226.164105) (xy 343.283828 -226.170239) (xy 343.232976 -226.16819) (xy 343.183112 -226.15801)
			(xy 343.135526 -226.139963) (xy 343.091452 -226.114517) (xy 343.05203 -226.08233) (xy 343.018282 -226.044236)
			(xy 342.991081 -226.001222) (xy 342.971133 -225.954402) (xy 342.958954 -225.904988) (xy 342.954859 -225.85426)
			(xy 342.646762 -225.85426) (xy 342.64625 -225.879706) (xy 342.638086 -225.92994) (xy 342.62197 -225.978214)
			(xy 342.598319 -226.023277) (xy 342.567746 -226.063963) (xy 342.531042 -226.099218) (xy 342.489158 -226.128128)
			(xy 342.443179 -226.149945) (xy 342.394295 -226.164105) (xy 342.343774 -226.170239) (xy 342.292922 -226.16819)
			(xy 342.243058 -226.15801) (xy 342.195472 -226.139963) (xy 342.151398 -226.114517) (xy 342.111976 -226.08233)
			(xy 342.078228 -226.044236) (xy 342.051027 -226.001222) (xy 342.031079 -225.954402) (xy 342.0189 -225.904988)
			(xy 342.014805 -225.85426) (xy 341.696897 -225.85426) (xy 341.6969 -225.8543) (xy 341.692728 -225.904651)
			(xy 341.680325 -225.953628) (xy 341.660029 -225.999896) (xy 341.632394 -226.042192) (xy 341.598175 -226.079363)
			(xy 341.558304 -226.110394) (xy 341.513869 -226.134439) (xy 341.466083 -226.150842) (xy 341.416248 -226.159156)
			(xy 341.390986 -226.159568) (xy 341.380412 -226.159514) (xy 341.359311 -226.158117) (xy 341.348822 -226.156774)
			(xy 341.3379 -226.15525) (xy 341.317072 -226.1616) (xy 341.250778 -226.219004) (xy 341.242396 -226.22637)
			(xy 341.233252 -226.246182) (xy 341.233252 -226.664266) (xy 341.544905 -226.664266) (xy 341.549 -226.613538)
			(xy 341.561179 -226.564124) (xy 341.581127 -226.517304) (xy 341.608328 -226.47429) (xy 341.642076 -226.436196)
			(xy 341.681498 -226.404009) (xy 341.725572 -226.378563) (xy 341.773158 -226.360516) (xy 341.823022 -226.350336)
			(xy 341.873874 -226.348287) (xy 341.924395 -226.354421) (xy 341.973279 -226.368581) (xy 342.019258 -226.390398)
			(xy 342.061142 -226.419308) (xy 342.097846 -226.454563) (xy 342.128419 -226.495249) (xy 342.15207 -226.540312)
			(xy 342.168186 -226.588586) (xy 342.17635 -226.63882) (xy 342.176862 -226.664266) (xy 342.49539 -226.664266)
			(xy 342.49935 -226.615212) (xy 342.511127 -226.567428) (xy 342.530418 -226.522152) (xy 342.556721 -226.480556)
			(xy 342.589356 -226.443719) (xy 342.627477 -226.412594) (xy 342.670098 -226.387987) (xy 342.716114 -226.370535)
			(xy 342.764333 -226.360691) (xy 342.813508 -226.35871) (xy 342.862363 -226.364642) (xy 342.909634 -226.378334)
			(xy 342.954096 -226.399432) (xy 342.994599 -226.427388) (xy 343.030092 -226.46148) (xy 343.059657 -226.500824)
			(xy 343.082528 -226.544401) (xy 343.098112 -226.591082) (xy 343.106007 -226.639659) (xy 343.106502 -226.664266)
			(xy 343.106007 -226.688873) (xy 343.098112 -226.73745) (xy 343.082528 -226.784131) (xy 343.059657 -226.827708)
			(xy 343.030092 -226.867052) (xy 342.994599 -226.901144) (xy 342.954096 -226.9291) (xy 342.909634 -226.950198)
			(xy 342.862363 -226.96389) (xy 342.813508 -226.969822) (xy 342.764333 -226.967841) (xy 342.716114 -226.957997)
			(xy 342.670098 -226.940545) (xy 342.627477 -226.915938) (xy 342.589356 -226.884813) (xy 342.556721 -226.847976)
			(xy 342.530418 -226.80638) (xy 342.511127 -226.761104) (xy 342.49935 -226.71332) (xy 342.49539 -226.664266)
			(xy 342.176862 -226.664266) (xy 342.17635 -226.689712) (xy 342.168186 -226.739946) (xy 342.15207 -226.78822)
			(xy 342.128419 -226.833283) (xy 342.097846 -226.873969) (xy 342.061142 -226.909224) (xy 342.019258 -226.938134)
			(xy 341.973279 -226.959951) (xy 341.924395 -226.974111) (xy 341.873874 -226.980245) (xy 341.823022 -226.978196)
			(xy 341.773158 -226.968016) (xy 341.725572 -226.949969) (xy 341.681498 -226.924523) (xy 341.642076 -226.892336)
			(xy 341.608328 -226.854242) (xy 341.581127 -226.811228) (xy 341.561179 -226.764408) (xy 341.549 -226.714994)
			(xy 341.544905 -226.664266) (xy 341.233252 -226.664266) (xy 341.233252 -227.071174) (xy 341.233808 -227.081869)
			(xy 341.24246 -227.101433) (xy 341.250016 -227.10902) (xy 341.250524 -227.109274) (xy 341.316564 -227.166932)
			(xy 341.327232 -227.16998) (xy 341.3379 -227.173282) (xy 341.348822 -227.171758) (xy 341.359312 -227.170425)
			(xy 341.380412 -227.169026) (xy 341.390986 -227.168964) (xy 341.416247 -227.169456) (xy 341.46608 -227.177769)
			(xy 341.513864 -227.194172) (xy 341.558297 -227.218216) (xy 341.598167 -227.249246) (xy 341.632385 -227.286415)
			(xy 341.660018 -227.32871) (xy 341.680313 -227.374976) (xy 341.692716 -227.423951) (xy 341.696886 -227.474272)
			(xy 342.014805 -227.474272) (xy 342.0189 -227.423544) (xy 342.031079 -227.37413) (xy 342.051027 -227.32731)
			(xy 342.078228 -227.284296) (xy 342.111976 -227.246202) (xy 342.151398 -227.214015) (xy 342.195472 -227.188569)
			(xy 342.243058 -227.170522) (xy 342.292922 -227.160342) (xy 342.343774 -227.158293) (xy 342.394295 -227.164427)
			(xy 342.443179 -227.178587) (xy 342.489158 -227.200404) (xy 342.531042 -227.229314) (xy 342.567746 -227.264569)
			(xy 342.598319 -227.305255) (xy 342.62197 -227.350318) (xy 342.638086 -227.398592) (xy 342.64625 -227.448826)
			(xy 342.646762 -227.474272) (xy 342.954859 -227.474272) (xy 342.958954 -227.423544) (xy 342.971133 -227.37413)
			(xy 342.991081 -227.32731) (xy 343.018282 -227.284296) (xy 343.05203 -227.246202) (xy 343.091452 -227.214015)
			(xy 343.135526 -227.188569) (xy 343.183112 -227.170522) (xy 343.232976 -227.160342) (xy 343.283828 -227.158293)
			(xy 343.334349 -227.164427) (xy 343.383233 -227.178587) (xy 343.429212 -227.200404) (xy 343.471096 -227.229314)
			(xy 343.5078 -227.264569) (xy 343.538373 -227.305255) (xy 343.562024 -227.350318) (xy 343.57814 -227.398592)
			(xy 343.586304 -227.448826) (xy 343.586816 -227.474272) (xy 343.586304 -227.499718) (xy 343.57814 -227.549952)
			(xy 343.562024 -227.598226) (xy 343.538373 -227.643289) (xy 343.5078 -227.683975) (xy 343.471096 -227.71923)
			(xy 343.429212 -227.74814) (xy 343.383233 -227.769957) (xy 343.334349 -227.784117) (xy 343.283828 -227.790251)
			(xy 343.232976 -227.788202) (xy 343.183112 -227.778022) (xy 343.135526 -227.759975) (xy 343.091452 -227.734529)
			(xy 343.05203 -227.702342) (xy 343.018282 -227.664248) (xy 342.991081 -227.621234) (xy 342.971133 -227.574414)
			(xy 342.958954 -227.525) (xy 342.954859 -227.474272) (xy 342.646762 -227.474272) (xy 342.64625 -227.499718)
			(xy 342.638086 -227.549952) (xy 342.62197 -227.598226) (xy 342.598319 -227.643289) (xy 342.567746 -227.683975)
			(xy 342.531042 -227.71923) (xy 342.489158 -227.74814) (xy 342.443179 -227.769957) (xy 342.394295 -227.784117)
			(xy 342.343774 -227.790251) (xy 342.292922 -227.788202) (xy 342.243058 -227.778022) (xy 342.195472 -227.759975)
			(xy 342.151398 -227.734529) (xy 342.111976 -227.702342) (xy 342.078228 -227.664248) (xy 342.051027 -227.621234)
			(xy 342.031079 -227.574414) (xy 342.0189 -227.525) (xy 342.014805 -227.474272) (xy 341.696886 -227.474272)
			(xy 341.696888 -227.4743) (xy 341.692716 -227.524649) (xy 341.680313 -227.573624) (xy 341.660018 -227.61989)
			(xy 341.632385 -227.662185) (xy 341.598167 -227.699354) (xy 341.558297 -227.730384) (xy 341.513864 -227.754428)
			(xy 341.46608 -227.770831) (xy 341.416247 -227.779144) (xy 341.390986 -227.77958) (xy 341.380412 -227.779526)
			(xy 341.359311 -227.778129) (xy 341.348822 -227.776786) (xy 341.3379 -227.775262) (xy 341.317072 -227.781612)
			(xy 341.250778 -227.839016) (xy 341.242396 -227.846382) (xy 341.233252 -227.866194) (xy 341.233252 -228.284278)
			(xy 341.544905 -228.284278) (xy 341.549 -228.23355) (xy 341.561179 -228.184136) (xy 341.581127 -228.137316)
			(xy 341.608328 -228.094302) (xy 341.642076 -228.056208) (xy 341.681498 -228.024021) (xy 341.725572 -227.998575)
			(xy 341.773158 -227.980528) (xy 341.823022 -227.970348) (xy 341.873874 -227.968299) (xy 341.924395 -227.974433)
			(xy 341.973279 -227.988593) (xy 342.019258 -228.01041) (xy 342.061142 -228.03932) (xy 342.097846 -228.074575)
			(xy 342.128419 -228.115261) (xy 342.15207 -228.160324) (xy 342.168186 -228.208598) (xy 342.17635 -228.258832)
			(xy 342.176862 -228.284278) (xy 342.49539 -228.284278) (xy 342.49935 -228.235224) (xy 342.511127 -228.18744)
			(xy 342.530418 -228.142164) (xy 342.556721 -228.100568) (xy 342.589356 -228.063731) (xy 342.627477 -228.032606)
			(xy 342.670098 -228.007999) (xy 342.716114 -227.990547) (xy 342.764333 -227.980703) (xy 342.813508 -227.978722)
			(xy 342.862363 -227.984654) (xy 342.909634 -227.998346) (xy 342.954096 -228.019444) (xy 342.994599 -228.0474)
			(xy 343.030092 -228.081492) (xy 343.059657 -228.120836) (xy 343.082528 -228.164413) (xy 343.098112 -228.211094)
			(xy 343.106007 -228.259671) (xy 343.106502 -228.284278) (xy 343.106007 -228.308885) (xy 343.098112 -228.357462)
			(xy 343.082528 -228.404143) (xy 343.059657 -228.44772) (xy 343.030092 -228.487064) (xy 342.994599 -228.521156)
			(xy 342.954096 -228.549112) (xy 342.909634 -228.57021) (xy 342.862363 -228.583902) (xy 342.813508 -228.589834)
			(xy 342.764333 -228.587853) (xy 342.716114 -228.578009) (xy 342.670098 -228.560557) (xy 342.627477 -228.53595)
			(xy 342.589356 -228.504825) (xy 342.556721 -228.467988) (xy 342.530418 -228.426392) (xy 342.511127 -228.381116)
			(xy 342.49935 -228.333332) (xy 342.49539 -228.284278) (xy 342.176862 -228.284278) (xy 342.17635 -228.309724)
			(xy 342.168186 -228.359958) (xy 342.15207 -228.408232) (xy 342.128419 -228.453295) (xy 342.097846 -228.493981)
			(xy 342.061142 -228.529236) (xy 342.019258 -228.558146) (xy 341.973279 -228.579963) (xy 341.924395 -228.594123)
			(xy 341.873874 -228.600257) (xy 341.823022 -228.598208) (xy 341.773158 -228.588028) (xy 341.725572 -228.569981)
			(xy 341.681498 -228.544535) (xy 341.642076 -228.512348) (xy 341.608328 -228.474254) (xy 341.581127 -228.43124)
			(xy 341.561179 -228.38442) (xy 341.549 -228.335006) (xy 341.544905 -228.284278) (xy 341.233252 -228.284278)
			(xy 341.233252 -228.691186) (xy 341.23381 -228.70188) (xy 341.242465 -228.72144) (xy 341.250016 -228.729032)
			(xy 341.250524 -228.729286) (xy 341.316564 -228.786944) (xy 341.327232 -228.789992) (xy 341.3379 -228.793294)
			(xy 341.348822 -228.79177) (xy 341.359312 -228.790437) (xy 341.380412 -228.789038) (xy 341.390986 -228.788976)
			(xy 341.416246 -228.789468) (xy 341.466077 -228.797781) (xy 341.51386 -228.814183) (xy 341.558291 -228.838226)
			(xy 341.598159 -228.869255) (xy 341.632376 -228.906422) (xy 341.660008 -228.948715) (xy 341.680302 -228.994979)
			(xy 341.692704 -229.043953) (xy 341.696875 -229.094284) (xy 342.014805 -229.094284) (xy 342.0189 -229.043556)
			(xy 342.031079 -228.994142) (xy 342.051027 -228.947322) (xy 342.078228 -228.904308) (xy 342.111976 -228.866214)
			(xy 342.151398 -228.834027) (xy 342.195472 -228.808581) (xy 342.243058 -228.790534) (xy 342.292922 -228.780354)
			(xy 342.343774 -228.778305) (xy 342.394295 -228.784439) (xy 342.443179 -228.798599) (xy 342.489158 -228.820416)
			(xy 342.531042 -228.849326) (xy 342.567746 -228.884581) (xy 342.598319 -228.925267) (xy 342.62197 -228.97033)
			(xy 342.638086 -229.018604) (xy 342.64625 -229.068838) (xy 342.646762 -229.094284) (xy 342.954859 -229.094284)
			(xy 342.958954 -229.043556) (xy 342.971133 -228.994142) (xy 342.991081 -228.947322) (xy 343.018282 -228.904308)
			(xy 343.05203 -228.866214) (xy 343.091452 -228.834027) (xy 343.135526 -228.808581) (xy 343.183112 -228.790534)
			(xy 343.232976 -228.780354) (xy 343.283828 -228.778305) (xy 343.334349 -228.784439) (xy 343.383233 -228.798599)
			(xy 343.429212 -228.820416) (xy 343.471096 -228.849326) (xy 343.5078 -228.884581) (xy 343.538373 -228.925267)
			(xy 343.562024 -228.97033) (xy 343.57814 -229.018604) (xy 343.586304 -229.068838) (xy 343.586816 -229.094284)
			(xy 343.586304 -229.11973) (xy 343.57814 -229.169964) (xy 343.562024 -229.218238) (xy 343.538373 -229.263301)
			(xy 343.5078 -229.303987) (xy 343.471096 -229.339242) (xy 343.429212 -229.368152) (xy 343.383233 -229.389969)
			(xy 343.334349 -229.404129) (xy 343.283828 -229.410263) (xy 343.232976 -229.408214) (xy 343.183112 -229.398034)
			(xy 343.135526 -229.379987) (xy 343.091452 -229.354541) (xy 343.05203 -229.322354) (xy 343.018282 -229.28426)
			(xy 342.991081 -229.241246) (xy 342.971133 -229.194426) (xy 342.958954 -229.145012) (xy 342.954859 -229.094284)
			(xy 342.646762 -229.094284) (xy 342.64625 -229.11973) (xy 342.638086 -229.169964) (xy 342.62197 -229.218238)
			(xy 342.598319 -229.263301) (xy 342.567746 -229.303987) (xy 342.531042 -229.339242) (xy 342.489158 -229.368152)
			(xy 342.443179 -229.389969) (xy 342.394295 -229.404129) (xy 342.343774 -229.410263) (xy 342.292922 -229.408214)
			(xy 342.243058 -229.398034) (xy 342.195472 -229.379987) (xy 342.151398 -229.354541) (xy 342.111976 -229.322354)
			(xy 342.078228 -229.28426) (xy 342.051027 -229.241246) (xy 342.031079 -229.194426) (xy 342.0189 -229.145012)
			(xy 342.014805 -229.094284) (xy 341.696875 -229.094284) (xy 341.696876 -229.0943) (xy 341.692704 -229.144647)
			(xy 341.680302 -229.193621) (xy 341.660008 -229.239885) (xy 341.632376 -229.282178) (xy 341.598159 -229.319345)
			(xy 341.558291 -229.350374) (xy 341.51386 -229.374417) (xy 341.466077 -229.390819) (xy 341.416246 -229.399132)
			(xy 341.390986 -229.399592) (xy 341.380412 -229.399538) (xy 341.359311 -229.398141) (xy 341.348822 -229.396798)
			(xy 341.3379 -229.395274) (xy 341.317072 -229.401624) (xy 341.250778 -229.459028) (xy 341.242396 -229.466394)
			(xy 341.233252 -229.486206) (xy 341.233252 -229.904036) (xy 341.544905 -229.904036) (xy 341.549 -229.853308)
			(xy 341.561179 -229.803894) (xy 341.581127 -229.757074) (xy 341.608328 -229.71406) (xy 341.642076 -229.675966)
			(xy 341.681498 -229.643779) (xy 341.725572 -229.618333) (xy 341.773158 -229.600286) (xy 341.823022 -229.590106)
			(xy 341.873874 -229.588057) (xy 341.924395 -229.594191) (xy 341.973279 -229.608351) (xy 342.019258 -229.630168)
			(xy 342.061142 -229.659078) (xy 342.097846 -229.694333) (xy 342.128419 -229.735019) (xy 342.15207 -229.780082)
			(xy 342.168186 -229.828356) (xy 342.17635 -229.87859) (xy 342.176862 -229.904036) (xy 342.49539 -229.904036)
			(xy 342.49935 -229.854982) (xy 342.511127 -229.807198) (xy 342.530418 -229.761922) (xy 342.556721 -229.720326)
			(xy 342.589356 -229.683489) (xy 342.627477 -229.652364) (xy 342.670098 -229.627757) (xy 342.716114 -229.610305)
			(xy 342.764333 -229.600461) (xy 342.813508 -229.59848) (xy 342.862363 -229.604412) (xy 342.909634 -229.618104)
			(xy 342.954096 -229.639202) (xy 342.994599 -229.667158) (xy 343.030092 -229.70125) (xy 343.059657 -229.740594)
			(xy 343.082528 -229.784171) (xy 343.098112 -229.830852) (xy 343.106007 -229.879429) (xy 343.106502 -229.904036)
			(xy 343.106007 -229.928643) (xy 343.098112 -229.97722) (xy 343.082528 -230.023901) (xy 343.059657 -230.067478)
			(xy 343.030092 -230.106822) (xy 342.994599 -230.140914) (xy 342.954096 -230.16887) (xy 342.909634 -230.189968)
			(xy 342.862363 -230.20366) (xy 342.813508 -230.209592) (xy 342.764333 -230.207611) (xy 342.716114 -230.197767)
			(xy 342.670098 -230.180315) (xy 342.627477 -230.155708) (xy 342.589356 -230.124583) (xy 342.556721 -230.087746)
			(xy 342.530418 -230.04615) (xy 342.511127 -230.000874) (xy 342.49935 -229.95309) (xy 342.49539 -229.904036)
			(xy 342.176862 -229.904036) (xy 342.17635 -229.929482) (xy 342.168186 -229.979716) (xy 342.15207 -230.02799)
			(xy 342.128419 -230.073053) (xy 342.097846 -230.113739) (xy 342.061142 -230.148994) (xy 342.019258 -230.177904)
			(xy 341.973279 -230.199721) (xy 341.924395 -230.213881) (xy 341.873874 -230.220015) (xy 341.823022 -230.217966)
			(xy 341.773158 -230.207786) (xy 341.725572 -230.189739) (xy 341.681498 -230.164293) (xy 341.642076 -230.132106)
			(xy 341.608328 -230.094012) (xy 341.581127 -230.050998) (xy 341.561179 -230.004178) (xy 341.549 -229.954764)
			(xy 341.544905 -229.904036) (xy 341.233252 -229.904036) (xy 341.233252 -230.311198) (xy 341.233812 -230.321891)
			(xy 341.242471 -230.341447) (xy 341.250016 -230.349044) (xy 341.250524 -230.349298) (xy 341.316564 -230.406956)
			(xy 341.327232 -230.410004) (xy 341.3379 -230.413052) (xy 341.348822 -230.411782) (xy 341.359308 -230.410386)
			(xy 341.380408 -230.408861) (xy 341.390986 -230.408734) (xy 341.414979 -230.409179) (xy 341.462373 -230.416684)
			(xy 341.50801 -230.431512) (xy 341.550765 -230.453298) (xy 341.589585 -230.481504) (xy 341.623515 -230.515436)
			(xy 341.651717 -230.554259) (xy 341.673498 -230.597016) (xy 341.688322 -230.642654) (xy 341.695823 -230.690049)
			(xy 341.696294 -230.714042) (xy 341.696294 -230.714296) (xy 342.014805 -230.714296) (xy 342.0189 -230.663568)
			(xy 342.031079 -230.614154) (xy 342.051027 -230.567334) (xy 342.078228 -230.52432) (xy 342.111976 -230.486226)
			(xy 342.151398 -230.454039) (xy 342.195472 -230.428593) (xy 342.243058 -230.410546) (xy 342.292922 -230.400366)
			(xy 342.343774 -230.398317) (xy 342.394295 -230.404451) (xy 342.443179 -230.418611) (xy 342.489158 -230.440428)
			(xy 342.531042 -230.469338) (xy 342.567746 -230.504593) (xy 342.598319 -230.545279) (xy 342.62197 -230.590342)
			(xy 342.638086 -230.638616) (xy 342.64625 -230.68885) (xy 342.646762 -230.714296) (xy 342.954859 -230.714296)
			(xy 342.958954 -230.663568) (xy 342.971133 -230.614154) (xy 342.991081 -230.567334) (xy 343.018282 -230.52432)
			(xy 343.05203 -230.486226) (xy 343.091452 -230.454039) (xy 343.135526 -230.428593) (xy 343.183112 -230.410546)
			(xy 343.232976 -230.400366) (xy 343.283828 -230.398317) (xy 343.334349 -230.404451) (xy 343.383233 -230.418611)
			(xy 343.429212 -230.440428) (xy 343.471096 -230.469338) (xy 343.5078 -230.504593) (xy 343.538373 -230.545279)
			(xy 343.562024 -230.590342) (xy 343.57814 -230.638616) (xy 343.586304 -230.68885) (xy 343.586816 -230.714296)
			(xy 343.586304 -230.739742) (xy 343.57814 -230.789976) (xy 343.562024 -230.83825) (xy 343.538373 -230.883313)
			(xy 343.5078 -230.923999) (xy 343.471096 -230.959254) (xy 343.429212 -230.988164) (xy 343.383233 -231.009981)
			(xy 343.334349 -231.024141) (xy 343.283828 -231.030275) (xy 343.232976 -231.028226) (xy 343.183112 -231.018046)
			(xy 343.135526 -230.999999) (xy 343.091452 -230.974553) (xy 343.05203 -230.942366) (xy 343.018282 -230.904272)
			(xy 342.991081 -230.861258) (xy 342.971133 -230.814438) (xy 342.958954 -230.765024) (xy 342.954859 -230.714296)
			(xy 342.646762 -230.714296) (xy 342.64625 -230.739742) (xy 342.638086 -230.789976) (xy 342.62197 -230.83825)
			(xy 342.598319 -230.883313) (xy 342.567746 -230.923999) (xy 342.531042 -230.959254) (xy 342.489158 -230.988164)
			(xy 342.443179 -231.009981) (xy 342.394295 -231.024141) (xy 342.343774 -231.030275) (xy 342.292922 -231.028226)
			(xy 342.243058 -231.018046) (xy 342.195472 -230.999999) (xy 342.151398 -230.974553) (xy 342.111976 -230.942366)
			(xy 342.078228 -230.904272) (xy 342.051027 -230.861258) (xy 342.031079 -230.814438) (xy 342.0189 -230.765024)
			(xy 342.014805 -230.714296) (xy 341.696294 -230.714296) (xy 341.695848 -230.738289) (xy 341.688342 -230.785684)
			(xy 341.673513 -230.831321) (xy 341.651728 -230.874077) (xy 341.623522 -230.912898) (xy 341.589591 -230.946829)
			(xy 341.550769 -230.975033) (xy 341.508012 -230.996817) (xy 341.462374 -231.011644) (xy 341.414979 -231.019149)
			(xy 341.390986 -231.019604) (xy 341.380412 -231.01955) (xy 341.359311 -231.018153) (xy 341.348822 -231.01681)
			(xy 341.3379 -231.015286) (xy 341.317072 -231.021636) (xy 341.250778 -231.07904) (xy 341.242396 -231.086406)
			(xy 341.233252 -231.106218) (xy 341.233252 -231.524048) (xy 341.544905 -231.524048) (xy 341.549 -231.47332)
			(xy 341.561179 -231.423906) (xy 341.581127 -231.377086) (xy 341.608328 -231.334072) (xy 341.642076 -231.295978)
			(xy 341.681498 -231.263791) (xy 341.725572 -231.238345) (xy 341.773158 -231.220298) (xy 341.823022 -231.210118)
			(xy 341.873874 -231.208069) (xy 341.924395 -231.214203) (xy 341.973279 -231.228363) (xy 342.019258 -231.25018)
			(xy 342.061142 -231.27909) (xy 342.097846 -231.314345) (xy 342.128419 -231.355031) (xy 342.15207 -231.400094)
			(xy 342.168186 -231.448368) (xy 342.17635 -231.498602) (xy 342.176862 -231.524048) (xy 342.49539 -231.524048)
			(xy 342.49935 -231.474994) (xy 342.511127 -231.42721) (xy 342.530418 -231.381934) (xy 342.556721 -231.340338)
			(xy 342.589356 -231.303501) (xy 342.627477 -231.272376) (xy 342.670098 -231.247769) (xy 342.716114 -231.230317)
			(xy 342.764333 -231.220473) (xy 342.813508 -231.218492) (xy 342.862363 -231.224424) (xy 342.909634 -231.238116)
			(xy 342.954096 -231.259214) (xy 342.994599 -231.28717) (xy 343.030092 -231.321262) (xy 343.059657 -231.360606)
			(xy 343.082528 -231.404183) (xy 343.098112 -231.450864) (xy 343.106007 -231.499441) (xy 343.106502 -231.524048)
			(xy 343.106007 -231.548655) (xy 343.098112 -231.597232) (xy 343.082528 -231.643913) (xy 343.059657 -231.68749)
			(xy 343.030092 -231.726834) (xy 342.994599 -231.760926) (xy 342.954096 -231.788882) (xy 342.909634 -231.80998)
			(xy 342.862363 -231.823672) (xy 342.813508 -231.829604) (xy 342.764333 -231.827623) (xy 342.716114 -231.817779)
			(xy 342.670098 -231.800327) (xy 342.627477 -231.77572) (xy 342.589356 -231.744595) (xy 342.556721 -231.707758)
			(xy 342.530418 -231.666162) (xy 342.511127 -231.620886) (xy 342.49935 -231.573102) (xy 342.49539 -231.524048)
			(xy 342.176862 -231.524048) (xy 342.17635 -231.549494) (xy 342.168186 -231.599728) (xy 342.15207 -231.648002)
			(xy 342.128419 -231.693065) (xy 342.097846 -231.733751) (xy 342.061142 -231.769006) (xy 342.019258 -231.797916)
			(xy 341.973279 -231.819733) (xy 341.924395 -231.833893) (xy 341.873874 -231.840027) (xy 341.823022 -231.837978)
			(xy 341.773158 -231.827798) (xy 341.725572 -231.809751) (xy 341.681498 -231.784305) (xy 341.642076 -231.752118)
			(xy 341.608328 -231.714024) (xy 341.581127 -231.67101) (xy 341.561179 -231.62419) (xy 341.549 -231.574776)
			(xy 341.544905 -231.524048) (xy 341.233252 -231.524048) (xy 341.233252 -231.930956) (xy 341.233823 -231.941643)
			(xy 341.242496 -231.961183) (xy 341.250016 -231.968802) (xy 341.250524 -231.969056) (xy 341.316564 -232.026714)
			(xy 341.327232 -232.029762) (xy 341.3379 -232.033064) (xy 341.348822 -232.03154) (xy 341.359312 -232.030207)
			(xy 341.380412 -232.028808) (xy 341.390986 -232.028746) (xy 341.416248 -232.029238) (xy 341.466084 -232.037552)
			(xy 341.513872 -232.053955) (xy 341.558307 -232.078001) (xy 341.598179 -232.109033) (xy 341.632399 -232.146204)
			(xy 341.660034 -232.188501) (xy 341.68033 -232.23477) (xy 341.692734 -232.283748) (xy 341.696902 -232.334054)
			(xy 342.014805 -232.334054) (xy 342.0189 -232.283326) (xy 342.031079 -232.233912) (xy 342.051027 -232.187092)
			(xy 342.078228 -232.144078) (xy 342.111976 -232.105984) (xy 342.151398 -232.073797) (xy 342.195472 -232.048351)
			(xy 342.243058 -232.030304) (xy 342.292922 -232.020124) (xy 342.343774 -232.018075) (xy 342.394295 -232.024209)
			(xy 342.443179 -232.038369) (xy 342.489158 -232.060186) (xy 342.531042 -232.089096) (xy 342.567746 -232.124351)
			(xy 342.598319 -232.165037) (xy 342.62197 -232.2101) (xy 342.638086 -232.258374) (xy 342.64625 -232.308608)
			(xy 342.646762 -232.334054) (xy 342.954859 -232.334054) (xy 342.958954 -232.283326) (xy 342.971133 -232.233912)
			(xy 342.991081 -232.187092) (xy 343.018282 -232.144078) (xy 343.05203 -232.105984) (xy 343.091452 -232.073797)
			(xy 343.135526 -232.048351) (xy 343.183112 -232.030304) (xy 343.232976 -232.020124) (xy 343.283828 -232.018075)
			(xy 343.334349 -232.024209) (xy 343.383233 -232.038369) (xy 343.429212 -232.060186) (xy 343.471096 -232.089096)
			(xy 343.5078 -232.124351) (xy 343.538373 -232.165037) (xy 343.562024 -232.2101) (xy 343.57814 -232.258374)
			(xy 343.586304 -232.308608) (xy 343.586816 -232.334054) (xy 343.905344 -232.334054) (xy 343.909304 -232.285)
			(xy 343.921081 -232.237216) (xy 343.940372 -232.19194) (xy 343.966675 -232.150344) (xy 343.99931 -232.113507)
			(xy 344.037431 -232.082382) (xy 344.080052 -232.057775) (xy 344.126068 -232.040323) (xy 344.174287 -232.030479)
			(xy 344.223462 -232.028498) (xy 344.272317 -232.03443) (xy 344.319588 -232.048122) (xy 344.36405 -232.06922)
			(xy 344.404553 -232.097176) (xy 344.440046 -232.131268) (xy 344.469611 -232.170612) (xy 344.492482 -232.214189)
			(xy 344.508066 -232.26087) (xy 344.515961 -232.309447) (xy 344.516456 -232.334054) (xy 344.515961 -232.358661)
			(xy 344.508066 -232.407238) (xy 344.492482 -232.453919) (xy 344.469611 -232.497496) (xy 344.440046 -232.53684)
			(xy 344.404553 -232.570932) (xy 344.36405 -232.598888) (xy 344.319588 -232.619986) (xy 344.272317 -232.633678)
			(xy 344.223462 -232.63961) (xy 344.174287 -232.637629) (xy 344.126068 -232.627785) (xy 344.080052 -232.610333)
			(xy 344.037431 -232.585726) (xy 343.99931 -232.554601) (xy 343.966675 -232.517764) (xy 343.940372 -232.476168)
			(xy 343.921081 -232.430892) (xy 343.909304 -232.383108) (xy 343.905344 -232.334054) (xy 343.586816 -232.334054)
			(xy 343.586304 -232.3595) (xy 343.57814 -232.409734) (xy 343.562024 -232.458008) (xy 343.538373 -232.503071)
			(xy 343.5078 -232.543757) (xy 343.471096 -232.579012) (xy 343.429212 -232.607922) (xy 343.383233 -232.629739)
			(xy 343.334349 -232.643899) (xy 343.283828 -232.650033) (xy 343.232976 -232.647984) (xy 343.183112 -232.637804)
			(xy 343.135526 -232.619757) (xy 343.091452 -232.594311) (xy 343.05203 -232.562124) (xy 343.018282 -232.52403)
			(xy 342.991081 -232.481016) (xy 342.971133 -232.434196) (xy 342.958954 -232.384782) (xy 342.954859 -232.334054)
			(xy 342.646762 -232.334054) (xy 342.64625 -232.3595) (xy 342.638086 -232.409734) (xy 342.62197 -232.458008)
			(xy 342.598319 -232.503071) (xy 342.567746 -232.543757) (xy 342.531042 -232.579012) (xy 342.489158 -232.607922)
			(xy 342.443179 -232.629739) (xy 342.394295 -232.643899) (xy 342.343774 -232.650033) (xy 342.292922 -232.647984)
			(xy 342.243058 -232.637804) (xy 342.195472 -232.619757) (xy 342.151398 -232.594311) (xy 342.111976 -232.562124)
			(xy 342.078228 -232.52403) (xy 342.051027 -232.481016) (xy 342.031079 -232.434196) (xy 342.0189 -232.384782)
			(xy 342.014805 -232.334054) (xy 341.696902 -232.334054) (xy 341.696906 -232.3341) (xy 341.692734 -232.384452)
			(xy 341.68033 -232.43343) (xy 341.660034 -232.479699) (xy 341.632399 -232.521996) (xy 341.598179 -232.559167)
			(xy 341.558307 -232.590199) (xy 341.513872 -232.614245) (xy 341.466084 -232.630648) (xy 341.416248 -232.638962)
			(xy 341.390986 -232.639362) (xy 341.380412 -232.639308) (xy 341.359311 -232.637911) (xy 341.348822 -232.636568)
			(xy 341.3379 -232.635044) (xy 341.317072 -232.641394) (xy 341.250778 -232.698798) (xy 341.242396 -232.706164)
			(xy 341.233252 -232.725976) (xy 341.233252 -233.14406) (xy 341.544905 -233.14406) (xy 341.549 -233.093332)
			(xy 341.561179 -233.043918) (xy 341.581127 -232.997098) (xy 341.608328 -232.954084) (xy 341.642076 -232.91599)
			(xy 341.681498 -232.883803) (xy 341.725572 -232.858357) (xy 341.773158 -232.84031) (xy 341.823022 -232.83013)
			(xy 341.873874 -232.828081) (xy 341.924395 -232.834215) (xy 341.973279 -232.848375) (xy 342.019258 -232.870192)
			(xy 342.061142 -232.899102) (xy 342.097846 -232.934357) (xy 342.128419 -232.975043) (xy 342.15207 -233.020106)
			(xy 342.168186 -233.06838) (xy 342.17635 -233.118614) (xy 342.176862 -233.14406) (xy 342.49539 -233.14406)
			(xy 342.49935 -233.095006) (xy 342.511127 -233.047222) (xy 342.530418 -233.001946) (xy 342.556721 -232.96035)
			(xy 342.589356 -232.923513) (xy 342.627477 -232.892388) (xy 342.670098 -232.867781) (xy 342.716114 -232.850329)
			(xy 342.764333 -232.840485) (xy 342.813508 -232.838504) (xy 342.862363 -232.844436) (xy 342.909634 -232.858128)
			(xy 342.954096 -232.879226) (xy 342.994599 -232.907182) (xy 343.030092 -232.941274) (xy 343.059657 -232.980618)
			(xy 343.082528 -233.024195) (xy 343.098112 -233.070876) (xy 343.106007 -233.119453) (xy 343.106502 -233.14406)
			(xy 343.424759 -233.14406) (xy 343.428854 -233.093332) (xy 343.441033 -233.043918) (xy 343.460981 -232.997098)
			(xy 343.488182 -232.954084) (xy 343.52193 -232.91599) (xy 343.561352 -232.883803) (xy 343.605426 -232.858357)
			(xy 343.653012 -232.84031) (xy 343.702876 -232.83013) (xy 343.753728 -232.828081) (xy 343.804249 -232.834215)
			(xy 343.853133 -232.848375) (xy 343.899112 -232.870192) (xy 343.940996 -232.899102) (xy 343.9777 -232.934357)
			(xy 344.008273 -232.975043) (xy 344.031924 -233.020106) (xy 344.04804 -233.06838) (xy 344.056204 -233.118614)
			(xy 344.056716 -233.14406) (xy 344.375244 -233.14406) (xy 344.379204 -233.095006) (xy 344.390981 -233.047222)
			(xy 344.410272 -233.001946) (xy 344.436575 -232.96035) (xy 344.46921 -232.923513) (xy 344.507331 -232.892388)
			(xy 344.549952 -232.867781) (xy 344.595968 -232.850329) (xy 344.644187 -232.840485) (xy 344.693362 -232.838504)
			(xy 344.742217 -232.844436) (xy 344.789488 -232.858128) (xy 344.83395 -232.879226) (xy 344.874453 -232.907182)
			(xy 344.909946 -232.941274) (xy 344.939511 -232.980618) (xy 344.962382 -233.024195) (xy 344.977966 -233.070876)
			(xy 344.985861 -233.119453) (xy 344.986356 -233.14406) (xy 345.315298 -233.14406) (xy 345.319258 -233.095006)
			(xy 345.331035 -233.047222) (xy 345.350326 -233.001946) (xy 345.376629 -232.96035) (xy 345.409264 -232.923513)
			(xy 345.447385 -232.892388) (xy 345.490006 -232.867781) (xy 345.536022 -232.850329) (xy 345.584241 -232.840485)
			(xy 345.633416 -232.838504) (xy 345.682271 -232.844436) (xy 345.729542 -232.858128) (xy 345.774004 -232.879226)
			(xy 345.814507 -232.907182) (xy 345.85 -232.941274) (xy 345.879565 -232.980618) (xy 345.902436 -233.024195)
			(xy 345.91802 -233.070876) (xy 345.925915 -233.119453) (xy 345.92641 -233.14406) (xy 346.255352 -233.14406)
			(xy 346.259312 -233.095006) (xy 346.271089 -233.047222) (xy 346.29038 -233.001946) (xy 346.316683 -232.96035)
			(xy 346.349318 -232.923513) (xy 346.387439 -232.892388) (xy 346.43006 -232.867781) (xy 346.476076 -232.850329)
			(xy 346.524295 -232.840485) (xy 346.57347 -232.838504) (xy 346.622325 -232.844436) (xy 346.669596 -232.858128)
			(xy 346.714058 -232.879226) (xy 346.754561 -232.907182) (xy 346.790054 -232.941274) (xy 346.819619 -232.980618)
			(xy 346.84249 -233.024195) (xy 346.858074 -233.070876) (xy 346.865969 -233.119453) (xy 346.866464 -233.14406)
			(xy 347.195406 -233.14406) (xy 347.199366 -233.095006) (xy 347.211143 -233.047222) (xy 347.230434 -233.001946)
			(xy 347.256737 -232.96035) (xy 347.289372 -232.923513) (xy 347.327493 -232.892388) (xy 347.370114 -232.867781)
			(xy 347.41613 -232.850329) (xy 347.464349 -232.840485) (xy 347.513524 -232.838504) (xy 347.562379 -232.844436)
			(xy 347.60965 -232.858128) (xy 347.654112 -232.879226) (xy 347.694615 -232.907182) (xy 347.730108 -232.941274)
			(xy 347.759673 -232.980618) (xy 347.782544 -233.024195) (xy 347.798128 -233.070876) (xy 347.806023 -233.119453)
			(xy 347.806518 -233.14406) (xy 348.135206 -233.14406) (xy 348.139166 -233.095006) (xy 348.150943 -233.047222)
			(xy 348.170234 -233.001946) (xy 348.196537 -232.96035) (xy 348.229172 -232.923513) (xy 348.267293 -232.892388)
			(xy 348.309914 -232.867781) (xy 348.35593 -232.850329) (xy 348.404149 -232.840485) (xy 348.453324 -232.838504)
			(xy 348.502179 -232.844436) (xy 348.54945 -232.858128) (xy 348.593912 -232.879226) (xy 348.634415 -232.907182)
			(xy 348.669908 -232.941274) (xy 348.699473 -232.980618) (xy 348.722344 -233.024195) (xy 348.737928 -233.070876)
			(xy 348.745823 -233.119453) (xy 348.746318 -233.14406) (xy 349.07526 -233.14406) (xy 349.07922 -233.095006)
			(xy 349.090997 -233.047222) (xy 349.110288 -233.001946) (xy 349.136591 -232.96035) (xy 349.169226 -232.923513)
			(xy 349.207347 -232.892388) (xy 349.249968 -232.867781) (xy 349.295984 -232.850329) (xy 349.344203 -232.840485)
			(xy 349.393378 -232.838504) (xy 349.442233 -232.844436) (xy 349.489504 -232.858128) (xy 349.533966 -232.879226)
			(xy 349.574469 -232.907182) (xy 349.609962 -232.941274) (xy 349.639527 -232.980618) (xy 349.662398 -233.024195)
			(xy 349.677982 -233.070876) (xy 349.685877 -233.119453) (xy 349.686372 -233.14406) (xy 350.015314 -233.14406)
			(xy 350.019274 -233.095006) (xy 350.031051 -233.047222) (xy 350.050342 -233.001946) (xy 350.076645 -232.96035)
			(xy 350.10928 -232.923513) (xy 350.147401 -232.892388) (xy 350.190022 -232.867781) (xy 350.236038 -232.850329)
			(xy 350.284257 -232.840485) (xy 350.333432 -232.838504) (xy 350.382287 -232.844436) (xy 350.429558 -232.858128)
			(xy 350.47402 -232.879226) (xy 350.514523 -232.907182) (xy 350.550016 -232.941274) (xy 350.579581 -232.980618)
			(xy 350.602452 -233.024195) (xy 350.618036 -233.070876) (xy 350.625931 -233.119453) (xy 350.626426 -233.14406)
			(xy 350.955368 -233.14406) (xy 350.959328 -233.095006) (xy 350.971105 -233.047222) (xy 350.990396 -233.001946)
			(xy 351.016699 -232.96035) (xy 351.049334 -232.923513) (xy 351.087455 -232.892388) (xy 351.130076 -232.867781)
			(xy 351.176092 -232.850329) (xy 351.224311 -232.840485) (xy 351.273486 -232.838504) (xy 351.322341 -232.844436)
			(xy 351.369612 -232.858128) (xy 351.414074 -232.879226) (xy 351.454577 -232.907182) (xy 351.49007 -232.941274)
			(xy 351.519635 -232.980618) (xy 351.542506 -233.024195) (xy 351.55809 -233.070876) (xy 351.565985 -233.119453)
			(xy 351.56648 -233.14406) (xy 351.895422 -233.14406) (xy 351.899382 -233.095006) (xy 351.911159 -233.047222)
			(xy 351.93045 -233.001946) (xy 351.956753 -232.96035) (xy 351.989388 -232.923513) (xy 352.027509 -232.892388)
			(xy 352.07013 -232.867781) (xy 352.116146 -232.850329) (xy 352.164365 -232.840485) (xy 352.21354 -232.838504)
			(xy 352.262395 -232.844436) (xy 352.309666 -232.858128) (xy 352.354128 -232.879226) (xy 352.394631 -232.907182)
			(xy 352.430124 -232.941274) (xy 352.459689 -232.980618) (xy 352.48256 -233.024195) (xy 352.498144 -233.070876)
			(xy 352.506039 -233.119453) (xy 352.506534 -233.14406) (xy 352.835222 -233.14406) (xy 352.839182 -233.095006)
			(xy 352.850959 -233.047222) (xy 352.87025 -233.001946) (xy 352.896553 -232.96035) (xy 352.929188 -232.923513)
			(xy 352.967309 -232.892388) (xy 353.00993 -232.867781) (xy 353.055946 -232.850329) (xy 353.104165 -232.840485)
			(xy 353.15334 -232.838504) (xy 353.202195 -232.844436) (xy 353.249466 -232.858128) (xy 353.293928 -232.879226)
			(xy 353.334431 -232.907182) (xy 353.369924 -232.941274) (xy 353.399489 -232.980618) (xy 353.42236 -233.024195)
			(xy 353.437944 -233.070876) (xy 353.445839 -233.119453) (xy 353.446334 -233.14406) (xy 353.775276 -233.14406)
			(xy 353.779236 -233.095006) (xy 353.791013 -233.047222) (xy 353.810304 -233.001946) (xy 353.836607 -232.96035)
			(xy 353.869242 -232.923513) (xy 353.907363 -232.892388) (xy 353.949984 -232.867781) (xy 353.996 -232.850329)
			(xy 354.044219 -232.840485) (xy 354.093394 -232.838504) (xy 354.142249 -232.844436) (xy 354.18952 -232.858128)
			(xy 354.233982 -232.879226) (xy 354.274485 -232.907182) (xy 354.309978 -232.941274) (xy 354.339543 -232.980618)
			(xy 354.362414 -233.024195) (xy 354.377998 -233.070876) (xy 354.385893 -233.119453) (xy 354.386388 -233.14406)
			(xy 354.71533 -233.14406) (xy 354.71929 -233.095006) (xy 354.731067 -233.047222) (xy 354.750358 -233.001946)
			(xy 354.776661 -232.96035) (xy 354.809296 -232.923513) (xy 354.847417 -232.892388) (xy 354.890038 -232.867781)
			(xy 354.936054 -232.850329) (xy 354.984273 -232.840485) (xy 355.033448 -232.838504) (xy 355.082303 -232.844436)
			(xy 355.129574 -232.858128) (xy 355.174036 -232.879226) (xy 355.214539 -232.907182) (xy 355.250032 -232.941274)
			(xy 355.279597 -232.980618) (xy 355.302468 -233.024195) (xy 355.318052 -233.070876) (xy 355.325947 -233.119453)
			(xy 355.326442 -233.14406) (xy 355.655384 -233.14406) (xy 355.659344 -233.095006) (xy 355.671121 -233.047222)
			(xy 355.690412 -233.001946) (xy 355.716715 -232.96035) (xy 355.74935 -232.923513) (xy 355.787471 -232.892388)
			(xy 355.830092 -232.867781) (xy 355.876108 -232.850329) (xy 355.924327 -232.840485) (xy 355.973502 -232.838504)
			(xy 356.022357 -232.844436) (xy 356.069628 -232.858128) (xy 356.11409 -232.879226) (xy 356.154593 -232.907182)
			(xy 356.190086 -232.941274) (xy 356.219651 -232.980618) (xy 356.242522 -233.024195) (xy 356.258106 -233.070876)
			(xy 356.266001 -233.119453) (xy 356.266496 -233.14406) (xy 356.595438 -233.14406) (xy 356.599398 -233.095006)
			(xy 356.611175 -233.047222) (xy 356.630466 -233.001946) (xy 356.656769 -232.96035) (xy 356.689404 -232.923513)
			(xy 356.727525 -232.892388) (xy 356.770146 -232.867781) (xy 356.816162 -232.850329) (xy 356.864381 -232.840485)
			(xy 356.913556 -232.838504) (xy 356.962411 -232.844436) (xy 357.009682 -232.858128) (xy 357.054144 -232.879226)
			(xy 357.094647 -232.907182) (xy 357.13014 -232.941274) (xy 357.159705 -232.980618) (xy 357.182576 -233.024195)
			(xy 357.19816 -233.070876) (xy 357.206055 -233.119453) (xy 357.20655 -233.14406) (xy 357.535238 -233.14406)
			(xy 357.539198 -233.095006) (xy 357.550975 -233.047222) (xy 357.570266 -233.001946) (xy 357.596569 -232.96035)
			(xy 357.629204 -232.923513) (xy 357.667325 -232.892388) (xy 357.709946 -232.867781) (xy 357.755962 -232.850329)
			(xy 357.804181 -232.840485) (xy 357.853356 -232.838504) (xy 357.902211 -232.844436) (xy 357.949482 -232.858128)
			(xy 357.993944 -232.879226) (xy 358.034447 -232.907182) (xy 358.06994 -232.941274) (xy 358.099505 -232.980618)
			(xy 358.122376 -233.024195) (xy 358.13796 -233.070876) (xy 358.145855 -233.119453) (xy 358.14635 -233.14406)
			(xy 358.145855 -233.168667) (xy 358.13796 -233.217244) (xy 358.122376 -233.263925) (xy 358.099505 -233.307502)
			(xy 358.06994 -233.346846) (xy 358.034447 -233.380938) (xy 357.993944 -233.408894) (xy 357.949482 -233.429992)
			(xy 357.902211 -233.443684) (xy 357.853356 -233.449616) (xy 357.804181 -233.447635) (xy 357.755962 -233.437791)
			(xy 357.709946 -233.420339) (xy 357.667325 -233.395732) (xy 357.629204 -233.364607) (xy 357.596569 -233.32777)
			(xy 357.570266 -233.286174) (xy 357.550975 -233.240898) (xy 357.539198 -233.193114) (xy 357.535238 -233.14406)
			(xy 357.20655 -233.14406) (xy 357.206055 -233.168667) (xy 357.19816 -233.217244) (xy 357.182576 -233.263925)
			(xy 357.159705 -233.307502) (xy 357.13014 -233.346846) (xy 357.094647 -233.380938) (xy 357.054144 -233.408894)
			(xy 357.009682 -233.429992) (xy 356.962411 -233.443684) (xy 356.913556 -233.449616) (xy 356.864381 -233.447635)
			(xy 356.816162 -233.437791) (xy 356.770146 -233.420339) (xy 356.727525 -233.395732) (xy 356.689404 -233.364607)
			(xy 356.656769 -233.32777) (xy 356.630466 -233.286174) (xy 356.611175 -233.240898) (xy 356.599398 -233.193114)
			(xy 356.595438 -233.14406) (xy 356.266496 -233.14406) (xy 356.266001 -233.168667) (xy 356.258106 -233.217244)
			(xy 356.242522 -233.263925) (xy 356.219651 -233.307502) (xy 356.190086 -233.346846) (xy 356.154593 -233.380938)
			(xy 356.11409 -233.408894) (xy 356.069628 -233.429992) (xy 356.022357 -233.443684) (xy 355.973502 -233.449616)
			(xy 355.924327 -233.447635) (xy 355.876108 -233.437791) (xy 355.830092 -233.420339) (xy 355.787471 -233.395732)
			(xy 355.74935 -233.364607) (xy 355.716715 -233.32777) (xy 355.690412 -233.286174) (xy 355.671121 -233.240898)
			(xy 355.659344 -233.193114) (xy 355.655384 -233.14406) (xy 355.326442 -233.14406) (xy 355.325947 -233.168667)
			(xy 355.318052 -233.217244) (xy 355.302468 -233.263925) (xy 355.279597 -233.307502) (xy 355.250032 -233.346846)
			(xy 355.214539 -233.380938) (xy 355.174036 -233.408894) (xy 355.129574 -233.429992) (xy 355.082303 -233.443684)
			(xy 355.033448 -233.449616) (xy 354.984273 -233.447635) (xy 354.936054 -233.437791) (xy 354.890038 -233.420339)
			(xy 354.847417 -233.395732) (xy 354.809296 -233.364607) (xy 354.776661 -233.32777) (xy 354.750358 -233.286174)
			(xy 354.731067 -233.240898) (xy 354.71929 -233.193114) (xy 354.71533 -233.14406) (xy 354.386388 -233.14406)
			(xy 354.385893 -233.168667) (xy 354.377998 -233.217244) (xy 354.362414 -233.263925) (xy 354.339543 -233.307502)
			(xy 354.309978 -233.346846) (xy 354.274485 -233.380938) (xy 354.233982 -233.408894) (xy 354.18952 -233.429992)
			(xy 354.142249 -233.443684) (xy 354.093394 -233.449616) (xy 354.044219 -233.447635) (xy 353.996 -233.437791)
			(xy 353.949984 -233.420339) (xy 353.907363 -233.395732) (xy 353.869242 -233.364607) (xy 353.836607 -233.32777)
			(xy 353.810304 -233.286174) (xy 353.791013 -233.240898) (xy 353.779236 -233.193114) (xy 353.775276 -233.14406)
			(xy 353.446334 -233.14406) (xy 353.445839 -233.168667) (xy 353.437944 -233.217244) (xy 353.42236 -233.263925)
			(xy 353.399489 -233.307502) (xy 353.369924 -233.346846) (xy 353.334431 -233.380938) (xy 353.293928 -233.408894)
			(xy 353.249466 -233.429992) (xy 353.202195 -233.443684) (xy 353.15334 -233.449616) (xy 353.104165 -233.447635)
			(xy 353.055946 -233.437791) (xy 353.00993 -233.420339) (xy 352.967309 -233.395732) (xy 352.929188 -233.364607)
			(xy 352.896553 -233.32777) (xy 352.87025 -233.286174) (xy 352.850959 -233.240898) (xy 352.839182 -233.193114)
			(xy 352.835222 -233.14406) (xy 352.506534 -233.14406) (xy 352.506039 -233.168667) (xy 352.498144 -233.217244)
			(xy 352.48256 -233.263925) (xy 352.459689 -233.307502) (xy 352.430124 -233.346846) (xy 352.394631 -233.380938)
			(xy 352.354128 -233.408894) (xy 352.309666 -233.429992) (xy 352.262395 -233.443684) (xy 352.21354 -233.449616)
			(xy 352.164365 -233.447635) (xy 352.116146 -233.437791) (xy 352.07013 -233.420339) (xy 352.027509 -233.395732)
			(xy 351.989388 -233.364607) (xy 351.956753 -233.32777) (xy 351.93045 -233.286174) (xy 351.911159 -233.240898)
			(xy 351.899382 -233.193114) (xy 351.895422 -233.14406) (xy 351.56648 -233.14406) (xy 351.565985 -233.168667)
			(xy 351.55809 -233.217244) (xy 351.542506 -233.263925) (xy 351.519635 -233.307502) (xy 351.49007 -233.346846)
			(xy 351.454577 -233.380938) (xy 351.414074 -233.408894) (xy 351.369612 -233.429992) (xy 351.322341 -233.443684)
			(xy 351.273486 -233.449616) (xy 351.224311 -233.447635) (xy 351.176092 -233.437791) (xy 351.130076 -233.420339)
			(xy 351.087455 -233.395732) (xy 351.049334 -233.364607) (xy 351.016699 -233.32777) (xy 350.990396 -233.286174)
			(xy 350.971105 -233.240898) (xy 350.959328 -233.193114) (xy 350.955368 -233.14406) (xy 350.626426 -233.14406)
			(xy 350.625931 -233.168667) (xy 350.618036 -233.217244) (xy 350.602452 -233.263925) (xy 350.579581 -233.307502)
			(xy 350.550016 -233.346846) (xy 350.514523 -233.380938) (xy 350.47402 -233.408894) (xy 350.429558 -233.429992)
			(xy 350.382287 -233.443684) (xy 350.333432 -233.449616) (xy 350.284257 -233.447635) (xy 350.236038 -233.437791)
			(xy 350.190022 -233.420339) (xy 350.147401 -233.395732) (xy 350.10928 -233.364607) (xy 350.076645 -233.32777)
			(xy 350.050342 -233.286174) (xy 350.031051 -233.240898) (xy 350.019274 -233.193114) (xy 350.015314 -233.14406)
			(xy 349.686372 -233.14406) (xy 349.685877 -233.168667) (xy 349.677982 -233.217244) (xy 349.662398 -233.263925)
			(xy 349.639527 -233.307502) (xy 349.609962 -233.346846) (xy 349.574469 -233.380938) (xy 349.533966 -233.408894)
			(xy 349.489504 -233.429992) (xy 349.442233 -233.443684) (xy 349.393378 -233.449616) (xy 349.344203 -233.447635)
			(xy 349.295984 -233.437791) (xy 349.249968 -233.420339) (xy 349.207347 -233.395732) (xy 349.169226 -233.364607)
			(xy 349.136591 -233.32777) (xy 349.110288 -233.286174) (xy 349.090997 -233.240898) (xy 349.07922 -233.193114)
			(xy 349.07526 -233.14406) (xy 348.746318 -233.14406) (xy 348.745823 -233.168667) (xy 348.737928 -233.217244)
			(xy 348.722344 -233.263925) (xy 348.699473 -233.307502) (xy 348.669908 -233.346846) (xy 348.634415 -233.380938)
			(xy 348.593912 -233.408894) (xy 348.54945 -233.429992) (xy 348.502179 -233.443684) (xy 348.453324 -233.449616)
			(xy 348.404149 -233.447635) (xy 348.35593 -233.437791) (xy 348.309914 -233.420339) (xy 348.267293 -233.395732)
			(xy 348.229172 -233.364607) (xy 348.196537 -233.32777) (xy 348.170234 -233.286174) (xy 348.150943 -233.240898)
			(xy 348.139166 -233.193114) (xy 348.135206 -233.14406) (xy 347.806518 -233.14406) (xy 347.806023 -233.168667)
			(xy 347.798128 -233.217244) (xy 347.782544 -233.263925) (xy 347.759673 -233.307502) (xy 347.730108 -233.346846)
			(xy 347.694615 -233.380938) (xy 347.654112 -233.408894) (xy 347.60965 -233.429992) (xy 347.562379 -233.443684)
			(xy 347.513524 -233.449616) (xy 347.464349 -233.447635) (xy 347.41613 -233.437791) (xy 347.370114 -233.420339)
			(xy 347.327493 -233.395732) (xy 347.289372 -233.364607) (xy 347.256737 -233.32777) (xy 347.230434 -233.286174)
			(xy 347.211143 -233.240898) (xy 347.199366 -233.193114) (xy 347.195406 -233.14406) (xy 346.866464 -233.14406)
			(xy 346.865969 -233.168667) (xy 346.858074 -233.217244) (xy 346.84249 -233.263925) (xy 346.819619 -233.307502)
			(xy 346.790054 -233.346846) (xy 346.754561 -233.380938) (xy 346.714058 -233.408894) (xy 346.669596 -233.429992)
			(xy 346.622325 -233.443684) (xy 346.57347 -233.449616) (xy 346.524295 -233.447635) (xy 346.476076 -233.437791)
			(xy 346.43006 -233.420339) (xy 346.387439 -233.395732) (xy 346.349318 -233.364607) (xy 346.316683 -233.32777)
			(xy 346.29038 -233.286174) (xy 346.271089 -233.240898) (xy 346.259312 -233.193114) (xy 346.255352 -233.14406)
			(xy 345.92641 -233.14406) (xy 345.925915 -233.168667) (xy 345.91802 -233.217244) (xy 345.902436 -233.263925)
			(xy 345.879565 -233.307502) (xy 345.85 -233.346846) (xy 345.814507 -233.380938) (xy 345.774004 -233.408894)
			(xy 345.729542 -233.429992) (xy 345.682271 -233.443684) (xy 345.633416 -233.449616) (xy 345.584241 -233.447635)
			(xy 345.536022 -233.437791) (xy 345.490006 -233.420339) (xy 345.447385 -233.395732) (xy 345.409264 -233.364607)
			(xy 345.376629 -233.32777) (xy 345.350326 -233.286174) (xy 345.331035 -233.240898) (xy 345.319258 -233.193114)
			(xy 345.315298 -233.14406) (xy 344.986356 -233.14406) (xy 344.985861 -233.168667) (xy 344.977966 -233.217244)
			(xy 344.962382 -233.263925) (xy 344.939511 -233.307502) (xy 344.909946 -233.346846) (xy 344.874453 -233.380938)
			(xy 344.83395 -233.408894) (xy 344.789488 -233.429992) (xy 344.742217 -233.443684) (xy 344.693362 -233.449616)
			(xy 344.644187 -233.447635) (xy 344.595968 -233.437791) (xy 344.549952 -233.420339) (xy 344.507331 -233.395732)
			(xy 344.46921 -233.364607) (xy 344.436575 -233.32777) (xy 344.410272 -233.286174) (xy 344.390981 -233.240898)
			(xy 344.379204 -233.193114) (xy 344.375244 -233.14406) (xy 344.056716 -233.14406) (xy 344.056204 -233.169506)
			(xy 344.04804 -233.21974) (xy 344.031924 -233.268014) (xy 344.008273 -233.313077) (xy 343.9777 -233.353763)
			(xy 343.940996 -233.389018) (xy 343.899112 -233.417928) (xy 343.853133 -233.439745) (xy 343.804249 -233.453905)
			(xy 343.753728 -233.460039) (xy 343.702876 -233.45799) (xy 343.653012 -233.44781) (xy 343.605426 -233.429763)
			(xy 343.561352 -233.404317) (xy 343.52193 -233.37213) (xy 343.488182 -233.334036) (xy 343.460981 -233.291022)
			(xy 343.441033 -233.244202) (xy 343.428854 -233.194788) (xy 343.424759 -233.14406) (xy 343.106502 -233.14406)
			(xy 343.106007 -233.168667) (xy 343.098112 -233.217244) (xy 343.082528 -233.263925) (xy 343.059657 -233.307502)
			(xy 343.030092 -233.346846) (xy 342.994599 -233.380938) (xy 342.954096 -233.408894) (xy 342.909634 -233.429992)
			(xy 342.862363 -233.443684) (xy 342.813508 -233.449616) (xy 342.764333 -233.447635) (xy 342.716114 -233.437791)
			(xy 342.670098 -233.420339) (xy 342.627477 -233.395732) (xy 342.589356 -233.364607) (xy 342.556721 -233.32777)
			(xy 342.530418 -233.286174) (xy 342.511127 -233.240898) (xy 342.49935 -233.193114) (xy 342.49539 -233.14406)
			(xy 342.176862 -233.14406) (xy 342.17635 -233.169506) (xy 342.168186 -233.21974) (xy 342.15207 -233.268014)
			(xy 342.128419 -233.313077) (xy 342.097846 -233.353763) (xy 342.061142 -233.389018) (xy 342.019258 -233.417928)
			(xy 341.973279 -233.439745) (xy 341.924395 -233.453905) (xy 341.873874 -233.460039) (xy 341.823022 -233.45799)
			(xy 341.773158 -233.44781) (xy 341.725572 -233.429763) (xy 341.681498 -233.404317) (xy 341.642076 -233.37213)
			(xy 341.608328 -233.334036) (xy 341.581127 -233.291022) (xy 341.561179 -233.244202) (xy 341.549 -233.194788)
			(xy 341.544905 -233.14406) (xy 341.233252 -233.14406) (xy 341.233252 -233.550968) (xy 341.233825 -233.561654)
			(xy 341.242502 -233.581191) (xy 341.250016 -233.588814) (xy 341.250524 -233.589068) (xy 341.316564 -233.646726)
			(xy 341.327232 -233.649774) (xy 341.3379 -233.653076) (xy 341.348822 -233.651552) (xy 341.359312 -233.650219)
			(xy 341.380412 -233.64882) (xy 341.390986 -233.648758) (xy 341.416247 -233.64925) (xy 341.466081 -233.657563)
			(xy 341.513867 -233.673966) (xy 341.558301 -233.698011) (xy 341.598171 -233.729041) (xy 341.63239 -233.766211)
			(xy 341.660024 -233.808507) (xy 341.680319 -233.854774) (xy 341.692722 -233.90375) (xy 341.696891 -233.954066)
			(xy 342.014805 -233.954066) (xy 342.0189 -233.903338) (xy 342.031079 -233.853924) (xy 342.051027 -233.807104)
			(xy 342.078228 -233.76409) (xy 342.111976 -233.725996) (xy 342.151398 -233.693809) (xy 342.195472 -233.668363)
			(xy 342.243058 -233.650316) (xy 342.292922 -233.640136) (xy 342.343774 -233.638087) (xy 342.394295 -233.644221)
			(xy 342.443179 -233.658381) (xy 342.489158 -233.680198) (xy 342.531042 -233.709108) (xy 342.567746 -233.744363)
			(xy 342.598319 -233.785049) (xy 342.62197 -233.830112) (xy 342.638086 -233.878386) (xy 342.64625 -233.92862)
			(xy 342.646762 -233.954066) (xy 342.954859 -233.954066) (xy 342.958954 -233.903338) (xy 342.971133 -233.853924)
			(xy 342.991081 -233.807104) (xy 343.018282 -233.76409) (xy 343.05203 -233.725996) (xy 343.091452 -233.693809)
			(xy 343.135526 -233.668363) (xy 343.183112 -233.650316) (xy 343.232976 -233.640136) (xy 343.283828 -233.638087)
			(xy 343.334349 -233.644221) (xy 343.383233 -233.658381) (xy 343.429212 -233.680198) (xy 343.471096 -233.709108)
			(xy 343.5078 -233.744363) (xy 343.538373 -233.785049) (xy 343.562024 -233.830112) (xy 343.57814 -233.878386)
			(xy 343.586304 -233.92862) (xy 343.586816 -233.954066) (xy 343.905344 -233.954066) (xy 343.909304 -233.905012)
			(xy 343.921081 -233.857228) (xy 343.940372 -233.811952) (xy 343.966675 -233.770356) (xy 343.99931 -233.733519)
			(xy 344.037431 -233.702394) (xy 344.080052 -233.677787) (xy 344.126068 -233.660335) (xy 344.174287 -233.650491)
			(xy 344.223462 -233.64851) (xy 344.272317 -233.654442) (xy 344.319588 -233.668134) (xy 344.36405 -233.689232)
			(xy 344.404553 -233.717188) (xy 344.440046 -233.75128) (xy 344.469611 -233.790624) (xy 344.492482 -233.834201)
			(xy 344.508066 -233.880882) (xy 344.515961 -233.929459) (xy 344.516456 -233.954066) (xy 346.725252 -233.954066)
			(xy 346.729212 -233.905012) (xy 346.740989 -233.857228) (xy 346.76028 -233.811952) (xy 346.786583 -233.770356)
			(xy 346.819218 -233.733519) (xy 346.857339 -233.702394) (xy 346.89996 -233.677787) (xy 346.945976 -233.660335)
			(xy 346.994195 -233.650491) (xy 347.04337 -233.64851) (xy 347.092225 -233.654442) (xy 347.139496 -233.668134)
			(xy 347.183958 -233.689232) (xy 347.224461 -233.717188) (xy 347.259954 -233.75128) (xy 347.289519 -233.790624)
			(xy 347.31239 -233.834201) (xy 347.327974 -233.880882) (xy 347.335869 -233.929459) (xy 347.336364 -233.954066)
			(xy 349.545414 -233.954066) (xy 349.549374 -233.905012) (xy 349.561151 -233.857228) (xy 349.580442 -233.811952)
			(xy 349.606745 -233.770356) (xy 349.63938 -233.733519) (xy 349.677501 -233.702394) (xy 349.720122 -233.677787)
			(xy 349.766138 -233.660335) (xy 349.814357 -233.650491) (xy 349.863532 -233.64851) (xy 349.912387 -233.654442)
			(xy 349.959658 -233.668134) (xy 350.00412 -233.689232) (xy 350.044623 -233.717188) (xy 350.080116 -233.75128)
			(xy 350.109681 -233.790624) (xy 350.132552 -233.834201) (xy 350.148136 -233.880882) (xy 350.156031 -233.929459)
			(xy 350.156526 -233.954066) (xy 352.365322 -233.954066) (xy 352.369282 -233.905012) (xy 352.381059 -233.857228)
			(xy 352.40035 -233.811952) (xy 352.426653 -233.770356) (xy 352.459288 -233.733519) (xy 352.497409 -233.702394)
			(xy 352.54003 -233.677787) (xy 352.586046 -233.660335) (xy 352.634265 -233.650491) (xy 352.68344 -233.64851)
			(xy 352.732295 -233.654442) (xy 352.779566 -233.668134) (xy 352.824028 -233.689232) (xy 352.864531 -233.717188)
			(xy 352.900024 -233.75128) (xy 352.929589 -233.790624) (xy 352.95246 -233.834201) (xy 352.968044 -233.880882)
			(xy 352.975939 -233.929459) (xy 352.976434 -233.954066) (xy 355.18523 -233.954066) (xy 355.18919 -233.905012)
			(xy 355.200967 -233.857228) (xy 355.220258 -233.811952) (xy 355.246561 -233.770356) (xy 355.279196 -233.733519)
			(xy 355.317317 -233.702394) (xy 355.359938 -233.677787) (xy 355.405954 -233.660335) (xy 355.454173 -233.650491)
			(xy 355.503348 -233.64851) (xy 355.552203 -233.654442) (xy 355.599474 -233.668134) (xy 355.643936 -233.689232)
			(xy 355.684439 -233.717188) (xy 355.719932 -233.75128) (xy 355.749497 -233.790624) (xy 355.772368 -233.834201)
			(xy 355.787952 -233.880882) (xy 355.795847 -233.929459) (xy 355.796342 -233.954066) (xy 356.125284 -233.954066)
			(xy 356.129244 -233.905012) (xy 356.141021 -233.857228) (xy 356.160312 -233.811952) (xy 356.186615 -233.770356)
			(xy 356.21925 -233.733519) (xy 356.257371 -233.702394) (xy 356.299992 -233.677787) (xy 356.346008 -233.660335)
			(xy 356.394227 -233.650491) (xy 356.443402 -233.64851) (xy 356.492257 -233.654442) (xy 356.539528 -233.668134)
			(xy 356.58399 -233.689232) (xy 356.624493 -233.717188) (xy 356.659986 -233.75128) (xy 356.689551 -233.790624)
			(xy 356.712422 -233.834201) (xy 356.728006 -233.880882) (xy 356.735901 -233.929459) (xy 356.736396 -233.954066)
			(xy 357.065338 -233.954066) (xy 357.069298 -233.905012) (xy 357.081075 -233.857228) (xy 357.100366 -233.811952)
			(xy 357.126669 -233.770356) (xy 357.159304 -233.733519) (xy 357.197425 -233.702394) (xy 357.240046 -233.677787)
			(xy 357.286062 -233.660335) (xy 357.334281 -233.650491) (xy 357.383456 -233.64851) (xy 357.432311 -233.654442)
			(xy 357.479582 -233.668134) (xy 357.524044 -233.689232) (xy 357.564547 -233.717188) (xy 357.60004 -233.75128)
			(xy 357.629605 -233.790624) (xy 357.652476 -233.834201) (xy 357.66806 -233.880882) (xy 357.675955 -233.929459)
			(xy 357.67645 -233.954066) (xy 358.005392 -233.954066) (xy 358.009352 -233.905012) (xy 358.021129 -233.857228)
			(xy 358.04042 -233.811952) (xy 358.066723 -233.770356) (xy 358.099358 -233.733519) (xy 358.137479 -233.702394)
			(xy 358.1801 -233.677787) (xy 358.226116 -233.660335) (xy 358.274335 -233.650491) (xy 358.32351 -233.64851)
			(xy 358.372365 -233.654442) (xy 358.419636 -233.668134) (xy 358.464098 -233.689232) (xy 358.504601 -233.717188)
			(xy 358.540094 -233.75128) (xy 358.569659 -233.790624) (xy 358.59253 -233.834201) (xy 358.608114 -233.880882)
			(xy 358.616009 -233.929459) (xy 358.616504 -233.954066) (xy 358.616009 -233.978673) (xy 358.608114 -234.02725)
			(xy 358.59253 -234.073931) (xy 358.569659 -234.117508) (xy 358.540094 -234.156852) (xy 358.504601 -234.190944)
			(xy 358.464098 -234.2189) (xy 358.419636 -234.239998) (xy 358.372365 -234.25369) (xy 358.32351 -234.259622)
			(xy 358.274335 -234.257641) (xy 358.226116 -234.247797) (xy 358.1801 -234.230345) (xy 358.137479 -234.205738)
			(xy 358.099358 -234.174613) (xy 358.066723 -234.137776) (xy 358.04042 -234.09618) (xy 358.021129 -234.050904)
			(xy 358.009352 -234.00312) (xy 358.005392 -233.954066) (xy 357.67645 -233.954066) (xy 357.675955 -233.978673)
			(xy 357.66806 -234.02725) (xy 357.652476 -234.073931) (xy 357.629605 -234.117508) (xy 357.60004 -234.156852)
			(xy 357.564547 -234.190944) (xy 357.524044 -234.2189) (xy 357.479582 -234.239998) (xy 357.432311 -234.25369)
			(xy 357.383456 -234.259622) (xy 357.334281 -234.257641) (xy 357.286062 -234.247797) (xy 357.240046 -234.230345)
			(xy 357.197425 -234.205738) (xy 357.159304 -234.174613) (xy 357.126669 -234.137776) (xy 357.100366 -234.09618)
			(xy 357.081075 -234.050904) (xy 357.069298 -234.00312) (xy 357.065338 -233.954066) (xy 356.736396 -233.954066)
			(xy 356.735901 -233.978673) (xy 356.728006 -234.02725) (xy 356.712422 -234.073931) (xy 356.689551 -234.117508)
			(xy 356.659986 -234.156852) (xy 356.624493 -234.190944) (xy 356.58399 -234.2189) (xy 356.539528 -234.239998)
			(xy 356.492257 -234.25369) (xy 356.443402 -234.259622) (xy 356.394227 -234.257641) (xy 356.346008 -234.247797)
			(xy 356.299992 -234.230345) (xy 356.257371 -234.205738) (xy 356.21925 -234.174613) (xy 356.186615 -234.137776)
			(xy 356.160312 -234.09618) (xy 356.141021 -234.050904) (xy 356.129244 -234.00312) (xy 356.125284 -233.954066)
			(xy 355.796342 -233.954066) (xy 355.795847 -233.978673) (xy 355.787952 -234.02725) (xy 355.772368 -234.073931)
			(xy 355.749497 -234.117508) (xy 355.719932 -234.156852) (xy 355.684439 -234.190944) (xy 355.643936 -234.2189)
			(xy 355.599474 -234.239998) (xy 355.552203 -234.25369) (xy 355.503348 -234.259622) (xy 355.454173 -234.257641)
			(xy 355.405954 -234.247797) (xy 355.359938 -234.230345) (xy 355.317317 -234.205738) (xy 355.279196 -234.174613)
			(xy 355.246561 -234.137776) (xy 355.220258 -234.09618) (xy 355.200967 -234.050904) (xy 355.18919 -234.00312)
			(xy 355.18523 -233.954066) (xy 352.976434 -233.954066) (xy 352.975939 -233.978673) (xy 352.968044 -234.02725)
			(xy 352.95246 -234.073931) (xy 352.929589 -234.117508) (xy 352.900024 -234.156852) (xy 352.864531 -234.190944)
			(xy 352.824028 -234.2189) (xy 352.779566 -234.239998) (xy 352.732295 -234.25369) (xy 352.68344 -234.259622)
			(xy 352.634265 -234.257641) (xy 352.586046 -234.247797) (xy 352.54003 -234.230345) (xy 352.497409 -234.205738)
			(xy 352.459288 -234.174613) (xy 352.426653 -234.137776) (xy 352.40035 -234.09618) (xy 352.381059 -234.050904)
			(xy 352.369282 -234.00312) (xy 352.365322 -233.954066) (xy 350.156526 -233.954066) (xy 350.156031 -233.978673)
			(xy 350.148136 -234.02725) (xy 350.132552 -234.073931) (xy 350.109681 -234.117508) (xy 350.080116 -234.156852)
			(xy 350.044623 -234.190944) (xy 350.00412 -234.2189) (xy 349.959658 -234.239998) (xy 349.912387 -234.25369)
			(xy 349.863532 -234.259622) (xy 349.814357 -234.257641) (xy 349.766138 -234.247797) (xy 349.720122 -234.230345)
			(xy 349.677501 -234.205738) (xy 349.63938 -234.174613) (xy 349.606745 -234.137776) (xy 349.580442 -234.09618)
			(xy 349.561151 -234.050904) (xy 349.549374 -234.00312) (xy 349.545414 -233.954066) (xy 347.336364 -233.954066)
			(xy 347.335869 -233.978673) (xy 347.327974 -234.02725) (xy 347.31239 -234.073931) (xy 347.289519 -234.117508)
			(xy 347.259954 -234.156852) (xy 347.224461 -234.190944) (xy 347.183958 -234.2189) (xy 347.139496 -234.239998)
			(xy 347.092225 -234.25369) (xy 347.04337 -234.259622) (xy 346.994195 -234.257641) (xy 346.945976 -234.247797)
			(xy 346.89996 -234.230345) (xy 346.857339 -234.205738) (xy 346.819218 -234.174613) (xy 346.786583 -234.137776)
			(xy 346.76028 -234.09618) (xy 346.740989 -234.050904) (xy 346.729212 -234.00312) (xy 346.725252 -233.954066)
			(xy 344.516456 -233.954066) (xy 344.515961 -233.978673) (xy 344.508066 -234.02725) (xy 344.492482 -234.073931)
			(xy 344.469611 -234.117508) (xy 344.440046 -234.156852) (xy 344.404553 -234.190944) (xy 344.36405 -234.2189)
			(xy 344.319588 -234.239998) (xy 344.272317 -234.25369) (xy 344.223462 -234.259622) (xy 344.174287 -234.257641)
			(xy 344.126068 -234.247797) (xy 344.080052 -234.230345) (xy 344.037431 -234.205738) (xy 343.99931 -234.174613)
			(xy 343.966675 -234.137776) (xy 343.940372 -234.09618) (xy 343.921081 -234.050904) (xy 343.909304 -234.00312)
			(xy 343.905344 -233.954066) (xy 343.586816 -233.954066) (xy 343.586304 -233.979512) (xy 343.57814 -234.029746)
			(xy 343.562024 -234.07802) (xy 343.538373 -234.123083) (xy 343.5078 -234.163769) (xy 343.471096 -234.199024)
			(xy 343.429212 -234.227934) (xy 343.383233 -234.249751) (xy 343.334349 -234.263911) (xy 343.283828 -234.270045)
			(xy 343.232976 -234.267996) (xy 343.183112 -234.257816) (xy 343.135526 -234.239769) (xy 343.091452 -234.214323)
			(xy 343.05203 -234.182136) (xy 343.018282 -234.144042) (xy 342.991081 -234.101028) (xy 342.971133 -234.054208)
			(xy 342.958954 -234.004794) (xy 342.954859 -233.954066) (xy 342.646762 -233.954066) (xy 342.64625 -233.979512)
			(xy 342.638086 -234.029746) (xy 342.62197 -234.07802) (xy 342.598319 -234.123083) (xy 342.567746 -234.163769)
			(xy 342.531042 -234.199024) (xy 342.489158 -234.227934) (xy 342.443179 -234.249751) (xy 342.394295 -234.263911)
			(xy 342.343774 -234.270045) (xy 342.292922 -234.267996) (xy 342.243058 -234.257816) (xy 342.195472 -234.239769)
			(xy 342.151398 -234.214323) (xy 342.111976 -234.182136) (xy 342.078228 -234.144042) (xy 342.051027 -234.101028)
			(xy 342.031079 -234.054208) (xy 342.0189 -234.004794) (xy 342.014805 -233.954066) (xy 341.696891 -233.954066)
			(xy 341.696894 -233.9541) (xy 341.692722 -234.00445) (xy 341.680319 -234.053426) (xy 341.660024 -234.099693)
			(xy 341.63239 -234.141989) (xy 341.598171 -234.179159) (xy 341.558301 -234.210189) (xy 341.513867 -234.234234)
			(xy 341.466081 -234.250637) (xy 341.416247 -234.25895) (xy 341.390986 -234.259374) (xy 341.380412 -234.25932)
			(xy 341.359311 -234.257923) (xy 341.348822 -234.25658) (xy 341.3379 -234.255056) (xy 341.317072 -234.261406)
			(xy 341.250778 -234.31881) (xy 341.242396 -234.326176) (xy 341.233252 -234.345988) (xy 341.233252 -234.764072)
			(xy 341.544905 -234.764072) (xy 341.549 -234.713344) (xy 341.561179 -234.66393) (xy 341.581127 -234.61711)
			(xy 341.608328 -234.574096) (xy 341.642076 -234.536002) (xy 341.681498 -234.503815) (xy 341.725572 -234.478369)
			(xy 341.773158 -234.460322) (xy 341.823022 -234.450142) (xy 341.873874 -234.448093) (xy 341.924395 -234.454227)
			(xy 341.973279 -234.468387) (xy 342.019258 -234.490204) (xy 342.061142 -234.519114) (xy 342.097846 -234.554369)
			(xy 342.128419 -234.595055) (xy 342.15207 -234.640118) (xy 342.168186 -234.688392) (xy 342.17635 -234.738626)
			(xy 342.176862 -234.764072) (xy 342.49539 -234.764072) (xy 342.49935 -234.715018) (xy 342.511127 -234.667234)
			(xy 342.530418 -234.621958) (xy 342.556721 -234.580362) (xy 342.589356 -234.543525) (xy 342.627477 -234.5124)
			(xy 342.670098 -234.487793) (xy 342.716114 -234.470341) (xy 342.764333 -234.460497) (xy 342.813508 -234.458516)
			(xy 342.862363 -234.464448) (xy 342.909634 -234.47814) (xy 342.954096 -234.499238) (xy 342.994599 -234.527194)
			(xy 343.030092 -234.561286) (xy 343.059657 -234.60063) (xy 343.082528 -234.644207) (xy 343.098112 -234.690888)
			(xy 343.106007 -234.739465) (xy 343.106502 -234.764072) (xy 343.424759 -234.764072) (xy 343.428854 -234.713344)
			(xy 343.441033 -234.66393) (xy 343.460981 -234.61711) (xy 343.488182 -234.574096) (xy 343.52193 -234.536002)
			(xy 343.561352 -234.503815) (xy 343.605426 -234.478369) (xy 343.653012 -234.460322) (xy 343.702876 -234.450142)
			(xy 343.753728 -234.448093) (xy 343.804249 -234.454227) (xy 343.853133 -234.468387) (xy 343.899112 -234.490204)
			(xy 343.940996 -234.519114) (xy 343.9777 -234.554369) (xy 344.008273 -234.595055) (xy 344.031924 -234.640118)
			(xy 344.04804 -234.688392) (xy 344.056204 -234.738626) (xy 344.056716 -234.764072) (xy 344.375244 -234.764072)
			(xy 344.379204 -234.715018) (xy 344.390981 -234.667234) (xy 344.410272 -234.621958) (xy 344.436575 -234.580362)
			(xy 344.46921 -234.543525) (xy 344.507331 -234.5124) (xy 344.549952 -234.487793) (xy 344.595968 -234.470341)
			(xy 344.644187 -234.460497) (xy 344.693362 -234.458516) (xy 344.742217 -234.464448) (xy 344.789488 -234.47814)
			(xy 344.83395 -234.499238) (xy 344.874453 -234.527194) (xy 344.909946 -234.561286) (xy 344.939511 -234.60063)
			(xy 344.962382 -234.644207) (xy 344.977966 -234.690888) (xy 344.985861 -234.739465) (xy 344.986356 -234.764072)
			(xy 345.315298 -234.764072) (xy 345.319258 -234.715018) (xy 345.331035 -234.667234) (xy 345.350326 -234.621958)
			(xy 345.376629 -234.580362) (xy 345.409264 -234.543525) (xy 345.447385 -234.5124) (xy 345.490006 -234.487793)
			(xy 345.536022 -234.470341) (xy 345.584241 -234.460497) (xy 345.633416 -234.458516) (xy 345.682271 -234.464448)
			(xy 345.729542 -234.47814) (xy 345.774004 -234.499238) (xy 345.814507 -234.527194) (xy 345.85 -234.561286)
			(xy 345.879565 -234.60063) (xy 345.902436 -234.644207) (xy 345.91802 -234.690888) (xy 345.925915 -234.739465)
			(xy 345.92641 -234.764072) (xy 346.255352 -234.764072) (xy 346.259312 -234.715018) (xy 346.271089 -234.667234)
			(xy 346.29038 -234.621958) (xy 346.316683 -234.580362) (xy 346.349318 -234.543525) (xy 346.387439 -234.5124)
			(xy 346.43006 -234.487793) (xy 346.476076 -234.470341) (xy 346.524295 -234.460497) (xy 346.57347 -234.458516)
			(xy 346.622325 -234.464448) (xy 346.669596 -234.47814) (xy 346.714058 -234.499238) (xy 346.754561 -234.527194)
			(xy 346.790054 -234.561286) (xy 346.819619 -234.60063) (xy 346.84249 -234.644207) (xy 346.858074 -234.690888)
			(xy 346.865969 -234.739465) (xy 346.866464 -234.764072) (xy 347.195406 -234.764072) (xy 347.199366 -234.715018)
			(xy 347.211143 -234.667234) (xy 347.230434 -234.621958) (xy 347.256737 -234.580362) (xy 347.289372 -234.543525)
			(xy 347.327493 -234.5124) (xy 347.370114 -234.487793) (xy 347.41613 -234.470341) (xy 347.464349 -234.460497)
			(xy 347.513524 -234.458516) (xy 347.562379 -234.464448) (xy 347.60965 -234.47814) (xy 347.654112 -234.499238)
			(xy 347.694615 -234.527194) (xy 347.730108 -234.561286) (xy 347.759673 -234.60063) (xy 347.782544 -234.644207)
			(xy 347.798128 -234.690888) (xy 347.806023 -234.739465) (xy 347.806518 -234.764072) (xy 348.135206 -234.764072)
			(xy 348.139166 -234.715018) (xy 348.150943 -234.667234) (xy 348.170234 -234.621958) (xy 348.196537 -234.580362)
			(xy 348.229172 -234.543525) (xy 348.267293 -234.5124) (xy 348.309914 -234.487793) (xy 348.35593 -234.470341)
			(xy 348.404149 -234.460497) (xy 348.453324 -234.458516) (xy 348.502179 -234.464448) (xy 348.54945 -234.47814)
			(xy 348.593912 -234.499238) (xy 348.634415 -234.527194) (xy 348.669908 -234.561286) (xy 348.699473 -234.60063)
			(xy 348.722344 -234.644207) (xy 348.737928 -234.690888) (xy 348.745823 -234.739465) (xy 348.746318 -234.764072)
			(xy 349.07526 -234.764072) (xy 349.07922 -234.715018) (xy 349.090997 -234.667234) (xy 349.110288 -234.621958)
			(xy 349.136591 -234.580362) (xy 349.169226 -234.543525) (xy 349.207347 -234.5124) (xy 349.249968 -234.487793)
			(xy 349.295984 -234.470341) (xy 349.344203 -234.460497) (xy 349.393378 -234.458516) (xy 349.442233 -234.464448)
			(xy 349.489504 -234.47814) (xy 349.533966 -234.499238) (xy 349.574469 -234.527194) (xy 349.609962 -234.561286)
			(xy 349.639527 -234.60063) (xy 349.662398 -234.644207) (xy 349.677982 -234.690888) (xy 349.685877 -234.739465)
			(xy 349.686372 -234.764072) (xy 350.015314 -234.764072) (xy 350.019274 -234.715018) (xy 350.031051 -234.667234)
			(xy 350.050342 -234.621958) (xy 350.076645 -234.580362) (xy 350.10928 -234.543525) (xy 350.147401 -234.5124)
			(xy 350.190022 -234.487793) (xy 350.236038 -234.470341) (xy 350.284257 -234.460497) (xy 350.333432 -234.458516)
			(xy 350.382287 -234.464448) (xy 350.429558 -234.47814) (xy 350.47402 -234.499238) (xy 350.514523 -234.527194)
			(xy 350.550016 -234.561286) (xy 350.579581 -234.60063) (xy 350.602452 -234.644207) (xy 350.618036 -234.690888)
			(xy 350.625931 -234.739465) (xy 350.626426 -234.764072) (xy 350.955368 -234.764072) (xy 350.959328 -234.715018)
			(xy 350.971105 -234.667234) (xy 350.990396 -234.621958) (xy 351.016699 -234.580362) (xy 351.049334 -234.543525)
			(xy 351.087455 -234.5124) (xy 351.130076 -234.487793) (xy 351.176092 -234.470341) (xy 351.224311 -234.460497)
			(xy 351.273486 -234.458516) (xy 351.322341 -234.464448) (xy 351.369612 -234.47814) (xy 351.414074 -234.499238)
			(xy 351.454577 -234.527194) (xy 351.49007 -234.561286) (xy 351.519635 -234.60063) (xy 351.542506 -234.644207)
			(xy 351.55809 -234.690888) (xy 351.565985 -234.739465) (xy 351.56648 -234.764072) (xy 351.895422 -234.764072)
			(xy 351.899382 -234.715018) (xy 351.911159 -234.667234) (xy 351.93045 -234.621958) (xy 351.956753 -234.580362)
			(xy 351.989388 -234.543525) (xy 352.027509 -234.5124) (xy 352.07013 -234.487793) (xy 352.116146 -234.470341)
			(xy 352.164365 -234.460497) (xy 352.21354 -234.458516) (xy 352.262395 -234.464448) (xy 352.309666 -234.47814)
			(xy 352.354128 -234.499238) (xy 352.394631 -234.527194) (xy 352.430124 -234.561286) (xy 352.459689 -234.60063)
			(xy 352.48256 -234.644207) (xy 352.498144 -234.690888) (xy 352.506039 -234.739465) (xy 352.506534 -234.764072)
			(xy 352.835222 -234.764072) (xy 352.839182 -234.715018) (xy 352.850959 -234.667234) (xy 352.87025 -234.621958)
			(xy 352.896553 -234.580362) (xy 352.929188 -234.543525) (xy 352.967309 -234.5124) (xy 353.00993 -234.487793)
			(xy 353.055946 -234.470341) (xy 353.104165 -234.460497) (xy 353.15334 -234.458516) (xy 353.202195 -234.464448)
			(xy 353.249466 -234.47814) (xy 353.293928 -234.499238) (xy 353.334431 -234.527194) (xy 353.369924 -234.561286)
			(xy 353.399489 -234.60063) (xy 353.42236 -234.644207) (xy 353.437944 -234.690888) (xy 353.445839 -234.739465)
			(xy 353.446334 -234.764072) (xy 353.775276 -234.764072) (xy 353.779236 -234.715018) (xy 353.791013 -234.667234)
			(xy 353.810304 -234.621958) (xy 353.836607 -234.580362) (xy 353.869242 -234.543525) (xy 353.907363 -234.5124)
			(xy 353.949984 -234.487793) (xy 353.996 -234.470341) (xy 354.044219 -234.460497) (xy 354.093394 -234.458516)
			(xy 354.142249 -234.464448) (xy 354.18952 -234.47814) (xy 354.233982 -234.499238) (xy 354.274485 -234.527194)
			(xy 354.309978 -234.561286) (xy 354.339543 -234.60063) (xy 354.362414 -234.644207) (xy 354.377998 -234.690888)
			(xy 354.385893 -234.739465) (xy 354.386388 -234.764072) (xy 354.71533 -234.764072) (xy 354.71929 -234.715018)
			(xy 354.731067 -234.667234) (xy 354.750358 -234.621958) (xy 354.776661 -234.580362) (xy 354.809296 -234.543525)
			(xy 354.847417 -234.5124) (xy 354.890038 -234.487793) (xy 354.936054 -234.470341) (xy 354.984273 -234.460497)
			(xy 355.033448 -234.458516) (xy 355.082303 -234.464448) (xy 355.129574 -234.47814) (xy 355.174036 -234.499238)
			(xy 355.214539 -234.527194) (xy 355.250032 -234.561286) (xy 355.279597 -234.60063) (xy 355.302468 -234.644207)
			(xy 355.318052 -234.690888) (xy 355.325947 -234.739465) (xy 355.326442 -234.764072) (xy 355.655384 -234.764072)
			(xy 355.659344 -234.715018) (xy 355.671121 -234.667234) (xy 355.690412 -234.621958) (xy 355.716715 -234.580362)
			(xy 355.74935 -234.543525) (xy 355.787471 -234.5124) (xy 355.830092 -234.487793) (xy 355.876108 -234.470341)
			(xy 355.924327 -234.460497) (xy 355.973502 -234.458516) (xy 356.022357 -234.464448) (xy 356.069628 -234.47814)
			(xy 356.11409 -234.499238) (xy 356.154593 -234.527194) (xy 356.190086 -234.561286) (xy 356.219651 -234.60063)
			(xy 356.242522 -234.644207) (xy 356.258106 -234.690888) (xy 356.266001 -234.739465) (xy 356.266496 -234.764072)
			(xy 356.266001 -234.788679) (xy 356.258106 -234.837256) (xy 356.242522 -234.883937) (xy 356.219651 -234.927514)
			(xy 356.190086 -234.966858) (xy 356.154593 -235.00095) (xy 356.11409 -235.028906) (xy 356.069628 -235.050004)
			(xy 356.022357 -235.063696) (xy 355.973502 -235.069628) (xy 355.924327 -235.067647) (xy 355.876108 -235.057803)
			(xy 355.830092 -235.040351) (xy 355.787471 -235.015744) (xy 355.74935 -234.984619) (xy 355.716715 -234.947782)
			(xy 355.690412 -234.906186) (xy 355.671121 -234.86091) (xy 355.659344 -234.813126) (xy 355.655384 -234.764072)
			(xy 355.326442 -234.764072) (xy 355.325947 -234.788679) (xy 355.318052 -234.837256) (xy 355.302468 -234.883937)
			(xy 355.279597 -234.927514) (xy 355.250032 -234.966858) (xy 355.214539 -235.00095) (xy 355.174036 -235.028906)
			(xy 355.129574 -235.050004) (xy 355.082303 -235.063696) (xy 355.033448 -235.069628) (xy 354.984273 -235.067647)
			(xy 354.936054 -235.057803) (xy 354.890038 -235.040351) (xy 354.847417 -235.015744) (xy 354.809296 -234.984619)
			(xy 354.776661 -234.947782) (xy 354.750358 -234.906186) (xy 354.731067 -234.86091) (xy 354.71929 -234.813126)
			(xy 354.71533 -234.764072) (xy 354.386388 -234.764072) (xy 354.385893 -234.788679) (xy 354.377998 -234.837256)
			(xy 354.362414 -234.883937) (xy 354.339543 -234.927514) (xy 354.309978 -234.966858) (xy 354.274485 -235.00095)
			(xy 354.233982 -235.028906) (xy 354.18952 -235.050004) (xy 354.142249 -235.063696) (xy 354.093394 -235.069628)
			(xy 354.044219 -235.067647) (xy 353.996 -235.057803) (xy 353.949984 -235.040351) (xy 353.907363 -235.015744)
			(xy 353.869242 -234.984619) (xy 353.836607 -234.947782) (xy 353.810304 -234.906186) (xy 353.791013 -234.86091)
			(xy 353.779236 -234.813126) (xy 353.775276 -234.764072) (xy 353.446334 -234.764072) (xy 353.445839 -234.788679)
			(xy 353.437944 -234.837256) (xy 353.42236 -234.883937) (xy 353.399489 -234.927514) (xy 353.369924 -234.966858)
			(xy 353.334431 -235.00095) (xy 353.293928 -235.028906) (xy 353.249466 -235.050004) (xy 353.202195 -235.063696)
			(xy 353.15334 -235.069628) (xy 353.104165 -235.067647) (xy 353.055946 -235.057803) (xy 353.00993 -235.040351)
			(xy 352.967309 -235.015744) (xy 352.929188 -234.984619) (xy 352.896553 -234.947782) (xy 352.87025 -234.906186)
			(xy 352.850959 -234.86091) (xy 352.839182 -234.813126) (xy 352.835222 -234.764072) (xy 352.506534 -234.764072)
			(xy 352.506039 -234.788679) (xy 352.498144 -234.837256) (xy 352.48256 -234.883937) (xy 352.459689 -234.927514)
			(xy 352.430124 -234.966858) (xy 352.394631 -235.00095) (xy 352.354128 -235.028906) (xy 352.309666 -235.050004)
			(xy 352.262395 -235.063696) (xy 352.21354 -235.069628) (xy 352.164365 -235.067647) (xy 352.116146 -235.057803)
			(xy 352.07013 -235.040351) (xy 352.027509 -235.015744) (xy 351.989388 -234.984619) (xy 351.956753 -234.947782)
			(xy 351.93045 -234.906186) (xy 351.911159 -234.86091) (xy 351.899382 -234.813126) (xy 351.895422 -234.764072)
			(xy 351.56648 -234.764072) (xy 351.565985 -234.788679) (xy 351.55809 -234.837256) (xy 351.542506 -234.883937)
			(xy 351.519635 -234.927514) (xy 351.49007 -234.966858) (xy 351.454577 -235.00095) (xy 351.414074 -235.028906)
			(xy 351.369612 -235.050004) (xy 351.322341 -235.063696) (xy 351.273486 -235.069628) (xy 351.224311 -235.067647)
			(xy 351.176092 -235.057803) (xy 351.130076 -235.040351) (xy 351.087455 -235.015744) (xy 351.049334 -234.984619)
			(xy 351.016699 -234.947782) (xy 350.990396 -234.906186) (xy 350.971105 -234.86091) (xy 350.959328 -234.813126)
			(xy 350.955368 -234.764072) (xy 350.626426 -234.764072) (xy 350.625931 -234.788679) (xy 350.618036 -234.837256)
			(xy 350.602452 -234.883937) (xy 350.579581 -234.927514) (xy 350.550016 -234.966858) (xy 350.514523 -235.00095)
			(xy 350.47402 -235.028906) (xy 350.429558 -235.050004) (xy 350.382287 -235.063696) (xy 350.333432 -235.069628)
			(xy 350.284257 -235.067647) (xy 350.236038 -235.057803) (xy 350.190022 -235.040351) (xy 350.147401 -235.015744)
			(xy 350.10928 -234.984619) (xy 350.076645 -234.947782) (xy 350.050342 -234.906186) (xy 350.031051 -234.86091)
			(xy 350.019274 -234.813126) (xy 350.015314 -234.764072) (xy 349.686372 -234.764072) (xy 349.685877 -234.788679)
			(xy 349.677982 -234.837256) (xy 349.662398 -234.883937) (xy 349.639527 -234.927514) (xy 349.609962 -234.966858)
			(xy 349.574469 -235.00095) (xy 349.533966 -235.028906) (xy 349.489504 -235.050004) (xy 349.442233 -235.063696)
			(xy 349.393378 -235.069628) (xy 349.344203 -235.067647) (xy 349.295984 -235.057803) (xy 349.249968 -235.040351)
			(xy 349.207347 -235.015744) (xy 349.169226 -234.984619) (xy 349.136591 -234.947782) (xy 349.110288 -234.906186)
			(xy 349.090997 -234.86091) (xy 349.07922 -234.813126) (xy 349.07526 -234.764072) (xy 348.746318 -234.764072)
			(xy 348.745823 -234.788679) (xy 348.737928 -234.837256) (xy 348.722344 -234.883937) (xy 348.699473 -234.927514)
			(xy 348.669908 -234.966858) (xy 348.634415 -235.00095) (xy 348.593912 -235.028906) (xy 348.54945 -235.050004)
			(xy 348.502179 -235.063696) (xy 348.453324 -235.069628) (xy 348.404149 -235.067647) (xy 348.35593 -235.057803)
			(xy 348.309914 -235.040351) (xy 348.267293 -235.015744) (xy 348.229172 -234.984619) (xy 348.196537 -234.947782)
			(xy 348.170234 -234.906186) (xy 348.150943 -234.86091) (xy 348.139166 -234.813126) (xy 348.135206 -234.764072)
			(xy 347.806518 -234.764072) (xy 347.806023 -234.788679) (xy 347.798128 -234.837256) (xy 347.782544 -234.883937)
			(xy 347.759673 -234.927514) (xy 347.730108 -234.966858) (xy 347.694615 -235.00095) (xy 347.654112 -235.028906)
			(xy 347.60965 -235.050004) (xy 347.562379 -235.063696) (xy 347.513524 -235.069628) (xy 347.464349 -235.067647)
			(xy 347.41613 -235.057803) (xy 347.370114 -235.040351) (xy 347.327493 -235.015744) (xy 347.289372 -234.984619)
			(xy 347.256737 -234.947782) (xy 347.230434 -234.906186) (xy 347.211143 -234.86091) (xy 347.199366 -234.813126)
			(xy 347.195406 -234.764072) (xy 346.866464 -234.764072) (xy 346.865969 -234.788679) (xy 346.858074 -234.837256)
			(xy 346.84249 -234.883937) (xy 346.819619 -234.927514) (xy 346.790054 -234.966858) (xy 346.754561 -235.00095)
			(xy 346.714058 -235.028906) (xy 346.669596 -235.050004) (xy 346.622325 -235.063696) (xy 346.57347 -235.069628)
			(xy 346.524295 -235.067647) (xy 346.476076 -235.057803) (xy 346.43006 -235.040351) (xy 346.387439 -235.015744)
			(xy 346.349318 -234.984619) (xy 346.316683 -234.947782) (xy 346.29038 -234.906186) (xy 346.271089 -234.86091)
			(xy 346.259312 -234.813126) (xy 346.255352 -234.764072) (xy 345.92641 -234.764072) (xy 345.925915 -234.788679)
			(xy 345.91802 -234.837256) (xy 345.902436 -234.883937) (xy 345.879565 -234.927514) (xy 345.85 -234.966858)
			(xy 345.814507 -235.00095) (xy 345.774004 -235.028906) (xy 345.729542 -235.050004) (xy 345.682271 -235.063696)
			(xy 345.633416 -235.069628) (xy 345.584241 -235.067647) (xy 345.536022 -235.057803) (xy 345.490006 -235.040351)
			(xy 345.447385 -235.015744) (xy 345.409264 -234.984619) (xy 345.376629 -234.947782) (xy 345.350326 -234.906186)
			(xy 345.331035 -234.86091) (xy 345.319258 -234.813126) (xy 345.315298 -234.764072) (xy 344.986356 -234.764072)
			(xy 344.985861 -234.788679) (xy 344.977966 -234.837256) (xy 344.962382 -234.883937) (xy 344.939511 -234.927514)
			(xy 344.909946 -234.966858) (xy 344.874453 -235.00095) (xy 344.83395 -235.028906) (xy 344.789488 -235.050004)
			(xy 344.742217 -235.063696) (xy 344.693362 -235.069628) (xy 344.644187 -235.067647) (xy 344.595968 -235.057803)
			(xy 344.549952 -235.040351) (xy 344.507331 -235.015744) (xy 344.46921 -234.984619) (xy 344.436575 -234.947782)
			(xy 344.410272 -234.906186) (xy 344.390981 -234.86091) (xy 344.379204 -234.813126) (xy 344.375244 -234.764072)
			(xy 344.056716 -234.764072) (xy 344.056204 -234.789518) (xy 344.04804 -234.839752) (xy 344.031924 -234.888026)
			(xy 344.008273 -234.933089) (xy 343.9777 -234.973775) (xy 343.940996 -235.00903) (xy 343.899112 -235.03794)
			(xy 343.853133 -235.059757) (xy 343.804249 -235.073917) (xy 343.753728 -235.080051) (xy 343.702876 -235.078002)
			(xy 343.653012 -235.067822) (xy 343.605426 -235.049775) (xy 343.561352 -235.024329) (xy 343.52193 -234.992142)
			(xy 343.488182 -234.954048) (xy 343.460981 -234.911034) (xy 343.441033 -234.864214) (xy 343.428854 -234.8148)
			(xy 343.424759 -234.764072) (xy 343.106502 -234.764072) (xy 343.106007 -234.788679) (xy 343.098112 -234.837256)
			(xy 343.082528 -234.883937) (xy 343.059657 -234.927514) (xy 343.030092 -234.966858) (xy 342.994599 -235.00095)
			(xy 342.954096 -235.028906) (xy 342.909634 -235.050004) (xy 342.862363 -235.063696) (xy 342.813508 -235.069628)
			(xy 342.764333 -235.067647) (xy 342.716114 -235.057803) (xy 342.670098 -235.040351) (xy 342.627477 -235.015744)
			(xy 342.589356 -234.984619) (xy 342.556721 -234.947782) (xy 342.530418 -234.906186) (xy 342.511127 -234.86091)
			(xy 342.49935 -234.813126) (xy 342.49539 -234.764072) (xy 342.176862 -234.764072) (xy 342.17635 -234.789518)
			(xy 342.168186 -234.839752) (xy 342.15207 -234.888026) (xy 342.128419 -234.933089) (xy 342.097846 -234.973775)
			(xy 342.061142 -235.00903) (xy 342.019258 -235.03794) (xy 341.973279 -235.059757) (xy 341.924395 -235.073917)
			(xy 341.873874 -235.080051) (xy 341.823022 -235.078002) (xy 341.773158 -235.067822) (xy 341.725572 -235.049775)
			(xy 341.681498 -235.024329) (xy 341.642076 -234.992142) (xy 341.608328 -234.954048) (xy 341.581127 -234.911034)
			(xy 341.561179 -234.864214) (xy 341.549 -234.8148) (xy 341.544905 -234.764072) (xy 341.233252 -234.764072)
			(xy 341.233252 -235.17098) (xy 341.233809 -235.181674) (xy 341.242463 -235.201236) (xy 341.250016 -235.208826)
			(xy 341.250524 -235.20908) (xy 341.316564 -235.266738) (xy 341.327232 -235.269786) (xy 341.3379 -235.273088)
			(xy 341.348822 -235.271564) (xy 341.359312 -235.270231) (xy 341.380412 -235.268832) (xy 341.390986 -235.26877)
			(xy 341.416246 -235.269262) (xy 341.466078 -235.277575) (xy 341.513862 -235.293977) (xy 341.558294 -235.318021)
			(xy 341.598163 -235.34905) (xy 341.63238 -235.386219) (xy 341.660013 -235.428512) (xy 341.680308 -235.474777)
			(xy 341.69271 -235.523752) (xy 341.69688 -235.574078) (xy 342.014805 -235.574078) (xy 342.0189 -235.52335)
			(xy 342.031079 -235.473936) (xy 342.051027 -235.427116) (xy 342.078228 -235.384102) (xy 342.111976 -235.346008)
			(xy 342.151398 -235.313821) (xy 342.195472 -235.288375) (xy 342.243058 -235.270328) (xy 342.292922 -235.260148)
			(xy 342.343774 -235.258099) (xy 342.394295 -235.264233) (xy 342.443179 -235.278393) (xy 342.489158 -235.30021)
			(xy 342.531042 -235.32912) (xy 342.567746 -235.364375) (xy 342.598319 -235.405061) (xy 342.62197 -235.450124)
			(xy 342.638086 -235.498398) (xy 342.64625 -235.548632) (xy 342.646762 -235.574078) (xy 342.954859 -235.574078)
			(xy 342.958954 -235.52335) (xy 342.971133 -235.473936) (xy 342.991081 -235.427116) (xy 343.018282 -235.384102)
			(xy 343.05203 -235.346008) (xy 343.091452 -235.313821) (xy 343.135526 -235.288375) (xy 343.183112 -235.270328)
			(xy 343.232976 -235.260148) (xy 343.283828 -235.258099) (xy 343.334349 -235.264233) (xy 343.383233 -235.278393)
			(xy 343.429212 -235.30021) (xy 343.471096 -235.32912) (xy 343.5078 -235.364375) (xy 343.538373 -235.405061)
			(xy 343.562024 -235.450124) (xy 343.57814 -235.498398) (xy 343.586304 -235.548632) (xy 343.586816 -235.574078)
			(xy 343.905344 -235.574078) (xy 343.909304 -235.525024) (xy 343.921081 -235.47724) (xy 343.940372 -235.431964)
			(xy 343.966675 -235.390368) (xy 343.99931 -235.353531) (xy 344.037431 -235.322406) (xy 344.080052 -235.297799)
			(xy 344.126068 -235.280347) (xy 344.174287 -235.270503) (xy 344.223462 -235.268522) (xy 344.272317 -235.274454)
			(xy 344.319588 -235.288146) (xy 344.36405 -235.309244) (xy 344.404553 -235.3372) (xy 344.440046 -235.371292)
			(xy 344.469611 -235.410636) (xy 344.492482 -235.454213) (xy 344.508066 -235.500894) (xy 344.515961 -235.549471)
			(xy 344.516456 -235.574078) (xy 344.845398 -235.574078) (xy 344.849358 -235.525024) (xy 344.861135 -235.47724)
			(xy 344.880426 -235.431964) (xy 344.906729 -235.390368) (xy 344.939364 -235.353531) (xy 344.977485 -235.322406)
			(xy 345.020106 -235.297799) (xy 345.066122 -235.280347) (xy 345.114341 -235.270503) (xy 345.163516 -235.268522)
			(xy 345.212371 -235.274454) (xy 345.259642 -235.288146) (xy 345.304104 -235.309244) (xy 345.344607 -235.3372)
			(xy 345.3801 -235.371292) (xy 345.409665 -235.410636) (xy 345.432536 -235.454213) (xy 345.44812 -235.500894)
			(xy 345.456015 -235.549471) (xy 345.45651 -235.574078) (xy 345.785198 -235.574078) (xy 345.789158 -235.525024)
			(xy 345.800935 -235.47724) (xy 345.820226 -235.431964) (xy 345.846529 -235.390368) (xy 345.879164 -235.353531)
			(xy 345.917285 -235.322406) (xy 345.959906 -235.297799) (xy 346.005922 -235.280347) (xy 346.054141 -235.270503)
			(xy 346.103316 -235.268522) (xy 346.152171 -235.274454) (xy 346.199442 -235.288146) (xy 346.243904 -235.309244)
			(xy 346.284407 -235.3372) (xy 346.3199 -235.371292) (xy 346.349465 -235.410636) (xy 346.372336 -235.454213)
			(xy 346.38792 -235.500894) (xy 346.395815 -235.549471) (xy 346.39631 -235.574078) (xy 346.725252 -235.574078)
			(xy 346.729212 -235.525024) (xy 346.740989 -235.47724) (xy 346.76028 -235.431964) (xy 346.786583 -235.390368)
			(xy 346.819218 -235.353531) (xy 346.857339 -235.322406) (xy 346.89996 -235.297799) (xy 346.945976 -235.280347)
			(xy 346.994195 -235.270503) (xy 347.04337 -235.268522) (xy 347.092225 -235.274454) (xy 347.139496 -235.288146)
			(xy 347.183958 -235.309244) (xy 347.224461 -235.3372) (xy 347.259954 -235.371292) (xy 347.289519 -235.410636)
			(xy 347.31239 -235.454213) (xy 347.327974 -235.500894) (xy 347.335869 -235.549471) (xy 347.336364 -235.574078)
			(xy 347.665306 -235.574078) (xy 347.669266 -235.525024) (xy 347.681043 -235.47724) (xy 347.700334 -235.431964)
			(xy 347.726637 -235.390368) (xy 347.759272 -235.353531) (xy 347.797393 -235.322406) (xy 347.840014 -235.297799)
			(xy 347.88603 -235.280347) (xy 347.934249 -235.270503) (xy 347.983424 -235.268522) (xy 348.032279 -235.274454)
			(xy 348.07955 -235.288146) (xy 348.124012 -235.309244) (xy 348.164515 -235.3372) (xy 348.200008 -235.371292)
			(xy 348.229573 -235.410636) (xy 348.252444 -235.454213) (xy 348.268028 -235.500894) (xy 348.275923 -235.549471)
			(xy 348.276418 -235.574078) (xy 348.60536 -235.574078) (xy 348.60932 -235.525024) (xy 348.621097 -235.47724)
			(xy 348.640388 -235.431964) (xy 348.666691 -235.390368) (xy 348.699326 -235.353531) (xy 348.737447 -235.322406)
			(xy 348.780068 -235.297799) (xy 348.826084 -235.280347) (xy 348.874303 -235.270503) (xy 348.923478 -235.268522)
			(xy 348.972333 -235.274454) (xy 349.019604 -235.288146) (xy 349.064066 -235.309244) (xy 349.104569 -235.3372)
			(xy 349.140062 -235.371292) (xy 349.169627 -235.410636) (xy 349.192498 -235.454213) (xy 349.208082 -235.500894)
			(xy 349.215977 -235.549471) (xy 349.216472 -235.574078) (xy 349.545414 -235.574078) (xy 349.549374 -235.525024)
			(xy 349.561151 -235.47724) (xy 349.580442 -235.431964) (xy 349.606745 -235.390368) (xy 349.63938 -235.353531)
			(xy 349.677501 -235.322406) (xy 349.720122 -235.297799) (xy 349.766138 -235.280347) (xy 349.814357 -235.270503)
			(xy 349.863532 -235.268522) (xy 349.912387 -235.274454) (xy 349.959658 -235.288146) (xy 350.00412 -235.309244)
			(xy 350.044623 -235.3372) (xy 350.080116 -235.371292) (xy 350.109681 -235.410636) (xy 350.132552 -235.454213)
			(xy 350.148136 -235.500894) (xy 350.156031 -235.549471) (xy 350.156526 -235.574078) (xy 350.485214 -235.574078)
			(xy 350.489174 -235.525024) (xy 350.500951 -235.47724) (xy 350.520242 -235.431964) (xy 350.546545 -235.390368)
			(xy 350.57918 -235.353531) (xy 350.617301 -235.322406) (xy 350.659922 -235.297799) (xy 350.705938 -235.280347)
			(xy 350.754157 -235.270503) (xy 350.803332 -235.268522) (xy 350.852187 -235.274454) (xy 350.899458 -235.288146)
			(xy 350.94392 -235.309244) (xy 350.984423 -235.3372) (xy 351.019916 -235.371292) (xy 351.049481 -235.410636)
			(xy 351.072352 -235.454213) (xy 351.087936 -235.500894) (xy 351.095831 -235.549471) (xy 351.096326 -235.574078)
			(xy 351.425268 -235.574078) (xy 351.429228 -235.525024) (xy 351.441005 -235.47724) (xy 351.460296 -235.431964)
			(xy 351.486599 -235.390368) (xy 351.519234 -235.353531) (xy 351.557355 -235.322406) (xy 351.599976 -235.297799)
			(xy 351.645992 -235.280347) (xy 351.694211 -235.270503) (xy 351.743386 -235.268522) (xy 351.792241 -235.274454)
			(xy 351.839512 -235.288146) (xy 351.883974 -235.309244) (xy 351.924477 -235.3372) (xy 351.95997 -235.371292)
			(xy 351.989535 -235.410636) (xy 352.012406 -235.454213) (xy 352.02799 -235.500894) (xy 352.035885 -235.549471)
			(xy 352.03638 -235.574078) (xy 352.365322 -235.574078) (xy 352.369282 -235.525024) (xy 352.381059 -235.47724)
			(xy 352.40035 -235.431964) (xy 352.426653 -235.390368) (xy 352.459288 -235.353531) (xy 352.497409 -235.322406)
			(xy 352.54003 -235.297799) (xy 352.586046 -235.280347) (xy 352.634265 -235.270503) (xy 352.68344 -235.268522)
			(xy 352.732295 -235.274454) (xy 352.779566 -235.288146) (xy 352.824028 -235.309244) (xy 352.864531 -235.3372)
			(xy 352.900024 -235.371292) (xy 352.929589 -235.410636) (xy 352.95246 -235.454213) (xy 352.968044 -235.500894)
			(xy 352.975939 -235.549471) (xy 352.976434 -235.574078) (xy 353.305376 -235.574078) (xy 353.309336 -235.525024)
			(xy 353.321113 -235.47724) (xy 353.340404 -235.431964) (xy 353.366707 -235.390368) (xy 353.399342 -235.353531)
			(xy 353.437463 -235.322406) (xy 353.480084 -235.297799) (xy 353.5261 -235.280347) (xy 353.574319 -235.270503)
			(xy 353.623494 -235.268522) (xy 353.672349 -235.274454) (xy 353.71962 -235.288146) (xy 353.764082 -235.309244)
			(xy 353.804585 -235.3372) (xy 353.840078 -235.371292) (xy 353.869643 -235.410636) (xy 353.892514 -235.454213)
			(xy 353.908098 -235.500894) (xy 353.915993 -235.549471) (xy 353.916488 -235.574078) (xy 354.24543 -235.574078)
			(xy 354.24939 -235.525024) (xy 354.261167 -235.47724) (xy 354.280458 -235.431964) (xy 354.306761 -235.390368)
			(xy 354.339396 -235.353531) (xy 354.377517 -235.322406) (xy 354.420138 -235.297799) (xy 354.466154 -235.280347)
			(xy 354.514373 -235.270503) (xy 354.563548 -235.268522) (xy 354.612403 -235.274454) (xy 354.659674 -235.288146)
			(xy 354.704136 -235.309244) (xy 354.744639 -235.3372) (xy 354.780132 -235.371292) (xy 354.809697 -235.410636)
			(xy 354.832568 -235.454213) (xy 354.848152 -235.500894) (xy 354.856047 -235.549471) (xy 354.856542 -235.574078)
			(xy 355.18523 -235.574078) (xy 355.18919 -235.525024) (xy 355.200967 -235.47724) (xy 355.220258 -235.431964)
			(xy 355.246561 -235.390368) (xy 355.279196 -235.353531) (xy 355.317317 -235.322406) (xy 355.359938 -235.297799)
			(xy 355.405954 -235.280347) (xy 355.454173 -235.270503) (xy 355.503348 -235.268522) (xy 355.552203 -235.274454)
			(xy 355.599474 -235.288146) (xy 355.643936 -235.309244) (xy 355.684439 -235.3372) (xy 355.719932 -235.371292)
			(xy 355.749497 -235.410636) (xy 355.772368 -235.454213) (xy 355.787952 -235.500894) (xy 355.795847 -235.549471)
			(xy 355.796342 -235.574078) (xy 356.125284 -235.574078) (xy 356.129244 -235.525024) (xy 356.141021 -235.47724)
			(xy 356.160312 -235.431964) (xy 356.186615 -235.390368) (xy 356.21925 -235.353531) (xy 356.257371 -235.322406)
			(xy 356.299992 -235.297799) (xy 356.346008 -235.280347) (xy 356.394227 -235.270503) (xy 356.443402 -235.268522)
			(xy 356.492257 -235.274454) (xy 356.539528 -235.288146) (xy 356.58399 -235.309244) (xy 356.624493 -235.3372)
			(xy 356.659986 -235.371292) (xy 356.689551 -235.410636) (xy 356.712422 -235.454213) (xy 356.728006 -235.500894)
			(xy 356.735901 -235.549471) (xy 356.736396 -235.574078) (xy 357.065338 -235.574078) (xy 357.069298 -235.525024)
			(xy 357.081075 -235.47724) (xy 357.100366 -235.431964) (xy 357.126669 -235.390368) (xy 357.159304 -235.353531)
			(xy 357.197425 -235.322406) (xy 357.240046 -235.297799) (xy 357.286062 -235.280347) (xy 357.334281 -235.270503)
			(xy 357.383456 -235.268522) (xy 357.432311 -235.274454) (xy 357.479582 -235.288146) (xy 357.524044 -235.309244)
			(xy 357.564547 -235.3372) (xy 357.60004 -235.371292) (xy 357.629605 -235.410636) (xy 357.652476 -235.454213)
			(xy 357.66806 -235.500894) (xy 357.675955 -235.549471) (xy 357.67645 -235.574078) (xy 358.005392 -235.574078)
			(xy 358.009352 -235.525024) (xy 358.021129 -235.47724) (xy 358.04042 -235.431964) (xy 358.066723 -235.390368)
			(xy 358.099358 -235.353531) (xy 358.137479 -235.322406) (xy 358.1801 -235.297799) (xy 358.226116 -235.280347)
			(xy 358.274335 -235.270503) (xy 358.32351 -235.268522) (xy 358.372365 -235.274454) (xy 358.419636 -235.288146)
			(xy 358.464098 -235.309244) (xy 358.504601 -235.3372) (xy 358.540094 -235.371292) (xy 358.569659 -235.410636)
			(xy 358.59253 -235.454213) (xy 358.608114 -235.500894) (xy 358.616009 -235.549471) (xy 358.616504 -235.574078)
			(xy 358.616009 -235.598685) (xy 358.608114 -235.647262) (xy 358.59253 -235.693943) (xy 358.569659 -235.73752)
			(xy 358.540094 -235.776864) (xy 358.504601 -235.810956) (xy 358.464098 -235.838912) (xy 358.419636 -235.86001)
			(xy 358.372365 -235.873702) (xy 358.32351 -235.879634) (xy 358.274335 -235.877653) (xy 358.226116 -235.867809)
			(xy 358.1801 -235.850357) (xy 358.137479 -235.82575) (xy 358.099358 -235.794625) (xy 358.066723 -235.757788)
			(xy 358.04042 -235.716192) (xy 358.021129 -235.670916) (xy 358.009352 -235.623132) (xy 358.005392 -235.574078)
			(xy 357.67645 -235.574078) (xy 357.675955 -235.598685) (xy 357.66806 -235.647262) (xy 357.652476 -235.693943)
			(xy 357.629605 -235.73752) (xy 357.60004 -235.776864) (xy 357.564547 -235.810956) (xy 357.524044 -235.838912)
			(xy 357.479582 -235.86001) (xy 357.432311 -235.873702) (xy 357.383456 -235.879634) (xy 357.334281 -235.877653)
			(xy 357.286062 -235.867809) (xy 357.240046 -235.850357) (xy 357.197425 -235.82575) (xy 357.159304 -235.794625)
			(xy 357.126669 -235.757788) (xy 357.100366 -235.716192) (xy 357.081075 -235.670916) (xy 357.069298 -235.623132)
			(xy 357.065338 -235.574078) (xy 356.736396 -235.574078) (xy 356.735901 -235.598685) (xy 356.728006 -235.647262)
			(xy 356.712422 -235.693943) (xy 356.689551 -235.73752) (xy 356.659986 -235.776864) (xy 356.624493 -235.810956)
			(xy 356.58399 -235.838912) (xy 356.539528 -235.86001) (xy 356.492257 -235.873702) (xy 356.443402 -235.879634)
			(xy 356.394227 -235.877653) (xy 356.346008 -235.867809) (xy 356.299992 -235.850357) (xy 356.257371 -235.82575)
			(xy 356.21925 -235.794625) (xy 356.186615 -235.757788) (xy 356.160312 -235.716192) (xy 356.141021 -235.670916)
			(xy 356.129244 -235.623132) (xy 356.125284 -235.574078) (xy 355.796342 -235.574078) (xy 355.795847 -235.598685)
			(xy 355.787952 -235.647262) (xy 355.772368 -235.693943) (xy 355.749497 -235.73752) (xy 355.719932 -235.776864)
			(xy 355.684439 -235.810956) (xy 355.643936 -235.838912) (xy 355.599474 -235.86001) (xy 355.552203 -235.873702)
			(xy 355.503348 -235.879634) (xy 355.454173 -235.877653) (xy 355.405954 -235.867809) (xy 355.359938 -235.850357)
			(xy 355.317317 -235.82575) (xy 355.279196 -235.794625) (xy 355.246561 -235.757788) (xy 355.220258 -235.716192)
			(xy 355.200967 -235.670916) (xy 355.18919 -235.623132) (xy 355.18523 -235.574078) (xy 354.856542 -235.574078)
			(xy 354.856047 -235.598685) (xy 354.848152 -235.647262) (xy 354.832568 -235.693943) (xy 354.809697 -235.73752)
			(xy 354.780132 -235.776864) (xy 354.744639 -235.810956) (xy 354.704136 -235.838912) (xy 354.659674 -235.86001)
			(xy 354.612403 -235.873702) (xy 354.563548 -235.879634) (xy 354.514373 -235.877653) (xy 354.466154 -235.867809)
			(xy 354.420138 -235.850357) (xy 354.377517 -235.82575) (xy 354.339396 -235.794625) (xy 354.306761 -235.757788)
			(xy 354.280458 -235.716192) (xy 354.261167 -235.670916) (xy 354.24939 -235.623132) (xy 354.24543 -235.574078)
			(xy 353.916488 -235.574078) (xy 353.915993 -235.598685) (xy 353.908098 -235.647262) (xy 353.892514 -235.693943)
			(xy 353.869643 -235.73752) (xy 353.840078 -235.776864) (xy 353.804585 -235.810956) (xy 353.764082 -235.838912)
			(xy 353.71962 -235.86001) (xy 353.672349 -235.873702) (xy 353.623494 -235.879634) (xy 353.574319 -235.877653)
			(xy 353.5261 -235.867809) (xy 353.480084 -235.850357) (xy 353.437463 -235.82575) (xy 353.399342 -235.794625)
			(xy 353.366707 -235.757788) (xy 353.340404 -235.716192) (xy 353.321113 -235.670916) (xy 353.309336 -235.623132)
			(xy 353.305376 -235.574078) (xy 352.976434 -235.574078) (xy 352.975939 -235.598685) (xy 352.968044 -235.647262)
			(xy 352.95246 -235.693943) (xy 352.929589 -235.73752) (xy 352.900024 -235.776864) (xy 352.864531 -235.810956)
			(xy 352.824028 -235.838912) (xy 352.779566 -235.86001) (xy 352.732295 -235.873702) (xy 352.68344 -235.879634)
			(xy 352.634265 -235.877653) (xy 352.586046 -235.867809) (xy 352.54003 -235.850357) (xy 352.497409 -235.82575)
			(xy 352.459288 -235.794625) (xy 352.426653 -235.757788) (xy 352.40035 -235.716192) (xy 352.381059 -235.670916)
			(xy 352.369282 -235.623132) (xy 352.365322 -235.574078) (xy 352.03638 -235.574078) (xy 352.035885 -235.598685)
			(xy 352.02799 -235.647262) (xy 352.012406 -235.693943) (xy 351.989535 -235.73752) (xy 351.95997 -235.776864)
			(xy 351.924477 -235.810956) (xy 351.883974 -235.838912) (xy 351.839512 -235.86001) (xy 351.792241 -235.873702)
			(xy 351.743386 -235.879634) (xy 351.694211 -235.877653) (xy 351.645992 -235.867809) (xy 351.599976 -235.850357)
			(xy 351.557355 -235.82575) (xy 351.519234 -235.794625) (xy 351.486599 -235.757788) (xy 351.460296 -235.716192)
			(xy 351.441005 -235.670916) (xy 351.429228 -235.623132) (xy 351.425268 -235.574078) (xy 351.096326 -235.574078)
			(xy 351.095831 -235.598685) (xy 351.087936 -235.647262) (xy 351.072352 -235.693943) (xy 351.049481 -235.73752)
			(xy 351.019916 -235.776864) (xy 350.984423 -235.810956) (xy 350.94392 -235.838912) (xy 350.899458 -235.86001)
			(xy 350.852187 -235.873702) (xy 350.803332 -235.879634) (xy 350.754157 -235.877653) (xy 350.705938 -235.867809)
			(xy 350.659922 -235.850357) (xy 350.617301 -235.82575) (xy 350.57918 -235.794625) (xy 350.546545 -235.757788)
			(xy 350.520242 -235.716192) (xy 350.500951 -235.670916) (xy 350.489174 -235.623132) (xy 350.485214 -235.574078)
			(xy 350.156526 -235.574078) (xy 350.156031 -235.598685) (xy 350.148136 -235.647262) (xy 350.132552 -235.693943)
			(xy 350.109681 -235.73752) (xy 350.080116 -235.776864) (xy 350.044623 -235.810956) (xy 350.00412 -235.838912)
			(xy 349.959658 -235.86001) (xy 349.912387 -235.873702) (xy 349.863532 -235.879634) (xy 349.814357 -235.877653)
			(xy 349.766138 -235.867809) (xy 349.720122 -235.850357) (xy 349.677501 -235.82575) (xy 349.63938 -235.794625)
			(xy 349.606745 -235.757788) (xy 349.580442 -235.716192) (xy 349.561151 -235.670916) (xy 349.549374 -235.623132)
			(xy 349.545414 -235.574078) (xy 349.216472 -235.574078) (xy 349.215977 -235.598685) (xy 349.208082 -235.647262)
			(xy 349.192498 -235.693943) (xy 349.169627 -235.73752) (xy 349.140062 -235.776864) (xy 349.104569 -235.810956)
			(xy 349.064066 -235.838912) (xy 349.019604 -235.86001) (xy 348.972333 -235.873702) (xy 348.923478 -235.879634)
			(xy 348.874303 -235.877653) (xy 348.826084 -235.867809) (xy 348.780068 -235.850357) (xy 348.737447 -235.82575)
			(xy 348.699326 -235.794625) (xy 348.666691 -235.757788) (xy 348.640388 -235.716192) (xy 348.621097 -235.670916)
			(xy 348.60932 -235.623132) (xy 348.60536 -235.574078) (xy 348.276418 -235.574078) (xy 348.275923 -235.598685)
			(xy 348.268028 -235.647262) (xy 348.252444 -235.693943) (xy 348.229573 -235.73752) (xy 348.200008 -235.776864)
			(xy 348.164515 -235.810956) (xy 348.124012 -235.838912) (xy 348.07955 -235.86001) (xy 348.032279 -235.873702)
			(xy 347.983424 -235.879634) (xy 347.934249 -235.877653) (xy 347.88603 -235.867809) (xy 347.840014 -235.850357)
			(xy 347.797393 -235.82575) (xy 347.759272 -235.794625) (xy 347.726637 -235.757788) (xy 347.700334 -235.716192)
			(xy 347.681043 -235.670916) (xy 347.669266 -235.623132) (xy 347.665306 -235.574078) (xy 347.336364 -235.574078)
			(xy 347.335869 -235.598685) (xy 347.327974 -235.647262) (xy 347.31239 -235.693943) (xy 347.289519 -235.73752)
			(xy 347.259954 -235.776864) (xy 347.224461 -235.810956) (xy 347.183958 -235.838912) (xy 347.139496 -235.86001)
			(xy 347.092225 -235.873702) (xy 347.04337 -235.879634) (xy 346.994195 -235.877653) (xy 346.945976 -235.867809)
			(xy 346.89996 -235.850357) (xy 346.857339 -235.82575) (xy 346.819218 -235.794625) (xy 346.786583 -235.757788)
			(xy 346.76028 -235.716192) (xy 346.740989 -235.670916) (xy 346.729212 -235.623132) (xy 346.725252 -235.574078)
			(xy 346.39631 -235.574078) (xy 346.395815 -235.598685) (xy 346.38792 -235.647262) (xy 346.372336 -235.693943)
			(xy 346.349465 -235.73752) (xy 346.3199 -235.776864) (xy 346.284407 -235.810956) (xy 346.243904 -235.838912)
			(xy 346.199442 -235.86001) (xy 346.152171 -235.873702) (xy 346.103316 -235.879634) (xy 346.054141 -235.877653)
			(xy 346.005922 -235.867809) (xy 345.959906 -235.850357) (xy 345.917285 -235.82575) (xy 345.879164 -235.794625)
			(xy 345.846529 -235.757788) (xy 345.820226 -235.716192) (xy 345.800935 -235.670916) (xy 345.789158 -235.623132)
			(xy 345.785198 -235.574078) (xy 345.45651 -235.574078) (xy 345.456015 -235.598685) (xy 345.44812 -235.647262)
			(xy 345.432536 -235.693943) (xy 345.409665 -235.73752) (xy 345.3801 -235.776864) (xy 345.344607 -235.810956)
			(xy 345.304104 -235.838912) (xy 345.259642 -235.86001) (xy 345.212371 -235.873702) (xy 345.163516 -235.879634)
			(xy 345.114341 -235.877653) (xy 345.066122 -235.867809) (xy 345.020106 -235.850357) (xy 344.977485 -235.82575)
			(xy 344.939364 -235.794625) (xy 344.906729 -235.757788) (xy 344.880426 -235.716192) (xy 344.861135 -235.670916)
			(xy 344.849358 -235.623132) (xy 344.845398 -235.574078) (xy 344.516456 -235.574078) (xy 344.515961 -235.598685)
			(xy 344.508066 -235.647262) (xy 344.492482 -235.693943) (xy 344.469611 -235.73752) (xy 344.440046 -235.776864)
			(xy 344.404553 -235.810956) (xy 344.36405 -235.838912) (xy 344.319588 -235.86001) (xy 344.272317 -235.873702)
			(xy 344.223462 -235.879634) (xy 344.174287 -235.877653) (xy 344.126068 -235.867809) (xy 344.080052 -235.850357)
			(xy 344.037431 -235.82575) (xy 343.99931 -235.794625) (xy 343.966675 -235.757788) (xy 343.940372 -235.716192)
			(xy 343.921081 -235.670916) (xy 343.909304 -235.623132) (xy 343.905344 -235.574078) (xy 343.586816 -235.574078)
			(xy 343.586304 -235.599524) (xy 343.57814 -235.649758) (xy 343.562024 -235.698032) (xy 343.538373 -235.743095)
			(xy 343.5078 -235.783781) (xy 343.471096 -235.819036) (xy 343.429212 -235.847946) (xy 343.383233 -235.869763)
			(xy 343.334349 -235.883923) (xy 343.283828 -235.890057) (xy 343.232976 -235.888008) (xy 343.183112 -235.877828)
			(xy 343.135526 -235.859781) (xy 343.091452 -235.834335) (xy 343.05203 -235.802148) (xy 343.018282 -235.764054)
			(xy 342.991081 -235.72104) (xy 342.971133 -235.67422) (xy 342.958954 -235.624806) (xy 342.954859 -235.574078)
			(xy 342.646762 -235.574078) (xy 342.64625 -235.599524) (xy 342.638086 -235.649758) (xy 342.62197 -235.698032)
			(xy 342.598319 -235.743095) (xy 342.567746 -235.783781) (xy 342.531042 -235.819036) (xy 342.489158 -235.847946)
			(xy 342.443179 -235.869763) (xy 342.394295 -235.883923) (xy 342.343774 -235.890057) (xy 342.292922 -235.888008)
			(xy 342.243058 -235.877828) (xy 342.195472 -235.859781) (xy 342.151398 -235.834335) (xy 342.111976 -235.802148)
			(xy 342.078228 -235.764054) (xy 342.051027 -235.72104) (xy 342.031079 -235.67422) (xy 342.0189 -235.624806)
			(xy 342.014805 -235.574078) (xy 341.69688 -235.574078) (xy 341.696882 -235.5741) (xy 341.69271 -235.624448)
			(xy 341.680308 -235.673423) (xy 341.660013 -235.719688) (xy 341.63238 -235.761981) (xy 341.598163 -235.79915)
			(xy 341.558294 -235.830179) (xy 341.513862 -235.854223) (xy 341.466078 -235.870625) (xy 341.416246 -235.878938)
			(xy 341.390986 -235.879386) (xy 341.380412 -235.879332) (xy 341.359311 -235.877935) (xy 341.348822 -235.876592)
			(xy 341.3379 -235.875068) (xy 341.317072 -235.881418) (xy 341.250778 -235.938822) (xy 341.242396 -235.946188)
			(xy 341.233252 -235.966) (xy 341.233252 -236.384084) (xy 341.544905 -236.384084) (xy 341.549 -236.333356)
			(xy 341.561179 -236.283942) (xy 341.581127 -236.237122) (xy 341.608328 -236.194108) (xy 341.642076 -236.156014)
			(xy 341.681498 -236.123827) (xy 341.725572 -236.098381) (xy 341.773158 -236.080334) (xy 341.823022 -236.070154)
			(xy 341.873874 -236.068105) (xy 341.924395 -236.074239) (xy 341.973279 -236.088399) (xy 342.019258 -236.110216)
			(xy 342.061142 -236.139126) (xy 342.097846 -236.174381) (xy 342.128419 -236.215067) (xy 342.15207 -236.26013)
			(xy 342.168186 -236.308404) (xy 342.17635 -236.358638) (xy 342.176862 -236.384084) (xy 342.49539 -236.384084)
			(xy 342.49935 -236.33503) (xy 342.511127 -236.287246) (xy 342.530418 -236.24197) (xy 342.556721 -236.200374)
			(xy 342.589356 -236.163537) (xy 342.627477 -236.132412) (xy 342.670098 -236.107805) (xy 342.716114 -236.090353)
			(xy 342.764333 -236.080509) (xy 342.813508 -236.078528) (xy 342.862363 -236.08446) (xy 342.909634 -236.098152)
			(xy 342.954096 -236.11925) (xy 342.994599 -236.147206) (xy 343.030092 -236.181298) (xy 343.059657 -236.220642)
			(xy 343.082528 -236.264219) (xy 343.098112 -236.3109) (xy 343.106007 -236.359477) (xy 343.106502 -236.384084)
			(xy 343.424759 -236.384084) (xy 343.428854 -236.333356) (xy 343.441033 -236.283942) (xy 343.460981 -236.237122)
			(xy 343.488182 -236.194108) (xy 343.52193 -236.156014) (xy 343.561352 -236.123827) (xy 343.605426 -236.098381)
			(xy 343.653012 -236.080334) (xy 343.702876 -236.070154) (xy 343.753728 -236.068105) (xy 343.804249 -236.074239)
			(xy 343.853133 -236.088399) (xy 343.899112 -236.110216) (xy 343.940996 -236.139126) (xy 343.9777 -236.174381)
			(xy 344.008273 -236.215067) (xy 344.031924 -236.26013) (xy 344.04804 -236.308404) (xy 344.056204 -236.358638)
			(xy 344.056716 -236.384084) (xy 344.375244 -236.384084) (xy 344.379204 -236.33503) (xy 344.390981 -236.287246)
			(xy 344.410272 -236.24197) (xy 344.436575 -236.200374) (xy 344.46921 -236.163537) (xy 344.507331 -236.132412)
			(xy 344.549952 -236.107805) (xy 344.595968 -236.090353) (xy 344.644187 -236.080509) (xy 344.693362 -236.078528)
			(xy 344.742217 -236.08446) (xy 344.789488 -236.098152) (xy 344.83395 -236.11925) (xy 344.874453 -236.147206)
			(xy 344.909946 -236.181298) (xy 344.939511 -236.220642) (xy 344.962382 -236.264219) (xy 344.977966 -236.3109)
			(xy 344.985861 -236.359477) (xy 344.986356 -236.384084) (xy 345.315298 -236.384084) (xy 345.319258 -236.33503)
			(xy 345.331035 -236.287246) (xy 345.350326 -236.24197) (xy 345.376629 -236.200374) (xy 345.409264 -236.163537)
			(xy 345.447385 -236.132412) (xy 345.490006 -236.107805) (xy 345.536022 -236.090353) (xy 345.584241 -236.080509)
			(xy 345.633416 -236.078528) (xy 345.682271 -236.08446) (xy 345.729542 -236.098152) (xy 345.774004 -236.11925)
			(xy 345.814507 -236.147206) (xy 345.85 -236.181298) (xy 345.879565 -236.220642) (xy 345.902436 -236.264219)
			(xy 345.91802 -236.3109) (xy 345.925915 -236.359477) (xy 345.92641 -236.384084) (xy 346.255352 -236.384084)
			(xy 346.259312 -236.33503) (xy 346.271089 -236.287246) (xy 346.29038 -236.24197) (xy 346.316683 -236.200374)
			(xy 346.349318 -236.163537) (xy 346.387439 -236.132412) (xy 346.43006 -236.107805) (xy 346.476076 -236.090353)
			(xy 346.524295 -236.080509) (xy 346.57347 -236.078528) (xy 346.622325 -236.08446) (xy 346.669596 -236.098152)
			(xy 346.714058 -236.11925) (xy 346.754561 -236.147206) (xy 346.790054 -236.181298) (xy 346.819619 -236.220642)
			(xy 346.84249 -236.264219) (xy 346.858074 -236.3109) (xy 346.865969 -236.359477) (xy 346.866464 -236.384084)
			(xy 347.195406 -236.384084) (xy 347.199366 -236.33503) (xy 347.211143 -236.287246) (xy 347.230434 -236.24197)
			(xy 347.256737 -236.200374) (xy 347.289372 -236.163537) (xy 347.327493 -236.132412) (xy 347.370114 -236.107805)
			(xy 347.41613 -236.090353) (xy 347.464349 -236.080509) (xy 347.513524 -236.078528) (xy 347.562379 -236.08446)
			(xy 347.60965 -236.098152) (xy 347.654112 -236.11925) (xy 347.694615 -236.147206) (xy 347.730108 -236.181298)
			(xy 347.759673 -236.220642) (xy 347.782544 -236.264219) (xy 347.798128 -236.3109) (xy 347.806023 -236.359477)
			(xy 347.806518 -236.384084) (xy 348.135206 -236.384084) (xy 348.139166 -236.33503) (xy 348.150943 -236.287246)
			(xy 348.170234 -236.24197) (xy 348.196537 -236.200374) (xy 348.229172 -236.163537) (xy 348.267293 -236.132412)
			(xy 348.309914 -236.107805) (xy 348.35593 -236.090353) (xy 348.404149 -236.080509) (xy 348.453324 -236.078528)
			(xy 348.502179 -236.08446) (xy 348.54945 -236.098152) (xy 348.593912 -236.11925) (xy 348.634415 -236.147206)
			(xy 348.669908 -236.181298) (xy 348.699473 -236.220642) (xy 348.722344 -236.264219) (xy 348.737928 -236.3109)
			(xy 348.745823 -236.359477) (xy 348.746318 -236.384084) (xy 349.07526 -236.384084) (xy 349.07922 -236.33503)
			(xy 349.090997 -236.287246) (xy 349.110288 -236.24197) (xy 349.136591 -236.200374) (xy 349.169226 -236.163537)
			(xy 349.207347 -236.132412) (xy 349.249968 -236.107805) (xy 349.295984 -236.090353) (xy 349.344203 -236.080509)
			(xy 349.393378 -236.078528) (xy 349.442233 -236.08446) (xy 349.489504 -236.098152) (xy 349.533966 -236.11925)
			(xy 349.574469 -236.147206) (xy 349.609962 -236.181298) (xy 349.639527 -236.220642) (xy 349.662398 -236.264219)
			(xy 349.677982 -236.3109) (xy 349.685877 -236.359477) (xy 349.686372 -236.384084) (xy 350.015314 -236.384084)
			(xy 350.019274 -236.33503) (xy 350.031051 -236.287246) (xy 350.050342 -236.24197) (xy 350.076645 -236.200374)
			(xy 350.10928 -236.163537) (xy 350.147401 -236.132412) (xy 350.190022 -236.107805) (xy 350.236038 -236.090353)
			(xy 350.284257 -236.080509) (xy 350.333432 -236.078528) (xy 350.382287 -236.08446) (xy 350.429558 -236.098152)
			(xy 350.47402 -236.11925) (xy 350.514523 -236.147206) (xy 350.550016 -236.181298) (xy 350.579581 -236.220642)
			(xy 350.602452 -236.264219) (xy 350.618036 -236.3109) (xy 350.625931 -236.359477) (xy 350.626426 -236.384084)
			(xy 352.835222 -236.384084) (xy 352.839182 -236.33503) (xy 352.850959 -236.287246) (xy 352.87025 -236.24197)
			(xy 352.896553 -236.200374) (xy 352.929188 -236.163537) (xy 352.967309 -236.132412) (xy 353.00993 -236.107805)
			(xy 353.055946 -236.090353) (xy 353.104165 -236.080509) (xy 353.15334 -236.078528) (xy 353.202195 -236.08446)
			(xy 353.249466 -236.098152) (xy 353.293928 -236.11925) (xy 353.334431 -236.147206) (xy 353.369924 -236.181298)
			(xy 353.399489 -236.220642) (xy 353.42236 -236.264219) (xy 353.437944 -236.3109) (xy 353.445839 -236.359477)
			(xy 353.446334 -236.384084) (xy 355.655384 -236.384084) (xy 355.659344 -236.33503) (xy 355.671121 -236.287246)
			(xy 355.690412 -236.24197) (xy 355.716715 -236.200374) (xy 355.74935 -236.163537) (xy 355.787471 -236.132412)
			(xy 355.830092 -236.107805) (xy 355.876108 -236.090353) (xy 355.924327 -236.080509) (xy 355.973502 -236.078528)
			(xy 356.022357 -236.08446) (xy 356.069628 -236.098152) (xy 356.11409 -236.11925) (xy 356.154593 -236.147206)
			(xy 356.190086 -236.181298) (xy 356.219651 -236.220642) (xy 356.242522 -236.264219) (xy 356.258106 -236.3109)
			(xy 356.266001 -236.359477) (xy 356.266496 -236.384084) (xy 356.595438 -236.384084) (xy 356.599398 -236.33503)
			(xy 356.611175 -236.287246) (xy 356.630466 -236.24197) (xy 356.656769 -236.200374) (xy 356.689404 -236.163537)
			(xy 356.727525 -236.132412) (xy 356.770146 -236.107805) (xy 356.816162 -236.090353) (xy 356.864381 -236.080509)
			(xy 356.913556 -236.078528) (xy 356.962411 -236.08446) (xy 357.009682 -236.098152) (xy 357.054144 -236.11925)
			(xy 357.094647 -236.147206) (xy 357.13014 -236.181298) (xy 357.159705 -236.220642) (xy 357.182576 -236.264219)
			(xy 357.19816 -236.3109) (xy 357.206055 -236.359477) (xy 357.20655 -236.384084) (xy 357.535238 -236.384084)
			(xy 357.539198 -236.33503) (xy 357.550975 -236.287246) (xy 357.570266 -236.24197) (xy 357.596569 -236.200374)
			(xy 357.629204 -236.163537) (xy 357.667325 -236.132412) (xy 357.709946 -236.107805) (xy 357.755962 -236.090353)
			(xy 357.804181 -236.080509) (xy 357.853356 -236.078528) (xy 357.902211 -236.08446) (xy 357.949482 -236.098152)
			(xy 357.993944 -236.11925) (xy 358.034447 -236.147206) (xy 358.06994 -236.181298) (xy 358.099505 -236.220642)
			(xy 358.122376 -236.264219) (xy 358.13796 -236.3109) (xy 358.145855 -236.359477) (xy 358.14635 -236.384084)
			(xy 358.145855 -236.408691) (xy 358.13796 -236.457268) (xy 358.122376 -236.503949) (xy 358.099505 -236.547526)
			(xy 358.06994 -236.58687) (xy 358.034447 -236.620962) (xy 357.993944 -236.648918) (xy 357.949482 -236.670016)
			(xy 357.902211 -236.683708) (xy 357.853356 -236.68964) (xy 357.804181 -236.687659) (xy 357.755962 -236.677815)
			(xy 357.709946 -236.660363) (xy 357.667325 -236.635756) (xy 357.629204 -236.604631) (xy 357.596569 -236.567794)
			(xy 357.570266 -236.526198) (xy 357.550975 -236.480922) (xy 357.539198 -236.433138) (xy 357.535238 -236.384084)
			(xy 357.20655 -236.384084) (xy 357.206055 -236.408691) (xy 357.19816 -236.457268) (xy 357.182576 -236.503949)
			(xy 357.159705 -236.547526) (xy 357.13014 -236.58687) (xy 357.094647 -236.620962) (xy 357.054144 -236.648918)
			(xy 357.009682 -236.670016) (xy 356.962411 -236.683708) (xy 356.913556 -236.68964) (xy 356.864381 -236.687659)
			(xy 356.816162 -236.677815) (xy 356.770146 -236.660363) (xy 356.727525 -236.635756) (xy 356.689404 -236.604631)
			(xy 356.656769 -236.567794) (xy 356.630466 -236.526198) (xy 356.611175 -236.480922) (xy 356.599398 -236.433138)
			(xy 356.595438 -236.384084) (xy 356.266496 -236.384084) (xy 356.266001 -236.408691) (xy 356.258106 -236.457268)
			(xy 356.242522 -236.503949) (xy 356.219651 -236.547526) (xy 356.190086 -236.58687) (xy 356.154593 -236.620962)
			(xy 356.11409 -236.648918) (xy 356.069628 -236.670016) (xy 356.022357 -236.683708) (xy 355.973502 -236.68964)
			(xy 355.924327 -236.687659) (xy 355.876108 -236.677815) (xy 355.830092 -236.660363) (xy 355.787471 -236.635756)
			(xy 355.74935 -236.604631) (xy 355.716715 -236.567794) (xy 355.690412 -236.526198) (xy 355.671121 -236.480922)
			(xy 355.659344 -236.433138) (xy 355.655384 -236.384084) (xy 353.446334 -236.384084) (xy 353.445839 -236.408691)
			(xy 353.437944 -236.457268) (xy 353.42236 -236.503949) (xy 353.399489 -236.547526) (xy 353.369924 -236.58687)
			(xy 353.334431 -236.620962) (xy 353.293928 -236.648918) (xy 353.249466 -236.670016) (xy 353.202195 -236.683708)
			(xy 353.15334 -236.68964) (xy 353.104165 -236.687659) (xy 353.055946 -236.677815) (xy 353.00993 -236.660363)
			(xy 352.967309 -236.635756) (xy 352.929188 -236.604631) (xy 352.896553 -236.567794) (xy 352.87025 -236.526198)
			(xy 352.850959 -236.480922) (xy 352.839182 -236.433138) (xy 352.835222 -236.384084) (xy 350.626426 -236.384084)
			(xy 350.625931 -236.408691) (xy 350.618036 -236.457268) (xy 350.602452 -236.503949) (xy 350.579581 -236.547526)
			(xy 350.550016 -236.58687) (xy 350.514523 -236.620962) (xy 350.47402 -236.648918) (xy 350.429558 -236.670016)
			(xy 350.382287 -236.683708) (xy 350.333432 -236.68964) (xy 350.284257 -236.687659) (xy 350.236038 -236.677815)
			(xy 350.190022 -236.660363) (xy 350.147401 -236.635756) (xy 350.10928 -236.604631) (xy 350.076645 -236.567794)
			(xy 350.050342 -236.526198) (xy 350.031051 -236.480922) (xy 350.019274 -236.433138) (xy 350.015314 -236.384084)
			(xy 349.686372 -236.384084) (xy 349.685877 -236.408691) (xy 349.677982 -236.457268) (xy 349.662398 -236.503949)
			(xy 349.639527 -236.547526) (xy 349.609962 -236.58687) (xy 349.574469 -236.620962) (xy 349.533966 -236.648918)
			(xy 349.489504 -236.670016) (xy 349.442233 -236.683708) (xy 349.393378 -236.68964) (xy 349.344203 -236.687659)
			(xy 349.295984 -236.677815) (xy 349.249968 -236.660363) (xy 349.207347 -236.635756) (xy 349.169226 -236.604631)
			(xy 349.136591 -236.567794) (xy 349.110288 -236.526198) (xy 349.090997 -236.480922) (xy 349.07922 -236.433138)
			(xy 349.07526 -236.384084) (xy 348.746318 -236.384084) (xy 348.745823 -236.408691) (xy 348.737928 -236.457268)
			(xy 348.722344 -236.503949) (xy 348.699473 -236.547526) (xy 348.669908 -236.58687) (xy 348.634415 -236.620962)
			(xy 348.593912 -236.648918) (xy 348.54945 -236.670016) (xy 348.502179 -236.683708) (xy 348.453324 -236.68964)
			(xy 348.404149 -236.687659) (xy 348.35593 -236.677815) (xy 348.309914 -236.660363) (xy 348.267293 -236.635756)
			(xy 348.229172 -236.604631) (xy 348.196537 -236.567794) (xy 348.170234 -236.526198) (xy 348.150943 -236.480922)
			(xy 348.139166 -236.433138) (xy 348.135206 -236.384084) (xy 347.806518 -236.384084) (xy 347.806023 -236.408691)
			(xy 347.798128 -236.457268) (xy 347.782544 -236.503949) (xy 347.759673 -236.547526) (xy 347.730108 -236.58687)
			(xy 347.694615 -236.620962) (xy 347.654112 -236.648918) (xy 347.60965 -236.670016) (xy 347.562379 -236.683708)
			(xy 347.513524 -236.68964) (xy 347.464349 -236.687659) (xy 347.41613 -236.677815) (xy 347.370114 -236.660363)
			(xy 347.327493 -236.635756) (xy 347.289372 -236.604631) (xy 347.256737 -236.567794) (xy 347.230434 -236.526198)
			(xy 347.211143 -236.480922) (xy 347.199366 -236.433138) (xy 347.195406 -236.384084) (xy 346.866464 -236.384084)
			(xy 346.865969 -236.408691) (xy 346.858074 -236.457268) (xy 346.84249 -236.503949) (xy 346.819619 -236.547526)
			(xy 346.790054 -236.58687) (xy 346.754561 -236.620962) (xy 346.714058 -236.648918) (xy 346.669596 -236.670016)
			(xy 346.622325 -236.683708) (xy 346.57347 -236.68964) (xy 346.524295 -236.687659) (xy 346.476076 -236.677815)
			(xy 346.43006 -236.660363) (xy 346.387439 -236.635756) (xy 346.349318 -236.604631) (xy 346.316683 -236.567794)
			(xy 346.29038 -236.526198) (xy 346.271089 -236.480922) (xy 346.259312 -236.433138) (xy 346.255352 -236.384084)
			(xy 345.92641 -236.384084) (xy 345.925915 -236.408691) (xy 345.91802 -236.457268) (xy 345.902436 -236.503949)
			(xy 345.879565 -236.547526) (xy 345.85 -236.58687) (xy 345.814507 -236.620962) (xy 345.774004 -236.648918)
			(xy 345.729542 -236.670016) (xy 345.682271 -236.683708) (xy 345.633416 -236.68964) (xy 345.584241 -236.687659)
			(xy 345.536022 -236.677815) (xy 345.490006 -236.660363) (xy 345.447385 -236.635756) (xy 345.409264 -236.604631)
			(xy 345.376629 -236.567794) (xy 345.350326 -236.526198) (xy 345.331035 -236.480922) (xy 345.319258 -236.433138)
			(xy 345.315298 -236.384084) (xy 344.986356 -236.384084) (xy 344.985861 -236.408691) (xy 344.977966 -236.457268)
			(xy 344.962382 -236.503949) (xy 344.939511 -236.547526) (xy 344.909946 -236.58687) (xy 344.874453 -236.620962)
			(xy 344.83395 -236.648918) (xy 344.789488 -236.670016) (xy 344.742217 -236.683708) (xy 344.693362 -236.68964)
			(xy 344.644187 -236.687659) (xy 344.595968 -236.677815) (xy 344.549952 -236.660363) (xy 344.507331 -236.635756)
			(xy 344.46921 -236.604631) (xy 344.436575 -236.567794) (xy 344.410272 -236.526198) (xy 344.390981 -236.480922)
			(xy 344.379204 -236.433138) (xy 344.375244 -236.384084) (xy 344.056716 -236.384084) (xy 344.056204 -236.40953)
			(xy 344.04804 -236.459764) (xy 344.031924 -236.508038) (xy 344.008273 -236.553101) (xy 343.9777 -236.593787)
			(xy 343.940996 -236.629042) (xy 343.899112 -236.657952) (xy 343.853133 -236.679769) (xy 343.804249 -236.693929)
			(xy 343.753728 -236.700063) (xy 343.702876 -236.698014) (xy 343.653012 -236.687834) (xy 343.605426 -236.669787)
			(xy 343.561352 -236.644341) (xy 343.52193 -236.612154) (xy 343.488182 -236.57406) (xy 343.460981 -236.531046)
			(xy 343.441033 -236.484226) (xy 343.428854 -236.434812) (xy 343.424759 -236.384084) (xy 343.106502 -236.384084)
			(xy 343.106007 -236.408691) (xy 343.098112 -236.457268) (xy 343.082528 -236.503949) (xy 343.059657 -236.547526)
			(xy 343.030092 -236.58687) (xy 342.994599 -236.620962) (xy 342.954096 -236.648918) (xy 342.909634 -236.670016)
			(xy 342.862363 -236.683708) (xy 342.813508 -236.68964) (xy 342.764333 -236.687659) (xy 342.716114 -236.677815)
			(xy 342.670098 -236.660363) (xy 342.627477 -236.635756) (xy 342.589356 -236.604631) (xy 342.556721 -236.567794)
			(xy 342.530418 -236.526198) (xy 342.511127 -236.480922) (xy 342.49935 -236.433138) (xy 342.49539 -236.384084)
			(xy 342.176862 -236.384084) (xy 342.17635 -236.40953) (xy 342.168186 -236.459764) (xy 342.15207 -236.508038)
			(xy 342.128419 -236.553101) (xy 342.097846 -236.593787) (xy 342.061142 -236.629042) (xy 342.019258 -236.657952)
			(xy 341.973279 -236.679769) (xy 341.924395 -236.693929) (xy 341.873874 -236.700063) (xy 341.823022 -236.698014)
			(xy 341.773158 -236.687834) (xy 341.725572 -236.669787) (xy 341.681498 -236.644341) (xy 341.642076 -236.612154)
			(xy 341.608328 -236.57406) (xy 341.581127 -236.531046) (xy 341.561179 -236.484226) (xy 341.549 -236.434812)
			(xy 341.544905 -236.384084) (xy 341.233252 -236.384084) (xy 341.233252 -236.790992) (xy 341.233811 -236.801685)
			(xy 341.242468 -236.821244) (xy 341.250016 -236.828838) (xy 341.250524 -236.829092) (xy 341.316564 -236.88675)
			(xy 341.327232 -236.889798) (xy 341.3379 -236.8931) (xy 341.348822 -236.891576) (xy 341.359312 -236.890243)
			(xy 341.380412 -236.888844) (xy 341.390986 -236.888782) (xy 341.416245 -236.889274) (xy 341.466075 -236.897587)
			(xy 341.513857 -236.913988) (xy 341.558288 -236.938031) (xy 341.598155 -236.969059) (xy 341.632371 -237.006226)
			(xy 341.660003 -237.048518) (xy 341.680296 -237.094781) (xy 341.692698 -237.143754) (xy 341.696869 -237.19409)
			(xy 342.014805 -237.19409) (xy 342.0189 -237.143362) (xy 342.031079 -237.093948) (xy 342.051027 -237.047128)
			(xy 342.078228 -237.004114) (xy 342.111976 -236.96602) (xy 342.151398 -236.933833) (xy 342.195472 -236.908387)
			(xy 342.243058 -236.89034) (xy 342.292922 -236.88016) (xy 342.343774 -236.878111) (xy 342.394295 -236.884245)
			(xy 342.443179 -236.898405) (xy 342.489158 -236.920222) (xy 342.531042 -236.949132) (xy 342.567746 -236.984387)
			(xy 342.598319 -237.025073) (xy 342.62197 -237.070136) (xy 342.638086 -237.11841) (xy 342.64625 -237.168644)
			(xy 342.646762 -237.19409) (xy 342.954859 -237.19409) (xy 342.958954 -237.143362) (xy 342.971133 -237.093948)
			(xy 342.991081 -237.047128) (xy 343.018282 -237.004114) (xy 343.05203 -236.96602) (xy 343.091452 -236.933833)
			(xy 343.135526 -236.908387) (xy 343.183112 -236.89034) (xy 343.232976 -236.88016) (xy 343.283828 -236.878111)
			(xy 343.334349 -236.884245) (xy 343.383233 -236.898405) (xy 343.429212 -236.920222) (xy 343.471096 -236.949132)
			(xy 343.5078 -236.984387) (xy 343.538373 -237.025073) (xy 343.562024 -237.070136) (xy 343.57814 -237.11841)
			(xy 343.586304 -237.168644) (xy 343.586816 -237.19409) (xy 343.905344 -237.19409) (xy 343.909304 -237.145036)
			(xy 343.921081 -237.097252) (xy 343.940372 -237.051976) (xy 343.966675 -237.01038) (xy 343.99931 -236.973543)
			(xy 344.037431 -236.942418) (xy 344.080052 -236.917811) (xy 344.126068 -236.900359) (xy 344.174287 -236.890515)
			(xy 344.223462 -236.888534) (xy 344.272317 -236.894466) (xy 344.319588 -236.908158) (xy 344.36405 -236.929256)
			(xy 344.404553 -236.957212) (xy 344.440046 -236.991304) (xy 344.469611 -237.030648) (xy 344.492482 -237.074225)
			(xy 344.508066 -237.120906) (xy 344.515961 -237.169483) (xy 344.516456 -237.19409) (xy 344.845398 -237.19409)
			(xy 344.849358 -237.145036) (xy 344.861135 -237.097252) (xy 344.880426 -237.051976) (xy 344.906729 -237.01038)
			(xy 344.939364 -236.973543) (xy 344.977485 -236.942418) (xy 345.020106 -236.917811) (xy 345.066122 -236.900359)
			(xy 345.114341 -236.890515) (xy 345.163516 -236.888534) (xy 345.212371 -236.894466) (xy 345.259642 -236.908158)
			(xy 345.304104 -236.929256) (xy 345.344607 -236.957212) (xy 345.3801 -236.991304) (xy 345.409665 -237.030648)
			(xy 345.432536 -237.074225) (xy 345.44812 -237.120906) (xy 345.456015 -237.169483) (xy 345.45651 -237.19409)
			(xy 345.785198 -237.19409) (xy 345.789158 -237.145036) (xy 345.800935 -237.097252) (xy 345.820226 -237.051976)
			(xy 345.846529 -237.01038) (xy 345.879164 -236.973543) (xy 345.917285 -236.942418) (xy 345.959906 -236.917811)
			(xy 346.005922 -236.900359) (xy 346.054141 -236.890515) (xy 346.103316 -236.888534) (xy 346.152171 -236.894466)
			(xy 346.199442 -236.908158) (xy 346.243904 -236.929256) (xy 346.284407 -236.957212) (xy 346.3199 -236.991304)
			(xy 346.349465 -237.030648) (xy 346.372336 -237.074225) (xy 346.38792 -237.120906) (xy 346.395815 -237.169483)
			(xy 346.39631 -237.19409) (xy 346.725252 -237.19409) (xy 346.729212 -237.145036) (xy 346.740989 -237.097252)
			(xy 346.76028 -237.051976) (xy 346.786583 -237.01038) (xy 346.819218 -236.973543) (xy 346.857339 -236.942418)
			(xy 346.89996 -236.917811) (xy 346.945976 -236.900359) (xy 346.994195 -236.890515) (xy 347.04337 -236.888534)
			(xy 347.092225 -236.894466) (xy 347.139496 -236.908158) (xy 347.183958 -236.929256) (xy 347.224461 -236.957212)
			(xy 347.259954 -236.991304) (xy 347.289519 -237.030648) (xy 347.31239 -237.074225) (xy 347.327974 -237.120906)
			(xy 347.335869 -237.169483) (xy 347.336364 -237.19409) (xy 347.665306 -237.19409) (xy 347.669266 -237.145036)
			(xy 347.681043 -237.097252) (xy 347.700334 -237.051976) (xy 347.726637 -237.01038) (xy 347.759272 -236.973543)
			(xy 347.797393 -236.942418) (xy 347.840014 -236.917811) (xy 347.88603 -236.900359) (xy 347.934249 -236.890515)
			(xy 347.983424 -236.888534) (xy 348.032279 -236.894466) (xy 348.07955 -236.908158) (xy 348.124012 -236.929256)
			(xy 348.164515 -236.957212) (xy 348.200008 -236.991304) (xy 348.229573 -237.030648) (xy 348.252444 -237.074225)
			(xy 348.268028 -237.120906) (xy 348.275923 -237.169483) (xy 348.276418 -237.19409) (xy 348.60536 -237.19409)
			(xy 348.60932 -237.145036) (xy 348.621097 -237.097252) (xy 348.640388 -237.051976) (xy 348.666691 -237.01038)
			(xy 348.699326 -236.973543) (xy 348.737447 -236.942418) (xy 348.780068 -236.917811) (xy 348.826084 -236.900359)
			(xy 348.874303 -236.890515) (xy 348.923478 -236.888534) (xy 348.972333 -236.894466) (xy 349.019604 -236.908158)
			(xy 349.064066 -236.929256) (xy 349.104569 -236.957212) (xy 349.140062 -236.991304) (xy 349.169627 -237.030648)
			(xy 349.192498 -237.074225) (xy 349.208082 -237.120906) (xy 349.215977 -237.169483) (xy 349.216472 -237.19409)
			(xy 349.545414 -237.19409) (xy 349.549374 -237.145036) (xy 349.561151 -237.097252) (xy 349.580442 -237.051976)
			(xy 349.606745 -237.01038) (xy 349.63938 -236.973543) (xy 349.677501 -236.942418) (xy 349.720122 -236.917811)
			(xy 349.766138 -236.900359) (xy 349.814357 -236.890515) (xy 349.863532 -236.888534) (xy 349.912387 -236.894466)
			(xy 349.959658 -236.908158) (xy 350.00412 -236.929256) (xy 350.044623 -236.957212) (xy 350.080116 -236.991304)
			(xy 350.109681 -237.030648) (xy 350.132552 -237.074225) (xy 350.148136 -237.120906) (xy 350.156031 -237.169483)
			(xy 350.156526 -237.19409) (xy 350.485214 -237.19409) (xy 350.489174 -237.145036) (xy 350.500951 -237.097252)
			(xy 350.520242 -237.051976) (xy 350.546545 -237.01038) (xy 350.57918 -236.973543) (xy 350.617301 -236.942418)
			(xy 350.659922 -236.917811) (xy 350.705938 -236.900359) (xy 350.754157 -236.890515) (xy 350.803332 -236.888534)
			(xy 350.852187 -236.894466) (xy 350.899458 -236.908158) (xy 350.94392 -236.929256) (xy 350.984423 -236.957212)
			(xy 351.019916 -236.991304) (xy 351.049481 -237.030648) (xy 351.072352 -237.074225) (xy 351.087936 -237.120906)
			(xy 351.095831 -237.169483) (xy 351.096326 -237.19409) (xy 351.425268 -237.19409) (xy 351.429228 -237.145036)
			(xy 351.441005 -237.097252) (xy 351.460296 -237.051976) (xy 351.486599 -237.01038) (xy 351.519234 -236.973543)
			(xy 351.557355 -236.942418) (xy 351.599976 -236.917811) (xy 351.645992 -236.900359) (xy 351.694211 -236.890515)
			(xy 351.743386 -236.888534) (xy 351.792241 -236.894466) (xy 351.839512 -236.908158) (xy 351.883974 -236.929256)
			(xy 351.924477 -236.957212) (xy 351.95997 -236.991304) (xy 351.989535 -237.030648) (xy 352.012406 -237.074225)
			(xy 352.02799 -237.120906) (xy 352.035885 -237.169483) (xy 352.03638 -237.19409) (xy 352.365322 -237.19409)
			(xy 352.369282 -237.145036) (xy 352.381059 -237.097252) (xy 352.40035 -237.051976) (xy 352.426653 -237.01038)
			(xy 352.459288 -236.973543) (xy 352.497409 -236.942418) (xy 352.54003 -236.917811) (xy 352.586046 -236.900359)
			(xy 352.634265 -236.890515) (xy 352.68344 -236.888534) (xy 352.732295 -236.894466) (xy 352.779566 -236.908158)
			(xy 352.824028 -236.929256) (xy 352.864531 -236.957212) (xy 352.900024 -236.991304) (xy 352.929589 -237.030648)
			(xy 352.95246 -237.074225) (xy 352.968044 -237.120906) (xy 352.975939 -237.169483) (xy 352.976434 -237.19409)
			(xy 353.305376 -237.19409) (xy 353.309336 -237.145036) (xy 353.321113 -237.097252) (xy 353.340404 -237.051976)
			(xy 353.366707 -237.01038) (xy 353.399342 -236.973543) (xy 353.437463 -236.942418) (xy 353.480084 -236.917811)
			(xy 353.5261 -236.900359) (xy 353.574319 -236.890515) (xy 353.623494 -236.888534) (xy 353.672349 -236.894466)
			(xy 353.71962 -236.908158) (xy 353.764082 -236.929256) (xy 353.804585 -236.957212) (xy 353.840078 -236.991304)
			(xy 353.869643 -237.030648) (xy 353.892514 -237.074225) (xy 353.908098 -237.120906) (xy 353.915993 -237.169483)
			(xy 353.916488 -237.19409) (xy 354.24543 -237.19409) (xy 354.24939 -237.145036) (xy 354.261167 -237.097252)
			(xy 354.280458 -237.051976) (xy 354.306761 -237.01038) (xy 354.339396 -236.973543) (xy 354.377517 -236.942418)
			(xy 354.420138 -236.917811) (xy 354.466154 -236.900359) (xy 354.514373 -236.890515) (xy 354.563548 -236.888534)
			(xy 354.612403 -236.894466) (xy 354.659674 -236.908158) (xy 354.704136 -236.929256) (xy 354.744639 -236.957212)
			(xy 354.780132 -236.991304) (xy 354.809697 -237.030648) (xy 354.832568 -237.074225) (xy 354.848152 -237.120906)
			(xy 354.856047 -237.169483) (xy 354.856542 -237.19409) (xy 355.18523 -237.19409) (xy 355.18919 -237.145036)
			(xy 355.200967 -237.097252) (xy 355.220258 -237.051976) (xy 355.246561 -237.01038) (xy 355.279196 -236.973543)
			(xy 355.317317 -236.942418) (xy 355.359938 -236.917811) (xy 355.405954 -236.900359) (xy 355.454173 -236.890515)
			(xy 355.503348 -236.888534) (xy 355.552203 -236.894466) (xy 355.599474 -236.908158) (xy 355.643936 -236.929256)
			(xy 355.684439 -236.957212) (xy 355.719932 -236.991304) (xy 355.749497 -237.030648) (xy 355.772368 -237.074225)
			(xy 355.787952 -237.120906) (xy 355.795847 -237.169483) (xy 355.796342 -237.19409) (xy 358.005392 -237.19409)
			(xy 358.009352 -237.145036) (xy 358.021129 -237.097252) (xy 358.04042 -237.051976) (xy 358.066723 -237.01038)
			(xy 358.099358 -236.973543) (xy 358.137479 -236.942418) (xy 358.1801 -236.917811) (xy 358.226116 -236.900359)
			(xy 358.274335 -236.890515) (xy 358.32351 -236.888534) (xy 358.372365 -236.894466) (xy 358.419636 -236.908158)
			(xy 358.464098 -236.929256) (xy 358.504601 -236.957212) (xy 358.540094 -236.991304) (xy 358.569659 -237.030648)
			(xy 358.59253 -237.074225) (xy 358.608114 -237.120906) (xy 358.616009 -237.169483) (xy 358.616504 -237.19409)
			(xy 360.81895 -237.19409) (xy 360.82291 -237.145036) (xy 360.834687 -237.097252) (xy 360.853978 -237.051976)
			(xy 360.880281 -237.01038) (xy 360.912916 -236.973543) (xy 360.951037 -236.942418) (xy 360.993658 -236.917811)
			(xy 361.039674 -236.900359) (xy 361.087893 -236.890515) (xy 361.137068 -236.888534) (xy 361.185923 -236.894466)
			(xy 361.233194 -236.908158) (xy 361.277656 -236.929256) (xy 361.318159 -236.957212) (xy 361.353652 -236.991304)
			(xy 361.383217 -237.030648) (xy 361.406088 -237.074225) (xy 361.421672 -237.120906) (xy 361.429567 -237.169483)
			(xy 361.430062 -237.19409) (xy 363.639112 -237.19409) (xy 363.643072 -237.145036) (xy 363.654849 -237.097252)
			(xy 363.67414 -237.051976) (xy 363.700443 -237.01038) (xy 363.733078 -236.973543) (xy 363.771199 -236.942418)
			(xy 363.81382 -236.917811) (xy 363.859836 -236.900359) (xy 363.908055 -236.890515) (xy 363.95723 -236.888534)
			(xy 364.006085 -236.894466) (xy 364.053356 -236.908158) (xy 364.097818 -236.929256) (xy 364.138321 -236.957212)
			(xy 364.173814 -236.991304) (xy 364.203379 -237.030648) (xy 364.22625 -237.074225) (xy 364.241834 -237.120906)
			(xy 364.249729 -237.169483) (xy 364.250224 -237.19409) (xy 364.578912 -237.19409) (xy 364.582872 -237.145036)
			(xy 364.594649 -237.097252) (xy 364.61394 -237.051976) (xy 364.640243 -237.01038) (xy 364.672878 -236.973543)
			(xy 364.710999 -236.942418) (xy 364.75362 -236.917811) (xy 364.799636 -236.900359) (xy 364.847855 -236.890515)
			(xy 364.89703 -236.888534) (xy 364.945885 -236.894466) (xy 364.993156 -236.908158) (xy 365.037618 -236.929256)
			(xy 365.078121 -236.957212) (xy 365.113614 -236.991304) (xy 365.143179 -237.030648) (xy 365.16605 -237.074225)
			(xy 365.181634 -237.120906) (xy 365.189529 -237.169483) (xy 365.190024 -237.19409) (xy 365.518966 -237.19409)
			(xy 365.522926 -237.145036) (xy 365.534703 -237.097252) (xy 365.553994 -237.051976) (xy 365.580297 -237.01038)
			(xy 365.612932 -236.973543) (xy 365.651053 -236.942418) (xy 365.693674 -236.917811) (xy 365.73969 -236.900359)
			(xy 365.787909 -236.890515) (xy 365.837084 -236.888534) (xy 365.885939 -236.894466) (xy 365.93321 -236.908158)
			(xy 365.977672 -236.929256) (xy 366.018175 -236.957212) (xy 366.053668 -236.991304) (xy 366.083233 -237.030648)
			(xy 366.106104 -237.074225) (xy 366.121688 -237.120906) (xy 366.129583 -237.169483) (xy 366.130078 -237.19409)
			(xy 366.45902 -237.19409) (xy 366.46298 -237.145036) (xy 366.474757 -237.097252) (xy 366.494048 -237.051976)
			(xy 366.520351 -237.01038) (xy 366.552986 -236.973543) (xy 366.591107 -236.942418) (xy 366.633728 -236.917811)
			(xy 366.679744 -236.900359) (xy 366.727963 -236.890515) (xy 366.777138 -236.888534) (xy 366.825993 -236.894466)
			(xy 366.873264 -236.908158) (xy 366.917726 -236.929256) (xy 366.958229 -236.957212) (xy 366.993722 -236.991304)
			(xy 367.023287 -237.030648) (xy 367.046158 -237.074225) (xy 367.061742 -237.120906) (xy 367.069637 -237.169483)
			(xy 367.070132 -237.19409) (xy 367.399074 -237.19409) (xy 367.403034 -237.145036) (xy 367.414811 -237.097252)
			(xy 367.434102 -237.051976) (xy 367.460405 -237.01038) (xy 367.49304 -236.973543) (xy 367.531161 -236.942418)
			(xy 367.573782 -236.917811) (xy 367.619798 -236.900359) (xy 367.668017 -236.890515) (xy 367.717192 -236.888534)
			(xy 367.766047 -236.894466) (xy 367.813318 -236.908158) (xy 367.85778 -236.929256) (xy 367.898283 -236.957212)
			(xy 367.933776 -236.991304) (xy 367.963341 -237.030648) (xy 367.986212 -237.074225) (xy 368.001796 -237.120906)
			(xy 368.009691 -237.169483) (xy 368.010186 -237.19409) (xy 368.338874 -237.19409) (xy 368.342834 -237.145036)
			(xy 368.354611 -237.097252) (xy 368.373902 -237.051976) (xy 368.400205 -237.01038) (xy 368.43284 -236.973543)
			(xy 368.470961 -236.942418) (xy 368.513582 -236.917811) (xy 368.559598 -236.900359) (xy 368.607817 -236.890515)
			(xy 368.656992 -236.888534) (xy 368.705847 -236.894466) (xy 368.753118 -236.908158) (xy 368.79758 -236.929256)
			(xy 368.838083 -236.957212) (xy 368.873576 -236.991304) (xy 368.903141 -237.030648) (xy 368.926012 -237.074225)
			(xy 368.941596 -237.120906) (xy 368.949491 -237.169483) (xy 368.949986 -237.19409) (xy 368.949491 -237.218697)
			(xy 368.941596 -237.267274) (xy 368.926012 -237.313955) (xy 368.903141 -237.357532) (xy 368.873576 -237.396876)
			(xy 368.838083 -237.430968) (xy 368.79758 -237.458924) (xy 368.753118 -237.480022) (xy 368.705847 -237.493714)
			(xy 368.656992 -237.499646) (xy 368.607817 -237.497665) (xy 368.559598 -237.487821) (xy 368.513582 -237.470369)
			(xy 368.470961 -237.445762) (xy 368.43284 -237.414637) (xy 368.400205 -237.3778) (xy 368.373902 -237.336204)
			(xy 368.354611 -237.290928) (xy 368.342834 -237.243144) (xy 368.338874 -237.19409) (xy 368.010186 -237.19409)
			(xy 368.009691 -237.218697) (xy 368.001796 -237.267274) (xy 367.986212 -237.313955) (xy 367.963341 -237.357532)
			(xy 367.933776 -237.396876) (xy 367.898283 -237.430968) (xy 367.85778 -237.458924) (xy 367.813318 -237.480022)
			(xy 367.766047 -237.493714) (xy 367.717192 -237.499646) (xy 367.668017 -237.497665) (xy 367.619798 -237.487821)
			(xy 367.573782 -237.470369) (xy 367.531161 -237.445762) (xy 367.49304 -237.414637) (xy 367.460405 -237.3778)
			(xy 367.434102 -237.336204) (xy 367.414811 -237.290928) (xy 367.403034 -237.243144) (xy 367.399074 -237.19409)
			(xy 367.070132 -237.19409) (xy 367.069637 -237.218697) (xy 367.061742 -237.267274) (xy 367.046158 -237.313955)
			(xy 367.023287 -237.357532) (xy 366.993722 -237.396876) (xy 366.958229 -237.430968) (xy 366.917726 -237.458924)
			(xy 366.873264 -237.480022) (xy 366.825993 -237.493714) (xy 366.777138 -237.499646) (xy 366.727963 -237.497665)
			(xy 366.679744 -237.487821) (xy 366.633728 -237.470369) (xy 366.591107 -237.445762) (xy 366.552986 -237.414637)
			(xy 366.520351 -237.3778) (xy 366.494048 -237.336204) (xy 366.474757 -237.290928) (xy 366.46298 -237.243144)
			(xy 366.45902 -237.19409) (xy 366.130078 -237.19409) (xy 366.129583 -237.218697) (xy 366.121688 -237.267274)
			(xy 366.106104 -237.313955) (xy 366.083233 -237.357532) (xy 366.053668 -237.396876) (xy 366.018175 -237.430968)
			(xy 365.977672 -237.458924) (xy 365.93321 -237.480022) (xy 365.885939 -237.493714) (xy 365.837084 -237.499646)
			(xy 365.787909 -237.497665) (xy 365.73969 -237.487821) (xy 365.693674 -237.470369) (xy 365.651053 -237.445762)
			(xy 365.612932 -237.414637) (xy 365.580297 -237.3778) (xy 365.553994 -237.336204) (xy 365.534703 -237.290928)
			(xy 365.522926 -237.243144) (xy 365.518966 -237.19409) (xy 365.190024 -237.19409) (xy 365.189529 -237.218697)
			(xy 365.181634 -237.267274) (xy 365.16605 -237.313955) (xy 365.143179 -237.357532) (xy 365.113614 -237.396876)
			(xy 365.078121 -237.430968) (xy 365.037618 -237.458924) (xy 364.993156 -237.480022) (xy 364.945885 -237.493714)
			(xy 364.89703 -237.499646) (xy 364.847855 -237.497665) (xy 364.799636 -237.487821) (xy 364.75362 -237.470369)
			(xy 364.710999 -237.445762) (xy 364.672878 -237.414637) (xy 364.640243 -237.3778) (xy 364.61394 -237.336204)
			(xy 364.594649 -237.290928) (xy 364.582872 -237.243144) (xy 364.578912 -237.19409) (xy 364.250224 -237.19409)
			(xy 364.249729 -237.218697) (xy 364.241834 -237.267274) (xy 364.22625 -237.313955) (xy 364.203379 -237.357532)
			(xy 364.173814 -237.396876) (xy 364.138321 -237.430968) (xy 364.097818 -237.458924) (xy 364.053356 -237.480022)
			(xy 364.006085 -237.493714) (xy 363.95723 -237.499646) (xy 363.908055 -237.497665) (xy 363.859836 -237.487821)
			(xy 363.81382 -237.470369) (xy 363.771199 -237.445762) (xy 363.733078 -237.414637) (xy 363.700443 -237.3778)
			(xy 363.67414 -237.336204) (xy 363.654849 -237.290928) (xy 363.643072 -237.243144) (xy 363.639112 -237.19409)
			(xy 361.430062 -237.19409) (xy 361.429567 -237.218697) (xy 361.421672 -237.267274) (xy 361.406088 -237.313955)
			(xy 361.383217 -237.357532) (xy 361.353652 -237.396876) (xy 361.318159 -237.430968) (xy 361.277656 -237.458924)
			(xy 361.233194 -237.480022) (xy 361.185923 -237.493714) (xy 361.137068 -237.499646) (xy 361.087893 -237.497665)
			(xy 361.039674 -237.487821) (xy 360.993658 -237.470369) (xy 360.951037 -237.445762) (xy 360.912916 -237.414637)
			(xy 360.880281 -237.3778) (xy 360.853978 -237.336204) (xy 360.834687 -237.290928) (xy 360.82291 -237.243144)
			(xy 360.81895 -237.19409) (xy 358.616504 -237.19409) (xy 358.616009 -237.218697) (xy 358.608114 -237.267274)
			(xy 358.59253 -237.313955) (xy 358.569659 -237.357532) (xy 358.540094 -237.396876) (xy 358.504601 -237.430968)
			(xy 358.464098 -237.458924) (xy 358.419636 -237.480022) (xy 358.372365 -237.493714) (xy 358.32351 -237.499646)
			(xy 358.274335 -237.497665) (xy 358.226116 -237.487821) (xy 358.1801 -237.470369) (xy 358.137479 -237.445762)
			(xy 358.099358 -237.414637) (xy 358.066723 -237.3778) (xy 358.04042 -237.336204) (xy 358.021129 -237.290928)
			(xy 358.009352 -237.243144) (xy 358.005392 -237.19409) (xy 355.796342 -237.19409) (xy 355.795847 -237.218697)
			(xy 355.787952 -237.267274) (xy 355.772368 -237.313955) (xy 355.749497 -237.357532) (xy 355.719932 -237.396876)
			(xy 355.684439 -237.430968) (xy 355.643936 -237.458924) (xy 355.599474 -237.480022) (xy 355.552203 -237.493714)
			(xy 355.503348 -237.499646) (xy 355.454173 -237.497665) (xy 355.405954 -237.487821) (xy 355.359938 -237.470369)
			(xy 355.317317 -237.445762) (xy 355.279196 -237.414637) (xy 355.246561 -237.3778) (xy 355.220258 -237.336204)
			(xy 355.200967 -237.290928) (xy 355.18919 -237.243144) (xy 355.18523 -237.19409) (xy 354.856542 -237.19409)
			(xy 354.856047 -237.218697) (xy 354.848152 -237.267274) (xy 354.832568 -237.313955) (xy 354.809697 -237.357532)
			(xy 354.780132 -237.396876) (xy 354.744639 -237.430968) (xy 354.704136 -237.458924) (xy 354.659674 -237.480022)
			(xy 354.612403 -237.493714) (xy 354.563548 -237.499646) (xy 354.514373 -237.497665) (xy 354.466154 -237.487821)
			(xy 354.420138 -237.470369) (xy 354.377517 -237.445762) (xy 354.339396 -237.414637) (xy 354.306761 -237.3778)
			(xy 354.280458 -237.336204) (xy 354.261167 -237.290928) (xy 354.24939 -237.243144) (xy 354.24543 -237.19409)
			(xy 353.916488 -237.19409) (xy 353.915993 -237.218697) (xy 353.908098 -237.267274) (xy 353.892514 -237.313955)
			(xy 353.869643 -237.357532) (xy 353.840078 -237.396876) (xy 353.804585 -237.430968) (xy 353.764082 -237.458924)
			(xy 353.71962 -237.480022) (xy 353.672349 -237.493714) (xy 353.623494 -237.499646) (xy 353.574319 -237.497665)
			(xy 353.5261 -237.487821) (xy 353.480084 -237.470369) (xy 353.437463 -237.445762) (xy 353.399342 -237.414637)
			(xy 353.366707 -237.3778) (xy 353.340404 -237.336204) (xy 353.321113 -237.290928) (xy 353.309336 -237.243144)
			(xy 353.305376 -237.19409) (xy 352.976434 -237.19409) (xy 352.975939 -237.218697) (xy 352.968044 -237.267274)
			(xy 352.95246 -237.313955) (xy 352.929589 -237.357532) (xy 352.900024 -237.396876) (xy 352.864531 -237.430968)
			(xy 352.824028 -237.458924) (xy 352.779566 -237.480022) (xy 352.732295 -237.493714) (xy 352.68344 -237.499646)
			(xy 352.634265 -237.497665) (xy 352.586046 -237.487821) (xy 352.54003 -237.470369) (xy 352.497409 -237.445762)
			(xy 352.459288 -237.414637) (xy 352.426653 -237.3778) (xy 352.40035 -237.336204) (xy 352.381059 -237.290928)
			(xy 352.369282 -237.243144) (xy 352.365322 -237.19409) (xy 352.03638 -237.19409) (xy 352.035885 -237.218697)
			(xy 352.02799 -237.267274) (xy 352.012406 -237.313955) (xy 351.989535 -237.357532) (xy 351.95997 -237.396876)
			(xy 351.924477 -237.430968) (xy 351.883974 -237.458924) (xy 351.839512 -237.480022) (xy 351.792241 -237.493714)
			(xy 351.743386 -237.499646) (xy 351.694211 -237.497665) (xy 351.645992 -237.487821) (xy 351.599976 -237.470369)
			(xy 351.557355 -237.445762) (xy 351.519234 -237.414637) (xy 351.486599 -237.3778) (xy 351.460296 -237.336204)
			(xy 351.441005 -237.290928) (xy 351.429228 -237.243144) (xy 351.425268 -237.19409) (xy 351.096326 -237.19409)
			(xy 351.095831 -237.218697) (xy 351.087936 -237.267274) (xy 351.072352 -237.313955) (xy 351.049481 -237.357532)
			(xy 351.019916 -237.396876) (xy 350.984423 -237.430968) (xy 350.94392 -237.458924) (xy 350.899458 -237.480022)
			(xy 350.852187 -237.493714) (xy 350.803332 -237.499646) (xy 350.754157 -237.497665) (xy 350.705938 -237.487821)
			(xy 350.659922 -237.470369) (xy 350.617301 -237.445762) (xy 350.57918 -237.414637) (xy 350.546545 -237.3778)
			(xy 350.520242 -237.336204) (xy 350.500951 -237.290928) (xy 350.489174 -237.243144) (xy 350.485214 -237.19409)
			(xy 350.156526 -237.19409) (xy 350.156031 -237.218697) (xy 350.148136 -237.267274) (xy 350.132552 -237.313955)
			(xy 350.109681 -237.357532) (xy 350.080116 -237.396876) (xy 350.044623 -237.430968) (xy 350.00412 -237.458924)
			(xy 349.959658 -237.480022) (xy 349.912387 -237.493714) (xy 349.863532 -237.499646) (xy 349.814357 -237.497665)
			(xy 349.766138 -237.487821) (xy 349.720122 -237.470369) (xy 349.677501 -237.445762) (xy 349.63938 -237.414637)
			(xy 349.606745 -237.3778) (xy 349.580442 -237.336204) (xy 349.561151 -237.290928) (xy 349.549374 -237.243144)
			(xy 349.545414 -237.19409) (xy 349.216472 -237.19409) (xy 349.215977 -237.218697) (xy 349.208082 -237.267274)
			(xy 349.192498 -237.313955) (xy 349.169627 -237.357532) (xy 349.140062 -237.396876) (xy 349.104569 -237.430968)
			(xy 349.064066 -237.458924) (xy 349.019604 -237.480022) (xy 348.972333 -237.493714) (xy 348.923478 -237.499646)
			(xy 348.874303 -237.497665) (xy 348.826084 -237.487821) (xy 348.780068 -237.470369) (xy 348.737447 -237.445762)
			(xy 348.699326 -237.414637) (xy 348.666691 -237.3778) (xy 348.640388 -237.336204) (xy 348.621097 -237.290928)
			(xy 348.60932 -237.243144) (xy 348.60536 -237.19409) (xy 348.276418 -237.19409) (xy 348.275923 -237.218697)
			(xy 348.268028 -237.267274) (xy 348.252444 -237.313955) (xy 348.229573 -237.357532) (xy 348.200008 -237.396876)
			(xy 348.164515 -237.430968) (xy 348.124012 -237.458924) (xy 348.07955 -237.480022) (xy 348.032279 -237.493714)
			(xy 347.983424 -237.499646) (xy 347.934249 -237.497665) (xy 347.88603 -237.487821) (xy 347.840014 -237.470369)
			(xy 347.797393 -237.445762) (xy 347.759272 -237.414637) (xy 347.726637 -237.3778) (xy 347.700334 -237.336204)
			(xy 347.681043 -237.290928) (xy 347.669266 -237.243144) (xy 347.665306 -237.19409) (xy 347.336364 -237.19409)
			(xy 347.335869 -237.218697) (xy 347.327974 -237.267274) (xy 347.31239 -237.313955) (xy 347.289519 -237.357532)
			(xy 347.259954 -237.396876) (xy 347.224461 -237.430968) (xy 347.183958 -237.458924) (xy 347.139496 -237.480022)
			(xy 347.092225 -237.493714) (xy 347.04337 -237.499646) (xy 346.994195 -237.497665) (xy 346.945976 -237.487821)
			(xy 346.89996 -237.470369) (xy 346.857339 -237.445762) (xy 346.819218 -237.414637) (xy 346.786583 -237.3778)
			(xy 346.76028 -237.336204) (xy 346.740989 -237.290928) (xy 346.729212 -237.243144) (xy 346.725252 -237.19409)
			(xy 346.39631 -237.19409) (xy 346.395815 -237.218697) (xy 346.38792 -237.267274) (xy 346.372336 -237.313955)
			(xy 346.349465 -237.357532) (xy 346.3199 -237.396876) (xy 346.284407 -237.430968) (xy 346.243904 -237.458924)
			(xy 346.199442 -237.480022) (xy 346.152171 -237.493714) (xy 346.103316 -237.499646) (xy 346.054141 -237.497665)
			(xy 346.005922 -237.487821) (xy 345.959906 -237.470369) (xy 345.917285 -237.445762) (xy 345.879164 -237.414637)
			(xy 345.846529 -237.3778) (xy 345.820226 -237.336204) (xy 345.800935 -237.290928) (xy 345.789158 -237.243144)
			(xy 345.785198 -237.19409) (xy 345.45651 -237.19409) (xy 345.456015 -237.218697) (xy 345.44812 -237.267274)
			(xy 345.432536 -237.313955) (xy 345.409665 -237.357532) (xy 345.3801 -237.396876) (xy 345.344607 -237.430968)
			(xy 345.304104 -237.458924) (xy 345.259642 -237.480022) (xy 345.212371 -237.493714) (xy 345.163516 -237.499646)
			(xy 345.114341 -237.497665) (xy 345.066122 -237.487821) (xy 345.020106 -237.470369) (xy 344.977485 -237.445762)
			(xy 344.939364 -237.414637) (xy 344.906729 -237.3778) (xy 344.880426 -237.336204) (xy 344.861135 -237.290928)
			(xy 344.849358 -237.243144) (xy 344.845398 -237.19409) (xy 344.516456 -237.19409) (xy 344.515961 -237.218697)
			(xy 344.508066 -237.267274) (xy 344.492482 -237.313955) (xy 344.469611 -237.357532) (xy 344.440046 -237.396876)
			(xy 344.404553 -237.430968) (xy 344.36405 -237.458924) (xy 344.319588 -237.480022) (xy 344.272317 -237.493714)
			(xy 344.223462 -237.499646) (xy 344.174287 -237.497665) (xy 344.126068 -237.487821) (xy 344.080052 -237.470369)
			(xy 344.037431 -237.445762) (xy 343.99931 -237.414637) (xy 343.966675 -237.3778) (xy 343.940372 -237.336204)
			(xy 343.921081 -237.290928) (xy 343.909304 -237.243144) (xy 343.905344 -237.19409) (xy 343.586816 -237.19409)
			(xy 343.586304 -237.219536) (xy 343.57814 -237.26977) (xy 343.562024 -237.318044) (xy 343.538373 -237.363107)
			(xy 343.5078 -237.403793) (xy 343.471096 -237.439048) (xy 343.429212 -237.467958) (xy 343.383233 -237.489775)
			(xy 343.334349 -237.503935) (xy 343.283828 -237.510069) (xy 343.232976 -237.50802) (xy 343.183112 -237.49784)
			(xy 343.135526 -237.479793) (xy 343.091452 -237.454347) (xy 343.05203 -237.42216) (xy 343.018282 -237.384066)
			(xy 342.991081 -237.341052) (xy 342.971133 -237.294232) (xy 342.958954 -237.244818) (xy 342.954859 -237.19409)
			(xy 342.646762 -237.19409) (xy 342.64625 -237.219536) (xy 342.638086 -237.26977) (xy 342.62197 -237.318044)
			(xy 342.598319 -237.363107) (xy 342.567746 -237.403793) (xy 342.531042 -237.439048) (xy 342.489158 -237.467958)
			(xy 342.443179 -237.489775) (xy 342.394295 -237.503935) (xy 342.343774 -237.510069) (xy 342.292922 -237.50802)
			(xy 342.243058 -237.49784) (xy 342.195472 -237.479793) (xy 342.151398 -237.454347) (xy 342.111976 -237.42216)
			(xy 342.078228 -237.384066) (xy 342.051027 -237.341052) (xy 342.031079 -237.294232) (xy 342.0189 -237.244818)
			(xy 342.014805 -237.19409) (xy 341.696869 -237.19409) (xy 341.69687 -237.1941) (xy 341.692698 -237.244446)
			(xy 341.680296 -237.293419) (xy 341.660003 -237.339682) (xy 341.632371 -237.381974) (xy 341.598155 -237.419141)
			(xy 341.558288 -237.450169) (xy 341.513857 -237.474212) (xy 341.466075 -237.490613) (xy 341.416245 -237.498926)
			(xy 341.390986 -237.499398) (xy 341.380412 -237.499344) (xy 341.359311 -237.497947) (xy 341.348822 -237.496604)
			(xy 341.3379 -237.49508) (xy 341.317072 -237.50143) (xy 341.250778 -237.558834) (xy 341.242396 -237.5662)
			(xy 341.233252 -237.586012) (xy 341.233252 -238.004096) (xy 341.544905 -238.004096) (xy 341.549 -237.953368)
			(xy 341.561179 -237.903954) (xy 341.581127 -237.857134) (xy 341.608328 -237.81412) (xy 341.642076 -237.776026)
			(xy 341.681498 -237.743839) (xy 341.725572 -237.718393) (xy 341.773158 -237.700346) (xy 341.823022 -237.690166)
			(xy 341.873874 -237.688117) (xy 341.924395 -237.694251) (xy 341.973279 -237.708411) (xy 342.019258 -237.730228)
			(xy 342.061142 -237.759138) (xy 342.097846 -237.794393) (xy 342.128419 -237.835079) (xy 342.15207 -237.880142)
			(xy 342.168186 -237.928416) (xy 342.17635 -237.97865) (xy 342.176862 -238.004096) (xy 342.49539 -238.004096)
			(xy 342.49935 -237.955042) (xy 342.511127 -237.907258) (xy 342.530418 -237.861982) (xy 342.556721 -237.820386)
			(xy 342.589356 -237.783549) (xy 342.627477 -237.752424) (xy 342.670098 -237.727817) (xy 342.716114 -237.710365)
			(xy 342.764333 -237.700521) (xy 342.813508 -237.69854) (xy 342.862363 -237.704472) (xy 342.909634 -237.718164)
			(xy 342.954096 -237.739262) (xy 342.994599 -237.767218) (xy 343.030092 -237.80131) (xy 343.059657 -237.840654)
			(xy 343.082528 -237.884231) (xy 343.098112 -237.930912) (xy 343.106007 -237.979489) (xy 343.106502 -238.004096)
			(xy 343.424759 -238.004096) (xy 343.428854 -237.953368) (xy 343.441033 -237.903954) (xy 343.460981 -237.857134)
			(xy 343.488182 -237.81412) (xy 343.52193 -237.776026) (xy 343.561352 -237.743839) (xy 343.605426 -237.718393)
			(xy 343.653012 -237.700346) (xy 343.702876 -237.690166) (xy 343.753728 -237.688117) (xy 343.804249 -237.694251)
			(xy 343.853133 -237.708411) (xy 343.899112 -237.730228) (xy 343.940996 -237.759138) (xy 343.9777 -237.794393)
			(xy 344.008273 -237.835079) (xy 344.031924 -237.880142) (xy 344.04804 -237.928416) (xy 344.056204 -237.97865)
			(xy 344.056716 -238.004096) (xy 344.375244 -238.004096) (xy 344.379204 -237.955042) (xy 344.390981 -237.907258)
			(xy 344.410272 -237.861982) (xy 344.436575 -237.820386) (xy 344.46921 -237.783549) (xy 344.507331 -237.752424)
			(xy 344.549952 -237.727817) (xy 344.595968 -237.710365) (xy 344.644187 -237.700521) (xy 344.693362 -237.69854)
			(xy 344.742217 -237.704472) (xy 344.789488 -237.718164) (xy 344.83395 -237.739262) (xy 344.874453 -237.767218)
			(xy 344.909946 -237.80131) (xy 344.939511 -237.840654) (xy 344.962382 -237.884231) (xy 344.977966 -237.930912)
			(xy 344.985861 -237.979489) (xy 344.986356 -238.004096) (xy 345.315298 -238.004096) (xy 345.319258 -237.955042)
			(xy 345.331035 -237.907258) (xy 345.350326 -237.861982) (xy 345.376629 -237.820386) (xy 345.409264 -237.783549)
			(xy 345.447385 -237.752424) (xy 345.490006 -237.727817) (xy 345.536022 -237.710365) (xy 345.584241 -237.700521)
			(xy 345.633416 -237.69854) (xy 345.682271 -237.704472) (xy 345.729542 -237.718164) (xy 345.774004 -237.739262)
			(xy 345.814507 -237.767218) (xy 345.85 -237.80131) (xy 345.879565 -237.840654) (xy 345.902436 -237.884231)
			(xy 345.91802 -237.930912) (xy 345.925915 -237.979489) (xy 345.92641 -238.004096) (xy 346.255352 -238.004096)
			(xy 346.259312 -237.955042) (xy 346.271089 -237.907258) (xy 346.29038 -237.861982) (xy 346.316683 -237.820386)
			(xy 346.349318 -237.783549) (xy 346.387439 -237.752424) (xy 346.43006 -237.727817) (xy 346.476076 -237.710365)
			(xy 346.524295 -237.700521) (xy 346.57347 -237.69854) (xy 346.622325 -237.704472) (xy 346.669596 -237.718164)
			(xy 346.714058 -237.739262) (xy 346.754561 -237.767218) (xy 346.790054 -237.80131) (xy 346.819619 -237.840654)
			(xy 346.84249 -237.884231) (xy 346.858074 -237.930912) (xy 346.865969 -237.979489) (xy 346.866464 -238.004096)
			(xy 347.195406 -238.004096) (xy 347.199366 -237.955042) (xy 347.211143 -237.907258) (xy 347.230434 -237.861982)
			(xy 347.256737 -237.820386) (xy 347.289372 -237.783549) (xy 347.327493 -237.752424) (xy 347.370114 -237.727817)
			(xy 347.41613 -237.710365) (xy 347.464349 -237.700521) (xy 347.513524 -237.69854) (xy 347.562379 -237.704472)
			(xy 347.60965 -237.718164) (xy 347.654112 -237.739262) (xy 347.694615 -237.767218) (xy 347.730108 -237.80131)
			(xy 347.759673 -237.840654) (xy 347.782544 -237.884231) (xy 347.798128 -237.930912) (xy 347.806023 -237.979489)
			(xy 347.806518 -238.004096) (xy 348.135206 -238.004096) (xy 348.139166 -237.955042) (xy 348.150943 -237.907258)
			(xy 348.170234 -237.861982) (xy 348.196537 -237.820386) (xy 348.229172 -237.783549) (xy 348.267293 -237.752424)
			(xy 348.309914 -237.727817) (xy 348.35593 -237.710365) (xy 348.404149 -237.700521) (xy 348.453324 -237.69854)
			(xy 348.502179 -237.704472) (xy 348.54945 -237.718164) (xy 348.593912 -237.739262) (xy 348.634415 -237.767218)
			(xy 348.669908 -237.80131) (xy 348.699473 -237.840654) (xy 348.722344 -237.884231) (xy 348.737928 -237.930912)
			(xy 348.745823 -237.979489) (xy 348.746318 -238.004096) (xy 349.07526 -238.004096) (xy 349.07922 -237.955042)
			(xy 349.090997 -237.907258) (xy 349.110288 -237.861982) (xy 349.136591 -237.820386) (xy 349.169226 -237.783549)
			(xy 349.207347 -237.752424) (xy 349.249968 -237.727817) (xy 349.295984 -237.710365) (xy 349.344203 -237.700521)
			(xy 349.393378 -237.69854) (xy 349.442233 -237.704472) (xy 349.489504 -237.718164) (xy 349.533966 -237.739262)
			(xy 349.574469 -237.767218) (xy 349.609962 -237.80131) (xy 349.639527 -237.840654) (xy 349.662398 -237.884231)
			(xy 349.677982 -237.930912) (xy 349.685877 -237.979489) (xy 349.686372 -238.004096) (xy 350.015314 -238.004096)
			(xy 350.019274 -237.955042) (xy 350.031051 -237.907258) (xy 350.050342 -237.861982) (xy 350.076645 -237.820386)
			(xy 350.10928 -237.783549) (xy 350.147401 -237.752424) (xy 350.190022 -237.727817) (xy 350.236038 -237.710365)
			(xy 350.284257 -237.700521) (xy 350.333432 -237.69854) (xy 350.382287 -237.704472) (xy 350.429558 -237.718164)
			(xy 350.47402 -237.739262) (xy 350.514523 -237.767218) (xy 350.550016 -237.80131) (xy 350.579581 -237.840654)
			(xy 350.602452 -237.884231) (xy 350.618036 -237.930912) (xy 350.625931 -237.979489) (xy 350.626426 -238.004096)
			(xy 350.955368 -238.004096) (xy 350.959328 -237.955042) (xy 350.971105 -237.907258) (xy 350.990396 -237.861982)
			(xy 351.016699 -237.820386) (xy 351.049334 -237.783549) (xy 351.087455 -237.752424) (xy 351.130076 -237.727817)
			(xy 351.176092 -237.710365) (xy 351.224311 -237.700521) (xy 351.273486 -237.69854) (xy 351.322341 -237.704472)
			(xy 351.369612 -237.718164) (xy 351.414074 -237.739262) (xy 351.454577 -237.767218) (xy 351.49007 -237.80131)
			(xy 351.519635 -237.840654) (xy 351.542506 -237.884231) (xy 351.55809 -237.930912) (xy 351.565985 -237.979489)
			(xy 351.56648 -238.004096) (xy 351.895422 -238.004096) (xy 351.899382 -237.955042) (xy 351.911159 -237.907258)
			(xy 351.93045 -237.861982) (xy 351.956753 -237.820386) (xy 351.989388 -237.783549) (xy 352.027509 -237.752424)
			(xy 352.07013 -237.727817) (xy 352.116146 -237.710365) (xy 352.164365 -237.700521) (xy 352.21354 -237.69854)
			(xy 352.262395 -237.704472) (xy 352.309666 -237.718164) (xy 352.354128 -237.739262) (xy 352.394631 -237.767218)
			(xy 352.430124 -237.80131) (xy 352.459689 -237.840654) (xy 352.48256 -237.884231) (xy 352.498144 -237.930912)
			(xy 352.506039 -237.979489) (xy 352.506534 -238.004096) (xy 352.835222 -238.004096) (xy 352.839182 -237.955042)
			(xy 352.850959 -237.907258) (xy 352.87025 -237.861982) (xy 352.896553 -237.820386) (xy 352.929188 -237.783549)
			(xy 352.967309 -237.752424) (xy 353.00993 -237.727817) (xy 353.055946 -237.710365) (xy 353.104165 -237.700521)
			(xy 353.15334 -237.69854) (xy 353.202195 -237.704472) (xy 353.249466 -237.718164) (xy 353.293928 -237.739262)
			(xy 353.334431 -237.767218) (xy 353.369924 -237.80131) (xy 353.399489 -237.840654) (xy 353.42236 -237.884231)
			(xy 353.437944 -237.930912) (xy 353.445839 -237.979489) (xy 353.446334 -238.004096) (xy 353.775276 -238.004096)
			(xy 353.779236 -237.955042) (xy 353.791013 -237.907258) (xy 353.810304 -237.861982) (xy 353.836607 -237.820386)
			(xy 353.869242 -237.783549) (xy 353.907363 -237.752424) (xy 353.949984 -237.727817) (xy 353.996 -237.710365)
			(xy 354.044219 -237.700521) (xy 354.093394 -237.69854) (xy 354.142249 -237.704472) (xy 354.18952 -237.718164)
			(xy 354.233982 -237.739262) (xy 354.274485 -237.767218) (xy 354.309978 -237.80131) (xy 354.339543 -237.840654)
			(xy 354.362414 -237.884231) (xy 354.377998 -237.930912) (xy 354.385893 -237.979489) (xy 354.386388 -238.004096)
			(xy 354.71533 -238.004096) (xy 354.71929 -237.955042) (xy 354.731067 -237.907258) (xy 354.750358 -237.861982)
			(xy 354.776661 -237.820386) (xy 354.809296 -237.783549) (xy 354.847417 -237.752424) (xy 354.890038 -237.727817)
			(xy 354.936054 -237.710365) (xy 354.984273 -237.700521) (xy 355.033448 -237.69854) (xy 355.082303 -237.704472)
			(xy 355.129574 -237.718164) (xy 355.174036 -237.739262) (xy 355.214539 -237.767218) (xy 355.250032 -237.80131)
			(xy 355.279597 -237.840654) (xy 355.302468 -237.884231) (xy 355.318052 -237.930912) (xy 355.325947 -237.979489)
			(xy 355.326442 -238.004096) (xy 355.655384 -238.004096) (xy 355.659344 -237.955042) (xy 355.671121 -237.907258)
			(xy 355.690412 -237.861982) (xy 355.716715 -237.820386) (xy 355.74935 -237.783549) (xy 355.787471 -237.752424)
			(xy 355.830092 -237.727817) (xy 355.876108 -237.710365) (xy 355.924327 -237.700521) (xy 355.973502 -237.69854)
			(xy 356.022357 -237.704472) (xy 356.069628 -237.718164) (xy 356.11409 -237.739262) (xy 356.154593 -237.767218)
			(xy 356.190086 -237.80131) (xy 356.219651 -237.840654) (xy 356.242522 -237.884231) (xy 356.258106 -237.930912)
			(xy 356.266001 -237.979489) (xy 356.266496 -238.004096) (xy 356.595438 -238.004096) (xy 356.599398 -237.955042)
			(xy 356.611175 -237.907258) (xy 356.630466 -237.861982) (xy 356.656769 -237.820386) (xy 356.689404 -237.783549)
			(xy 356.727525 -237.752424) (xy 356.770146 -237.727817) (xy 356.816162 -237.710365) (xy 356.864381 -237.700521)
			(xy 356.913556 -237.69854) (xy 356.962411 -237.704472) (xy 357.009682 -237.718164) (xy 357.054144 -237.739262)
			(xy 357.094647 -237.767218) (xy 357.13014 -237.80131) (xy 357.159705 -237.840654) (xy 357.182576 -237.884231)
			(xy 357.19816 -237.930912) (xy 357.206055 -237.979489) (xy 357.20655 -238.004096) (xy 357.535238 -238.004096)
			(xy 357.539198 -237.955042) (xy 357.550975 -237.907258) (xy 357.570266 -237.861982) (xy 357.596569 -237.820386)
			(xy 357.629204 -237.783549) (xy 357.667325 -237.752424) (xy 357.709946 -237.727817) (xy 357.755962 -237.710365)
			(xy 357.804181 -237.700521) (xy 357.853356 -237.69854) (xy 357.902211 -237.704472) (xy 357.949482 -237.718164)
			(xy 357.993944 -237.739262) (xy 358.034447 -237.767218) (xy 358.06994 -237.80131) (xy 358.099505 -237.840654)
			(xy 358.122376 -237.884231) (xy 358.13796 -237.930912) (xy 358.145855 -237.979489) (xy 358.14635 -238.004096)
			(xy 361.289104 -238.004096) (xy 361.293064 -237.955042) (xy 361.304841 -237.907258) (xy 361.324132 -237.861982)
			(xy 361.350435 -237.820386) (xy 361.38307 -237.783549) (xy 361.421191 -237.752424) (xy 361.463812 -237.727817)
			(xy 361.509828 -237.710365) (xy 361.558047 -237.700521) (xy 361.607222 -237.69854) (xy 361.656077 -237.704472)
			(xy 361.703348 -237.718164) (xy 361.74781 -237.739262) (xy 361.788313 -237.767218) (xy 361.823806 -237.80131)
			(xy 361.853371 -237.840654) (xy 361.876242 -237.884231) (xy 361.891826 -237.930912) (xy 361.899721 -237.979489)
			(xy 361.900216 -238.004096) (xy 362.228904 -238.004096) (xy 362.232864 -237.955042) (xy 362.244641 -237.907258)
			(xy 362.263932 -237.861982) (xy 362.290235 -237.820386) (xy 362.32287 -237.783549) (xy 362.360991 -237.752424)
			(xy 362.403612 -237.727817) (xy 362.449628 -237.710365) (xy 362.497847 -237.700521) (xy 362.547022 -237.69854)
			(xy 362.595877 -237.704472) (xy 362.643148 -237.718164) (xy 362.68761 -237.739262) (xy 362.728113 -237.767218)
			(xy 362.763606 -237.80131) (xy 362.793171 -237.840654) (xy 362.816042 -237.884231) (xy 362.831626 -237.930912)
			(xy 362.839521 -237.979489) (xy 362.840016 -238.004096) (xy 363.168958 -238.004096) (xy 363.172918 -237.955042)
			(xy 363.184695 -237.907258) (xy 363.203986 -237.861982) (xy 363.230289 -237.820386) (xy 363.262924 -237.783549)
			(xy 363.301045 -237.752424) (xy 363.343666 -237.727817) (xy 363.389682 -237.710365) (xy 363.437901 -237.700521)
			(xy 363.487076 -237.69854) (xy 363.535931 -237.704472) (xy 363.583202 -237.718164) (xy 363.627664 -237.739262)
			(xy 363.668167 -237.767218) (xy 363.70366 -237.80131) (xy 363.733225 -237.840654) (xy 363.756096 -237.884231)
			(xy 363.77168 -237.930912) (xy 363.779575 -237.979489) (xy 363.78007 -238.004096) (xy 364.109012 -238.004096)
			(xy 364.112972 -237.955042) (xy 364.124749 -237.907258) (xy 364.14404 -237.861982) (xy 364.170343 -237.820386)
			(xy 364.202978 -237.783549) (xy 364.241099 -237.752424) (xy 364.28372 -237.727817) (xy 364.329736 -237.710365)
			(xy 364.377955 -237.700521) (xy 364.42713 -237.69854) (xy 364.475985 -237.704472) (xy 364.523256 -237.718164)
			(xy 364.567718 -237.739262) (xy 364.608221 -237.767218) (xy 364.643714 -237.80131) (xy 364.673279 -237.840654)
			(xy 364.69615 -237.884231) (xy 364.711734 -237.930912) (xy 364.719629 -237.979489) (xy 364.720124 -238.004096)
			(xy 365.049066 -238.004096) (xy 365.053026 -237.955042) (xy 365.064803 -237.907258) (xy 365.084094 -237.861982)
			(xy 365.110397 -237.820386) (xy 365.143032 -237.783549) (xy 365.181153 -237.752424) (xy 365.223774 -237.727817)
			(xy 365.26979 -237.710365) (xy 365.318009 -237.700521) (xy 365.367184 -237.69854) (xy 365.416039 -237.704472)
			(xy 365.46331 -237.718164) (xy 365.507772 -237.739262) (xy 365.548275 -237.767218) (xy 365.583768 -237.80131)
			(xy 365.613333 -237.840654) (xy 365.636204 -237.884231) (xy 365.651788 -237.930912) (xy 365.659683 -237.979489)
			(xy 365.660178 -238.004096) (xy 365.98912 -238.004096) (xy 365.99308 -237.955042) (xy 366.004857 -237.907258)
			(xy 366.024148 -237.861982) (xy 366.050451 -237.820386) (xy 366.083086 -237.783549) (xy 366.121207 -237.752424)
			(xy 366.163828 -237.727817) (xy 366.209844 -237.710365) (xy 366.258063 -237.700521) (xy 366.307238 -237.69854)
			(xy 366.356093 -237.704472) (xy 366.403364 -237.718164) (xy 366.447826 -237.739262) (xy 366.488329 -237.767218)
			(xy 366.523822 -237.80131) (xy 366.553387 -237.840654) (xy 366.576258 -237.884231) (xy 366.591842 -237.930912)
			(xy 366.599737 -237.979489) (xy 366.600232 -238.004096) (xy 366.92892 -238.004096) (xy 366.93288 -237.955042)
			(xy 366.944657 -237.907258) (xy 366.963948 -237.861982) (xy 366.990251 -237.820386) (xy 367.022886 -237.783549)
			(xy 367.061007 -237.752424) (xy 367.103628 -237.727817) (xy 367.149644 -237.710365) (xy 367.197863 -237.700521)
			(xy 367.247038 -237.69854) (xy 367.295893 -237.704472) (xy 367.343164 -237.718164) (xy 367.387626 -237.739262)
			(xy 367.428129 -237.767218) (xy 367.463622 -237.80131) (xy 367.493187 -237.840654) (xy 367.516058 -237.884231)
			(xy 367.531642 -237.930912) (xy 367.539537 -237.979489) (xy 367.540032 -238.004096) (xy 367.868974 -238.004096)
			(xy 367.872934 -237.955042) (xy 367.884711 -237.907258) (xy 367.904002 -237.861982) (xy 367.930305 -237.820386)
			(xy 367.96294 -237.783549) (xy 368.001061 -237.752424) (xy 368.043682 -237.727817) (xy 368.089698 -237.710365)
			(xy 368.137917 -237.700521) (xy 368.187092 -237.69854) (xy 368.235947 -237.704472) (xy 368.283218 -237.718164)
			(xy 368.32768 -237.739262) (xy 368.368183 -237.767218) (xy 368.403676 -237.80131) (xy 368.433241 -237.840654)
			(xy 368.456112 -237.884231) (xy 368.471696 -237.930912) (xy 368.479591 -237.979489) (xy 368.480086 -238.004096)
			(xy 368.809028 -238.004096) (xy 368.812988 -237.955042) (xy 368.824765 -237.907258) (xy 368.844056 -237.861982)
			(xy 368.870359 -237.820386) (xy 368.902994 -237.783549) (xy 368.941115 -237.752424) (xy 368.983736 -237.727817)
			(xy 369.029752 -237.710365) (xy 369.077971 -237.700521) (xy 369.127146 -237.69854) (xy 369.176001 -237.704472)
			(xy 369.223272 -237.718164) (xy 369.267734 -237.739262) (xy 369.308237 -237.767218) (xy 369.34373 -237.80131)
			(xy 369.373295 -237.840654) (xy 369.396166 -237.884231) (xy 369.41175 -237.930912) (xy 369.419645 -237.979489)
			(xy 369.42014 -238.004096) (xy 369.749082 -238.004096) (xy 369.753042 -237.955042) (xy 369.764819 -237.907258)
			(xy 369.78411 -237.861982) (xy 369.810413 -237.820386) (xy 369.843048 -237.783549) (xy 369.881169 -237.752424)
			(xy 369.92379 -237.727817) (xy 369.969806 -237.710365) (xy 370.018025 -237.700521) (xy 370.0672 -237.69854)
			(xy 370.116055 -237.704472) (xy 370.163326 -237.718164) (xy 370.207788 -237.739262) (xy 370.248291 -237.767218)
			(xy 370.283784 -237.80131) (xy 370.313349 -237.840654) (xy 370.33622 -237.884231) (xy 370.351804 -237.930912)
			(xy 370.359699 -237.979489) (xy 370.360194 -238.004096) (xy 370.688882 -238.004096) (xy 370.692842 -237.955042)
			(xy 370.704619 -237.907258) (xy 370.72391 -237.861982) (xy 370.750213 -237.820386) (xy 370.782848 -237.783549)
			(xy 370.820969 -237.752424) (xy 370.86359 -237.727817) (xy 370.909606 -237.710365) (xy 370.957825 -237.700521)
			(xy 371.007 -237.69854) (xy 371.055855 -237.704472) (xy 371.103126 -237.718164) (xy 371.147588 -237.739262)
			(xy 371.188091 -237.767218) (xy 371.223584 -237.80131) (xy 371.253149 -237.840654) (xy 371.27602 -237.884231)
			(xy 371.291604 -237.930912) (xy 371.299499 -237.979489) (xy 371.299994 -238.004096) (xy 371.628936 -238.004096)
			(xy 371.632896 -237.955042) (xy 371.644673 -237.907258) (xy 371.663964 -237.861982) (xy 371.690267 -237.820386)
			(xy 371.722902 -237.783549) (xy 371.761023 -237.752424) (xy 371.803644 -237.727817) (xy 371.84966 -237.710365)
			(xy 371.897879 -237.700521) (xy 371.947054 -237.69854) (xy 371.995909 -237.704472) (xy 372.04318 -237.718164)
			(xy 372.087642 -237.739262) (xy 372.128145 -237.767218) (xy 372.163638 -237.80131) (xy 372.193203 -237.840654)
			(xy 372.216074 -237.884231) (xy 372.231658 -237.930912) (xy 372.239553 -237.979489) (xy 372.240048 -238.004096)
			(xy 372.56899 -238.004096) (xy 372.57295 -237.955042) (xy 372.584727 -237.907258) (xy 372.604018 -237.861982)
			(xy 372.630321 -237.820386) (xy 372.662956 -237.783549) (xy 372.701077 -237.752424) (xy 372.743698 -237.727817)
			(xy 372.789714 -237.710365) (xy 372.837933 -237.700521) (xy 372.887108 -237.69854) (xy 372.935963 -237.704472)
			(xy 372.983234 -237.718164) (xy 373.027696 -237.739262) (xy 373.068199 -237.767218) (xy 373.103692 -237.80131)
			(xy 373.133257 -237.840654) (xy 373.156128 -237.884231) (xy 373.171712 -237.930912) (xy 373.179607 -237.979489)
			(xy 373.180102 -238.004096) (xy 373.509044 -238.004096) (xy 373.513004 -237.955042) (xy 373.524781 -237.907258)
			(xy 373.544072 -237.861982) (xy 373.570375 -237.820386) (xy 373.60301 -237.783549) (xy 373.641131 -237.752424)
			(xy 373.683752 -237.727817) (xy 373.729768 -237.710365) (xy 373.777987 -237.700521) (xy 373.827162 -237.69854)
			(xy 373.876017 -237.704472) (xy 373.923288 -237.718164) (xy 373.96775 -237.739262) (xy 374.008253 -237.767218)
			(xy 374.043746 -237.80131) (xy 374.073311 -237.840654) (xy 374.096182 -237.884231) (xy 374.111766 -237.930912)
			(xy 374.119661 -237.979489) (xy 374.120156 -238.004096) (xy 374.449098 -238.004096) (xy 374.453058 -237.955042)
			(xy 374.464835 -237.907258) (xy 374.484126 -237.861982) (xy 374.510429 -237.820386) (xy 374.543064 -237.783549)
			(xy 374.581185 -237.752424) (xy 374.623806 -237.727817) (xy 374.669822 -237.710365) (xy 374.718041 -237.700521)
			(xy 374.767216 -237.69854) (xy 374.816071 -237.704472) (xy 374.863342 -237.718164) (xy 374.907804 -237.739262)
			(xy 374.948307 -237.767218) (xy 374.9838 -237.80131) (xy 375.013365 -237.840654) (xy 375.036236 -237.884231)
			(xy 375.05182 -237.930912) (xy 375.059715 -237.979489) (xy 375.06021 -238.004096) (xy 375.378467 -238.004096)
			(xy 375.382562 -237.953368) (xy 375.394741 -237.903954) (xy 375.414689 -237.857134) (xy 375.44189 -237.81412)
			(xy 375.475638 -237.776026) (xy 375.51506 -237.743839) (xy 375.559134 -237.718393) (xy 375.60672 -237.700346)
			(xy 375.656584 -237.690166) (xy 375.707436 -237.688117) (xy 375.757957 -237.694251) (xy 375.806841 -237.708411)
			(xy 375.85282 -237.730228) (xy 375.894704 -237.759138) (xy 375.931408 -237.794393) (xy 375.961981 -237.835079)
			(xy 375.985632 -237.880142) (xy 376.001748 -237.928416) (xy 376.009912 -237.97865) (xy 376.010424 -238.004096)
			(xy 376.328952 -238.004096) (xy 376.332912 -237.955042) (xy 376.344689 -237.907258) (xy 376.36398 -237.861982)
			(xy 376.390283 -237.820386) (xy 376.422918 -237.783549) (xy 376.461039 -237.752424) (xy 376.50366 -237.727817)
			(xy 376.549676 -237.710365) (xy 376.597895 -237.700521) (xy 376.64707 -237.69854) (xy 376.695925 -237.704472)
			(xy 376.743196 -237.718164) (xy 376.787658 -237.739262) (xy 376.828161 -237.767218) (xy 376.863654 -237.80131)
			(xy 376.893219 -237.840654) (xy 376.91609 -237.884231) (xy 376.931674 -237.930912) (xy 376.939569 -237.979489)
			(xy 376.940064 -238.004096) (xy 376.939569 -238.028703) (xy 376.931674 -238.07728) (xy 376.91609 -238.123961)
			(xy 376.893219 -238.167538) (xy 376.863654 -238.206882) (xy 376.828161 -238.240974) (xy 376.787658 -238.26893)
			(xy 376.743196 -238.290028) (xy 376.695925 -238.30372) (xy 376.64707 -238.309652) (xy 376.597895 -238.307671)
			(xy 376.549676 -238.297827) (xy 376.50366 -238.280375) (xy 376.461039 -238.255768) (xy 376.422918 -238.224643)
			(xy 376.390283 -238.187806) (xy 376.36398 -238.14621) (xy 376.344689 -238.100934) (xy 376.332912 -238.05315)
			(xy 376.328952 -238.004096) (xy 376.010424 -238.004096) (xy 376.009912 -238.029542) (xy 376.001748 -238.079776)
			(xy 375.985632 -238.12805) (xy 375.961981 -238.173113) (xy 375.931408 -238.213799) (xy 375.894704 -238.249054)
			(xy 375.85282 -238.277964) (xy 375.806841 -238.299781) (xy 375.757957 -238.313941) (xy 375.707436 -238.320075)
			(xy 375.656584 -238.318026) (xy 375.60672 -238.307846) (xy 375.559134 -238.289799) (xy 375.51506 -238.264353)
			(xy 375.475638 -238.232166) (xy 375.44189 -238.194072) (xy 375.414689 -238.151058) (xy 375.394741 -238.104238)
			(xy 375.382562 -238.054824) (xy 375.378467 -238.004096) (xy 375.06021 -238.004096) (xy 375.059715 -238.028703)
			(xy 375.05182 -238.07728) (xy 375.036236 -238.123961) (xy 375.013365 -238.167538) (xy 374.9838 -238.206882)
			(xy 374.948307 -238.240974) (xy 374.907804 -238.26893) (xy 374.863342 -238.290028) (xy 374.816071 -238.30372)
			(xy 374.767216 -238.309652) (xy 374.718041 -238.307671) (xy 374.669822 -238.297827) (xy 374.623806 -238.280375)
			(xy 374.581185 -238.255768) (xy 374.543064 -238.224643) (xy 374.510429 -238.187806) (xy 374.484126 -238.14621)
			(xy 374.464835 -238.100934) (xy 374.453058 -238.05315) (xy 374.449098 -238.004096) (xy 374.120156 -238.004096)
			(xy 374.119661 -238.028703) (xy 374.111766 -238.07728) (xy 374.096182 -238.123961) (xy 374.073311 -238.167538)
			(xy 374.043746 -238.206882) (xy 374.008253 -238.240974) (xy 373.96775 -238.26893) (xy 373.923288 -238.290028)
			(xy 373.876017 -238.30372) (xy 373.827162 -238.309652) (xy 373.777987 -238.307671) (xy 373.729768 -238.297827)
			(xy 373.683752 -238.280375) (xy 373.641131 -238.255768) (xy 373.60301 -238.224643) (xy 373.570375 -238.187806)
			(xy 373.544072 -238.14621) (xy 373.524781 -238.100934) (xy 373.513004 -238.05315) (xy 373.509044 -238.004096)
			(xy 373.180102 -238.004096) (xy 373.179607 -238.028703) (xy 373.171712 -238.07728) (xy 373.156128 -238.123961)
			(xy 373.133257 -238.167538) (xy 373.103692 -238.206882) (xy 373.068199 -238.240974) (xy 373.027696 -238.26893)
			(xy 372.983234 -238.290028) (xy 372.935963 -238.30372) (xy 372.887108 -238.309652) (xy 372.837933 -238.307671)
			(xy 372.789714 -238.297827) (xy 372.743698 -238.280375) (xy 372.701077 -238.255768) (xy 372.662956 -238.224643)
			(xy 372.630321 -238.187806) (xy 372.604018 -238.14621) (xy 372.584727 -238.100934) (xy 372.57295 -238.05315)
			(xy 372.56899 -238.004096) (xy 372.240048 -238.004096) (xy 372.239553 -238.028703) (xy 372.231658 -238.07728)
			(xy 372.216074 -238.123961) (xy 372.193203 -238.167538) (xy 372.163638 -238.206882) (xy 372.128145 -238.240974)
			(xy 372.087642 -238.26893) (xy 372.04318 -238.290028) (xy 371.995909 -238.30372) (xy 371.947054 -238.309652)
			(xy 371.897879 -238.307671) (xy 371.84966 -238.297827) (xy 371.803644 -238.280375) (xy 371.761023 -238.255768)
			(xy 371.722902 -238.224643) (xy 371.690267 -238.187806) (xy 371.663964 -238.14621) (xy 371.644673 -238.100934)
			(xy 371.632896 -238.05315) (xy 371.628936 -238.004096) (xy 371.299994 -238.004096) (xy 371.299499 -238.028703)
			(xy 371.291604 -238.07728) (xy 371.27602 -238.123961) (xy 371.253149 -238.167538) (xy 371.223584 -238.206882)
			(xy 371.188091 -238.240974) (xy 371.147588 -238.26893) (xy 371.103126 -238.290028) (xy 371.055855 -238.30372)
			(xy 371.007 -238.309652) (xy 370.957825 -238.307671) (xy 370.909606 -238.297827) (xy 370.86359 -238.280375)
			(xy 370.820969 -238.255768) (xy 370.782848 -238.224643) (xy 370.750213 -238.187806) (xy 370.72391 -238.14621)
			(xy 370.704619 -238.100934) (xy 370.692842 -238.05315) (xy 370.688882 -238.004096) (xy 370.360194 -238.004096)
			(xy 370.359699 -238.028703) (xy 370.351804 -238.07728) (xy 370.33622 -238.123961) (xy 370.313349 -238.167538)
			(xy 370.283784 -238.206882) (xy 370.248291 -238.240974) (xy 370.207788 -238.26893) (xy 370.163326 -238.290028)
			(xy 370.116055 -238.30372) (xy 370.0672 -238.309652) (xy 370.018025 -238.307671) (xy 369.969806 -238.297827)
			(xy 369.92379 -238.280375) (xy 369.881169 -238.255768) (xy 369.843048 -238.224643) (xy 369.810413 -238.187806)
			(xy 369.78411 -238.14621) (xy 369.764819 -238.100934) (xy 369.753042 -238.05315) (xy 369.749082 -238.004096)
			(xy 369.42014 -238.004096) (xy 369.419645 -238.028703) (xy 369.41175 -238.07728) (xy 369.396166 -238.123961)
			(xy 369.373295 -238.167538) (xy 369.34373 -238.206882) (xy 369.308237 -238.240974) (xy 369.267734 -238.26893)
			(xy 369.223272 -238.290028) (xy 369.176001 -238.30372) (xy 369.127146 -238.309652) (xy 369.077971 -238.307671)
			(xy 369.029752 -238.297827) (xy 368.983736 -238.280375) (xy 368.941115 -238.255768) (xy 368.902994 -238.224643)
			(xy 368.870359 -238.187806) (xy 368.844056 -238.14621) (xy 368.824765 -238.100934) (xy 368.812988 -238.05315)
			(xy 368.809028 -238.004096) (xy 368.480086 -238.004096) (xy 368.479591 -238.028703) (xy 368.471696 -238.07728)
			(xy 368.456112 -238.123961) (xy 368.433241 -238.167538) (xy 368.403676 -238.206882) (xy 368.368183 -238.240974)
			(xy 368.32768 -238.26893) (xy 368.283218 -238.290028) (xy 368.235947 -238.30372) (xy 368.187092 -238.309652)
			(xy 368.137917 -238.307671) (xy 368.089698 -238.297827) (xy 368.043682 -238.280375) (xy 368.001061 -238.255768)
			(xy 367.96294 -238.224643) (xy 367.930305 -238.187806) (xy 367.904002 -238.14621) (xy 367.884711 -238.100934)
			(xy 367.872934 -238.05315) (xy 367.868974 -238.004096) (xy 367.540032 -238.004096) (xy 367.539537 -238.028703)
			(xy 367.531642 -238.07728) (xy 367.516058 -238.123961) (xy 367.493187 -238.167538) (xy 367.463622 -238.206882)
			(xy 367.428129 -238.240974) (xy 367.387626 -238.26893) (xy 367.343164 -238.290028) (xy 367.295893 -238.30372)
			(xy 367.247038 -238.309652) (xy 367.197863 -238.307671) (xy 367.149644 -238.297827) (xy 367.103628 -238.280375)
			(xy 367.061007 -238.255768) (xy 367.022886 -238.224643) (xy 366.990251 -238.187806) (xy 366.963948 -238.14621)
			(xy 366.944657 -238.100934) (xy 366.93288 -238.05315) (xy 366.92892 -238.004096) (xy 366.600232 -238.004096)
			(xy 366.599737 -238.028703) (xy 366.591842 -238.07728) (xy 366.576258 -238.123961) (xy 366.553387 -238.167538)
			(xy 366.523822 -238.206882) (xy 366.488329 -238.240974) (xy 366.447826 -238.26893) (xy 366.403364 -238.290028)
			(xy 366.356093 -238.30372) (xy 366.307238 -238.309652) (xy 366.258063 -238.307671) (xy 366.209844 -238.297827)
			(xy 366.163828 -238.280375) (xy 366.121207 -238.255768) (xy 366.083086 -238.224643) (xy 366.050451 -238.187806)
			(xy 366.024148 -238.14621) (xy 366.004857 -238.100934) (xy 365.99308 -238.05315) (xy 365.98912 -238.004096)
			(xy 365.660178 -238.004096) (xy 365.659683 -238.028703) (xy 365.651788 -238.07728) (xy 365.636204 -238.123961)
			(xy 365.613333 -238.167538) (xy 365.583768 -238.206882) (xy 365.548275 -238.240974) (xy 365.507772 -238.26893)
			(xy 365.46331 -238.290028) (xy 365.416039 -238.30372) (xy 365.367184 -238.309652) (xy 365.318009 -238.307671)
			(xy 365.26979 -238.297827) (xy 365.223774 -238.280375) (xy 365.181153 -238.255768) (xy 365.143032 -238.224643)
			(xy 365.110397 -238.187806) (xy 365.084094 -238.14621) (xy 365.064803 -238.100934) (xy 365.053026 -238.05315)
			(xy 365.049066 -238.004096) (xy 364.720124 -238.004096) (xy 364.719629 -238.028703) (xy 364.711734 -238.07728)
			(xy 364.69615 -238.123961) (xy 364.673279 -238.167538) (xy 364.643714 -238.206882) (xy 364.608221 -238.240974)
			(xy 364.567718 -238.26893) (xy 364.523256 -238.290028) (xy 364.475985 -238.30372) (xy 364.42713 -238.309652)
			(xy 364.377955 -238.307671) (xy 364.329736 -238.297827) (xy 364.28372 -238.280375) (xy 364.241099 -238.255768)
			(xy 364.202978 -238.224643) (xy 364.170343 -238.187806) (xy 364.14404 -238.14621) (xy 364.124749 -238.100934)
			(xy 364.112972 -238.05315) (xy 364.109012 -238.004096) (xy 363.78007 -238.004096) (xy 363.779575 -238.028703)
			(xy 363.77168 -238.07728) (xy 363.756096 -238.123961) (xy 363.733225 -238.167538) (xy 363.70366 -238.206882)
			(xy 363.668167 -238.240974) (xy 363.627664 -238.26893) (xy 363.583202 -238.290028) (xy 363.535931 -238.30372)
			(xy 363.487076 -238.309652) (xy 363.437901 -238.307671) (xy 363.389682 -238.297827) (xy 363.343666 -238.280375)
			(xy 363.301045 -238.255768) (xy 363.262924 -238.224643) (xy 363.230289 -238.187806) (xy 363.203986 -238.14621)
			(xy 363.184695 -238.100934) (xy 363.172918 -238.05315) (xy 363.168958 -238.004096) (xy 362.840016 -238.004096)
			(xy 362.839521 -238.028703) (xy 362.831626 -238.07728) (xy 362.816042 -238.123961) (xy 362.793171 -238.167538)
			(xy 362.763606 -238.206882) (xy 362.728113 -238.240974) (xy 362.68761 -238.26893) (xy 362.643148 -238.290028)
			(xy 362.595877 -238.30372) (xy 362.547022 -238.309652) (xy 362.497847 -238.307671) (xy 362.449628 -238.297827)
			(xy 362.403612 -238.280375) (xy 362.360991 -238.255768) (xy 362.32287 -238.224643) (xy 362.290235 -238.187806)
			(xy 362.263932 -238.14621) (xy 362.244641 -238.100934) (xy 362.232864 -238.05315) (xy 362.228904 -238.004096)
			(xy 361.900216 -238.004096) (xy 361.899721 -238.028703) (xy 361.891826 -238.07728) (xy 361.876242 -238.123961)
			(xy 361.853371 -238.167538) (xy 361.823806 -238.206882) (xy 361.788313 -238.240974) (xy 361.74781 -238.26893)
			(xy 361.703348 -238.290028) (xy 361.656077 -238.30372) (xy 361.607222 -238.309652) (xy 361.558047 -238.307671)
			(xy 361.509828 -238.297827) (xy 361.463812 -238.280375) (xy 361.421191 -238.255768) (xy 361.38307 -238.224643)
			(xy 361.350435 -238.187806) (xy 361.324132 -238.14621) (xy 361.304841 -238.100934) (xy 361.293064 -238.05315)
			(xy 361.289104 -238.004096) (xy 358.14635 -238.004096) (xy 358.145855 -238.028703) (xy 358.13796 -238.07728)
			(xy 358.122376 -238.123961) (xy 358.099505 -238.167538) (xy 358.06994 -238.206882) (xy 358.034447 -238.240974)
			(xy 357.993944 -238.26893) (xy 357.949482 -238.290028) (xy 357.902211 -238.30372) (xy 357.853356 -238.309652)
			(xy 357.804181 -238.307671) (xy 357.755962 -238.297827) (xy 357.709946 -238.280375) (xy 357.667325 -238.255768)
			(xy 357.629204 -238.224643) (xy 357.596569 -238.187806) (xy 357.570266 -238.14621) (xy 357.550975 -238.100934)
			(xy 357.539198 -238.05315) (xy 357.535238 -238.004096) (xy 357.20655 -238.004096) (xy 357.206055 -238.028703)
			(xy 357.19816 -238.07728) (xy 357.182576 -238.123961) (xy 357.159705 -238.167538) (xy 357.13014 -238.206882)
			(xy 357.094647 -238.240974) (xy 357.054144 -238.26893) (xy 357.009682 -238.290028) (xy 356.962411 -238.30372)
			(xy 356.913556 -238.309652) (xy 356.864381 -238.307671) (xy 356.816162 -238.297827) (xy 356.770146 -238.280375)
			(xy 356.727525 -238.255768) (xy 356.689404 -238.224643) (xy 356.656769 -238.187806) (xy 356.630466 -238.14621)
			(xy 356.611175 -238.100934) (xy 356.599398 -238.05315) (xy 356.595438 -238.004096) (xy 356.266496 -238.004096)
			(xy 356.266001 -238.028703) (xy 356.258106 -238.07728) (xy 356.242522 -238.123961) (xy 356.219651 -238.167538)
			(xy 356.190086 -238.206882) (xy 356.154593 -238.240974) (xy 356.11409 -238.26893) (xy 356.069628 -238.290028)
			(xy 356.022357 -238.30372) (xy 355.973502 -238.309652) (xy 355.924327 -238.307671) (xy 355.876108 -238.297827)
			(xy 355.830092 -238.280375) (xy 355.787471 -238.255768) (xy 355.74935 -238.224643) (xy 355.716715 -238.187806)
			(xy 355.690412 -238.14621) (xy 355.671121 -238.100934) (xy 355.659344 -238.05315) (xy 355.655384 -238.004096)
			(xy 355.326442 -238.004096) (xy 355.325947 -238.028703) (xy 355.318052 -238.07728) (xy 355.302468 -238.123961)
			(xy 355.279597 -238.167538) (xy 355.250032 -238.206882) (xy 355.214539 -238.240974) (xy 355.174036 -238.26893)
			(xy 355.129574 -238.290028) (xy 355.082303 -238.30372) (xy 355.033448 -238.309652) (xy 354.984273 -238.307671)
			(xy 354.936054 -238.297827) (xy 354.890038 -238.280375) (xy 354.847417 -238.255768) (xy 354.809296 -238.224643)
			(xy 354.776661 -238.187806) (xy 354.750358 -238.14621) (xy 354.731067 -238.100934) (xy 354.71929 -238.05315)
			(xy 354.71533 -238.004096) (xy 354.386388 -238.004096) (xy 354.385893 -238.028703) (xy 354.377998 -238.07728)
			(xy 354.362414 -238.123961) (xy 354.339543 -238.167538) (xy 354.309978 -238.206882) (xy 354.274485 -238.240974)
			(xy 354.233982 -238.26893) (xy 354.18952 -238.290028) (xy 354.142249 -238.30372) (xy 354.093394 -238.309652)
			(xy 354.044219 -238.307671) (xy 353.996 -238.297827) (xy 353.949984 -238.280375) (xy 353.907363 -238.255768)
			(xy 353.869242 -238.224643) (xy 353.836607 -238.187806) (xy 353.810304 -238.14621) (xy 353.791013 -238.100934)
			(xy 353.779236 -238.05315) (xy 353.775276 -238.004096) (xy 353.446334 -238.004096) (xy 353.445839 -238.028703)
			(xy 353.437944 -238.07728) (xy 353.42236 -238.123961) (xy 353.399489 -238.167538) (xy 353.369924 -238.206882)
			(xy 353.334431 -238.240974) (xy 353.293928 -238.26893) (xy 353.249466 -238.290028) (xy 353.202195 -238.30372)
			(xy 353.15334 -238.309652) (xy 353.104165 -238.307671) (xy 353.055946 -238.297827) (xy 353.00993 -238.280375)
			(xy 352.967309 -238.255768) (xy 352.929188 -238.224643) (xy 352.896553 -238.187806) (xy 352.87025 -238.14621)
			(xy 352.850959 -238.100934) (xy 352.839182 -238.05315) (xy 352.835222 -238.004096) (xy 352.506534 -238.004096)
			(xy 352.506039 -238.028703) (xy 352.498144 -238.07728) (xy 352.48256 -238.123961) (xy 352.459689 -238.167538)
			(xy 352.430124 -238.206882) (xy 352.394631 -238.240974) (xy 352.354128 -238.26893) (xy 352.309666 -238.290028)
			(xy 352.262395 -238.30372) (xy 352.21354 -238.309652) (xy 352.164365 -238.307671) (xy 352.116146 -238.297827)
			(xy 352.07013 -238.280375) (xy 352.027509 -238.255768) (xy 351.989388 -238.224643) (xy 351.956753 -238.187806)
			(xy 351.93045 -238.14621) (xy 351.911159 -238.100934) (xy 351.899382 -238.05315) (xy 351.895422 -238.004096)
			(xy 351.56648 -238.004096) (xy 351.565985 -238.028703) (xy 351.55809 -238.07728) (xy 351.542506 -238.123961)
			(xy 351.519635 -238.167538) (xy 351.49007 -238.206882) (xy 351.454577 -238.240974) (xy 351.414074 -238.26893)
			(xy 351.369612 -238.290028) (xy 351.322341 -238.30372) (xy 351.273486 -238.309652) (xy 351.224311 -238.307671)
			(xy 351.176092 -238.297827) (xy 351.130076 -238.280375) (xy 351.087455 -238.255768) (xy 351.049334 -238.224643)
			(xy 351.016699 -238.187806) (xy 350.990396 -238.14621) (xy 350.971105 -238.100934) (xy 350.959328 -238.05315)
			(xy 350.955368 -238.004096) (xy 350.626426 -238.004096) (xy 350.625931 -238.028703) (xy 350.618036 -238.07728)
			(xy 350.602452 -238.123961) (xy 350.579581 -238.167538) (xy 350.550016 -238.206882) (xy 350.514523 -238.240974)
			(xy 350.47402 -238.26893) (xy 350.429558 -238.290028) (xy 350.382287 -238.30372) (xy 350.333432 -238.309652)
			(xy 350.284257 -238.307671) (xy 350.236038 -238.297827) (xy 350.190022 -238.280375) (xy 350.147401 -238.255768)
			(xy 350.10928 -238.224643) (xy 350.076645 -238.187806) (xy 350.050342 -238.14621) (xy 350.031051 -238.100934)
			(xy 350.019274 -238.05315) (xy 350.015314 -238.004096) (xy 349.686372 -238.004096) (xy 349.685877 -238.028703)
			(xy 349.677982 -238.07728) (xy 349.662398 -238.123961) (xy 349.639527 -238.167538) (xy 349.609962 -238.206882)
			(xy 349.574469 -238.240974) (xy 349.533966 -238.26893) (xy 349.489504 -238.290028) (xy 349.442233 -238.30372)
			(xy 349.393378 -238.309652) (xy 349.344203 -238.307671) (xy 349.295984 -238.297827) (xy 349.249968 -238.280375)
			(xy 349.207347 -238.255768) (xy 349.169226 -238.224643) (xy 349.136591 -238.187806) (xy 349.110288 -238.14621)
			(xy 349.090997 -238.100934) (xy 349.07922 -238.05315) (xy 349.07526 -238.004096) (xy 348.746318 -238.004096)
			(xy 348.745823 -238.028703) (xy 348.737928 -238.07728) (xy 348.722344 -238.123961) (xy 348.699473 -238.167538)
			(xy 348.669908 -238.206882) (xy 348.634415 -238.240974) (xy 348.593912 -238.26893) (xy 348.54945 -238.290028)
			(xy 348.502179 -238.30372) (xy 348.453324 -238.309652) (xy 348.404149 -238.307671) (xy 348.35593 -238.297827)
			(xy 348.309914 -238.280375) (xy 348.267293 -238.255768) (xy 348.229172 -238.224643) (xy 348.196537 -238.187806)
			(xy 348.170234 -238.14621) (xy 348.150943 -238.100934) (xy 348.139166 -238.05315) (xy 348.135206 -238.004096)
			(xy 347.806518 -238.004096) (xy 347.806023 -238.028703) (xy 347.798128 -238.07728) (xy 347.782544 -238.123961)
			(xy 347.759673 -238.167538) (xy 347.730108 -238.206882) (xy 347.694615 -238.240974) (xy 347.654112 -238.26893)
			(xy 347.60965 -238.290028) (xy 347.562379 -238.30372) (xy 347.513524 -238.309652) (xy 347.464349 -238.307671)
			(xy 347.41613 -238.297827) (xy 347.370114 -238.280375) (xy 347.327493 -238.255768) (xy 347.289372 -238.224643)
			(xy 347.256737 -238.187806) (xy 347.230434 -238.14621) (xy 347.211143 -238.100934) (xy 347.199366 -238.05315)
			(xy 347.195406 -238.004096) (xy 346.866464 -238.004096) (xy 346.865969 -238.028703) (xy 346.858074 -238.07728)
			(xy 346.84249 -238.123961) (xy 346.819619 -238.167538) (xy 346.790054 -238.206882) (xy 346.754561 -238.240974)
			(xy 346.714058 -238.26893) (xy 346.669596 -238.290028) (xy 346.622325 -238.30372) (xy 346.57347 -238.309652)
			(xy 346.524295 -238.307671) (xy 346.476076 -238.297827) (xy 346.43006 -238.280375) (xy 346.387439 -238.255768)
			(xy 346.349318 -238.224643) (xy 346.316683 -238.187806) (xy 346.29038 -238.14621) (xy 346.271089 -238.100934)
			(xy 346.259312 -238.05315) (xy 346.255352 -238.004096) (xy 345.92641 -238.004096) (xy 345.925915 -238.028703)
			(xy 345.91802 -238.07728) (xy 345.902436 -238.123961) (xy 345.879565 -238.167538) (xy 345.85 -238.206882)
			(xy 345.814507 -238.240974) (xy 345.774004 -238.26893) (xy 345.729542 -238.290028) (xy 345.682271 -238.30372)
			(xy 345.633416 -238.309652) (xy 345.584241 -238.307671) (xy 345.536022 -238.297827) (xy 345.490006 -238.280375)
			(xy 345.447385 -238.255768) (xy 345.409264 -238.224643) (xy 345.376629 -238.187806) (xy 345.350326 -238.14621)
			(xy 345.331035 -238.100934) (xy 345.319258 -238.05315) (xy 345.315298 -238.004096) (xy 344.986356 -238.004096)
			(xy 344.985861 -238.028703) (xy 344.977966 -238.07728) (xy 344.962382 -238.123961) (xy 344.939511 -238.167538)
			(xy 344.909946 -238.206882) (xy 344.874453 -238.240974) (xy 344.83395 -238.26893) (xy 344.789488 -238.290028)
			(xy 344.742217 -238.30372) (xy 344.693362 -238.309652) (xy 344.644187 -238.307671) (xy 344.595968 -238.297827)
			(xy 344.549952 -238.280375) (xy 344.507331 -238.255768) (xy 344.46921 -238.224643) (xy 344.436575 -238.187806)
			(xy 344.410272 -238.14621) (xy 344.390981 -238.100934) (xy 344.379204 -238.05315) (xy 344.375244 -238.004096)
			(xy 344.056716 -238.004096) (xy 344.056204 -238.029542) (xy 344.04804 -238.079776) (xy 344.031924 -238.12805)
			(xy 344.008273 -238.173113) (xy 343.9777 -238.213799) (xy 343.940996 -238.249054) (xy 343.899112 -238.277964)
			(xy 343.853133 -238.299781) (xy 343.804249 -238.313941) (xy 343.753728 -238.320075) (xy 343.702876 -238.318026)
			(xy 343.653012 -238.307846) (xy 343.605426 -238.289799) (xy 343.561352 -238.264353) (xy 343.52193 -238.232166)
			(xy 343.488182 -238.194072) (xy 343.460981 -238.151058) (xy 343.441033 -238.104238) (xy 343.428854 -238.054824)
			(xy 343.424759 -238.004096) (xy 343.106502 -238.004096) (xy 343.106007 -238.028703) (xy 343.098112 -238.07728)
			(xy 343.082528 -238.123961) (xy 343.059657 -238.167538) (xy 343.030092 -238.206882) (xy 342.994599 -238.240974)
			(xy 342.954096 -238.26893) (xy 342.909634 -238.290028) (xy 342.862363 -238.30372) (xy 342.813508 -238.309652)
			(xy 342.764333 -238.307671) (xy 342.716114 -238.297827) (xy 342.670098 -238.280375) (xy 342.627477 -238.255768)
			(xy 342.589356 -238.224643) (xy 342.556721 -238.187806) (xy 342.530418 -238.14621) (xy 342.511127 -238.100934)
			(xy 342.49935 -238.05315) (xy 342.49539 -238.004096) (xy 342.176862 -238.004096) (xy 342.17635 -238.029542)
			(xy 342.168186 -238.079776) (xy 342.15207 -238.12805) (xy 342.128419 -238.173113) (xy 342.097846 -238.213799)
			(xy 342.061142 -238.249054) (xy 342.019258 -238.277964) (xy 341.973279 -238.299781) (xy 341.924395 -238.313941)
			(xy 341.873874 -238.320075) (xy 341.823022 -238.318026) (xy 341.773158 -238.307846) (xy 341.725572 -238.289799)
			(xy 341.681498 -238.264353) (xy 341.642076 -238.232166) (xy 341.608328 -238.194072) (xy 341.581127 -238.151058)
			(xy 341.561179 -238.104238) (xy 341.549 -238.054824) (xy 341.544905 -238.004096) (xy 341.233252 -238.004096)
			(xy 341.233252 -238.411004) (xy 341.233813 -238.421696) (xy 341.242473 -238.441251) (xy 341.250016 -238.44885)
			(xy 341.250524 -238.449104) (xy 341.316564 -238.506762) (xy 341.327232 -238.50981) (xy 341.3379 -238.513112)
			(xy 341.348822 -238.511588) (xy 341.359312 -238.510255) (xy 341.380412 -238.508856) (xy 341.390986 -238.508794)
			(xy 341.416244 -238.509286) (xy 341.466072 -238.517598) (xy 341.513852 -238.533999) (xy 341.558281 -238.558041)
			(xy 341.598147 -238.589068) (xy 341.632361 -238.626233) (xy 341.659992 -238.668524) (xy 341.680285 -238.714785)
			(xy 341.692686 -238.763756) (xy 341.696858 -238.8141) (xy 341.696858 -238.814102) (xy 342.014805 -238.814102)
			(xy 342.0189 -238.763374) (xy 342.031079 -238.71396) (xy 342.051027 -238.66714) (xy 342.078228 -238.624126)
			(xy 342.111976 -238.586032) (xy 342.151398 -238.553845) (xy 342.195472 -238.528399) (xy 342.243058 -238.510352)
			(xy 342.292922 -238.500172) (xy 342.343774 -238.498123) (xy 342.394295 -238.504257) (xy 342.443179 -238.518417)
			(xy 342.489158 -238.540234) (xy 342.531042 -238.569144) (xy 342.567746 -238.604399) (xy 342.598319 -238.645085)
			(xy 342.62197 -238.690148) (xy 342.638086 -238.738422) (xy 342.64625 -238.788656) (xy 342.646762 -238.814102)
			(xy 342.954859 -238.814102) (xy 342.958954 -238.763374) (xy 342.971133 -238.71396) (xy 342.991081 -238.66714)
			(xy 343.018282 -238.624126) (xy 343.05203 -238.586032) (xy 343.091452 -238.553845) (xy 343.135526 -238.528399)
			(xy 343.183112 -238.510352) (xy 343.232976 -238.500172) (xy 343.283828 -238.498123) (xy 343.334349 -238.504257)
			(xy 343.383233 -238.518417) (xy 343.429212 -238.540234) (xy 343.471096 -238.569144) (xy 343.5078 -238.604399)
			(xy 343.538373 -238.645085) (xy 343.562024 -238.690148) (xy 343.57814 -238.738422) (xy 343.586304 -238.788656)
			(xy 343.586816 -238.814102) (xy 343.905344 -238.814102) (xy 343.909304 -238.765048) (xy 343.921081 -238.717264)
			(xy 343.940372 -238.671988) (xy 343.966675 -238.630392) (xy 343.99931 -238.593555) (xy 344.037431 -238.56243)
			(xy 344.080052 -238.537823) (xy 344.126068 -238.520371) (xy 344.174287 -238.510527) (xy 344.223462 -238.508546)
			(xy 344.272317 -238.514478) (xy 344.319588 -238.52817) (xy 344.36405 -238.549268) (xy 344.404553 -238.577224)
			(xy 344.440046 -238.611316) (xy 344.469611 -238.65066) (xy 344.492482 -238.694237) (xy 344.508066 -238.740918)
			(xy 344.515961 -238.789495) (xy 344.516456 -238.814102) (xy 346.725252 -238.814102) (xy 346.729212 -238.765048)
			(xy 346.740989 -238.717264) (xy 346.76028 -238.671988) (xy 346.786583 -238.630392) (xy 346.819218 -238.593555)
			(xy 346.857339 -238.56243) (xy 346.89996 -238.537823) (xy 346.945976 -238.520371) (xy 346.994195 -238.510527)
			(xy 347.04337 -238.508546) (xy 347.092225 -238.514478) (xy 347.139496 -238.52817) (xy 347.183958 -238.549268)
			(xy 347.224461 -238.577224) (xy 347.259954 -238.611316) (xy 347.289519 -238.65066) (xy 347.31239 -238.694237)
			(xy 347.327974 -238.740918) (xy 347.335869 -238.789495) (xy 347.336364 -238.814102) (xy 349.545414 -238.814102)
			(xy 349.549374 -238.765048) (xy 349.561151 -238.717264) (xy 349.580442 -238.671988) (xy 349.606745 -238.630392)
			(xy 349.63938 -238.593555) (xy 349.677501 -238.56243) (xy 349.720122 -238.537823) (xy 349.766138 -238.520371)
			(xy 349.814357 -238.510527) (xy 349.863532 -238.508546) (xy 349.912387 -238.514478) (xy 349.959658 -238.52817)
			(xy 350.00412 -238.549268) (xy 350.044623 -238.577224) (xy 350.080116 -238.611316) (xy 350.109681 -238.65066)
			(xy 350.132552 -238.694237) (xy 350.148136 -238.740918) (xy 350.156031 -238.789495) (xy 350.156526 -238.814102)
			(xy 352.365322 -238.814102) (xy 352.369282 -238.765048) (xy 352.381059 -238.717264) (xy 352.40035 -238.671988)
			(xy 352.426653 -238.630392) (xy 352.459288 -238.593555) (xy 352.497409 -238.56243) (xy 352.54003 -238.537823)
			(xy 352.586046 -238.520371) (xy 352.634265 -238.510527) (xy 352.68344 -238.508546) (xy 352.732295 -238.514478)
			(xy 352.779566 -238.52817) (xy 352.824028 -238.549268) (xy 352.864531 -238.577224) (xy 352.900024 -238.611316)
			(xy 352.929589 -238.65066) (xy 352.95246 -238.694237) (xy 352.968044 -238.740918) (xy 352.975939 -238.789495)
			(xy 352.976434 -238.814102) (xy 355.18523 -238.814102) (xy 355.18919 -238.765048) (xy 355.200967 -238.717264)
			(xy 355.220258 -238.671988) (xy 355.246561 -238.630392) (xy 355.279196 -238.593555) (xy 355.317317 -238.56243)
			(xy 355.359938 -238.537823) (xy 355.405954 -238.520371) (xy 355.454173 -238.510527) (xy 355.503348 -238.508546)
			(xy 355.552203 -238.514478) (xy 355.599474 -238.52817) (xy 355.643936 -238.549268) (xy 355.684439 -238.577224)
			(xy 355.719932 -238.611316) (xy 355.749497 -238.65066) (xy 355.772368 -238.694237) (xy 355.787952 -238.740918)
			(xy 355.795847 -238.789495) (xy 355.796342 -238.814102) (xy 356.125284 -238.814102) (xy 356.129244 -238.765048)
			(xy 356.141021 -238.717264) (xy 356.160312 -238.671988) (xy 356.186615 -238.630392) (xy 356.21925 -238.593555)
			(xy 356.257371 -238.56243) (xy 356.299992 -238.537823) (xy 356.346008 -238.520371) (xy 356.394227 -238.510527)
			(xy 356.443402 -238.508546) (xy 356.492257 -238.514478) (xy 356.539528 -238.52817) (xy 356.58399 -238.549268)
			(xy 356.624493 -238.577224) (xy 356.659986 -238.611316) (xy 356.689551 -238.65066) (xy 356.712422 -238.694237)
			(xy 356.728006 -238.740918) (xy 356.735901 -238.789495) (xy 356.736396 -238.814102) (xy 357.065338 -238.814102)
			(xy 357.069298 -238.765048) (xy 357.081075 -238.717264) (xy 357.100366 -238.671988) (xy 357.126669 -238.630392)
			(xy 357.159304 -238.593555) (xy 357.197425 -238.56243) (xy 357.240046 -238.537823) (xy 357.286062 -238.520371)
			(xy 357.334281 -238.510527) (xy 357.383456 -238.508546) (xy 357.432311 -238.514478) (xy 357.479582 -238.52817)
			(xy 357.524044 -238.549268) (xy 357.564547 -238.577224) (xy 357.60004 -238.611316) (xy 357.629605 -238.65066)
			(xy 357.652476 -238.694237) (xy 357.66806 -238.740918) (xy 357.675955 -238.789495) (xy 357.67645 -238.814102)
			(xy 358.005392 -238.814102) (xy 358.009352 -238.765048) (xy 358.021129 -238.717264) (xy 358.04042 -238.671988)
			(xy 358.066723 -238.630392) (xy 358.099358 -238.593555) (xy 358.137479 -238.56243) (xy 358.1801 -238.537823)
			(xy 358.226116 -238.520371) (xy 358.274335 -238.510527) (xy 358.32351 -238.508546) (xy 358.372365 -238.514478)
			(xy 358.419636 -238.52817) (xy 358.464098 -238.549268) (xy 358.504601 -238.577224) (xy 358.540094 -238.611316)
			(xy 358.569659 -238.65066) (xy 358.59253 -238.694237) (xy 358.608114 -238.740918) (xy 358.616009 -238.789495)
			(xy 358.616504 -238.814102) (xy 360.81895 -238.814102) (xy 360.82291 -238.765048) (xy 360.834687 -238.717264)
			(xy 360.853978 -238.671988) (xy 360.880281 -238.630392) (xy 360.912916 -238.593555) (xy 360.951037 -238.56243)
			(xy 360.993658 -238.537823) (xy 361.039674 -238.520371) (xy 361.087893 -238.510527) (xy 361.137068 -238.508546)
			(xy 361.185923 -238.514478) (xy 361.233194 -238.52817) (xy 361.277656 -238.549268) (xy 361.318159 -238.577224)
			(xy 361.353652 -238.611316) (xy 361.383217 -238.65066) (xy 361.406088 -238.694237) (xy 361.421672 -238.740918)
			(xy 361.429567 -238.789495) (xy 361.430062 -238.814102) (xy 361.759004 -238.814102) (xy 361.762964 -238.765048)
			(xy 361.774741 -238.717264) (xy 361.794032 -238.671988) (xy 361.820335 -238.630392) (xy 361.85297 -238.593555)
			(xy 361.891091 -238.56243) (xy 361.933712 -238.537823) (xy 361.979728 -238.520371) (xy 362.027947 -238.510527)
			(xy 362.077122 -238.508546) (xy 362.125977 -238.514478) (xy 362.173248 -238.52817) (xy 362.21771 -238.549268)
			(xy 362.258213 -238.577224) (xy 362.293706 -238.611316) (xy 362.323271 -238.65066) (xy 362.346142 -238.694237)
			(xy 362.361726 -238.740918) (xy 362.369621 -238.789495) (xy 362.370116 -238.814102) (xy 362.699058 -238.814102)
			(xy 362.703018 -238.765048) (xy 362.714795 -238.717264) (xy 362.734086 -238.671988) (xy 362.760389 -238.630392)
			(xy 362.793024 -238.593555) (xy 362.831145 -238.56243) (xy 362.873766 -238.537823) (xy 362.919782 -238.520371)
			(xy 362.968001 -238.510527) (xy 363.017176 -238.508546) (xy 363.066031 -238.514478) (xy 363.113302 -238.52817)
			(xy 363.157764 -238.549268) (xy 363.198267 -238.577224) (xy 363.23376 -238.611316) (xy 363.263325 -238.65066)
			(xy 363.286196 -238.694237) (xy 363.30178 -238.740918) (xy 363.309675 -238.789495) (xy 363.31017 -238.814102)
			(xy 363.639112 -238.814102) (xy 363.643072 -238.765048) (xy 363.654849 -238.717264) (xy 363.67414 -238.671988)
			(xy 363.700443 -238.630392) (xy 363.733078 -238.593555) (xy 363.771199 -238.56243) (xy 363.81382 -238.537823)
			(xy 363.859836 -238.520371) (xy 363.908055 -238.510527) (xy 363.95723 -238.508546) (xy 364.006085 -238.514478)
			(xy 364.053356 -238.52817) (xy 364.097818 -238.549268) (xy 364.138321 -238.577224) (xy 364.173814 -238.611316)
			(xy 364.203379 -238.65066) (xy 364.22625 -238.694237) (xy 364.241834 -238.740918) (xy 364.249729 -238.789495)
			(xy 364.250224 -238.814102) (xy 366.45902 -238.814102) (xy 366.46298 -238.765048) (xy 366.474757 -238.717264)
			(xy 366.494048 -238.671988) (xy 366.520351 -238.630392) (xy 366.552986 -238.593555) (xy 366.591107 -238.56243)
			(xy 366.633728 -238.537823) (xy 366.679744 -238.520371) (xy 366.727963 -238.510527) (xy 366.777138 -238.508546)
			(xy 366.825993 -238.514478) (xy 366.873264 -238.52817) (xy 366.917726 -238.549268) (xy 366.958229 -238.577224)
			(xy 366.993722 -238.611316) (xy 367.023287 -238.65066) (xy 367.046158 -238.694237) (xy 367.061742 -238.740918)
			(xy 367.069637 -238.789495) (xy 367.070132 -238.814102) (xy 369.278928 -238.814102) (xy 369.282888 -238.765048)
			(xy 369.294665 -238.717264) (xy 369.313956 -238.671988) (xy 369.340259 -238.630392) (xy 369.372894 -238.593555)
			(xy 369.411015 -238.56243) (xy 369.453636 -238.537823) (xy 369.499652 -238.520371) (xy 369.547871 -238.510527)
			(xy 369.597046 -238.508546) (xy 369.645901 -238.514478) (xy 369.693172 -238.52817) (xy 369.737634 -238.549268)
			(xy 369.778137 -238.577224) (xy 369.81363 -238.611316) (xy 369.843195 -238.65066) (xy 369.866066 -238.694237)
			(xy 369.88165 -238.740918) (xy 369.889545 -238.789495) (xy 369.89004 -238.814102) (xy 372.09909 -238.814102)
			(xy 372.10305 -238.765048) (xy 372.114827 -238.717264) (xy 372.134118 -238.671988) (xy 372.160421 -238.630392)
			(xy 372.193056 -238.593555) (xy 372.231177 -238.56243) (xy 372.273798 -238.537823) (xy 372.319814 -238.520371)
			(xy 372.368033 -238.510527) (xy 372.417208 -238.508546) (xy 372.466063 -238.514478) (xy 372.513334 -238.52817)
			(xy 372.557796 -238.549268) (xy 372.598299 -238.577224) (xy 372.633792 -238.611316) (xy 372.663357 -238.65066)
			(xy 372.686228 -238.694237) (xy 372.701812 -238.740918) (xy 372.709707 -238.789495) (xy 372.710202 -238.814102)
			(xy 374.918998 -238.814102) (xy 374.922958 -238.765048) (xy 374.934735 -238.717264) (xy 374.954026 -238.671988)
			(xy 374.980329 -238.630392) (xy 375.012964 -238.593555) (xy 375.051085 -238.56243) (xy 375.093706 -238.537823)
			(xy 375.139722 -238.520371) (xy 375.187941 -238.510527) (xy 375.237116 -238.508546) (xy 375.285971 -238.514478)
			(xy 375.333242 -238.52817) (xy 375.377704 -238.549268) (xy 375.418207 -238.577224) (xy 375.4537 -238.611316)
			(xy 375.483265 -238.65066) (xy 375.506136 -238.694237) (xy 375.52172 -238.740918) (xy 375.529615 -238.789495)
			(xy 375.53011 -238.814102) (xy 375.848621 -238.814102) (xy 375.852716 -238.763374) (xy 375.864895 -238.71396)
			(xy 375.884843 -238.66714) (xy 375.912044 -238.624126) (xy 375.945792 -238.586032) (xy 375.985214 -238.553845)
			(xy 376.029288 -238.528399) (xy 376.076874 -238.510352) (xy 376.126738 -238.500172) (xy 376.17759 -238.498123)
			(xy 376.228111 -238.504257) (xy 376.276995 -238.518417) (xy 376.322974 -238.540234) (xy 376.364858 -238.569144)
			(xy 376.401562 -238.604399) (xy 376.432135 -238.645085) (xy 376.455786 -238.690148) (xy 376.471902 -238.738422)
			(xy 376.480066 -238.788656) (xy 376.480578 -238.814102) (xy 376.788675 -238.814102) (xy 376.79277 -238.763374)
			(xy 376.804949 -238.71396) (xy 376.824897 -238.66714) (xy 376.852098 -238.624126) (xy 376.885846 -238.586032)
			(xy 376.925268 -238.553845) (xy 376.969342 -238.528399) (xy 377.016928 -238.510352) (xy 377.066792 -238.500172)
			(xy 377.117644 -238.498123) (xy 377.168165 -238.504257) (xy 377.217049 -238.518417) (xy 377.263028 -238.540234)
			(xy 377.304912 -238.569144) (xy 377.341616 -238.604399) (xy 377.372189 -238.645085) (xy 377.39584 -238.690148)
			(xy 377.411956 -238.738422) (xy 377.42012 -238.788656) (xy 377.420632 -238.814102) (xy 377.42012 -238.839548)
			(xy 377.411956 -238.889782) (xy 377.39584 -238.938056) (xy 377.372189 -238.983119) (xy 377.341616 -239.023805)
			(xy 377.304912 -239.05906) (xy 377.263028 -239.08797) (xy 377.217049 -239.109787) (xy 377.168165 -239.123947)
			(xy 377.117644 -239.130081) (xy 377.066792 -239.128032) (xy 377.016928 -239.117852) (xy 376.969342 -239.099805)
			(xy 376.925268 -239.074359) (xy 376.885846 -239.042172) (xy 376.852098 -239.004078) (xy 376.824897 -238.961064)
			(xy 376.804949 -238.914244) (xy 376.79277 -238.86483) (xy 376.788675 -238.814102) (xy 376.480578 -238.814102)
			(xy 376.480066 -238.839548) (xy 376.471902 -238.889782) (xy 376.455786 -238.938056) (xy 376.432135 -238.983119)
			(xy 376.401562 -239.023805) (xy 376.364858 -239.05906) (xy 376.322974 -239.08797) (xy 376.276995 -239.109787)
			(xy 376.228111 -239.123947) (xy 376.17759 -239.130081) (xy 376.126738 -239.128032) (xy 376.076874 -239.117852)
			(xy 376.029288 -239.099805) (xy 375.985214 -239.074359) (xy 375.945792 -239.042172) (xy 375.912044 -239.004078)
			(xy 375.884843 -238.961064) (xy 375.864895 -238.914244) (xy 375.852716 -238.86483) (xy 375.848621 -238.814102)
			(xy 375.53011 -238.814102) (xy 375.529615 -238.838709) (xy 375.52172 -238.887286) (xy 375.506136 -238.933967)
			(xy 375.483265 -238.977544) (xy 375.4537 -239.016888) (xy 375.418207 -239.05098) (xy 375.377704 -239.078936)
			(xy 375.333242 -239.100034) (xy 375.285971 -239.113726) (xy 375.237116 -239.119658) (xy 375.187941 -239.117677)
			(xy 375.139722 -239.107833) (xy 375.093706 -239.090381) (xy 375.051085 -239.065774) (xy 375.012964 -239.034649)
			(xy 374.980329 -238.997812) (xy 374.954026 -238.956216) (xy 374.934735 -238.91094) (xy 374.922958 -238.863156)
			(xy 374.918998 -238.814102) (xy 372.710202 -238.814102) (xy 372.709707 -238.838709) (xy 372.701812 -238.887286)
			(xy 372.686228 -238.933967) (xy 372.663357 -238.977544) (xy 372.633792 -239.016888) (xy 372.598299 -239.05098)
			(xy 372.557796 -239.078936) (xy 372.513334 -239.100034) (xy 372.466063 -239.113726) (xy 372.417208 -239.119658)
			(xy 372.368033 -239.117677) (xy 372.319814 -239.107833) (xy 372.273798 -239.090381) (xy 372.231177 -239.065774)
			(xy 372.193056 -239.034649) (xy 372.160421 -238.997812) (xy 372.134118 -238.956216) (xy 372.114827 -238.91094)
			(xy 372.10305 -238.863156) (xy 372.09909 -238.814102) (xy 369.89004 -238.814102) (xy 369.889545 -238.838709)
			(xy 369.88165 -238.887286) (xy 369.866066 -238.933967) (xy 369.843195 -238.977544) (xy 369.81363 -239.016888)
			(xy 369.778137 -239.05098) (xy 369.737634 -239.078936) (xy 369.693172 -239.100034) (xy 369.645901 -239.113726)
			(xy 369.597046 -239.119658) (xy 369.547871 -239.117677) (xy 369.499652 -239.107833) (xy 369.453636 -239.090381)
			(xy 369.411015 -239.065774) (xy 369.372894 -239.034649) (xy 369.340259 -238.997812) (xy 369.313956 -238.956216)
			(xy 369.294665 -238.91094) (xy 369.282888 -238.863156) (xy 369.278928 -238.814102) (xy 367.070132 -238.814102)
			(xy 367.069637 -238.838709) (xy 367.061742 -238.887286) (xy 367.046158 -238.933967) (xy 367.023287 -238.977544)
			(xy 366.993722 -239.016888) (xy 366.958229 -239.05098) (xy 366.917726 -239.078936) (xy 366.873264 -239.100034)
			(xy 366.825993 -239.113726) (xy 366.777138 -239.119658) (xy 366.727963 -239.117677) (xy 366.679744 -239.107833)
			(xy 366.633728 -239.090381) (xy 366.591107 -239.065774) (xy 366.552986 -239.034649) (xy 366.520351 -238.997812)
			(xy 366.494048 -238.956216) (xy 366.474757 -238.91094) (xy 366.46298 -238.863156) (xy 366.45902 -238.814102)
			(xy 364.250224 -238.814102) (xy 364.249729 -238.838709) (xy 364.241834 -238.887286) (xy 364.22625 -238.933967)
			(xy 364.203379 -238.977544) (xy 364.173814 -239.016888) (xy 364.138321 -239.05098) (xy 364.097818 -239.078936)
			(xy 364.053356 -239.100034) (xy 364.006085 -239.113726) (xy 363.95723 -239.119658) (xy 363.908055 -239.117677)
			(xy 363.859836 -239.107833) (xy 363.81382 -239.090381) (xy 363.771199 -239.065774) (xy 363.733078 -239.034649)
			(xy 363.700443 -238.997812) (xy 363.67414 -238.956216) (xy 363.654849 -238.91094) (xy 363.643072 -238.863156)
			(xy 363.639112 -238.814102) (xy 363.31017 -238.814102) (xy 363.309675 -238.838709) (xy 363.30178 -238.887286)
			(xy 363.286196 -238.933967) (xy 363.263325 -238.977544) (xy 363.23376 -239.016888) (xy 363.198267 -239.05098)
			(xy 363.157764 -239.078936) (xy 363.113302 -239.100034) (xy 363.066031 -239.113726) (xy 363.017176 -239.119658)
			(xy 362.968001 -239.117677) (xy 362.919782 -239.107833) (xy 362.873766 -239.090381) (xy 362.831145 -239.065774)
			(xy 362.793024 -239.034649) (xy 362.760389 -238.997812) (xy 362.734086 -238.956216) (xy 362.714795 -238.91094)
			(xy 362.703018 -238.863156) (xy 362.699058 -238.814102) (xy 362.370116 -238.814102) (xy 362.369621 -238.838709)
			(xy 362.361726 -238.887286) (xy 362.346142 -238.933967) (xy 362.323271 -238.977544) (xy 362.293706 -239.016888)
			(xy 362.258213 -239.05098) (xy 362.21771 -239.078936) (xy 362.173248 -239.100034) (xy 362.125977 -239.113726)
			(xy 362.077122 -239.119658) (xy 362.027947 -239.117677) (xy 361.979728 -239.107833) (xy 361.933712 -239.090381)
			(xy 361.891091 -239.065774) (xy 361.85297 -239.034649) (xy 361.820335 -238.997812) (xy 361.794032 -238.956216)
			(xy 361.774741 -238.91094) (xy 361.762964 -238.863156) (xy 361.759004 -238.814102) (xy 361.430062 -238.814102)
			(xy 361.429567 -238.838709) (xy 361.421672 -238.887286) (xy 361.406088 -238.933967) (xy 361.383217 -238.977544)
			(xy 361.353652 -239.016888) (xy 361.318159 -239.05098) (xy 361.277656 -239.078936) (xy 361.233194 -239.100034)
			(xy 361.185923 -239.113726) (xy 361.137068 -239.119658) (xy 361.087893 -239.117677) (xy 361.039674 -239.107833)
			(xy 360.993658 -239.090381) (xy 360.951037 -239.065774) (xy 360.912916 -239.034649) (xy 360.880281 -238.997812)
			(xy 360.853978 -238.956216) (xy 360.834687 -238.91094) (xy 360.82291 -238.863156) (xy 360.81895 -238.814102)
			(xy 358.616504 -238.814102) (xy 358.616009 -238.838709) (xy 358.608114 -238.887286) (xy 358.59253 -238.933967)
			(xy 358.569659 -238.977544) (xy 358.540094 -239.016888) (xy 358.504601 -239.05098) (xy 358.464098 -239.078936)
			(xy 358.419636 -239.100034) (xy 358.372365 -239.113726) (xy 358.32351 -239.119658) (xy 358.274335 -239.117677)
			(xy 358.226116 -239.107833) (xy 358.1801 -239.090381) (xy 358.137479 -239.065774) (xy 358.099358 -239.034649)
			(xy 358.066723 -238.997812) (xy 358.04042 -238.956216) (xy 358.021129 -238.91094) (xy 358.009352 -238.863156)
			(xy 358.005392 -238.814102) (xy 357.67645 -238.814102) (xy 357.675955 -238.838709) (xy 357.66806 -238.887286)
			(xy 357.652476 -238.933967) (xy 357.629605 -238.977544) (xy 357.60004 -239.016888) (xy 357.564547 -239.05098)
			(xy 357.524044 -239.078936) (xy 357.479582 -239.100034) (xy 357.432311 -239.113726) (xy 357.383456 -239.119658)
			(xy 357.334281 -239.117677) (xy 357.286062 -239.107833) (xy 357.240046 -239.090381) (xy 357.197425 -239.065774)
			(xy 357.159304 -239.034649) (xy 357.126669 -238.997812) (xy 357.100366 -238.956216) (xy 357.081075 -238.91094)
			(xy 357.069298 -238.863156) (xy 357.065338 -238.814102) (xy 356.736396 -238.814102) (xy 356.735901 -238.838709)
			(xy 356.728006 -238.887286) (xy 356.712422 -238.933967) (xy 356.689551 -238.977544) (xy 356.659986 -239.016888)
			(xy 356.624493 -239.05098) (xy 356.58399 -239.078936) (xy 356.539528 -239.100034) (xy 356.492257 -239.113726)
			(xy 356.443402 -239.119658) (xy 356.394227 -239.117677) (xy 356.346008 -239.107833) (xy 356.299992 -239.090381)
			(xy 356.257371 -239.065774) (xy 356.21925 -239.034649) (xy 356.186615 -238.997812) (xy 356.160312 -238.956216)
			(xy 356.141021 -238.91094) (xy 356.129244 -238.863156) (xy 356.125284 -238.814102) (xy 355.796342 -238.814102)
			(xy 355.795847 -238.838709) (xy 355.787952 -238.887286) (xy 355.772368 -238.933967) (xy 355.749497 -238.977544)
			(xy 355.719932 -239.016888) (xy 355.684439 -239.05098) (xy 355.643936 -239.078936) (xy 355.599474 -239.100034)
			(xy 355.552203 -239.113726) (xy 355.503348 -239.119658) (xy 355.454173 -239.117677) (xy 355.405954 -239.107833)
			(xy 355.359938 -239.090381) (xy 355.317317 -239.065774) (xy 355.279196 -239.034649) (xy 355.246561 -238.997812)
			(xy 355.220258 -238.956216) (xy 355.200967 -238.91094) (xy 355.18919 -238.863156) (xy 355.18523 -238.814102)
			(xy 352.976434 -238.814102) (xy 352.975939 -238.838709) (xy 352.968044 -238.887286) (xy 352.95246 -238.933967)
			(xy 352.929589 -238.977544) (xy 352.900024 -239.016888) (xy 352.864531 -239.05098) (xy 352.824028 -239.078936)
			(xy 352.779566 -239.100034) (xy 352.732295 -239.113726) (xy 352.68344 -239.119658) (xy 352.634265 -239.117677)
			(xy 352.586046 -239.107833) (xy 352.54003 -239.090381) (xy 352.497409 -239.065774) (xy 352.459288 -239.034649)
			(xy 352.426653 -238.997812) (xy 352.40035 -238.956216) (xy 352.381059 -238.91094) (xy 352.369282 -238.863156)
			(xy 352.365322 -238.814102) (xy 350.156526 -238.814102) (xy 350.156031 -238.838709) (xy 350.148136 -238.887286)
			(xy 350.132552 -238.933967) (xy 350.109681 -238.977544) (xy 350.080116 -239.016888) (xy 350.044623 -239.05098)
			(xy 350.00412 -239.078936) (xy 349.959658 -239.100034) (xy 349.912387 -239.113726) (xy 349.863532 -239.119658)
			(xy 349.814357 -239.117677) (xy 349.766138 -239.107833) (xy 349.720122 -239.090381) (xy 349.677501 -239.065774)
			(xy 349.63938 -239.034649) (xy 349.606745 -238.997812) (xy 349.580442 -238.956216) (xy 349.561151 -238.91094)
			(xy 349.549374 -238.863156) (xy 349.545414 -238.814102) (xy 347.336364 -238.814102) (xy 347.335869 -238.838709)
			(xy 347.327974 -238.887286) (xy 347.31239 -238.933967) (xy 347.289519 -238.977544) (xy 347.259954 -239.016888)
			(xy 347.224461 -239.05098) (xy 347.183958 -239.078936) (xy 347.139496 -239.100034) (xy 347.092225 -239.113726)
			(xy 347.04337 -239.119658) (xy 346.994195 -239.117677) (xy 346.945976 -239.107833) (xy 346.89996 -239.090381)
			(xy 346.857339 -239.065774) (xy 346.819218 -239.034649) (xy 346.786583 -238.997812) (xy 346.76028 -238.956216)
			(xy 346.740989 -238.91094) (xy 346.729212 -238.863156) (xy 346.725252 -238.814102) (xy 344.516456 -238.814102)
			(xy 344.515961 -238.838709) (xy 344.508066 -238.887286) (xy 344.492482 -238.933967) (xy 344.469611 -238.977544)
			(xy 344.440046 -239.016888) (xy 344.404553 -239.05098) (xy 344.36405 -239.078936) (xy 344.319588 -239.100034)
			(xy 344.272317 -239.113726) (xy 344.223462 -239.119658) (xy 344.174287 -239.117677) (xy 344.126068 -239.107833)
			(xy 344.080052 -239.090381) (xy 344.037431 -239.065774) (xy 343.99931 -239.034649) (xy 343.966675 -238.997812)
			(xy 343.940372 -238.956216) (xy 343.921081 -238.91094) (xy 343.909304 -238.863156) (xy 343.905344 -238.814102)
			(xy 343.586816 -238.814102) (xy 343.586304 -238.839548) (xy 343.57814 -238.889782) (xy 343.562024 -238.938056)
			(xy 343.538373 -238.983119) (xy 343.5078 -239.023805) (xy 343.471096 -239.05906) (xy 343.429212 -239.08797)
			(xy 343.383233 -239.109787) (xy 343.334349 -239.123947) (xy 343.283828 -239.130081) (xy 343.232976 -239.128032)
			(xy 343.183112 -239.117852) (xy 343.135526 -239.099805) (xy 343.091452 -239.074359) (xy 343.05203 -239.042172)
			(xy 343.018282 -239.004078) (xy 342.991081 -238.961064) (xy 342.971133 -238.914244) (xy 342.958954 -238.86483)
			(xy 342.954859 -238.814102) (xy 342.646762 -238.814102) (xy 342.64625 -238.839548) (xy 342.638086 -238.889782)
			(xy 342.62197 -238.938056) (xy 342.598319 -238.983119) (xy 342.567746 -239.023805) (xy 342.531042 -239.05906)
			(xy 342.489158 -239.08797) (xy 342.443179 -239.109787) (xy 342.394295 -239.123947) (xy 342.343774 -239.130081)
			(xy 342.292922 -239.128032) (xy 342.243058 -239.117852) (xy 342.195472 -239.099805) (xy 342.151398 -239.074359)
			(xy 342.111976 -239.042172) (xy 342.078228 -239.004078) (xy 342.051027 -238.961064) (xy 342.031079 -238.914244)
			(xy 342.0189 -238.86483) (xy 342.014805 -238.814102) (xy 341.696858 -238.814102) (xy 341.692686 -238.864444)
			(xy 341.680285 -238.913415) (xy 341.659992 -238.959676) (xy 341.632361 -239.001967) (xy 341.598147 -239.039132)
			(xy 341.558281 -239.070159) (xy 341.513852 -239.094201) (xy 341.466072 -239.110602) (xy 341.416244 -239.118914)
			(xy 341.390986 -239.11941) (xy 341.380412 -239.119356) (xy 341.359311 -239.117959) (xy 341.348822 -239.116616)
			(xy 341.3379 -239.115092) (xy 341.317072 -239.121442) (xy 341.250778 -239.178846) (xy 341.242396 -239.186212)
			(xy 341.233252 -239.206024) (xy 341.233252 -239.624108) (xy 341.544905 -239.624108) (xy 341.549 -239.57338)
			(xy 341.561179 -239.523966) (xy 341.581127 -239.477146) (xy 341.608328 -239.434132) (xy 341.642076 -239.396038)
			(xy 341.681498 -239.363851) (xy 341.725572 -239.338405) (xy 341.773158 -239.320358) (xy 341.823022 -239.310178)
			(xy 341.873874 -239.308129) (xy 341.924395 -239.314263) (xy 341.973279 -239.328423) (xy 342.019258 -239.35024)
			(xy 342.061142 -239.37915) (xy 342.097846 -239.414405) (xy 342.128419 -239.455091) (xy 342.15207 -239.500154)
			(xy 342.168186 -239.548428) (xy 342.17635 -239.598662) (xy 342.176862 -239.624108) (xy 342.49539 -239.624108)
			(xy 342.49935 -239.575054) (xy 342.511127 -239.52727) (xy 342.530418 -239.481994) (xy 342.556721 -239.440398)
			(xy 342.589356 -239.403561) (xy 342.627477 -239.372436) (xy 342.670098 -239.347829) (xy 342.716114 -239.330377)
			(xy 342.764333 -239.320533) (xy 342.813508 -239.318552) (xy 342.862363 -239.324484) (xy 342.909634 -239.338176)
			(xy 342.954096 -239.359274) (xy 342.994599 -239.38723) (xy 343.030092 -239.421322) (xy 343.059657 -239.460666)
			(xy 343.082528 -239.504243) (xy 343.098112 -239.550924) (xy 343.106007 -239.599501) (xy 343.106502 -239.624108)
			(xy 343.424759 -239.624108) (xy 343.428854 -239.57338) (xy 343.441033 -239.523966) (xy 343.460981 -239.477146)
			(xy 343.488182 -239.434132) (xy 343.52193 -239.396038) (xy 343.561352 -239.363851) (xy 343.605426 -239.338405)
			(xy 343.653012 -239.320358) (xy 343.702876 -239.310178) (xy 343.753728 -239.308129) (xy 343.804249 -239.314263)
			(xy 343.853133 -239.328423) (xy 343.899112 -239.35024) (xy 343.940996 -239.37915) (xy 343.9777 -239.414405)
			(xy 344.008273 -239.455091) (xy 344.031924 -239.500154) (xy 344.04804 -239.548428) (xy 344.056204 -239.598662)
			(xy 344.056716 -239.624108) (xy 344.375244 -239.624108) (xy 344.379204 -239.575054) (xy 344.390981 -239.52727)
			(xy 344.410272 -239.481994) (xy 344.436575 -239.440398) (xy 344.46921 -239.403561) (xy 344.507331 -239.372436)
			(xy 344.549952 -239.347829) (xy 344.595968 -239.330377) (xy 344.644187 -239.320533) (xy 344.693362 -239.318552)
			(xy 344.742217 -239.324484) (xy 344.789488 -239.338176) (xy 344.83395 -239.359274) (xy 344.874453 -239.38723)
			(xy 344.909946 -239.421322) (xy 344.939511 -239.460666) (xy 344.962382 -239.504243) (xy 344.977966 -239.550924)
			(xy 344.985861 -239.599501) (xy 344.986356 -239.624108) (xy 345.315298 -239.624108) (xy 345.319258 -239.575054)
			(xy 345.331035 -239.52727) (xy 345.350326 -239.481994) (xy 345.376629 -239.440398) (xy 345.409264 -239.403561)
			(xy 345.447385 -239.372436) (xy 345.490006 -239.347829) (xy 345.536022 -239.330377) (xy 345.584241 -239.320533)
			(xy 345.633416 -239.318552) (xy 345.682271 -239.324484) (xy 345.729542 -239.338176) (xy 345.774004 -239.359274)
			(xy 345.814507 -239.38723) (xy 345.85 -239.421322) (xy 345.879565 -239.460666) (xy 345.902436 -239.504243)
			(xy 345.91802 -239.550924) (xy 345.925915 -239.599501) (xy 345.92641 -239.624108) (xy 346.255352 -239.624108)
			(xy 346.259312 -239.575054) (xy 346.271089 -239.52727) (xy 346.29038 -239.481994) (xy 346.316683 -239.440398)
			(xy 346.349318 -239.403561) (xy 346.387439 -239.372436) (xy 346.43006 -239.347829) (xy 346.476076 -239.330377)
			(xy 346.524295 -239.320533) (xy 346.57347 -239.318552) (xy 346.622325 -239.324484) (xy 346.669596 -239.338176)
			(xy 346.714058 -239.359274) (xy 346.754561 -239.38723) (xy 346.790054 -239.421322) (xy 346.819619 -239.460666)
			(xy 346.84249 -239.504243) (xy 346.858074 -239.550924) (xy 346.865969 -239.599501) (xy 346.866464 -239.624108)
			(xy 347.195406 -239.624108) (xy 347.199366 -239.575054) (xy 347.211143 -239.52727) (xy 347.230434 -239.481994)
			(xy 347.256737 -239.440398) (xy 347.289372 -239.403561) (xy 347.327493 -239.372436) (xy 347.370114 -239.347829)
			(xy 347.41613 -239.330377) (xy 347.464349 -239.320533) (xy 347.513524 -239.318552) (xy 347.562379 -239.324484)
			(xy 347.60965 -239.338176) (xy 347.654112 -239.359274) (xy 347.694615 -239.38723) (xy 347.730108 -239.421322)
			(xy 347.759673 -239.460666) (xy 347.782544 -239.504243) (xy 347.798128 -239.550924) (xy 347.806023 -239.599501)
			(xy 347.806518 -239.624108) (xy 348.135206 -239.624108) (xy 348.139166 -239.575054) (xy 348.150943 -239.52727)
			(xy 348.170234 -239.481994) (xy 348.196537 -239.440398) (xy 348.229172 -239.403561) (xy 348.267293 -239.372436)
			(xy 348.309914 -239.347829) (xy 348.35593 -239.330377) (xy 348.404149 -239.320533) (xy 348.453324 -239.318552)
			(xy 348.502179 -239.324484) (xy 348.54945 -239.338176) (xy 348.593912 -239.359274) (xy 348.634415 -239.38723)
			(xy 348.669908 -239.421322) (xy 348.699473 -239.460666) (xy 348.722344 -239.504243) (xy 348.737928 -239.550924)
			(xy 348.745823 -239.599501) (xy 348.746318 -239.624108) (xy 349.07526 -239.624108) (xy 349.07922 -239.575054)
			(xy 349.090997 -239.52727) (xy 349.110288 -239.481994) (xy 349.136591 -239.440398) (xy 349.169226 -239.403561)
			(xy 349.207347 -239.372436) (xy 349.249968 -239.347829) (xy 349.295984 -239.330377) (xy 349.344203 -239.320533)
			(xy 349.393378 -239.318552) (xy 349.442233 -239.324484) (xy 349.489504 -239.338176) (xy 349.533966 -239.359274)
			(xy 349.574469 -239.38723) (xy 349.609962 -239.421322) (xy 349.639527 -239.460666) (xy 349.662398 -239.504243)
			(xy 349.677982 -239.550924) (xy 349.685877 -239.599501) (xy 349.686372 -239.624108) (xy 350.015314 -239.624108)
			(xy 350.019274 -239.575054) (xy 350.031051 -239.52727) (xy 350.050342 -239.481994) (xy 350.076645 -239.440398)
			(xy 350.10928 -239.403561) (xy 350.147401 -239.372436) (xy 350.190022 -239.347829) (xy 350.236038 -239.330377)
			(xy 350.284257 -239.320533) (xy 350.333432 -239.318552) (xy 350.382287 -239.324484) (xy 350.429558 -239.338176)
			(xy 350.47402 -239.359274) (xy 350.514523 -239.38723) (xy 350.550016 -239.421322) (xy 350.579581 -239.460666)
			(xy 350.602452 -239.504243) (xy 350.618036 -239.550924) (xy 350.625931 -239.599501) (xy 350.626426 -239.624108)
			(xy 350.955368 -239.624108) (xy 350.959328 -239.575054) (xy 350.971105 -239.52727) (xy 350.990396 -239.481994)
			(xy 351.016699 -239.440398) (xy 351.049334 -239.403561) (xy 351.087455 -239.372436) (xy 351.130076 -239.347829)
			(xy 351.176092 -239.330377) (xy 351.224311 -239.320533) (xy 351.273486 -239.318552) (xy 351.322341 -239.324484)
			(xy 351.369612 -239.338176) (xy 351.414074 -239.359274) (xy 351.454577 -239.38723) (xy 351.49007 -239.421322)
			(xy 351.519635 -239.460666) (xy 351.542506 -239.504243) (xy 351.55809 -239.550924) (xy 351.565985 -239.599501)
			(xy 351.56648 -239.624108) (xy 351.895422 -239.624108) (xy 351.899382 -239.575054) (xy 351.911159 -239.52727)
			(xy 351.93045 -239.481994) (xy 351.956753 -239.440398) (xy 351.989388 -239.403561) (xy 352.027509 -239.372436)
			(xy 352.07013 -239.347829) (xy 352.116146 -239.330377) (xy 352.164365 -239.320533) (xy 352.21354 -239.318552)
			(xy 352.262395 -239.324484) (xy 352.309666 -239.338176) (xy 352.354128 -239.359274) (xy 352.394631 -239.38723)
			(xy 352.430124 -239.421322) (xy 352.459689 -239.460666) (xy 352.48256 -239.504243) (xy 352.498144 -239.550924)
			(xy 352.506039 -239.599501) (xy 352.506534 -239.624108) (xy 352.835222 -239.624108) (xy 352.839182 -239.575054)
			(xy 352.850959 -239.52727) (xy 352.87025 -239.481994) (xy 352.896553 -239.440398) (xy 352.929188 -239.403561)
			(xy 352.967309 -239.372436) (xy 353.00993 -239.347829) (xy 353.055946 -239.330377) (xy 353.104165 -239.320533)
			(xy 353.15334 -239.318552) (xy 353.202195 -239.324484) (xy 353.249466 -239.338176) (xy 353.293928 -239.359274)
			(xy 353.334431 -239.38723) (xy 353.369924 -239.421322) (xy 353.399489 -239.460666) (xy 353.42236 -239.504243)
			(xy 353.437944 -239.550924) (xy 353.445839 -239.599501) (xy 353.446334 -239.624108) (xy 353.775276 -239.624108)
			(xy 353.779236 -239.575054) (xy 353.791013 -239.52727) (xy 353.810304 -239.481994) (xy 353.836607 -239.440398)
			(xy 353.869242 -239.403561) (xy 353.907363 -239.372436) (xy 353.949984 -239.347829) (xy 353.996 -239.330377)
			(xy 354.044219 -239.320533) (xy 354.093394 -239.318552) (xy 354.142249 -239.324484) (xy 354.18952 -239.338176)
			(xy 354.233982 -239.359274) (xy 354.274485 -239.38723) (xy 354.309978 -239.421322) (xy 354.339543 -239.460666)
			(xy 354.362414 -239.504243) (xy 354.377998 -239.550924) (xy 354.385893 -239.599501) (xy 354.386388 -239.624108)
			(xy 354.71533 -239.624108) (xy 354.71929 -239.575054) (xy 354.731067 -239.52727) (xy 354.750358 -239.481994)
			(xy 354.776661 -239.440398) (xy 354.809296 -239.403561) (xy 354.847417 -239.372436) (xy 354.890038 -239.347829)
			(xy 354.936054 -239.330377) (xy 354.984273 -239.320533) (xy 355.033448 -239.318552) (xy 355.082303 -239.324484)
			(xy 355.129574 -239.338176) (xy 355.174036 -239.359274) (xy 355.214539 -239.38723) (xy 355.250032 -239.421322)
			(xy 355.279597 -239.460666) (xy 355.302468 -239.504243) (xy 355.318052 -239.550924) (xy 355.325947 -239.599501)
			(xy 355.326442 -239.624108) (xy 355.655384 -239.624108) (xy 355.659344 -239.575054) (xy 355.671121 -239.52727)
			(xy 355.690412 -239.481994) (xy 355.716715 -239.440398) (xy 355.74935 -239.403561) (xy 355.787471 -239.372436)
			(xy 355.830092 -239.347829) (xy 355.876108 -239.330377) (xy 355.924327 -239.320533) (xy 355.973502 -239.318552)
			(xy 356.022357 -239.324484) (xy 356.069628 -239.338176) (xy 356.11409 -239.359274) (xy 356.154593 -239.38723)
			(xy 356.190086 -239.421322) (xy 356.219651 -239.460666) (xy 356.242522 -239.504243) (xy 356.258106 -239.550924)
			(xy 356.266001 -239.599501) (xy 356.266496 -239.624108) (xy 363.168958 -239.624108) (xy 363.172918 -239.575054)
			(xy 363.184695 -239.52727) (xy 363.203986 -239.481994) (xy 363.230289 -239.440398) (xy 363.262924 -239.403561)
			(xy 363.301045 -239.372436) (xy 363.343666 -239.347829) (xy 363.389682 -239.330377) (xy 363.437901 -239.320533)
			(xy 363.487076 -239.318552) (xy 363.535931 -239.324484) (xy 363.583202 -239.338176) (xy 363.627664 -239.359274)
			(xy 363.668167 -239.38723) (xy 363.70366 -239.421322) (xy 363.733225 -239.460666) (xy 363.756096 -239.504243)
			(xy 363.77168 -239.550924) (xy 363.779575 -239.599501) (xy 363.78007 -239.624108) (xy 364.109012 -239.624108)
			(xy 364.112972 -239.575054) (xy 364.124749 -239.52727) (xy 364.14404 -239.481994) (xy 364.170343 -239.440398)
			(xy 364.202978 -239.403561) (xy 364.241099 -239.372436) (xy 364.28372 -239.347829) (xy 364.329736 -239.330377)
			(xy 364.377955 -239.320533) (xy 364.42713 -239.318552) (xy 364.475985 -239.324484) (xy 364.523256 -239.338176)
			(xy 364.567718 -239.359274) (xy 364.608221 -239.38723) (xy 364.643714 -239.421322) (xy 364.673279 -239.460666)
			(xy 364.69615 -239.504243) (xy 364.711734 -239.550924) (xy 364.719629 -239.599501) (xy 364.720124 -239.624108)
			(xy 365.049066 -239.624108) (xy 365.053026 -239.575054) (xy 365.064803 -239.52727) (xy 365.084094 -239.481994)
			(xy 365.110397 -239.440398) (xy 365.143032 -239.403561) (xy 365.181153 -239.372436) (xy 365.223774 -239.347829)
			(xy 365.26979 -239.330377) (xy 365.318009 -239.320533) (xy 365.367184 -239.318552) (xy 365.416039 -239.324484)
			(xy 365.46331 -239.338176) (xy 365.507772 -239.359274) (xy 365.548275 -239.38723) (xy 365.583768 -239.421322)
			(xy 365.613333 -239.460666) (xy 365.636204 -239.504243) (xy 365.651788 -239.550924) (xy 365.659683 -239.599501)
			(xy 365.660178 -239.624108) (xy 365.98912 -239.624108) (xy 365.99308 -239.575054) (xy 366.004857 -239.52727)
			(xy 366.024148 -239.481994) (xy 366.050451 -239.440398) (xy 366.083086 -239.403561) (xy 366.121207 -239.372436)
			(xy 366.163828 -239.347829) (xy 366.209844 -239.330377) (xy 366.258063 -239.320533) (xy 366.307238 -239.318552)
			(xy 366.356093 -239.324484) (xy 366.403364 -239.338176) (xy 366.447826 -239.359274) (xy 366.488329 -239.38723)
			(xy 366.523822 -239.421322) (xy 366.553387 -239.460666) (xy 366.576258 -239.504243) (xy 366.591842 -239.550924)
			(xy 366.599737 -239.599501) (xy 366.600232 -239.624108) (xy 366.92892 -239.624108) (xy 366.93288 -239.575054)
			(xy 366.944657 -239.52727) (xy 366.963948 -239.481994) (xy 366.990251 -239.440398) (xy 367.022886 -239.403561)
			(xy 367.061007 -239.372436) (xy 367.103628 -239.347829) (xy 367.149644 -239.330377) (xy 367.197863 -239.320533)
			(xy 367.247038 -239.318552) (xy 367.295893 -239.324484) (xy 367.343164 -239.338176) (xy 367.387626 -239.359274)
			(xy 367.428129 -239.38723) (xy 367.463622 -239.421322) (xy 367.493187 -239.460666) (xy 367.516058 -239.504243)
			(xy 367.531642 -239.550924) (xy 367.539537 -239.599501) (xy 367.540032 -239.624108) (xy 367.868974 -239.624108)
			(xy 367.872934 -239.575054) (xy 367.884711 -239.52727) (xy 367.904002 -239.481994) (xy 367.930305 -239.440398)
			(xy 367.96294 -239.403561) (xy 368.001061 -239.372436) (xy 368.043682 -239.347829) (xy 368.089698 -239.330377)
			(xy 368.137917 -239.320533) (xy 368.187092 -239.318552) (xy 368.235947 -239.324484) (xy 368.283218 -239.338176)
			(xy 368.32768 -239.359274) (xy 368.368183 -239.38723) (xy 368.403676 -239.421322) (xy 368.433241 -239.460666)
			(xy 368.456112 -239.504243) (xy 368.471696 -239.550924) (xy 368.479591 -239.599501) (xy 368.480086 -239.624108)
			(xy 368.809028 -239.624108) (xy 368.812988 -239.575054) (xy 368.824765 -239.52727) (xy 368.844056 -239.481994)
			(xy 368.870359 -239.440398) (xy 368.902994 -239.403561) (xy 368.941115 -239.372436) (xy 368.983736 -239.347829)
			(xy 369.029752 -239.330377) (xy 369.077971 -239.320533) (xy 369.127146 -239.318552) (xy 369.176001 -239.324484)
			(xy 369.223272 -239.338176) (xy 369.267734 -239.359274) (xy 369.308237 -239.38723) (xy 369.34373 -239.421322)
			(xy 369.373295 -239.460666) (xy 369.396166 -239.504243) (xy 369.41175 -239.550924) (xy 369.419645 -239.599501)
			(xy 369.42014 -239.624108) (xy 369.749082 -239.624108) (xy 369.753042 -239.575054) (xy 369.764819 -239.52727)
			(xy 369.78411 -239.481994) (xy 369.810413 -239.440398) (xy 369.843048 -239.403561) (xy 369.881169 -239.372436)
			(xy 369.92379 -239.347829) (xy 369.969806 -239.330377) (xy 370.018025 -239.320533) (xy 370.0672 -239.318552)
			(xy 370.116055 -239.324484) (xy 370.163326 -239.338176) (xy 370.207788 -239.359274) (xy 370.248291 -239.38723)
			(xy 370.283784 -239.421322) (xy 370.313349 -239.460666) (xy 370.33622 -239.504243) (xy 370.351804 -239.550924)
			(xy 370.359699 -239.599501) (xy 370.360194 -239.624108) (xy 370.688882 -239.624108) (xy 370.692842 -239.575054)
			(xy 370.704619 -239.52727) (xy 370.72391 -239.481994) (xy 370.750213 -239.440398) (xy 370.782848 -239.403561)
			(xy 370.820969 -239.372436) (xy 370.86359 -239.347829) (xy 370.909606 -239.330377) (xy 370.957825 -239.320533)
			(xy 371.007 -239.318552) (xy 371.055855 -239.324484) (xy 371.103126 -239.338176) (xy 371.147588 -239.359274)
			(xy 371.188091 -239.38723) (xy 371.223584 -239.421322) (xy 371.253149 -239.460666) (xy 371.27602 -239.504243)
			(xy 371.291604 -239.550924) (xy 371.299499 -239.599501) (xy 371.299994 -239.624108) (xy 371.628936 -239.624108)
			(xy 371.632896 -239.575054) (xy 371.644673 -239.52727) (xy 371.663964 -239.481994) (xy 371.690267 -239.440398)
			(xy 371.722902 -239.403561) (xy 371.761023 -239.372436) (xy 371.803644 -239.347829) (xy 371.84966 -239.330377)
			(xy 371.897879 -239.320533) (xy 371.947054 -239.318552) (xy 371.995909 -239.324484) (xy 372.04318 -239.338176)
			(xy 372.087642 -239.359274) (xy 372.128145 -239.38723) (xy 372.163638 -239.421322) (xy 372.193203 -239.460666)
			(xy 372.216074 -239.504243) (xy 372.231658 -239.550924) (xy 372.239553 -239.599501) (xy 372.240048 -239.624108)
			(xy 372.56899 -239.624108) (xy 372.57295 -239.575054) (xy 372.584727 -239.52727) (xy 372.604018 -239.481994)
			(xy 372.630321 -239.440398) (xy 372.662956 -239.403561) (xy 372.701077 -239.372436) (xy 372.743698 -239.347829)
			(xy 372.789714 -239.330377) (xy 372.837933 -239.320533) (xy 372.887108 -239.318552) (xy 372.935963 -239.324484)
			(xy 372.983234 -239.338176) (xy 373.027696 -239.359274) (xy 373.068199 -239.38723) (xy 373.103692 -239.421322)
			(xy 373.133257 -239.460666) (xy 373.156128 -239.504243) (xy 373.171712 -239.550924) (xy 373.179607 -239.599501)
			(xy 373.180102 -239.624108) (xy 373.509044 -239.624108) (xy 373.513004 -239.575054) (xy 373.524781 -239.52727)
			(xy 373.544072 -239.481994) (xy 373.570375 -239.440398) (xy 373.60301 -239.403561) (xy 373.641131 -239.372436)
			(xy 373.683752 -239.347829) (xy 373.729768 -239.330377) (xy 373.777987 -239.320533) (xy 373.827162 -239.318552)
			(xy 373.876017 -239.324484) (xy 373.923288 -239.338176) (xy 373.96775 -239.359274) (xy 374.008253 -239.38723)
			(xy 374.043746 -239.421322) (xy 374.073311 -239.460666) (xy 374.096182 -239.504243) (xy 374.111766 -239.550924)
			(xy 374.119661 -239.599501) (xy 374.120156 -239.624108) (xy 374.449098 -239.624108) (xy 374.453058 -239.575054)
			(xy 374.464835 -239.52727) (xy 374.484126 -239.481994) (xy 374.510429 -239.440398) (xy 374.543064 -239.403561)
			(xy 374.581185 -239.372436) (xy 374.623806 -239.347829) (xy 374.669822 -239.330377) (xy 374.718041 -239.320533)
			(xy 374.767216 -239.318552) (xy 374.816071 -239.324484) (xy 374.863342 -239.338176) (xy 374.907804 -239.359274)
			(xy 374.948307 -239.38723) (xy 374.9838 -239.421322) (xy 375.013365 -239.460666) (xy 375.036236 -239.504243)
			(xy 375.05182 -239.550924) (xy 375.059715 -239.599501) (xy 375.06021 -239.624108) (xy 375.378467 -239.624108)
			(xy 375.382562 -239.57338) (xy 375.394741 -239.523966) (xy 375.414689 -239.477146) (xy 375.44189 -239.434132)
			(xy 375.475638 -239.396038) (xy 375.51506 -239.363851) (xy 375.559134 -239.338405) (xy 375.60672 -239.320358)
			(xy 375.656584 -239.310178) (xy 375.707436 -239.308129) (xy 375.757957 -239.314263) (xy 375.806841 -239.328423)
			(xy 375.85282 -239.35024) (xy 375.894704 -239.37915) (xy 375.931408 -239.414405) (xy 375.961981 -239.455091)
			(xy 375.985632 -239.500154) (xy 376.001748 -239.548428) (xy 376.009912 -239.598662) (xy 376.010424 -239.624108)
			(xy 376.328952 -239.624108) (xy 376.332912 -239.575054) (xy 376.344689 -239.52727) (xy 376.36398 -239.481994)
			(xy 376.390283 -239.440398) (xy 376.422918 -239.403561) (xy 376.461039 -239.372436) (xy 376.50366 -239.347829)
			(xy 376.549676 -239.330377) (xy 376.597895 -239.320533) (xy 376.64707 -239.318552) (xy 376.695925 -239.324484)
			(xy 376.743196 -239.338176) (xy 376.787658 -239.359274) (xy 376.828161 -239.38723) (xy 376.863654 -239.421322)
			(xy 376.893219 -239.460666) (xy 376.91609 -239.504243) (xy 376.931674 -239.550924) (xy 376.939569 -239.599501)
			(xy 376.940064 -239.624108) (xy 376.939569 -239.648715) (xy 376.931674 -239.697292) (xy 376.91609 -239.743973)
			(xy 376.893219 -239.78755) (xy 376.863654 -239.826894) (xy 376.828161 -239.860986) (xy 376.787658 -239.888942)
			(xy 376.743196 -239.91004) (xy 376.695925 -239.923732) (xy 376.64707 -239.929664) (xy 376.597895 -239.927683)
			(xy 376.549676 -239.917839) (xy 376.50366 -239.900387) (xy 376.461039 -239.87578) (xy 376.422918 -239.844655)
			(xy 376.390283 -239.807818) (xy 376.36398 -239.766222) (xy 376.344689 -239.720946) (xy 376.332912 -239.673162)
			(xy 376.328952 -239.624108) (xy 376.010424 -239.624108) (xy 376.009912 -239.649554) (xy 376.001748 -239.699788)
			(xy 375.985632 -239.748062) (xy 375.961981 -239.793125) (xy 375.931408 -239.833811) (xy 375.894704 -239.869066)
			(xy 375.85282 -239.897976) (xy 375.806841 -239.919793) (xy 375.757957 -239.933953) (xy 375.707436 -239.940087)
			(xy 375.656584 -239.938038) (xy 375.60672 -239.927858) (xy 375.559134 -239.909811) (xy 375.51506 -239.884365)
			(xy 375.475638 -239.852178) (xy 375.44189 -239.814084) (xy 375.414689 -239.77107) (xy 375.394741 -239.72425)
			(xy 375.382562 -239.674836) (xy 375.378467 -239.624108) (xy 375.06021 -239.624108) (xy 375.059715 -239.648715)
			(xy 375.05182 -239.697292) (xy 375.036236 -239.743973) (xy 375.013365 -239.78755) (xy 374.9838 -239.826894)
			(xy 374.948307 -239.860986) (xy 374.907804 -239.888942) (xy 374.863342 -239.91004) (xy 374.816071 -239.923732)
			(xy 374.767216 -239.929664) (xy 374.718041 -239.927683) (xy 374.669822 -239.917839) (xy 374.623806 -239.900387)
			(xy 374.581185 -239.87578) (xy 374.543064 -239.844655) (xy 374.510429 -239.807818) (xy 374.484126 -239.766222)
			(xy 374.464835 -239.720946) (xy 374.453058 -239.673162) (xy 374.449098 -239.624108) (xy 374.120156 -239.624108)
			(xy 374.119661 -239.648715) (xy 374.111766 -239.697292) (xy 374.096182 -239.743973) (xy 374.073311 -239.78755)
			(xy 374.043746 -239.826894) (xy 374.008253 -239.860986) (xy 373.96775 -239.888942) (xy 373.923288 -239.91004)
			(xy 373.876017 -239.923732) (xy 373.827162 -239.929664) (xy 373.777987 -239.927683) (xy 373.729768 -239.917839)
			(xy 373.683752 -239.900387) (xy 373.641131 -239.87578) (xy 373.60301 -239.844655) (xy 373.570375 -239.807818)
			(xy 373.544072 -239.766222) (xy 373.524781 -239.720946) (xy 373.513004 -239.673162) (xy 373.509044 -239.624108)
			(xy 373.180102 -239.624108) (xy 373.179607 -239.648715) (xy 373.171712 -239.697292) (xy 373.156128 -239.743973)
			(xy 373.133257 -239.78755) (xy 373.103692 -239.826894) (xy 373.068199 -239.860986) (xy 373.027696 -239.888942)
			(xy 372.983234 -239.91004) (xy 372.935963 -239.923732) (xy 372.887108 -239.929664) (xy 372.837933 -239.927683)
			(xy 372.789714 -239.917839) (xy 372.743698 -239.900387) (xy 372.701077 -239.87578) (xy 372.662956 -239.844655)
			(xy 372.630321 -239.807818) (xy 372.604018 -239.766222) (xy 372.584727 -239.720946) (xy 372.57295 -239.673162)
			(xy 372.56899 -239.624108) (xy 372.240048 -239.624108) (xy 372.239553 -239.648715) (xy 372.231658 -239.697292)
			(xy 372.216074 -239.743973) (xy 372.193203 -239.78755) (xy 372.163638 -239.826894) (xy 372.128145 -239.860986)
			(xy 372.087642 -239.888942) (xy 372.04318 -239.91004) (xy 371.995909 -239.923732) (xy 371.947054 -239.929664)
			(xy 371.897879 -239.927683) (xy 371.84966 -239.917839) (xy 371.803644 -239.900387) (xy 371.761023 -239.87578)
			(xy 371.722902 -239.844655) (xy 371.690267 -239.807818) (xy 371.663964 -239.766222) (xy 371.644673 -239.720946)
			(xy 371.632896 -239.673162) (xy 371.628936 -239.624108) (xy 371.299994 -239.624108) (xy 371.299499 -239.648715)
			(xy 371.291604 -239.697292) (xy 371.27602 -239.743973) (xy 371.253149 -239.78755) (xy 371.223584 -239.826894)
			(xy 371.188091 -239.860986) (xy 371.147588 -239.888942) (xy 371.103126 -239.91004) (xy 371.055855 -239.923732)
			(xy 371.007 -239.929664) (xy 370.957825 -239.927683) (xy 370.909606 -239.917839) (xy 370.86359 -239.900387)
			(xy 370.820969 -239.87578) (xy 370.782848 -239.844655) (xy 370.750213 -239.807818) (xy 370.72391 -239.766222)
			(xy 370.704619 -239.720946) (xy 370.692842 -239.673162) (xy 370.688882 -239.624108) (xy 370.360194 -239.624108)
			(xy 370.359699 -239.648715) (xy 370.351804 -239.697292) (xy 370.33622 -239.743973) (xy 370.313349 -239.78755)
			(xy 370.283784 -239.826894) (xy 370.248291 -239.860986) (xy 370.207788 -239.888942) (xy 370.163326 -239.91004)
			(xy 370.116055 -239.923732) (xy 370.0672 -239.929664) (xy 370.018025 -239.927683) (xy 369.969806 -239.917839)
			(xy 369.92379 -239.900387) (xy 369.881169 -239.87578) (xy 369.843048 -239.844655) (xy 369.810413 -239.807818)
			(xy 369.78411 -239.766222) (xy 369.764819 -239.720946) (xy 369.753042 -239.673162) (xy 369.749082 -239.624108)
			(xy 369.42014 -239.624108) (xy 369.419645 -239.648715) (xy 369.41175 -239.697292) (xy 369.396166 -239.743973)
			(xy 369.373295 -239.78755) (xy 369.34373 -239.826894) (xy 369.308237 -239.860986) (xy 369.267734 -239.888942)
			(xy 369.223272 -239.91004) (xy 369.176001 -239.923732) (xy 369.127146 -239.929664) (xy 369.077971 -239.927683)
			(xy 369.029752 -239.917839) (xy 368.983736 -239.900387) (xy 368.941115 -239.87578) (xy 368.902994 -239.844655)
			(xy 368.870359 -239.807818) (xy 368.844056 -239.766222) (xy 368.824765 -239.720946) (xy 368.812988 -239.673162)
			(xy 368.809028 -239.624108) (xy 368.480086 -239.624108) (xy 368.479591 -239.648715) (xy 368.471696 -239.697292)
			(xy 368.456112 -239.743973) (xy 368.433241 -239.78755) (xy 368.403676 -239.826894) (xy 368.368183 -239.860986)
			(xy 368.32768 -239.888942) (xy 368.283218 -239.91004) (xy 368.235947 -239.923732) (xy 368.187092 -239.929664)
			(xy 368.137917 -239.927683) (xy 368.089698 -239.917839) (xy 368.043682 -239.900387) (xy 368.001061 -239.87578)
			(xy 367.96294 -239.844655) (xy 367.930305 -239.807818) (xy 367.904002 -239.766222) (xy 367.884711 -239.720946)
			(xy 367.872934 -239.673162) (xy 367.868974 -239.624108) (xy 367.540032 -239.624108) (xy 367.539537 -239.648715)
			(xy 367.531642 -239.697292) (xy 367.516058 -239.743973) (xy 367.493187 -239.78755) (xy 367.463622 -239.826894)
			(xy 367.428129 -239.860986) (xy 367.387626 -239.888942) (xy 367.343164 -239.91004) (xy 367.295893 -239.923732)
			(xy 367.247038 -239.929664) (xy 367.197863 -239.927683) (xy 367.149644 -239.917839) (xy 367.103628 -239.900387)
			(xy 367.061007 -239.87578) (xy 367.022886 -239.844655) (xy 366.990251 -239.807818) (xy 366.963948 -239.766222)
			(xy 366.944657 -239.720946) (xy 366.93288 -239.673162) (xy 366.92892 -239.624108) (xy 366.600232 -239.624108)
			(xy 366.599737 -239.648715) (xy 366.591842 -239.697292) (xy 366.576258 -239.743973) (xy 366.553387 -239.78755)
			(xy 366.523822 -239.826894) (xy 366.488329 -239.860986) (xy 366.447826 -239.888942) (xy 366.403364 -239.91004)
			(xy 366.356093 -239.923732) (xy 366.307238 -239.929664) (xy 366.258063 -239.927683) (xy 366.209844 -239.917839)
			(xy 366.163828 -239.900387) (xy 366.121207 -239.87578) (xy 366.083086 -239.844655) (xy 366.050451 -239.807818)
			(xy 366.024148 -239.766222) (xy 366.004857 -239.720946) (xy 365.99308 -239.673162) (xy 365.98912 -239.624108)
			(xy 365.660178 -239.624108) (xy 365.659683 -239.648715) (xy 365.651788 -239.697292) (xy 365.636204 -239.743973)
			(xy 365.613333 -239.78755) (xy 365.583768 -239.826894) (xy 365.548275 -239.860986) (xy 365.507772 -239.888942)
			(xy 365.46331 -239.91004) (xy 365.416039 -239.923732) (xy 365.367184 -239.929664) (xy 365.318009 -239.927683)
			(xy 365.26979 -239.917839) (xy 365.223774 -239.900387) (xy 365.181153 -239.87578) (xy 365.143032 -239.844655)
			(xy 365.110397 -239.807818) (xy 365.084094 -239.766222) (xy 365.064803 -239.720946) (xy 365.053026 -239.673162)
			(xy 365.049066 -239.624108) (xy 364.720124 -239.624108) (xy 364.719629 -239.648715) (xy 364.711734 -239.697292)
			(xy 364.69615 -239.743973) (xy 364.673279 -239.78755) (xy 364.643714 -239.826894) (xy 364.608221 -239.860986)
			(xy 364.567718 -239.888942) (xy 364.523256 -239.91004) (xy 364.475985 -239.923732) (xy 364.42713 -239.929664)
			(xy 364.377955 -239.927683) (xy 364.329736 -239.917839) (xy 364.28372 -239.900387) (xy 364.241099 -239.87578)
			(xy 364.202978 -239.844655) (xy 364.170343 -239.807818) (xy 364.14404 -239.766222) (xy 364.124749 -239.720946)
			(xy 364.112972 -239.673162) (xy 364.109012 -239.624108) (xy 363.78007 -239.624108) (xy 363.779575 -239.648715)
			(xy 363.77168 -239.697292) (xy 363.756096 -239.743973) (xy 363.733225 -239.78755) (xy 363.70366 -239.826894)
			(xy 363.668167 -239.860986) (xy 363.627664 -239.888942) (xy 363.583202 -239.91004) (xy 363.535931 -239.923732)
			(xy 363.487076 -239.929664) (xy 363.437901 -239.927683) (xy 363.389682 -239.917839) (xy 363.343666 -239.900387)
			(xy 363.301045 -239.87578) (xy 363.262924 -239.844655) (xy 363.230289 -239.807818) (xy 363.203986 -239.766222)
			(xy 363.184695 -239.720946) (xy 363.172918 -239.673162) (xy 363.168958 -239.624108) (xy 356.266496 -239.624108)
			(xy 356.266001 -239.648715) (xy 356.258106 -239.697292) (xy 356.242522 -239.743973) (xy 356.219651 -239.78755)
			(xy 356.190086 -239.826894) (xy 356.154593 -239.860986) (xy 356.11409 -239.888942) (xy 356.069628 -239.91004)
			(xy 356.022357 -239.923732) (xy 355.973502 -239.929664) (xy 355.924327 -239.927683) (xy 355.876108 -239.917839)
			(xy 355.830092 -239.900387) (xy 355.787471 -239.87578) (xy 355.74935 -239.844655) (xy 355.716715 -239.807818)
			(xy 355.690412 -239.766222) (xy 355.671121 -239.720946) (xy 355.659344 -239.673162) (xy 355.655384 -239.624108)
			(xy 355.326442 -239.624108) (xy 355.325947 -239.648715) (xy 355.318052 -239.697292) (xy 355.302468 -239.743973)
			(xy 355.279597 -239.78755) (xy 355.250032 -239.826894) (xy 355.214539 -239.860986) (xy 355.174036 -239.888942)
			(xy 355.129574 -239.91004) (xy 355.082303 -239.923732) (xy 355.033448 -239.929664) (xy 354.984273 -239.927683)
			(xy 354.936054 -239.917839) (xy 354.890038 -239.900387) (xy 354.847417 -239.87578) (xy 354.809296 -239.844655)
			(xy 354.776661 -239.807818) (xy 354.750358 -239.766222) (xy 354.731067 -239.720946) (xy 354.71929 -239.673162)
			(xy 354.71533 -239.624108) (xy 354.386388 -239.624108) (xy 354.385893 -239.648715) (xy 354.377998 -239.697292)
			(xy 354.362414 -239.743973) (xy 354.339543 -239.78755) (xy 354.309978 -239.826894) (xy 354.274485 -239.860986)
			(xy 354.233982 -239.888942) (xy 354.18952 -239.91004) (xy 354.142249 -239.923732) (xy 354.093394 -239.929664)
			(xy 354.044219 -239.927683) (xy 353.996 -239.917839) (xy 353.949984 -239.900387) (xy 353.907363 -239.87578)
			(xy 353.869242 -239.844655) (xy 353.836607 -239.807818) (xy 353.810304 -239.766222) (xy 353.791013 -239.720946)
			(xy 353.779236 -239.673162) (xy 353.775276 -239.624108) (xy 353.446334 -239.624108) (xy 353.445839 -239.648715)
			(xy 353.437944 -239.697292) (xy 353.42236 -239.743973) (xy 353.399489 -239.78755) (xy 353.369924 -239.826894)
			(xy 353.334431 -239.860986) (xy 353.293928 -239.888942) (xy 353.249466 -239.91004) (xy 353.202195 -239.923732)
			(xy 353.15334 -239.929664) (xy 353.104165 -239.927683) (xy 353.055946 -239.917839) (xy 353.00993 -239.900387)
			(xy 352.967309 -239.87578) (xy 352.929188 -239.844655) (xy 352.896553 -239.807818) (xy 352.87025 -239.766222)
			(xy 352.850959 -239.720946) (xy 352.839182 -239.673162) (xy 352.835222 -239.624108) (xy 352.506534 -239.624108)
			(xy 352.506039 -239.648715) (xy 352.498144 -239.697292) (xy 352.48256 -239.743973) (xy 352.459689 -239.78755)
			(xy 352.430124 -239.826894) (xy 352.394631 -239.860986) (xy 352.354128 -239.888942) (xy 352.309666 -239.91004)
			(xy 352.262395 -239.923732) (xy 352.21354 -239.929664) (xy 352.164365 -239.927683) (xy 352.116146 -239.917839)
			(xy 352.07013 -239.900387) (xy 352.027509 -239.87578) (xy 351.989388 -239.844655) (xy 351.956753 -239.807818)
			(xy 351.93045 -239.766222) (xy 351.911159 -239.720946) (xy 351.899382 -239.673162) (xy 351.895422 -239.624108)
			(xy 351.56648 -239.624108) (xy 351.565985 -239.648715) (xy 351.55809 -239.697292) (xy 351.542506 -239.743973)
			(xy 351.519635 -239.78755) (xy 351.49007 -239.826894) (xy 351.454577 -239.860986) (xy 351.414074 -239.888942)
			(xy 351.369612 -239.91004) (xy 351.322341 -239.923732) (xy 351.273486 -239.929664) (xy 351.224311 -239.927683)
			(xy 351.176092 -239.917839) (xy 351.130076 -239.900387) (xy 351.087455 -239.87578) (xy 351.049334 -239.844655)
			(xy 351.016699 -239.807818) (xy 350.990396 -239.766222) (xy 350.971105 -239.720946) (xy 350.959328 -239.673162)
			(xy 350.955368 -239.624108) (xy 350.626426 -239.624108) (xy 350.625931 -239.648715) (xy 350.618036 -239.697292)
			(xy 350.602452 -239.743973) (xy 350.579581 -239.78755) (xy 350.550016 -239.826894) (xy 350.514523 -239.860986)
			(xy 350.47402 -239.888942) (xy 350.429558 -239.91004) (xy 350.382287 -239.923732) (xy 350.333432 -239.929664)
			(xy 350.284257 -239.927683) (xy 350.236038 -239.917839) (xy 350.190022 -239.900387) (xy 350.147401 -239.87578)
			(xy 350.10928 -239.844655) (xy 350.076645 -239.807818) (xy 350.050342 -239.766222) (xy 350.031051 -239.720946)
			(xy 350.019274 -239.673162) (xy 350.015314 -239.624108) (xy 349.686372 -239.624108) (xy 349.685877 -239.648715)
			(xy 349.677982 -239.697292) (xy 349.662398 -239.743973) (xy 349.639527 -239.78755) (xy 349.609962 -239.826894)
			(xy 349.574469 -239.860986) (xy 349.533966 -239.888942) (xy 349.489504 -239.91004) (xy 349.442233 -239.923732)
			(xy 349.393378 -239.929664) (xy 349.344203 -239.927683) (xy 349.295984 -239.917839) (xy 349.249968 -239.900387)
			(xy 349.207347 -239.87578) (xy 349.169226 -239.844655) (xy 349.136591 -239.807818) (xy 349.110288 -239.766222)
			(xy 349.090997 -239.720946) (xy 349.07922 -239.673162) (xy 349.07526 -239.624108) (xy 348.746318 -239.624108)
			(xy 348.745823 -239.648715) (xy 348.737928 -239.697292) (xy 348.722344 -239.743973) (xy 348.699473 -239.78755)
			(xy 348.669908 -239.826894) (xy 348.634415 -239.860986) (xy 348.593912 -239.888942) (xy 348.54945 -239.91004)
			(xy 348.502179 -239.923732) (xy 348.453324 -239.929664) (xy 348.404149 -239.927683) (xy 348.35593 -239.917839)
			(xy 348.309914 -239.900387) (xy 348.267293 -239.87578) (xy 348.229172 -239.844655) (xy 348.196537 -239.807818)
			(xy 348.170234 -239.766222) (xy 348.150943 -239.720946) (xy 348.139166 -239.673162) (xy 348.135206 -239.624108)
			(xy 347.806518 -239.624108) (xy 347.806023 -239.648715) (xy 347.798128 -239.697292) (xy 347.782544 -239.743973)
			(xy 347.759673 -239.78755) (xy 347.730108 -239.826894) (xy 347.694615 -239.860986) (xy 347.654112 -239.888942)
			(xy 347.60965 -239.91004) (xy 347.562379 -239.923732) (xy 347.513524 -239.929664) (xy 347.464349 -239.927683)
			(xy 347.41613 -239.917839) (xy 347.370114 -239.900387) (xy 347.327493 -239.87578) (xy 347.289372 -239.844655)
			(xy 347.256737 -239.807818) (xy 347.230434 -239.766222) (xy 347.211143 -239.720946) (xy 347.199366 -239.673162)
			(xy 347.195406 -239.624108) (xy 346.866464 -239.624108) (xy 346.865969 -239.648715) (xy 346.858074 -239.697292)
			(xy 346.84249 -239.743973) (xy 346.819619 -239.78755) (xy 346.790054 -239.826894) (xy 346.754561 -239.860986)
			(xy 346.714058 -239.888942) (xy 346.669596 -239.91004) (xy 346.622325 -239.923732) (xy 346.57347 -239.929664)
			(xy 346.524295 -239.927683) (xy 346.476076 -239.917839) (xy 346.43006 -239.900387) (xy 346.387439 -239.87578)
			(xy 346.349318 -239.844655) (xy 346.316683 -239.807818) (xy 346.29038 -239.766222) (xy 346.271089 -239.720946)
			(xy 346.259312 -239.673162) (xy 346.255352 -239.624108) (xy 345.92641 -239.624108) (xy 345.925915 -239.648715)
			(xy 345.91802 -239.697292) (xy 345.902436 -239.743973) (xy 345.879565 -239.78755) (xy 345.85 -239.826894)
			(xy 345.814507 -239.860986) (xy 345.774004 -239.888942) (xy 345.729542 -239.91004) (xy 345.682271 -239.923732)
			(xy 345.633416 -239.929664) (xy 345.584241 -239.927683) (xy 345.536022 -239.917839) (xy 345.490006 -239.900387)
			(xy 345.447385 -239.87578) (xy 345.409264 -239.844655) (xy 345.376629 -239.807818) (xy 345.350326 -239.766222)
			(xy 345.331035 -239.720946) (xy 345.319258 -239.673162) (xy 345.315298 -239.624108) (xy 344.986356 -239.624108)
			(xy 344.985861 -239.648715) (xy 344.977966 -239.697292) (xy 344.962382 -239.743973) (xy 344.939511 -239.78755)
			(xy 344.909946 -239.826894) (xy 344.874453 -239.860986) (xy 344.83395 -239.888942) (xy 344.789488 -239.91004)
			(xy 344.742217 -239.923732) (xy 344.693362 -239.929664) (xy 344.644187 -239.927683) (xy 344.595968 -239.917839)
			(xy 344.549952 -239.900387) (xy 344.507331 -239.87578) (xy 344.46921 -239.844655) (xy 344.436575 -239.807818)
			(xy 344.410272 -239.766222) (xy 344.390981 -239.720946) (xy 344.379204 -239.673162) (xy 344.375244 -239.624108)
			(xy 344.056716 -239.624108) (xy 344.056204 -239.649554) (xy 344.04804 -239.699788) (xy 344.031924 -239.748062)
			(xy 344.008273 -239.793125) (xy 343.9777 -239.833811) (xy 343.940996 -239.869066) (xy 343.899112 -239.897976)
			(xy 343.853133 -239.919793) (xy 343.804249 -239.933953) (xy 343.753728 -239.940087) (xy 343.702876 -239.938038)
			(xy 343.653012 -239.927858) (xy 343.605426 -239.909811) (xy 343.561352 -239.884365) (xy 343.52193 -239.852178)
			(xy 343.488182 -239.814084) (xy 343.460981 -239.77107) (xy 343.441033 -239.72425) (xy 343.428854 -239.674836)
			(xy 343.424759 -239.624108) (xy 343.106502 -239.624108) (xy 343.106007 -239.648715) (xy 343.098112 -239.697292)
			(xy 343.082528 -239.743973) (xy 343.059657 -239.78755) (xy 343.030092 -239.826894) (xy 342.994599 -239.860986)
			(xy 342.954096 -239.888942) (xy 342.909634 -239.91004) (xy 342.862363 -239.923732) (xy 342.813508 -239.929664)
			(xy 342.764333 -239.927683) (xy 342.716114 -239.917839) (xy 342.670098 -239.900387) (xy 342.627477 -239.87578)
			(xy 342.589356 -239.844655) (xy 342.556721 -239.807818) (xy 342.530418 -239.766222) (xy 342.511127 -239.720946)
			(xy 342.49935 -239.673162) (xy 342.49539 -239.624108) (xy 342.176862 -239.624108) (xy 342.17635 -239.649554)
			(xy 342.168186 -239.699788) (xy 342.15207 -239.748062) (xy 342.128419 -239.793125) (xy 342.097846 -239.833811)
			(xy 342.061142 -239.869066) (xy 342.019258 -239.897976) (xy 341.973279 -239.919793) (xy 341.924395 -239.933953)
			(xy 341.873874 -239.940087) (xy 341.823022 -239.938038) (xy 341.773158 -239.927858) (xy 341.725572 -239.909811)
			(xy 341.681498 -239.884365) (xy 341.642076 -239.852178) (xy 341.608328 -239.814084) (xy 341.581127 -239.77107)
			(xy 341.561179 -239.72425) (xy 341.549 -239.674836) (xy 341.544905 -239.624108) (xy 341.233252 -239.624108)
			(xy 341.233252 -240.031016) (xy 341.233816 -240.041707) (xy 341.242479 -240.061259) (xy 341.250016 -240.068862)
			(xy 341.250524 -240.069116) (xy 341.316564 -240.126774) (xy 341.327232 -240.129822) (xy 341.3379 -240.133124)
			(xy 341.348822 -240.1316) (xy 341.359312 -240.130267) (xy 341.380412 -240.128868) (xy 341.390986 -240.128806)
			(xy 341.416243 -240.129298) (xy 341.466069 -240.13761) (xy 341.513847 -240.15401) (xy 341.558274 -240.178051)
			(xy 341.598138 -240.209077) (xy 341.632352 -240.246241) (xy 341.659981 -240.288529) (xy 341.680273 -240.334789)
			(xy 341.692674 -240.383758) (xy 341.696846 -240.4341) (xy 341.696845 -240.434114) (xy 342.014805 -240.434114)
			(xy 342.0189 -240.383386) (xy 342.031079 -240.333972) (xy 342.051027 -240.287152) (xy 342.078228 -240.244138)
			(xy 342.111976 -240.206044) (xy 342.151398 -240.173857) (xy 342.195472 -240.148411) (xy 342.243058 -240.130364)
			(xy 342.292922 -240.120184) (xy 342.343774 -240.118135) (xy 342.394295 -240.124269) (xy 342.443179 -240.138429)
			(xy 342.489158 -240.160246) (xy 342.531042 -240.189156) (xy 342.567746 -240.224411) (xy 342.598319 -240.265097)
			(xy 342.62197 -240.31016) (xy 342.638086 -240.358434) (xy 342.64625 -240.408668) (xy 342.646762 -240.434114)
			(xy 342.954859 -240.434114) (xy 342.958954 -240.383386) (xy 342.971133 -240.333972) (xy 342.991081 -240.287152)
			(xy 343.018282 -240.244138) (xy 343.05203 -240.206044) (xy 343.091452 -240.173857) (xy 343.135526 -240.148411)
			(xy 343.183112 -240.130364) (xy 343.232976 -240.120184) (xy 343.283828 -240.118135) (xy 343.334349 -240.124269)
			(xy 343.383233 -240.138429) (xy 343.429212 -240.160246) (xy 343.471096 -240.189156) (xy 343.5078 -240.224411)
			(xy 343.538373 -240.265097) (xy 343.562024 -240.31016) (xy 343.57814 -240.358434) (xy 343.586304 -240.408668)
			(xy 343.586816 -240.434114) (xy 343.905344 -240.434114) (xy 343.909304 -240.38506) (xy 343.921081 -240.337276)
			(xy 343.940372 -240.292) (xy 343.966675 -240.250404) (xy 343.99931 -240.213567) (xy 344.037431 -240.182442)
			(xy 344.080052 -240.157835) (xy 344.126068 -240.140383) (xy 344.174287 -240.130539) (xy 344.223462 -240.128558)
			(xy 344.272317 -240.13449) (xy 344.319588 -240.148182) (xy 344.36405 -240.16928) (xy 344.404553 -240.197236)
			(xy 344.440046 -240.231328) (xy 344.469611 -240.270672) (xy 344.492482 -240.314249) (xy 344.508066 -240.36093)
			(xy 344.515961 -240.409507) (xy 344.516456 -240.434114) (xy 344.845398 -240.434114) (xy 344.849358 -240.38506)
			(xy 344.861135 -240.337276) (xy 344.880426 -240.292) (xy 344.906729 -240.250404) (xy 344.939364 -240.213567)
			(xy 344.977485 -240.182442) (xy 345.020106 -240.157835) (xy 345.066122 -240.140383) (xy 345.114341 -240.130539)
			(xy 345.163516 -240.128558) (xy 345.212371 -240.13449) (xy 345.259642 -240.148182) (xy 345.304104 -240.16928)
			(xy 345.344607 -240.197236) (xy 345.3801 -240.231328) (xy 345.409665 -240.270672) (xy 345.432536 -240.314249)
			(xy 345.44812 -240.36093) (xy 345.456015 -240.409507) (xy 345.45651 -240.434114) (xy 345.785198 -240.434114)
			(xy 345.789158 -240.38506) (xy 345.800935 -240.337276) (xy 345.820226 -240.292) (xy 345.846529 -240.250404)
			(xy 345.879164 -240.213567) (xy 345.917285 -240.182442) (xy 345.959906 -240.157835) (xy 346.005922 -240.140383)
			(xy 346.054141 -240.130539) (xy 346.103316 -240.128558) (xy 346.152171 -240.13449) (xy 346.199442 -240.148182)
			(xy 346.243904 -240.16928) (xy 346.284407 -240.197236) (xy 346.3199 -240.231328) (xy 346.349465 -240.270672)
			(xy 346.372336 -240.314249) (xy 346.38792 -240.36093) (xy 346.395815 -240.409507) (xy 346.39631 -240.434114)
			(xy 346.725252 -240.434114) (xy 346.729212 -240.38506) (xy 346.740989 -240.337276) (xy 346.76028 -240.292)
			(xy 346.786583 -240.250404) (xy 346.819218 -240.213567) (xy 346.857339 -240.182442) (xy 346.89996 -240.157835)
			(xy 346.945976 -240.140383) (xy 346.994195 -240.130539) (xy 347.04337 -240.128558) (xy 347.092225 -240.13449)
			(xy 347.139496 -240.148182) (xy 347.183958 -240.16928) (xy 347.224461 -240.197236) (xy 347.259954 -240.231328)
			(xy 347.289519 -240.270672) (xy 347.31239 -240.314249) (xy 347.327974 -240.36093) (xy 347.335869 -240.409507)
			(xy 347.336364 -240.434114) (xy 347.665306 -240.434114) (xy 347.669266 -240.38506) (xy 347.681043 -240.337276)
			(xy 347.700334 -240.292) (xy 347.726637 -240.250404) (xy 347.759272 -240.213567) (xy 347.797393 -240.182442)
			(xy 347.840014 -240.157835) (xy 347.88603 -240.140383) (xy 347.934249 -240.130539) (xy 347.983424 -240.128558)
			(xy 348.032279 -240.13449) (xy 348.07955 -240.148182) (xy 348.124012 -240.16928) (xy 348.164515 -240.197236)
			(xy 348.200008 -240.231328) (xy 348.229573 -240.270672) (xy 348.252444 -240.314249) (xy 348.268028 -240.36093)
			(xy 348.275923 -240.409507) (xy 348.276418 -240.434114) (xy 348.60536 -240.434114) (xy 348.60932 -240.38506)
			(xy 348.621097 -240.337276) (xy 348.640388 -240.292) (xy 348.666691 -240.250404) (xy 348.699326 -240.213567)
			(xy 348.737447 -240.182442) (xy 348.780068 -240.157835) (xy 348.826084 -240.140383) (xy 348.874303 -240.130539)
			(xy 348.923478 -240.128558) (xy 348.972333 -240.13449) (xy 349.019604 -240.148182) (xy 349.064066 -240.16928)
			(xy 349.104569 -240.197236) (xy 349.140062 -240.231328) (xy 349.169627 -240.270672) (xy 349.192498 -240.314249)
			(xy 349.208082 -240.36093) (xy 349.215977 -240.409507) (xy 349.216472 -240.434114) (xy 349.545414 -240.434114)
			(xy 349.549374 -240.38506) (xy 349.561151 -240.337276) (xy 349.580442 -240.292) (xy 349.606745 -240.250404)
			(xy 349.63938 -240.213567) (xy 349.677501 -240.182442) (xy 349.720122 -240.157835) (xy 349.766138 -240.140383)
			(xy 349.814357 -240.130539) (xy 349.863532 -240.128558) (xy 349.912387 -240.13449) (xy 349.959658 -240.148182)
			(xy 350.00412 -240.16928) (xy 350.044623 -240.197236) (xy 350.080116 -240.231328) (xy 350.109681 -240.270672)
			(xy 350.132552 -240.314249) (xy 350.148136 -240.36093) (xy 350.156031 -240.409507) (xy 350.156526 -240.434114)
			(xy 350.485214 -240.434114) (xy 350.489174 -240.38506) (xy 350.500951 -240.337276) (xy 350.520242 -240.292)
			(xy 350.546545 -240.250404) (xy 350.57918 -240.213567) (xy 350.617301 -240.182442) (xy 350.659922 -240.157835)
			(xy 350.705938 -240.140383) (xy 350.754157 -240.130539) (xy 350.803332 -240.128558) (xy 350.852187 -240.13449)
			(xy 350.899458 -240.148182) (xy 350.94392 -240.16928) (xy 350.984423 -240.197236) (xy 351.019916 -240.231328)
			(xy 351.049481 -240.270672) (xy 351.072352 -240.314249) (xy 351.087936 -240.36093) (xy 351.095831 -240.409507)
			(xy 351.096326 -240.434114) (xy 351.425268 -240.434114) (xy 351.429228 -240.38506) (xy 351.441005 -240.337276)
			(xy 351.460296 -240.292) (xy 351.486599 -240.250404) (xy 351.519234 -240.213567) (xy 351.557355 -240.182442)
			(xy 351.599976 -240.157835) (xy 351.645992 -240.140383) (xy 351.694211 -240.130539) (xy 351.743386 -240.128558)
			(xy 351.792241 -240.13449) (xy 351.839512 -240.148182) (xy 351.883974 -240.16928) (xy 351.924477 -240.197236)
			(xy 351.95997 -240.231328) (xy 351.989535 -240.270672) (xy 352.012406 -240.314249) (xy 352.02799 -240.36093)
			(xy 352.035885 -240.409507) (xy 352.03638 -240.434114) (xy 352.365322 -240.434114) (xy 352.369282 -240.38506)
			(xy 352.381059 -240.337276) (xy 352.40035 -240.292) (xy 352.426653 -240.250404) (xy 352.459288 -240.213567)
			(xy 352.497409 -240.182442) (xy 352.54003 -240.157835) (xy 352.586046 -240.140383) (xy 352.634265 -240.130539)
			(xy 352.68344 -240.128558) (xy 352.732295 -240.13449) (xy 352.779566 -240.148182) (xy 352.824028 -240.16928)
			(xy 352.864531 -240.197236) (xy 352.900024 -240.231328) (xy 352.929589 -240.270672) (xy 352.95246 -240.314249)
			(xy 352.968044 -240.36093) (xy 352.975939 -240.409507) (xy 352.976434 -240.434114) (xy 353.305376 -240.434114)
			(xy 353.309336 -240.38506) (xy 353.321113 -240.337276) (xy 353.340404 -240.292) (xy 353.366707 -240.250404)
			(xy 353.399342 -240.213567) (xy 353.437463 -240.182442) (xy 353.480084 -240.157835) (xy 353.5261 -240.140383)
			(xy 353.574319 -240.130539) (xy 353.623494 -240.128558) (xy 353.672349 -240.13449) (xy 353.71962 -240.148182)
			(xy 353.764082 -240.16928) (xy 353.804585 -240.197236) (xy 353.840078 -240.231328) (xy 353.869643 -240.270672)
			(xy 353.892514 -240.314249) (xy 353.908098 -240.36093) (xy 353.915993 -240.409507) (xy 353.916488 -240.434114)
			(xy 354.24543 -240.434114) (xy 354.24939 -240.38506) (xy 354.261167 -240.337276) (xy 354.280458 -240.292)
			(xy 354.306761 -240.250404) (xy 354.339396 -240.213567) (xy 354.377517 -240.182442) (xy 354.420138 -240.157835)
			(xy 354.466154 -240.140383) (xy 354.514373 -240.130539) (xy 354.563548 -240.128558) (xy 354.612403 -240.13449)
			(xy 354.659674 -240.148182) (xy 354.704136 -240.16928) (xy 354.744639 -240.197236) (xy 354.780132 -240.231328)
			(xy 354.809697 -240.270672) (xy 354.832568 -240.314249) (xy 354.848152 -240.36093) (xy 354.856047 -240.409507)
			(xy 354.856542 -240.434114) (xy 355.18523 -240.434114) (xy 355.18919 -240.38506) (xy 355.200967 -240.337276)
			(xy 355.220258 -240.292) (xy 355.246561 -240.250404) (xy 355.279196 -240.213567) (xy 355.317317 -240.182442)
			(xy 355.359938 -240.157835) (xy 355.405954 -240.140383) (xy 355.454173 -240.130539) (xy 355.503348 -240.128558)
			(xy 355.552203 -240.13449) (xy 355.599474 -240.148182) (xy 355.643936 -240.16928) (xy 355.684439 -240.197236)
			(xy 355.719932 -240.231328) (xy 355.749497 -240.270672) (xy 355.772368 -240.314249) (xy 355.787952 -240.36093)
			(xy 355.795847 -240.409507) (xy 355.796342 -240.434114) (xy 356.125284 -240.434114) (xy 356.129244 -240.38506)
			(xy 356.141021 -240.337276) (xy 356.160312 -240.292) (xy 356.186615 -240.250404) (xy 356.21925 -240.213567)
			(xy 356.257371 -240.182442) (xy 356.299992 -240.157835) (xy 356.346008 -240.140383) (xy 356.394227 -240.130539)
			(xy 356.443402 -240.128558) (xy 356.492257 -240.13449) (xy 356.539528 -240.148182) (xy 356.58399 -240.16928)
			(xy 356.624493 -240.197236) (xy 356.659986 -240.231328) (xy 356.689551 -240.270672) (xy 356.712422 -240.314249)
			(xy 356.728006 -240.36093) (xy 356.735901 -240.409507) (xy 356.736396 -240.434114) (xy 357.065338 -240.434114)
			(xy 357.069298 -240.38506) (xy 357.081075 -240.337276) (xy 357.100366 -240.292) (xy 357.126669 -240.250404)
			(xy 357.159304 -240.213567) (xy 357.197425 -240.182442) (xy 357.240046 -240.157835) (xy 357.286062 -240.140383)
			(xy 357.334281 -240.130539) (xy 357.383456 -240.128558) (xy 357.432311 -240.13449) (xy 357.479582 -240.148182)
			(xy 357.524044 -240.16928) (xy 357.564547 -240.197236) (xy 357.60004 -240.231328) (xy 357.629605 -240.270672)
			(xy 357.652476 -240.314249) (xy 357.66806 -240.36093) (xy 357.675955 -240.409507) (xy 357.67645 -240.434114)
			(xy 358.005392 -240.434114) (xy 358.009352 -240.38506) (xy 358.021129 -240.337276) (xy 358.04042 -240.292)
			(xy 358.066723 -240.250404) (xy 358.099358 -240.213567) (xy 358.137479 -240.182442) (xy 358.1801 -240.157835)
			(xy 358.226116 -240.140383) (xy 358.274335 -240.130539) (xy 358.32351 -240.128558) (xy 358.372365 -240.13449)
			(xy 358.419636 -240.148182) (xy 358.464098 -240.16928) (xy 358.504601 -240.197236) (xy 358.540094 -240.231328)
			(xy 358.569659 -240.270672) (xy 358.59253 -240.314249) (xy 358.608114 -240.36093) (xy 358.616009 -240.409507)
			(xy 358.616504 -240.434114) (xy 360.81895 -240.434114) (xy 360.82291 -240.38506) (xy 360.834687 -240.337276)
			(xy 360.853978 -240.292) (xy 360.880281 -240.250404) (xy 360.912916 -240.213567) (xy 360.951037 -240.182442)
			(xy 360.993658 -240.157835) (xy 361.039674 -240.140383) (xy 361.087893 -240.130539) (xy 361.137068 -240.128558)
			(xy 361.185923 -240.13449) (xy 361.233194 -240.148182) (xy 361.277656 -240.16928) (xy 361.318159 -240.197236)
			(xy 361.353652 -240.231328) (xy 361.383217 -240.270672) (xy 361.406088 -240.314249) (xy 361.421672 -240.36093)
			(xy 361.429567 -240.409507) (xy 361.430062 -240.434114) (xy 361.759004 -240.434114) (xy 361.762964 -240.38506)
			(xy 361.774741 -240.337276) (xy 361.794032 -240.292) (xy 361.820335 -240.250404) (xy 361.85297 -240.213567)
			(xy 361.891091 -240.182442) (xy 361.933712 -240.157835) (xy 361.979728 -240.140383) (xy 362.027947 -240.130539)
			(xy 362.077122 -240.128558) (xy 362.125977 -240.13449) (xy 362.173248 -240.148182) (xy 362.21771 -240.16928)
			(xy 362.258213 -240.197236) (xy 362.293706 -240.231328) (xy 362.323271 -240.270672) (xy 362.346142 -240.314249)
			(xy 362.361726 -240.36093) (xy 362.369621 -240.409507) (xy 362.370116 -240.434114) (xy 362.699058 -240.434114)
			(xy 362.703018 -240.38506) (xy 362.714795 -240.337276) (xy 362.734086 -240.292) (xy 362.760389 -240.250404)
			(xy 362.793024 -240.213567) (xy 362.831145 -240.182442) (xy 362.873766 -240.157835) (xy 362.919782 -240.140383)
			(xy 362.968001 -240.130539) (xy 363.017176 -240.128558) (xy 363.066031 -240.13449) (xy 363.113302 -240.148182)
			(xy 363.157764 -240.16928) (xy 363.198267 -240.197236) (xy 363.23376 -240.231328) (xy 363.263325 -240.270672)
			(xy 363.286196 -240.314249) (xy 363.30178 -240.36093) (xy 363.309675 -240.409507) (xy 363.31017 -240.434114)
			(xy 363.639112 -240.434114) (xy 363.643072 -240.38506) (xy 363.654849 -240.337276) (xy 363.67414 -240.292)
			(xy 363.700443 -240.250404) (xy 363.733078 -240.213567) (xy 363.771199 -240.182442) (xy 363.81382 -240.157835)
			(xy 363.859836 -240.140383) (xy 363.908055 -240.130539) (xy 363.95723 -240.128558) (xy 364.006085 -240.13449)
			(xy 364.053356 -240.148182) (xy 364.097818 -240.16928) (xy 364.138321 -240.197236) (xy 364.173814 -240.231328)
			(xy 364.203379 -240.270672) (xy 364.22625 -240.314249) (xy 364.241834 -240.36093) (xy 364.249729 -240.409507)
			(xy 364.250224 -240.434114) (xy 364.578912 -240.434114) (xy 364.582872 -240.38506) (xy 364.594649 -240.337276)
			(xy 364.61394 -240.292) (xy 364.640243 -240.250404) (xy 364.672878 -240.213567) (xy 364.710999 -240.182442)
			(xy 364.75362 -240.157835) (xy 364.799636 -240.140383) (xy 364.847855 -240.130539) (xy 364.89703 -240.128558)
			(xy 364.945885 -240.13449) (xy 364.993156 -240.148182) (xy 365.037618 -240.16928) (xy 365.078121 -240.197236)
			(xy 365.113614 -240.231328) (xy 365.143179 -240.270672) (xy 365.16605 -240.314249) (xy 365.181634 -240.36093)
			(xy 365.189529 -240.409507) (xy 365.190024 -240.434114) (xy 365.518966 -240.434114) (xy 365.522926 -240.38506)
			(xy 365.534703 -240.337276) (xy 365.553994 -240.292) (xy 365.580297 -240.250404) (xy 365.612932 -240.213567)
			(xy 365.651053 -240.182442) (xy 365.693674 -240.157835) (xy 365.73969 -240.140383) (xy 365.787909 -240.130539)
			(xy 365.837084 -240.128558) (xy 365.885939 -240.13449) (xy 365.93321 -240.148182) (xy 365.977672 -240.16928)
			(xy 366.018175 -240.197236) (xy 366.053668 -240.231328) (xy 366.083233 -240.270672) (xy 366.106104 -240.314249)
			(xy 366.121688 -240.36093) (xy 366.129583 -240.409507) (xy 366.130078 -240.434114) (xy 366.45902 -240.434114)
			(xy 366.46298 -240.38506) (xy 366.474757 -240.337276) (xy 366.494048 -240.292) (xy 366.520351 -240.250404)
			(xy 366.552986 -240.213567) (xy 366.591107 -240.182442) (xy 366.633728 -240.157835) (xy 366.679744 -240.140383)
			(xy 366.727963 -240.130539) (xy 366.777138 -240.128558) (xy 366.825993 -240.13449) (xy 366.873264 -240.148182)
			(xy 366.917726 -240.16928) (xy 366.958229 -240.197236) (xy 366.993722 -240.231328) (xy 367.023287 -240.270672)
			(xy 367.046158 -240.314249) (xy 367.061742 -240.36093) (xy 367.069637 -240.409507) (xy 367.070132 -240.434114)
			(xy 367.399074 -240.434114) (xy 367.403034 -240.38506) (xy 367.414811 -240.337276) (xy 367.434102 -240.292)
			(xy 367.460405 -240.250404) (xy 367.49304 -240.213567) (xy 367.531161 -240.182442) (xy 367.573782 -240.157835)
			(xy 367.619798 -240.140383) (xy 367.668017 -240.130539) (xy 367.717192 -240.128558) (xy 367.766047 -240.13449)
			(xy 367.813318 -240.148182) (xy 367.85778 -240.16928) (xy 367.898283 -240.197236) (xy 367.933776 -240.231328)
			(xy 367.963341 -240.270672) (xy 367.986212 -240.314249) (xy 368.001796 -240.36093) (xy 368.009691 -240.409507)
			(xy 368.010186 -240.434114) (xy 368.338874 -240.434114) (xy 368.342834 -240.38506) (xy 368.354611 -240.337276)
			(xy 368.373902 -240.292) (xy 368.400205 -240.250404) (xy 368.43284 -240.213567) (xy 368.470961 -240.182442)
			(xy 368.513582 -240.157835) (xy 368.559598 -240.140383) (xy 368.607817 -240.130539) (xy 368.656992 -240.128558)
			(xy 368.705847 -240.13449) (xy 368.753118 -240.148182) (xy 368.79758 -240.16928) (xy 368.838083 -240.197236)
			(xy 368.873576 -240.231328) (xy 368.903141 -240.270672) (xy 368.926012 -240.314249) (xy 368.941596 -240.36093)
			(xy 368.949491 -240.409507) (xy 368.949986 -240.434114) (xy 369.278928 -240.434114) (xy 369.282888 -240.38506)
			(xy 369.294665 -240.337276) (xy 369.313956 -240.292) (xy 369.340259 -240.250404) (xy 369.372894 -240.213567)
			(xy 369.411015 -240.182442) (xy 369.453636 -240.157835) (xy 369.499652 -240.140383) (xy 369.547871 -240.130539)
			(xy 369.597046 -240.128558) (xy 369.645901 -240.13449) (xy 369.693172 -240.148182) (xy 369.737634 -240.16928)
			(xy 369.778137 -240.197236) (xy 369.81363 -240.231328) (xy 369.843195 -240.270672) (xy 369.866066 -240.314249)
			(xy 369.88165 -240.36093) (xy 369.889545 -240.409507) (xy 369.89004 -240.434114) (xy 370.218982 -240.434114)
			(xy 370.222942 -240.38506) (xy 370.234719 -240.337276) (xy 370.25401 -240.292) (xy 370.280313 -240.250404)
			(xy 370.312948 -240.213567) (xy 370.351069 -240.182442) (xy 370.39369 -240.157835) (xy 370.439706 -240.140383)
			(xy 370.487925 -240.130539) (xy 370.5371 -240.128558) (xy 370.585955 -240.13449) (xy 370.633226 -240.148182)
			(xy 370.677688 -240.16928) (xy 370.718191 -240.197236) (xy 370.753684 -240.231328) (xy 370.783249 -240.270672)
			(xy 370.80612 -240.314249) (xy 370.821704 -240.36093) (xy 370.829599 -240.409507) (xy 370.830094 -240.434114)
			(xy 371.159036 -240.434114) (xy 371.162996 -240.38506) (xy 371.174773 -240.337276) (xy 371.194064 -240.292)
			(xy 371.220367 -240.250404) (xy 371.253002 -240.213567) (xy 371.291123 -240.182442) (xy 371.333744 -240.157835)
			(xy 371.37976 -240.140383) (xy 371.427979 -240.130539) (xy 371.477154 -240.128558) (xy 371.526009 -240.13449)
			(xy 371.57328 -240.148182) (xy 371.617742 -240.16928) (xy 371.658245 -240.197236) (xy 371.693738 -240.231328)
			(xy 371.723303 -240.270672) (xy 371.746174 -240.314249) (xy 371.761758 -240.36093) (xy 371.769653 -240.409507)
			(xy 371.770148 -240.434114) (xy 372.09909 -240.434114) (xy 372.10305 -240.38506) (xy 372.114827 -240.337276)
			(xy 372.134118 -240.292) (xy 372.160421 -240.250404) (xy 372.193056 -240.213567) (xy 372.231177 -240.182442)
			(xy 372.273798 -240.157835) (xy 372.319814 -240.140383) (xy 372.368033 -240.130539) (xy 372.417208 -240.128558)
			(xy 372.466063 -240.13449) (xy 372.513334 -240.148182) (xy 372.557796 -240.16928) (xy 372.598299 -240.197236)
			(xy 372.633792 -240.231328) (xy 372.663357 -240.270672) (xy 372.686228 -240.314249) (xy 372.701812 -240.36093)
			(xy 372.709707 -240.409507) (xy 372.710202 -240.434114) (xy 373.03889 -240.434114) (xy 373.04285 -240.38506)
			(xy 373.054627 -240.337276) (xy 373.073918 -240.292) (xy 373.100221 -240.250404) (xy 373.132856 -240.213567)
			(xy 373.170977 -240.182442) (xy 373.213598 -240.157835) (xy 373.259614 -240.140383) (xy 373.307833 -240.130539)
			(xy 373.357008 -240.128558) (xy 373.405863 -240.13449) (xy 373.453134 -240.148182) (xy 373.497596 -240.16928)
			(xy 373.538099 -240.197236) (xy 373.573592 -240.231328) (xy 373.603157 -240.270672) (xy 373.626028 -240.314249)
			(xy 373.641612 -240.36093) (xy 373.649507 -240.409507) (xy 373.650002 -240.434114) (xy 373.978944 -240.434114)
			(xy 373.982904 -240.38506) (xy 373.994681 -240.337276) (xy 374.013972 -240.292) (xy 374.040275 -240.250404)
			(xy 374.07291 -240.213567) (xy 374.111031 -240.182442) (xy 374.153652 -240.157835) (xy 374.199668 -240.140383)
			(xy 374.247887 -240.130539) (xy 374.297062 -240.128558) (xy 374.345917 -240.13449) (xy 374.393188 -240.148182)
			(xy 374.43765 -240.16928) (xy 374.478153 -240.197236) (xy 374.513646 -240.231328) (xy 374.543211 -240.270672)
			(xy 374.566082 -240.314249) (xy 374.581666 -240.36093) (xy 374.589561 -240.409507) (xy 374.590056 -240.434114)
			(xy 374.918998 -240.434114) (xy 374.922958 -240.38506) (xy 374.934735 -240.337276) (xy 374.954026 -240.292)
			(xy 374.980329 -240.250404) (xy 375.012964 -240.213567) (xy 375.051085 -240.182442) (xy 375.093706 -240.157835)
			(xy 375.139722 -240.140383) (xy 375.187941 -240.130539) (xy 375.237116 -240.128558) (xy 375.285971 -240.13449)
			(xy 375.333242 -240.148182) (xy 375.377704 -240.16928) (xy 375.418207 -240.197236) (xy 375.4537 -240.231328)
			(xy 375.483265 -240.270672) (xy 375.506136 -240.314249) (xy 375.52172 -240.36093) (xy 375.529615 -240.409507)
			(xy 375.53011 -240.434114) (xy 375.848621 -240.434114) (xy 375.852716 -240.383386) (xy 375.864895 -240.333972)
			(xy 375.884843 -240.287152) (xy 375.912044 -240.244138) (xy 375.945792 -240.206044) (xy 375.985214 -240.173857)
			(xy 376.029288 -240.148411) (xy 376.076874 -240.130364) (xy 376.126738 -240.120184) (xy 376.17759 -240.118135)
			(xy 376.228111 -240.124269) (xy 376.276995 -240.138429) (xy 376.322974 -240.160246) (xy 376.364858 -240.189156)
			(xy 376.401562 -240.224411) (xy 376.432135 -240.265097) (xy 376.455786 -240.31016) (xy 376.471902 -240.358434)
			(xy 376.480066 -240.408668) (xy 376.480578 -240.434114) (xy 376.788675 -240.434114) (xy 376.79277 -240.383386)
			(xy 376.804949 -240.333972) (xy 376.824897 -240.287152) (xy 376.852098 -240.244138) (xy 376.885846 -240.206044)
			(xy 376.925268 -240.173857) (xy 376.969342 -240.148411) (xy 377.016928 -240.130364) (xy 377.066792 -240.120184)
			(xy 377.117644 -240.118135) (xy 377.168165 -240.124269) (xy 377.217049 -240.138429) (xy 377.263028 -240.160246)
			(xy 377.304912 -240.189156) (xy 377.341616 -240.224411) (xy 377.372189 -240.265097) (xy 377.39584 -240.31016)
			(xy 377.411956 -240.358434) (xy 377.42012 -240.408668) (xy 377.420632 -240.434114) (xy 377.42012 -240.45956)
			(xy 377.411956 -240.509794) (xy 377.39584 -240.558068) (xy 377.372189 -240.603131) (xy 377.341616 -240.643817)
			(xy 377.304912 -240.679072) (xy 377.263028 -240.707982) (xy 377.217049 -240.729799) (xy 377.168165 -240.743959)
			(xy 377.117644 -240.750093) (xy 377.066792 -240.748044) (xy 377.016928 -240.737864) (xy 376.969342 -240.719817)
			(xy 376.925268 -240.694371) (xy 376.885846 -240.662184) (xy 376.852098 -240.62409) (xy 376.824897 -240.581076)
			(xy 376.804949 -240.534256) (xy 376.79277 -240.484842) (xy 376.788675 -240.434114) (xy 376.480578 -240.434114)
			(xy 376.480066 -240.45956) (xy 376.471902 -240.509794) (xy 376.455786 -240.558068) (xy 376.432135 -240.603131)
			(xy 376.401562 -240.643817) (xy 376.364858 -240.679072) (xy 376.322974 -240.707982) (xy 376.276995 -240.729799)
			(xy 376.228111 -240.743959) (xy 376.17759 -240.750093) (xy 376.126738 -240.748044) (xy 376.076874 -240.737864)
			(xy 376.029288 -240.719817) (xy 375.985214 -240.694371) (xy 375.945792 -240.662184) (xy 375.912044 -240.62409)
			(xy 375.884843 -240.581076) (xy 375.864895 -240.534256) (xy 375.852716 -240.484842) (xy 375.848621 -240.434114)
			(xy 375.53011 -240.434114) (xy 375.529615 -240.458721) (xy 375.52172 -240.507298) (xy 375.506136 -240.553979)
			(xy 375.483265 -240.597556) (xy 375.4537 -240.6369) (xy 375.418207 -240.670992) (xy 375.377704 -240.698948)
			(xy 375.333242 -240.720046) (xy 375.285971 -240.733738) (xy 375.237116 -240.73967) (xy 375.187941 -240.737689)
			(xy 375.139722 -240.727845) (xy 375.093706 -240.710393) (xy 375.051085 -240.685786) (xy 375.012964 -240.654661)
			(xy 374.980329 -240.617824) (xy 374.954026 -240.576228) (xy 374.934735 -240.530952) (xy 374.922958 -240.483168)
			(xy 374.918998 -240.434114) (xy 374.590056 -240.434114) (xy 374.589561 -240.458721) (xy 374.581666 -240.507298)
			(xy 374.566082 -240.553979) (xy 374.543211 -240.597556) (xy 374.513646 -240.6369) (xy 374.478153 -240.670992)
			(xy 374.43765 -240.698948) (xy 374.393188 -240.720046) (xy 374.345917 -240.733738) (xy 374.297062 -240.73967)
			(xy 374.247887 -240.737689) (xy 374.199668 -240.727845) (xy 374.153652 -240.710393) (xy 374.111031 -240.685786)
			(xy 374.07291 -240.654661) (xy 374.040275 -240.617824) (xy 374.013972 -240.576228) (xy 373.994681 -240.530952)
			(xy 373.982904 -240.483168) (xy 373.978944 -240.434114) (xy 373.650002 -240.434114) (xy 373.649507 -240.458721)
			(xy 373.641612 -240.507298) (xy 373.626028 -240.553979) (xy 373.603157 -240.597556) (xy 373.573592 -240.6369)
			(xy 373.538099 -240.670992) (xy 373.497596 -240.698948) (xy 373.453134 -240.720046) (xy 373.405863 -240.733738)
			(xy 373.357008 -240.73967) (xy 373.307833 -240.737689) (xy 373.259614 -240.727845) (xy 373.213598 -240.710393)
			(xy 373.170977 -240.685786) (xy 373.132856 -240.654661) (xy 373.100221 -240.617824) (xy 373.073918 -240.576228)
			(xy 373.054627 -240.530952) (xy 373.04285 -240.483168) (xy 373.03889 -240.434114) (xy 372.710202 -240.434114)
			(xy 372.709707 -240.458721) (xy 372.701812 -240.507298) (xy 372.686228 -240.553979) (xy 372.663357 -240.597556)
			(xy 372.633792 -240.6369) (xy 372.598299 -240.670992) (xy 372.557796 -240.698948) (xy 372.513334 -240.720046)
			(xy 372.466063 -240.733738) (xy 372.417208 -240.73967) (xy 372.368033 -240.737689) (xy 372.319814 -240.727845)
			(xy 372.273798 -240.710393) (xy 372.231177 -240.685786) (xy 372.193056 -240.654661) (xy 372.160421 -240.617824)
			(xy 372.134118 -240.576228) (xy 372.114827 -240.530952) (xy 372.10305 -240.483168) (xy 372.09909 -240.434114)
			(xy 371.770148 -240.434114) (xy 371.769653 -240.458721) (xy 371.761758 -240.507298) (xy 371.746174 -240.553979)
			(xy 371.723303 -240.597556) (xy 371.693738 -240.6369) (xy 371.658245 -240.670992) (xy 371.617742 -240.698948)
			(xy 371.57328 -240.720046) (xy 371.526009 -240.733738) (xy 371.477154 -240.73967) (xy 371.427979 -240.737689)
			(xy 371.37976 -240.727845) (xy 371.333744 -240.710393) (xy 371.291123 -240.685786) (xy 371.253002 -240.654661)
			(xy 371.220367 -240.617824) (xy 371.194064 -240.576228) (xy 371.174773 -240.530952) (xy 371.162996 -240.483168)
			(xy 371.159036 -240.434114) (xy 370.830094 -240.434114) (xy 370.829599 -240.458721) (xy 370.821704 -240.507298)
			(xy 370.80612 -240.553979) (xy 370.783249 -240.597556) (xy 370.753684 -240.6369) (xy 370.718191 -240.670992)
			(xy 370.677688 -240.698948) (xy 370.633226 -240.720046) (xy 370.585955 -240.733738) (xy 370.5371 -240.73967)
			(xy 370.487925 -240.737689) (xy 370.439706 -240.727845) (xy 370.39369 -240.710393) (xy 370.351069 -240.685786)
			(xy 370.312948 -240.654661) (xy 370.280313 -240.617824) (xy 370.25401 -240.576228) (xy 370.234719 -240.530952)
			(xy 370.222942 -240.483168) (xy 370.218982 -240.434114) (xy 369.89004 -240.434114) (xy 369.889545 -240.458721)
			(xy 369.88165 -240.507298) (xy 369.866066 -240.553979) (xy 369.843195 -240.597556) (xy 369.81363 -240.6369)
			(xy 369.778137 -240.670992) (xy 369.737634 -240.698948) (xy 369.693172 -240.720046) (xy 369.645901 -240.733738)
			(xy 369.597046 -240.73967) (xy 369.547871 -240.737689) (xy 369.499652 -240.727845) (xy 369.453636 -240.710393)
			(xy 369.411015 -240.685786) (xy 369.372894 -240.654661) (xy 369.340259 -240.617824) (xy 369.313956 -240.576228)
			(xy 369.294665 -240.530952) (xy 369.282888 -240.483168) (xy 369.278928 -240.434114) (xy 368.949986 -240.434114)
			(xy 368.949491 -240.458721) (xy 368.941596 -240.507298) (xy 368.926012 -240.553979) (xy 368.903141 -240.597556)
			(xy 368.873576 -240.6369) (xy 368.838083 -240.670992) (xy 368.79758 -240.698948) (xy 368.753118 -240.720046)
			(xy 368.705847 -240.733738) (xy 368.656992 -240.73967) (xy 368.607817 -240.737689) (xy 368.559598 -240.727845)
			(xy 368.513582 -240.710393) (xy 368.470961 -240.685786) (xy 368.43284 -240.654661) (xy 368.400205 -240.617824)
			(xy 368.373902 -240.576228) (xy 368.354611 -240.530952) (xy 368.342834 -240.483168) (xy 368.338874 -240.434114)
			(xy 368.010186 -240.434114) (xy 368.009691 -240.458721) (xy 368.001796 -240.507298) (xy 367.986212 -240.553979)
			(xy 367.963341 -240.597556) (xy 367.933776 -240.6369) (xy 367.898283 -240.670992) (xy 367.85778 -240.698948)
			(xy 367.813318 -240.720046) (xy 367.766047 -240.733738) (xy 367.717192 -240.73967) (xy 367.668017 -240.737689)
			(xy 367.619798 -240.727845) (xy 367.573782 -240.710393) (xy 367.531161 -240.685786) (xy 367.49304 -240.654661)
			(xy 367.460405 -240.617824) (xy 367.434102 -240.576228) (xy 367.414811 -240.530952) (xy 367.403034 -240.483168)
			(xy 367.399074 -240.434114) (xy 367.070132 -240.434114) (xy 367.069637 -240.458721) (xy 367.061742 -240.507298)
			(xy 367.046158 -240.553979) (xy 367.023287 -240.597556) (xy 366.993722 -240.6369) (xy 366.958229 -240.670992)
			(xy 366.917726 -240.698948) (xy 366.873264 -240.720046) (xy 366.825993 -240.733738) (xy 366.777138 -240.73967)
			(xy 366.727963 -240.737689) (xy 366.679744 -240.727845) (xy 366.633728 -240.710393) (xy 366.591107 -240.685786)
			(xy 366.552986 -240.654661) (xy 366.520351 -240.617824) (xy 366.494048 -240.576228) (xy 366.474757 -240.530952)
			(xy 366.46298 -240.483168) (xy 366.45902 -240.434114) (xy 366.130078 -240.434114) (xy 366.129583 -240.458721)
			(xy 366.121688 -240.507298) (xy 366.106104 -240.553979) (xy 366.083233 -240.597556) (xy 366.053668 -240.6369)
			(xy 366.018175 -240.670992) (xy 365.977672 -240.698948) (xy 365.93321 -240.720046) (xy 365.885939 -240.733738)
			(xy 365.837084 -240.73967) (xy 365.787909 -240.737689) (xy 365.73969 -240.727845) (xy 365.693674 -240.710393)
			(xy 365.651053 -240.685786) (xy 365.612932 -240.654661) (xy 365.580297 -240.617824) (xy 365.553994 -240.576228)
			(xy 365.534703 -240.530952) (xy 365.522926 -240.483168) (xy 365.518966 -240.434114) (xy 365.190024 -240.434114)
			(xy 365.189529 -240.458721) (xy 365.181634 -240.507298) (xy 365.16605 -240.553979) (xy 365.143179 -240.597556)
			(xy 365.113614 -240.6369) (xy 365.078121 -240.670992) (xy 365.037618 -240.698948) (xy 364.993156 -240.720046)
			(xy 364.945885 -240.733738) (xy 364.89703 -240.73967) (xy 364.847855 -240.737689) (xy 364.799636 -240.727845)
			(xy 364.75362 -240.710393) (xy 364.710999 -240.685786) (xy 364.672878 -240.654661) (xy 364.640243 -240.617824)
			(xy 364.61394 -240.576228) (xy 364.594649 -240.530952) (xy 364.582872 -240.483168) (xy 364.578912 -240.434114)
			(xy 364.250224 -240.434114) (xy 364.249729 -240.458721) (xy 364.241834 -240.507298) (xy 364.22625 -240.553979)
			(xy 364.203379 -240.597556) (xy 364.173814 -240.6369) (xy 364.138321 -240.670992) (xy 364.097818 -240.698948)
			(xy 364.053356 -240.720046) (xy 364.006085 -240.733738) (xy 363.95723 -240.73967) (xy 363.908055 -240.737689)
			(xy 363.859836 -240.727845) (xy 363.81382 -240.710393) (xy 363.771199 -240.685786) (xy 363.733078 -240.654661)
			(xy 363.700443 -240.617824) (xy 363.67414 -240.576228) (xy 363.654849 -240.530952) (xy 363.643072 -240.483168)
			(xy 363.639112 -240.434114) (xy 363.31017 -240.434114) (xy 363.309675 -240.458721) (xy 363.30178 -240.507298)
			(xy 363.286196 -240.553979) (xy 363.263325 -240.597556) (xy 363.23376 -240.6369) (xy 363.198267 -240.670992)
			(xy 363.157764 -240.698948) (xy 363.113302 -240.720046) (xy 363.066031 -240.733738) (xy 363.017176 -240.73967)
			(xy 362.968001 -240.737689) (xy 362.919782 -240.727845) (xy 362.873766 -240.710393) (xy 362.831145 -240.685786)
			(xy 362.793024 -240.654661) (xy 362.760389 -240.617824) (xy 362.734086 -240.576228) (xy 362.714795 -240.530952)
			(xy 362.703018 -240.483168) (xy 362.699058 -240.434114) (xy 362.370116 -240.434114) (xy 362.369621 -240.458721)
			(xy 362.361726 -240.507298) (xy 362.346142 -240.553979) (xy 362.323271 -240.597556) (xy 362.293706 -240.6369)
			(xy 362.258213 -240.670992) (xy 362.21771 -240.698948) (xy 362.173248 -240.720046) (xy 362.125977 -240.733738)
			(xy 362.077122 -240.73967) (xy 362.027947 -240.737689) (xy 361.979728 -240.727845) (xy 361.933712 -240.710393)
			(xy 361.891091 -240.685786) (xy 361.85297 -240.654661) (xy 361.820335 -240.617824) (xy 361.794032 -240.576228)
			(xy 361.774741 -240.530952) (xy 361.762964 -240.483168) (xy 361.759004 -240.434114) (xy 361.430062 -240.434114)
			(xy 361.429567 -240.458721) (xy 361.421672 -240.507298) (xy 361.406088 -240.553979) (xy 361.383217 -240.597556)
			(xy 361.353652 -240.6369) (xy 361.318159 -240.670992) (xy 361.277656 -240.698948) (xy 361.233194 -240.720046)
			(xy 361.185923 -240.733738) (xy 361.137068 -240.73967) (xy 361.087893 -240.737689) (xy 361.039674 -240.727845)
			(xy 360.993658 -240.710393) (xy 360.951037 -240.685786) (xy 360.912916 -240.654661) (xy 360.880281 -240.617824)
			(xy 360.853978 -240.576228) (xy 360.834687 -240.530952) (xy 360.82291 -240.483168) (xy 360.81895 -240.434114)
			(xy 358.616504 -240.434114) (xy 358.616009 -240.458721) (xy 358.608114 -240.507298) (xy 358.59253 -240.553979)
			(xy 358.569659 -240.597556) (xy 358.540094 -240.6369) (xy 358.504601 -240.670992) (xy 358.464098 -240.698948)
			(xy 358.419636 -240.720046) (xy 358.372365 -240.733738) (xy 358.32351 -240.73967) (xy 358.274335 -240.737689)
			(xy 358.226116 -240.727845) (xy 358.1801 -240.710393) (xy 358.137479 -240.685786) (xy 358.099358 -240.654661)
			(xy 358.066723 -240.617824) (xy 358.04042 -240.576228) (xy 358.021129 -240.530952) (xy 358.009352 -240.483168)
			(xy 358.005392 -240.434114) (xy 357.67645 -240.434114) (xy 357.675955 -240.458721) (xy 357.66806 -240.507298)
			(xy 357.652476 -240.553979) (xy 357.629605 -240.597556) (xy 357.60004 -240.6369) (xy 357.564547 -240.670992)
			(xy 357.524044 -240.698948) (xy 357.479582 -240.720046) (xy 357.432311 -240.733738) (xy 357.383456 -240.73967)
			(xy 357.334281 -240.737689) (xy 357.286062 -240.727845) (xy 357.240046 -240.710393) (xy 357.197425 -240.685786)
			(xy 357.159304 -240.654661) (xy 357.126669 -240.617824) (xy 357.100366 -240.576228) (xy 357.081075 -240.530952)
			(xy 357.069298 -240.483168) (xy 357.065338 -240.434114) (xy 356.736396 -240.434114) (xy 356.735901 -240.458721)
			(xy 356.728006 -240.507298) (xy 356.712422 -240.553979) (xy 356.689551 -240.597556) (xy 356.659986 -240.6369)
			(xy 356.624493 -240.670992) (xy 356.58399 -240.698948) (xy 356.539528 -240.720046) (xy 356.492257 -240.733738)
			(xy 356.443402 -240.73967) (xy 356.394227 -240.737689) (xy 356.346008 -240.727845) (xy 356.299992 -240.710393)
			(xy 356.257371 -240.685786) (xy 356.21925 -240.654661) (xy 356.186615 -240.617824) (xy 356.160312 -240.576228)
			(xy 356.141021 -240.530952) (xy 356.129244 -240.483168) (xy 356.125284 -240.434114) (xy 355.796342 -240.434114)
			(xy 355.795847 -240.458721) (xy 355.787952 -240.507298) (xy 355.772368 -240.553979) (xy 355.749497 -240.597556)
			(xy 355.719932 -240.6369) (xy 355.684439 -240.670992) (xy 355.643936 -240.698948) (xy 355.599474 -240.720046)
			(xy 355.552203 -240.733738) (xy 355.503348 -240.73967) (xy 355.454173 -240.737689) (xy 355.405954 -240.727845)
			(xy 355.359938 -240.710393) (xy 355.317317 -240.685786) (xy 355.279196 -240.654661) (xy 355.246561 -240.617824)
			(xy 355.220258 -240.576228) (xy 355.200967 -240.530952) (xy 355.18919 -240.483168) (xy 355.18523 -240.434114)
			(xy 354.856542 -240.434114) (xy 354.856047 -240.458721) (xy 354.848152 -240.507298) (xy 354.832568 -240.553979)
			(xy 354.809697 -240.597556) (xy 354.780132 -240.6369) (xy 354.744639 -240.670992) (xy 354.704136 -240.698948)
			(xy 354.659674 -240.720046) (xy 354.612403 -240.733738) (xy 354.563548 -240.73967) (xy 354.514373 -240.737689)
			(xy 354.466154 -240.727845) (xy 354.420138 -240.710393) (xy 354.377517 -240.685786) (xy 354.339396 -240.654661)
			(xy 354.306761 -240.617824) (xy 354.280458 -240.576228) (xy 354.261167 -240.530952) (xy 354.24939 -240.483168)
			(xy 354.24543 -240.434114) (xy 353.916488 -240.434114) (xy 353.915993 -240.458721) (xy 353.908098 -240.507298)
			(xy 353.892514 -240.553979) (xy 353.869643 -240.597556) (xy 353.840078 -240.6369) (xy 353.804585 -240.670992)
			(xy 353.764082 -240.698948) (xy 353.71962 -240.720046) (xy 353.672349 -240.733738) (xy 353.623494 -240.73967)
			(xy 353.574319 -240.737689) (xy 353.5261 -240.727845) (xy 353.480084 -240.710393) (xy 353.437463 -240.685786)
			(xy 353.399342 -240.654661) (xy 353.366707 -240.617824) (xy 353.340404 -240.576228) (xy 353.321113 -240.530952)
			(xy 353.309336 -240.483168) (xy 353.305376 -240.434114) (xy 352.976434 -240.434114) (xy 352.975939 -240.458721)
			(xy 352.968044 -240.507298) (xy 352.95246 -240.553979) (xy 352.929589 -240.597556) (xy 352.900024 -240.6369)
			(xy 352.864531 -240.670992) (xy 352.824028 -240.698948) (xy 352.779566 -240.720046) (xy 352.732295 -240.733738)
			(xy 352.68344 -240.73967) (xy 352.634265 -240.737689) (xy 352.586046 -240.727845) (xy 352.54003 -240.710393)
			(xy 352.497409 -240.685786) (xy 352.459288 -240.654661) (xy 352.426653 -240.617824) (xy 352.40035 -240.576228)
			(xy 352.381059 -240.530952) (xy 352.369282 -240.483168) (xy 352.365322 -240.434114) (xy 352.03638 -240.434114)
			(xy 352.035885 -240.458721) (xy 352.02799 -240.507298) (xy 352.012406 -240.553979) (xy 351.989535 -240.597556)
			(xy 351.95997 -240.6369) (xy 351.924477 -240.670992) (xy 351.883974 -240.698948) (xy 351.839512 -240.720046)
			(xy 351.792241 -240.733738) (xy 351.743386 -240.73967) (xy 351.694211 -240.737689) (xy 351.645992 -240.727845)
			(xy 351.599976 -240.710393) (xy 351.557355 -240.685786) (xy 351.519234 -240.654661) (xy 351.486599 -240.617824)
			(xy 351.460296 -240.576228) (xy 351.441005 -240.530952) (xy 351.429228 -240.483168) (xy 351.425268 -240.434114)
			(xy 351.096326 -240.434114) (xy 351.095831 -240.458721) (xy 351.087936 -240.507298) (xy 351.072352 -240.553979)
			(xy 351.049481 -240.597556) (xy 351.019916 -240.6369) (xy 350.984423 -240.670992) (xy 350.94392 -240.698948)
			(xy 350.899458 -240.720046) (xy 350.852187 -240.733738) (xy 350.803332 -240.73967) (xy 350.754157 -240.737689)
			(xy 350.705938 -240.727845) (xy 350.659922 -240.710393) (xy 350.617301 -240.685786) (xy 350.57918 -240.654661)
			(xy 350.546545 -240.617824) (xy 350.520242 -240.576228) (xy 350.500951 -240.530952) (xy 350.489174 -240.483168)
			(xy 350.485214 -240.434114) (xy 350.156526 -240.434114) (xy 350.156031 -240.458721) (xy 350.148136 -240.507298)
			(xy 350.132552 -240.553979) (xy 350.109681 -240.597556) (xy 350.080116 -240.6369) (xy 350.044623 -240.670992)
			(xy 350.00412 -240.698948) (xy 349.959658 -240.720046) (xy 349.912387 -240.733738) (xy 349.863532 -240.73967)
			(xy 349.814357 -240.737689) (xy 349.766138 -240.727845) (xy 349.720122 -240.710393) (xy 349.677501 -240.685786)
			(xy 349.63938 -240.654661) (xy 349.606745 -240.617824) (xy 349.580442 -240.576228) (xy 349.561151 -240.530952)
			(xy 349.549374 -240.483168) (xy 349.545414 -240.434114) (xy 349.216472 -240.434114) (xy 349.215977 -240.458721)
			(xy 349.208082 -240.507298) (xy 349.192498 -240.553979) (xy 349.169627 -240.597556) (xy 349.140062 -240.6369)
			(xy 349.104569 -240.670992) (xy 349.064066 -240.698948) (xy 349.019604 -240.720046) (xy 348.972333 -240.733738)
			(xy 348.923478 -240.73967) (xy 348.874303 -240.737689) (xy 348.826084 -240.727845) (xy 348.780068 -240.710393)
			(xy 348.737447 -240.685786) (xy 348.699326 -240.654661) (xy 348.666691 -240.617824) (xy 348.640388 -240.576228)
			(xy 348.621097 -240.530952) (xy 348.60932 -240.483168) (xy 348.60536 -240.434114) (xy 348.276418 -240.434114)
			(xy 348.275923 -240.458721) (xy 348.268028 -240.507298) (xy 348.252444 -240.553979) (xy 348.229573 -240.597556)
			(xy 348.200008 -240.6369) (xy 348.164515 -240.670992) (xy 348.124012 -240.698948) (xy 348.07955 -240.720046)
			(xy 348.032279 -240.733738) (xy 347.983424 -240.73967) (xy 347.934249 -240.737689) (xy 347.88603 -240.727845)
			(xy 347.840014 -240.710393) (xy 347.797393 -240.685786) (xy 347.759272 -240.654661) (xy 347.726637 -240.617824)
			(xy 347.700334 -240.576228) (xy 347.681043 -240.530952) (xy 347.669266 -240.483168) (xy 347.665306 -240.434114)
			(xy 347.336364 -240.434114) (xy 347.335869 -240.458721) (xy 347.327974 -240.507298) (xy 347.31239 -240.553979)
			(xy 347.289519 -240.597556) (xy 347.259954 -240.6369) (xy 347.224461 -240.670992) (xy 347.183958 -240.698948)
			(xy 347.139496 -240.720046) (xy 347.092225 -240.733738) (xy 347.04337 -240.73967) (xy 346.994195 -240.737689)
			(xy 346.945976 -240.727845) (xy 346.89996 -240.710393) (xy 346.857339 -240.685786) (xy 346.819218 -240.654661)
			(xy 346.786583 -240.617824) (xy 346.76028 -240.576228) (xy 346.740989 -240.530952) (xy 346.729212 -240.483168)
			(xy 346.725252 -240.434114) (xy 346.39631 -240.434114) (xy 346.395815 -240.458721) (xy 346.38792 -240.507298)
			(xy 346.372336 -240.553979) (xy 346.349465 -240.597556) (xy 346.3199 -240.6369) (xy 346.284407 -240.670992)
			(xy 346.243904 -240.698948) (xy 346.199442 -240.720046) (xy 346.152171 -240.733738) (xy 346.103316 -240.73967)
			(xy 346.054141 -240.737689) (xy 346.005922 -240.727845) (xy 345.959906 -240.710393) (xy 345.917285 -240.685786)
			(xy 345.879164 -240.654661) (xy 345.846529 -240.617824) (xy 345.820226 -240.576228) (xy 345.800935 -240.530952)
			(xy 345.789158 -240.483168) (xy 345.785198 -240.434114) (xy 345.45651 -240.434114) (xy 345.456015 -240.458721)
			(xy 345.44812 -240.507298) (xy 345.432536 -240.553979) (xy 345.409665 -240.597556) (xy 345.3801 -240.6369)
			(xy 345.344607 -240.670992) (xy 345.304104 -240.698948) (xy 345.259642 -240.720046) (xy 345.212371 -240.733738)
			(xy 345.163516 -240.73967) (xy 345.114341 -240.737689) (xy 345.066122 -240.727845) (xy 345.020106 -240.710393)
			(xy 344.977485 -240.685786) (xy 344.939364 -240.654661) (xy 344.906729 -240.617824) (xy 344.880426 -240.576228)
			(xy 344.861135 -240.530952) (xy 344.849358 -240.483168) (xy 344.845398 -240.434114) (xy 344.516456 -240.434114)
			(xy 344.515961 -240.458721) (xy 344.508066 -240.507298) (xy 344.492482 -240.553979) (xy 344.469611 -240.597556)
			(xy 344.440046 -240.6369) (xy 344.404553 -240.670992) (xy 344.36405 -240.698948) (xy 344.319588 -240.720046)
			(xy 344.272317 -240.733738) (xy 344.223462 -240.73967) (xy 344.174287 -240.737689) (xy 344.126068 -240.727845)
			(xy 344.080052 -240.710393) (xy 344.037431 -240.685786) (xy 343.99931 -240.654661) (xy 343.966675 -240.617824)
			(xy 343.940372 -240.576228) (xy 343.921081 -240.530952) (xy 343.909304 -240.483168) (xy 343.905344 -240.434114)
			(xy 343.586816 -240.434114) (xy 343.586304 -240.45956) (xy 343.57814 -240.509794) (xy 343.562024 -240.558068)
			(xy 343.538373 -240.603131) (xy 343.5078 -240.643817) (xy 343.471096 -240.679072) (xy 343.429212 -240.707982)
			(xy 343.383233 -240.729799) (xy 343.334349 -240.743959) (xy 343.283828 -240.750093) (xy 343.232976 -240.748044)
			(xy 343.183112 -240.737864) (xy 343.135526 -240.719817) (xy 343.091452 -240.694371) (xy 343.05203 -240.662184)
			(xy 343.018282 -240.62409) (xy 342.991081 -240.581076) (xy 342.971133 -240.534256) (xy 342.958954 -240.484842)
			(xy 342.954859 -240.434114) (xy 342.646762 -240.434114) (xy 342.64625 -240.45956) (xy 342.638086 -240.509794)
			(xy 342.62197 -240.558068) (xy 342.598319 -240.603131) (xy 342.567746 -240.643817) (xy 342.531042 -240.679072)
			(xy 342.489158 -240.707982) (xy 342.443179 -240.729799) (xy 342.394295 -240.743959) (xy 342.343774 -240.750093)
			(xy 342.292922 -240.748044) (xy 342.243058 -240.737864) (xy 342.195472 -240.719817) (xy 342.151398 -240.694371)
			(xy 342.111976 -240.662184) (xy 342.078228 -240.62409) (xy 342.051027 -240.581076) (xy 342.031079 -240.534256)
			(xy 342.0189 -240.484842) (xy 342.014805 -240.434114) (xy 341.696845 -240.434114) (xy 341.692674 -240.484442)
			(xy 341.680273 -240.533411) (xy 341.659981 -240.579671) (xy 341.632352 -240.621959) (xy 341.598138 -240.659123)
			(xy 341.558274 -240.690149) (xy 341.513847 -240.71419) (xy 341.466069 -240.73059) (xy 341.416243 -240.738902)
			(xy 341.390986 -240.739422) (xy 341.390224 -240.739422) (xy 341.367124 -240.738978) (xy 341.321461 -240.731959)
			(xy 341.299292 -240.725452) (xy 341.291926 -240.723166) (xy 341.284052 -240.723166) (xy 341.274048 -240.723662)
			(xy 341.255567 -240.731329) (xy 341.241421 -240.745479) (xy 341.233759 -240.763962) (xy 341.233252 -240.773966)
			(xy 341.233252 -240.782348) (xy 341.220044 -240.810542) (xy 341.217803 -240.815656) (xy 341.215367 -240.82655)
			(xy 341.215218 -240.832132) (xy 341.215218 -241.162078) (xy 341.216742 -241.168174) (xy 341.221256 -241.186835)
			(xy 341.226102 -241.224923) (xy 341.226394 -241.24412) (xy 341.544905 -241.24412) (xy 341.549 -241.193392)
			(xy 341.561179 -241.143978) (xy 341.581127 -241.097158) (xy 341.608328 -241.054144) (xy 341.642076 -241.01605)
			(xy 341.681498 -240.983863) (xy 341.725572 -240.958417) (xy 341.773158 -240.94037) (xy 341.823022 -240.93019)
			(xy 341.873874 -240.928141) (xy 341.924395 -240.934275) (xy 341.973279 -240.948435) (xy 342.019258 -240.970252)
			(xy 342.061142 -240.999162) (xy 342.097846 -241.034417) (xy 342.128419 -241.075103) (xy 342.15207 -241.120166)
			(xy 342.168186 -241.16844) (xy 342.17635 -241.218674) (xy 342.176862 -241.24412) (xy 342.49539 -241.24412)
			(xy 342.49935 -241.195066) (xy 342.511127 -241.147282) (xy 342.530418 -241.102006) (xy 342.556721 -241.06041)
			(xy 342.589356 -241.023573) (xy 342.627477 -240.992448) (xy 342.670098 -240.967841) (xy 342.716114 -240.950389)
			(xy 342.764333 -240.940545) (xy 342.813508 -240.938564) (xy 342.862363 -240.944496) (xy 342.909634 -240.958188)
			(xy 342.954096 -240.979286) (xy 342.994599 -241.007242) (xy 343.030092 -241.041334) (xy 343.059657 -241.080678)
			(xy 343.082528 -241.124255) (xy 343.098112 -241.170936) (xy 343.106007 -241.219513) (xy 343.106502 -241.24412)
			(xy 343.424759 -241.24412) (xy 343.428854 -241.193392) (xy 343.441033 -241.143978) (xy 343.460981 -241.097158)
			(xy 343.488182 -241.054144) (xy 343.52193 -241.01605) (xy 343.561352 -240.983863) (xy 343.605426 -240.958417)
			(xy 343.653012 -240.94037) (xy 343.702876 -240.93019) (xy 343.753728 -240.928141) (xy 343.804249 -240.934275)
			(xy 343.853133 -240.948435) (xy 343.899112 -240.970252) (xy 343.940996 -240.999162) (xy 343.9777 -241.034417)
			(xy 344.008273 -241.075103) (xy 344.031924 -241.120166) (xy 344.04804 -241.16844) (xy 344.056204 -241.218674)
			(xy 344.056716 -241.24412) (xy 344.375244 -241.24412) (xy 344.379204 -241.195066) (xy 344.390981 -241.147282)
			(xy 344.410272 -241.102006) (xy 344.436575 -241.06041) (xy 344.46921 -241.023573) (xy 344.507331 -240.992448)
			(xy 344.549952 -240.967841) (xy 344.595968 -240.950389) (xy 344.644187 -240.940545) (xy 344.693362 -240.938564)
			(xy 344.742217 -240.944496) (xy 344.789488 -240.958188) (xy 344.83395 -240.979286) (xy 344.874453 -241.007242)
			(xy 344.909946 -241.041334) (xy 344.939511 -241.080678) (xy 344.962382 -241.124255) (xy 344.977966 -241.170936)
			(xy 344.985861 -241.219513) (xy 344.986356 -241.24412) (xy 345.315298 -241.24412) (xy 345.319258 -241.195066)
			(xy 345.331035 -241.147282) (xy 345.350326 -241.102006) (xy 345.376629 -241.06041) (xy 345.409264 -241.023573)
			(xy 345.447385 -240.992448) (xy 345.490006 -240.967841) (xy 345.536022 -240.950389) (xy 345.584241 -240.940545)
			(xy 345.633416 -240.938564) (xy 345.682271 -240.944496) (xy 345.729542 -240.958188) (xy 345.774004 -240.979286)
			(xy 345.814507 -241.007242) (xy 345.85 -241.041334) (xy 345.879565 -241.080678) (xy 345.902436 -241.124255)
			(xy 345.91802 -241.170936) (xy 345.925915 -241.219513) (xy 345.92641 -241.24412) (xy 346.255352 -241.24412)
			(xy 346.259312 -241.195066) (xy 346.271089 -241.147282) (xy 346.29038 -241.102006) (xy 346.316683 -241.06041)
			(xy 346.349318 -241.023573) (xy 346.387439 -240.992448) (xy 346.43006 -240.967841) (xy 346.476076 -240.950389)
			(xy 346.524295 -240.940545) (xy 346.57347 -240.938564) (xy 346.622325 -240.944496) (xy 346.669596 -240.958188)
			(xy 346.714058 -240.979286) (xy 346.754561 -241.007242) (xy 346.790054 -241.041334) (xy 346.819619 -241.080678)
			(xy 346.84249 -241.124255) (xy 346.858074 -241.170936) (xy 346.865969 -241.219513) (xy 346.866464 -241.24412)
			(xy 347.195406 -241.24412) (xy 347.199366 -241.195066) (xy 347.211143 -241.147282) (xy 347.230434 -241.102006)
			(xy 347.256737 -241.06041) (xy 347.289372 -241.023573) (xy 347.327493 -240.992448) (xy 347.370114 -240.967841)
			(xy 347.41613 -240.950389) (xy 347.464349 -240.940545) (xy 347.513524 -240.938564) (xy 347.562379 -240.944496)
			(xy 347.60965 -240.958188) (xy 347.654112 -240.979286) (xy 347.694615 -241.007242) (xy 347.730108 -241.041334)
			(xy 347.759673 -241.080678) (xy 347.782544 -241.124255) (xy 347.798128 -241.170936) (xy 347.806023 -241.219513)
			(xy 347.806518 -241.24412) (xy 348.135206 -241.24412) (xy 348.139166 -241.195066) (xy 348.150943 -241.147282)
			(xy 348.170234 -241.102006) (xy 348.196537 -241.06041) (xy 348.229172 -241.023573) (xy 348.267293 -240.992448)
			(xy 348.309914 -240.967841) (xy 348.35593 -240.950389) (xy 348.404149 -240.940545) (xy 348.453324 -240.938564)
			(xy 348.502179 -240.944496) (xy 348.54945 -240.958188) (xy 348.593912 -240.979286) (xy 348.634415 -241.007242)
			(xy 348.669908 -241.041334) (xy 348.699473 -241.080678) (xy 348.722344 -241.124255) (xy 348.737928 -241.170936)
			(xy 348.745823 -241.219513) (xy 348.746318 -241.24412) (xy 349.07526 -241.24412) (xy 349.07922 -241.195066)
			(xy 349.090997 -241.147282) (xy 349.110288 -241.102006) (xy 349.136591 -241.06041) (xy 349.169226 -241.023573)
			(xy 349.207347 -240.992448) (xy 349.249968 -240.967841) (xy 349.295984 -240.950389) (xy 349.344203 -240.940545)
			(xy 349.393378 -240.938564) (xy 349.442233 -240.944496) (xy 349.489504 -240.958188) (xy 349.533966 -240.979286)
			(xy 349.574469 -241.007242) (xy 349.609962 -241.041334) (xy 349.639527 -241.080678) (xy 349.662398 -241.124255)
			(xy 349.677982 -241.170936) (xy 349.685877 -241.219513) (xy 349.686372 -241.24412) (xy 350.015314 -241.24412)
			(xy 350.019274 -241.195066) (xy 350.031051 -241.147282) (xy 350.050342 -241.102006) (xy 350.076645 -241.06041)
			(xy 350.10928 -241.023573) (xy 350.147401 -240.992448) (xy 350.190022 -240.967841) (xy 350.236038 -240.950389)
			(xy 350.284257 -240.940545) (xy 350.333432 -240.938564) (xy 350.382287 -240.944496) (xy 350.429558 -240.958188)
			(xy 350.47402 -240.979286) (xy 350.514523 -241.007242) (xy 350.550016 -241.041334) (xy 350.579581 -241.080678)
			(xy 350.602452 -241.124255) (xy 350.618036 -241.170936) (xy 350.625931 -241.219513) (xy 350.626426 -241.24412)
			(xy 350.955368 -241.24412) (xy 350.959328 -241.195066) (xy 350.971105 -241.147282) (xy 350.990396 -241.102006)
			(xy 351.016699 -241.06041) (xy 351.049334 -241.023573) (xy 351.087455 -240.992448) (xy 351.130076 -240.967841)
			(xy 351.176092 -240.950389) (xy 351.224311 -240.940545) (xy 351.273486 -240.938564) (xy 351.322341 -240.944496)
			(xy 351.369612 -240.958188) (xy 351.414074 -240.979286) (xy 351.454577 -241.007242) (xy 351.49007 -241.041334)
			(xy 351.519635 -241.080678) (xy 351.542506 -241.124255) (xy 351.55809 -241.170936) (xy 351.565985 -241.219513)
			(xy 351.56648 -241.24412) (xy 351.895422 -241.24412) (xy 351.899382 -241.195066) (xy 351.911159 -241.147282)
			(xy 351.93045 -241.102006) (xy 351.956753 -241.06041) (xy 351.989388 -241.023573) (xy 352.027509 -240.992448)
			(xy 352.07013 -240.967841) (xy 352.116146 -240.950389) (xy 352.164365 -240.940545) (xy 352.21354 -240.938564)
			(xy 352.262395 -240.944496) (xy 352.309666 -240.958188) (xy 352.354128 -240.979286) (xy 352.394631 -241.007242)
			(xy 352.430124 -241.041334) (xy 352.459689 -241.080678) (xy 352.48256 -241.124255) (xy 352.498144 -241.170936)
			(xy 352.506039 -241.219513) (xy 352.506534 -241.24412) (xy 352.835222 -241.24412) (xy 352.839182 -241.195066)
			(xy 352.850959 -241.147282) (xy 352.87025 -241.102006) (xy 352.896553 -241.06041) (xy 352.929188 -241.023573)
			(xy 352.967309 -240.992448) (xy 353.00993 -240.967841) (xy 353.055946 -240.950389) (xy 353.104165 -240.940545)
			(xy 353.15334 -240.938564) (xy 353.202195 -240.944496) (xy 353.249466 -240.958188) (xy 353.293928 -240.979286)
			(xy 353.334431 -241.007242) (xy 353.369924 -241.041334) (xy 353.399489 -241.080678) (xy 353.42236 -241.124255)
			(xy 353.437944 -241.170936) (xy 353.445839 -241.219513) (xy 353.446334 -241.24412) (xy 353.775276 -241.24412)
			(xy 353.779236 -241.195066) (xy 353.791013 -241.147282) (xy 353.810304 -241.102006) (xy 353.836607 -241.06041)
			(xy 353.869242 -241.023573) (xy 353.907363 -240.992448) (xy 353.949984 -240.967841) (xy 353.996 -240.950389)
			(xy 354.044219 -240.940545) (xy 354.093394 -240.938564) (xy 354.142249 -240.944496) (xy 354.18952 -240.958188)
			(xy 354.233982 -240.979286) (xy 354.274485 -241.007242) (xy 354.309978 -241.041334) (xy 354.339543 -241.080678)
			(xy 354.362414 -241.124255) (xy 354.377998 -241.170936) (xy 354.385893 -241.219513) (xy 354.386388 -241.24412)
			(xy 354.71533 -241.24412) (xy 354.71929 -241.195066) (xy 354.731067 -241.147282) (xy 354.750358 -241.102006)
			(xy 354.776661 -241.06041) (xy 354.809296 -241.023573) (xy 354.847417 -240.992448) (xy 354.890038 -240.967841)
			(xy 354.936054 -240.950389) (xy 354.984273 -240.940545) (xy 355.033448 -240.938564) (xy 355.082303 -240.944496)
			(xy 355.129574 -240.958188) (xy 355.174036 -240.979286) (xy 355.214539 -241.007242) (xy 355.250032 -241.041334)
			(xy 355.279597 -241.080678) (xy 355.302468 -241.124255) (xy 355.318052 -241.170936) (xy 355.325947 -241.219513)
			(xy 355.326442 -241.24412) (xy 355.655384 -241.24412) (xy 355.659344 -241.195066) (xy 355.671121 -241.147282)
			(xy 355.690412 -241.102006) (xy 355.716715 -241.06041) (xy 355.74935 -241.023573) (xy 355.787471 -240.992448)
			(xy 355.830092 -240.967841) (xy 355.876108 -240.950389) (xy 355.924327 -240.940545) (xy 355.973502 -240.938564)
			(xy 356.022357 -240.944496) (xy 356.069628 -240.958188) (xy 356.11409 -240.979286) (xy 356.154593 -241.007242)
			(xy 356.190086 -241.041334) (xy 356.219651 -241.080678) (xy 356.242522 -241.124255) (xy 356.258106 -241.170936)
			(xy 356.266001 -241.219513) (xy 356.266496 -241.24412) (xy 356.595438 -241.24412) (xy 356.599398 -241.195066)
			(xy 356.611175 -241.147282) (xy 356.630466 -241.102006) (xy 356.656769 -241.06041) (xy 356.689404 -241.023573)
			(xy 356.727525 -240.992448) (xy 356.770146 -240.967841) (xy 356.816162 -240.950389) (xy 356.864381 -240.940545)
			(xy 356.913556 -240.938564) (xy 356.962411 -240.944496) (xy 357.009682 -240.958188) (xy 357.054144 -240.979286)
			(xy 357.094647 -241.007242) (xy 357.13014 -241.041334) (xy 357.159705 -241.080678) (xy 357.182576 -241.124255)
			(xy 357.19816 -241.170936) (xy 357.206055 -241.219513) (xy 357.20655 -241.24412) (xy 357.535238 -241.24412)
			(xy 357.539198 -241.195066) (xy 357.550975 -241.147282) (xy 357.570266 -241.102006) (xy 357.596569 -241.06041)
			(xy 357.629204 -241.023573) (xy 357.667325 -240.992448) (xy 357.709946 -240.967841) (xy 357.755962 -240.950389)
			(xy 357.804181 -240.940545) (xy 357.853356 -240.938564) (xy 357.902211 -240.944496) (xy 357.949482 -240.958188)
			(xy 357.993944 -240.979286) (xy 358.034447 -241.007242) (xy 358.06994 -241.041334) (xy 358.099505 -241.080678)
			(xy 358.122376 -241.124255) (xy 358.13796 -241.170936) (xy 358.145855 -241.219513) (xy 358.14635 -241.24412)
			(xy 361.289104 -241.24412) (xy 361.293064 -241.195066) (xy 361.304841 -241.147282) (xy 361.324132 -241.102006)
			(xy 361.350435 -241.06041) (xy 361.38307 -241.023573) (xy 361.421191 -240.992448) (xy 361.463812 -240.967841)
			(xy 361.509828 -240.950389) (xy 361.558047 -240.940545) (xy 361.607222 -240.938564) (xy 361.656077 -240.944496)
			(xy 361.703348 -240.958188) (xy 361.74781 -240.979286) (xy 361.788313 -241.007242) (xy 361.823806 -241.041334)
			(xy 361.853371 -241.080678) (xy 361.876242 -241.124255) (xy 361.891826 -241.170936) (xy 361.899721 -241.219513)
			(xy 361.900216 -241.24412) (xy 362.228904 -241.24412) (xy 362.232864 -241.195066) (xy 362.244641 -241.147282)
			(xy 362.263932 -241.102006) (xy 362.290235 -241.06041) (xy 362.32287 -241.023573) (xy 362.360991 -240.992448)
			(xy 362.403612 -240.967841) (xy 362.449628 -240.950389) (xy 362.497847 -240.940545) (xy 362.547022 -240.938564)
			(xy 362.595877 -240.944496) (xy 362.643148 -240.958188) (xy 362.68761 -240.979286) (xy 362.728113 -241.007242)
			(xy 362.763606 -241.041334) (xy 362.793171 -241.080678) (xy 362.816042 -241.124255) (xy 362.831626 -241.170936)
			(xy 362.839521 -241.219513) (xy 362.840016 -241.24412) (xy 363.168958 -241.24412) (xy 363.172918 -241.195066)
			(xy 363.184695 -241.147282) (xy 363.203986 -241.102006) (xy 363.230289 -241.06041) (xy 363.262924 -241.023573)
			(xy 363.301045 -240.992448) (xy 363.343666 -240.967841) (xy 363.389682 -240.950389) (xy 363.437901 -240.940545)
			(xy 363.487076 -240.938564) (xy 363.535931 -240.944496) (xy 363.583202 -240.958188) (xy 363.627664 -240.979286)
			(xy 363.668167 -241.007242) (xy 363.70366 -241.041334) (xy 363.733225 -241.080678) (xy 363.756096 -241.124255)
			(xy 363.77168 -241.170936) (xy 363.779575 -241.219513) (xy 363.78007 -241.24412) (xy 364.109012 -241.24412)
			(xy 364.112972 -241.195066) (xy 364.124749 -241.147282) (xy 364.14404 -241.102006) (xy 364.170343 -241.06041)
			(xy 364.202978 -241.023573) (xy 364.241099 -240.992448) (xy 364.28372 -240.967841) (xy 364.329736 -240.950389)
			(xy 364.377955 -240.940545) (xy 364.42713 -240.938564) (xy 364.475985 -240.944496) (xy 364.523256 -240.958188)
			(xy 364.567718 -240.979286) (xy 364.608221 -241.007242) (xy 364.643714 -241.041334) (xy 364.673279 -241.080678)
			(xy 364.69615 -241.124255) (xy 364.711734 -241.170936) (xy 364.719629 -241.219513) (xy 364.720124 -241.24412)
			(xy 365.049066 -241.24412) (xy 365.053026 -241.195066) (xy 365.064803 -241.147282) (xy 365.084094 -241.102006)
			(xy 365.110397 -241.06041) (xy 365.143032 -241.023573) (xy 365.181153 -240.992448) (xy 365.223774 -240.967841)
			(xy 365.26979 -240.950389) (xy 365.318009 -240.940545) (xy 365.367184 -240.938564) (xy 365.416039 -240.944496)
			(xy 365.46331 -240.958188) (xy 365.507772 -240.979286) (xy 365.548275 -241.007242) (xy 365.583768 -241.041334)
			(xy 365.613333 -241.080678) (xy 365.636204 -241.124255) (xy 365.651788 -241.170936) (xy 365.659683 -241.219513)
			(xy 365.660178 -241.24412) (xy 365.98912 -241.24412) (xy 365.99308 -241.195066) (xy 366.004857 -241.147282)
			(xy 366.024148 -241.102006) (xy 366.050451 -241.06041) (xy 366.083086 -241.023573) (xy 366.121207 -240.992448)
			(xy 366.163828 -240.967841) (xy 366.209844 -240.950389) (xy 366.258063 -240.940545) (xy 366.307238 -240.938564)
			(xy 366.356093 -240.944496) (xy 366.403364 -240.958188) (xy 366.447826 -240.979286) (xy 366.488329 -241.007242)
			(xy 366.523822 -241.041334) (xy 366.553387 -241.080678) (xy 366.576258 -241.124255) (xy 366.591842 -241.170936)
			(xy 366.599737 -241.219513) (xy 366.600232 -241.24412) (xy 366.92892 -241.24412) (xy 366.93288 -241.195066)
			(xy 366.944657 -241.147282) (xy 366.963948 -241.102006) (xy 366.990251 -241.06041) (xy 367.022886 -241.023573)
			(xy 367.061007 -240.992448) (xy 367.103628 -240.967841) (xy 367.149644 -240.950389) (xy 367.197863 -240.940545)
			(xy 367.247038 -240.938564) (xy 367.295893 -240.944496) (xy 367.343164 -240.958188) (xy 367.387626 -240.979286)
			(xy 367.428129 -241.007242) (xy 367.463622 -241.041334) (xy 367.493187 -241.080678) (xy 367.516058 -241.124255)
			(xy 367.531642 -241.170936) (xy 367.539537 -241.219513) (xy 367.540032 -241.24412) (xy 367.868974 -241.24412)
			(xy 367.872934 -241.195066) (xy 367.884711 -241.147282) (xy 367.904002 -241.102006) (xy 367.930305 -241.06041)
			(xy 367.96294 -241.023573) (xy 368.001061 -240.992448) (xy 368.043682 -240.967841) (xy 368.089698 -240.950389)
			(xy 368.137917 -240.940545) (xy 368.187092 -240.938564) (xy 368.235947 -240.944496) (xy 368.283218 -240.958188)
			(xy 368.32768 -240.979286) (xy 368.368183 -241.007242) (xy 368.403676 -241.041334) (xy 368.433241 -241.080678)
			(xy 368.456112 -241.124255) (xy 368.471696 -241.170936) (xy 368.479591 -241.219513) (xy 368.480086 -241.24412)
			(xy 368.809028 -241.24412) (xy 368.812988 -241.195066) (xy 368.824765 -241.147282) (xy 368.844056 -241.102006)
			(xy 368.870359 -241.06041) (xy 368.902994 -241.023573) (xy 368.941115 -240.992448) (xy 368.983736 -240.967841)
			(xy 369.029752 -240.950389) (xy 369.077971 -240.940545) (xy 369.127146 -240.938564) (xy 369.176001 -240.944496)
			(xy 369.223272 -240.958188) (xy 369.267734 -240.979286) (xy 369.308237 -241.007242) (xy 369.34373 -241.041334)
			(xy 369.373295 -241.080678) (xy 369.396166 -241.124255) (xy 369.41175 -241.170936) (xy 369.419645 -241.219513)
			(xy 369.42014 -241.24412) (xy 369.749082 -241.24412) (xy 369.753042 -241.195066) (xy 369.764819 -241.147282)
			(xy 369.78411 -241.102006) (xy 369.810413 -241.06041) (xy 369.843048 -241.023573) (xy 369.881169 -240.992448)
			(xy 369.92379 -240.967841) (xy 369.969806 -240.950389) (xy 370.018025 -240.940545) (xy 370.0672 -240.938564)
			(xy 370.116055 -240.944496) (xy 370.163326 -240.958188) (xy 370.207788 -240.979286) (xy 370.248291 -241.007242)
			(xy 370.283784 -241.041334) (xy 370.313349 -241.080678) (xy 370.33622 -241.124255) (xy 370.351804 -241.170936)
			(xy 370.359699 -241.219513) (xy 370.360194 -241.24412) (xy 370.688882 -241.24412) (xy 370.692842 -241.195066)
			(xy 370.704619 -241.147282) (xy 370.72391 -241.102006) (xy 370.750213 -241.06041) (xy 370.782848 -241.023573)
			(xy 370.820969 -240.992448) (xy 370.86359 -240.967841) (xy 370.909606 -240.950389) (xy 370.957825 -240.940545)
			(xy 371.007 -240.938564) (xy 371.055855 -240.944496) (xy 371.103126 -240.958188) (xy 371.147588 -240.979286)
			(xy 371.188091 -241.007242) (xy 371.223584 -241.041334) (xy 371.253149 -241.080678) (xy 371.27602 -241.124255)
			(xy 371.291604 -241.170936) (xy 371.299499 -241.219513) (xy 371.299994 -241.24412) (xy 371.628936 -241.24412)
			(xy 371.632896 -241.195066) (xy 371.644673 -241.147282) (xy 371.663964 -241.102006) (xy 371.690267 -241.06041)
			(xy 371.722902 -241.023573) (xy 371.761023 -240.992448) (xy 371.803644 -240.967841) (xy 371.84966 -240.950389)
			(xy 371.897879 -240.940545) (xy 371.947054 -240.938564) (xy 371.995909 -240.944496) (xy 372.04318 -240.958188)
			(xy 372.087642 -240.979286) (xy 372.128145 -241.007242) (xy 372.163638 -241.041334) (xy 372.193203 -241.080678)
			(xy 372.216074 -241.124255) (xy 372.231658 -241.170936) (xy 372.239553 -241.219513) (xy 372.240048 -241.24412)
			(xy 372.56899 -241.24412) (xy 372.57295 -241.195066) (xy 372.584727 -241.147282) (xy 372.604018 -241.102006)
			(xy 372.630321 -241.06041) (xy 372.662956 -241.023573) (xy 372.701077 -240.992448) (xy 372.743698 -240.967841)
			(xy 372.789714 -240.950389) (xy 372.837933 -240.940545) (xy 372.887108 -240.938564) (xy 372.935963 -240.944496)
			(xy 372.983234 -240.958188) (xy 373.027696 -240.979286) (xy 373.068199 -241.007242) (xy 373.103692 -241.041334)
			(xy 373.133257 -241.080678) (xy 373.156128 -241.124255) (xy 373.171712 -241.170936) (xy 373.179607 -241.219513)
			(xy 373.180102 -241.24412) (xy 373.509044 -241.24412) (xy 373.513004 -241.195066) (xy 373.524781 -241.147282)
			(xy 373.544072 -241.102006) (xy 373.570375 -241.06041) (xy 373.60301 -241.023573) (xy 373.641131 -240.992448)
			(xy 373.683752 -240.967841) (xy 373.729768 -240.950389) (xy 373.777987 -240.940545) (xy 373.827162 -240.938564)
			(xy 373.876017 -240.944496) (xy 373.923288 -240.958188) (xy 373.96775 -240.979286) (xy 374.008253 -241.007242)
			(xy 374.043746 -241.041334) (xy 374.073311 -241.080678) (xy 374.096182 -241.124255) (xy 374.111766 -241.170936)
			(xy 374.119661 -241.219513) (xy 374.120156 -241.24412) (xy 374.449098 -241.24412) (xy 374.453058 -241.195066)
			(xy 374.464835 -241.147282) (xy 374.484126 -241.102006) (xy 374.510429 -241.06041) (xy 374.543064 -241.023573)
			(xy 374.581185 -240.992448) (xy 374.623806 -240.967841) (xy 374.669822 -240.950389) (xy 374.718041 -240.940545)
			(xy 374.767216 -240.938564) (xy 374.816071 -240.944496) (xy 374.863342 -240.958188) (xy 374.907804 -240.979286)
			(xy 374.948307 -241.007242) (xy 374.9838 -241.041334) (xy 375.013365 -241.080678) (xy 375.036236 -241.124255)
			(xy 375.05182 -241.170936) (xy 375.059715 -241.219513) (xy 375.06021 -241.24412) (xy 375.378467 -241.24412)
			(xy 375.382562 -241.193392) (xy 375.394741 -241.143978) (xy 375.414689 -241.097158) (xy 375.44189 -241.054144)
			(xy 375.475638 -241.01605) (xy 375.51506 -240.983863) (xy 375.559134 -240.958417) (xy 375.60672 -240.94037)
			(xy 375.656584 -240.93019) (xy 375.707436 -240.928141) (xy 375.757957 -240.934275) (xy 375.806841 -240.948435)
			(xy 375.85282 -240.970252) (xy 375.894704 -240.999162) (xy 375.931408 -241.034417) (xy 375.961981 -241.075103)
			(xy 375.985632 -241.120166) (xy 376.001748 -241.16844) (xy 376.009912 -241.218674) (xy 376.010424 -241.24412)
			(xy 376.328952 -241.24412) (xy 376.332912 -241.195066) (xy 376.344689 -241.147282) (xy 376.36398 -241.102006)
			(xy 376.390283 -241.06041) (xy 376.422918 -241.023573) (xy 376.461039 -240.992448) (xy 376.50366 -240.967841)
			(xy 376.549676 -240.950389) (xy 376.597895 -240.940545) (xy 376.64707 -240.938564) (xy 376.695925 -240.944496)
			(xy 376.743196 -240.958188) (xy 376.787658 -240.979286) (xy 376.828161 -241.007242) (xy 376.863654 -241.041334)
			(xy 376.893219 -241.080678) (xy 376.91609 -241.124255) (xy 376.931674 -241.170936) (xy 376.939569 -241.219513)
			(xy 376.940064 -241.24412) (xy 376.939569 -241.268727) (xy 376.931674 -241.317304) (xy 376.91609 -241.363985)
			(xy 376.893219 -241.407562) (xy 376.863654 -241.446906) (xy 376.828161 -241.480998) (xy 376.787658 -241.508954)
			(xy 376.743196 -241.530052) (xy 376.695925 -241.543744) (xy 376.64707 -241.549676) (xy 376.597895 -241.547695)
			(xy 376.549676 -241.537851) (xy 376.50366 -241.520399) (xy 376.461039 -241.495792) (xy 376.422918 -241.464667)
			(xy 376.390283 -241.42783) (xy 376.36398 -241.386234) (xy 376.344689 -241.340958) (xy 376.332912 -241.293174)
			(xy 376.328952 -241.24412) (xy 376.010424 -241.24412) (xy 376.009912 -241.269566) (xy 376.001748 -241.3198)
			(xy 375.985632 -241.368074) (xy 375.961981 -241.413137) (xy 375.931408 -241.453823) (xy 375.894704 -241.489078)
			(xy 375.85282 -241.517988) (xy 375.806841 -241.539805) (xy 375.757957 -241.553965) (xy 375.707436 -241.560099)
			(xy 375.656584 -241.55805) (xy 375.60672 -241.54787) (xy 375.559134 -241.529823) (xy 375.51506 -241.504377)
			(xy 375.475638 -241.47219) (xy 375.44189 -241.434096) (xy 375.414689 -241.391082) (xy 375.394741 -241.344262)
			(xy 375.382562 -241.294848) (xy 375.378467 -241.24412) (xy 375.06021 -241.24412) (xy 375.059715 -241.268727)
			(xy 375.05182 -241.317304) (xy 375.036236 -241.363985) (xy 375.013365 -241.407562) (xy 374.9838 -241.446906)
			(xy 374.948307 -241.480998) (xy 374.907804 -241.508954) (xy 374.863342 -241.530052) (xy 374.816071 -241.543744)
			(xy 374.767216 -241.549676) (xy 374.718041 -241.547695) (xy 374.669822 -241.537851) (xy 374.623806 -241.520399)
			(xy 374.581185 -241.495792) (xy 374.543064 -241.464667) (xy 374.510429 -241.42783) (xy 374.484126 -241.386234)
			(xy 374.464835 -241.340958) (xy 374.453058 -241.293174) (xy 374.449098 -241.24412) (xy 374.120156 -241.24412)
			(xy 374.119661 -241.268727) (xy 374.111766 -241.317304) (xy 374.096182 -241.363985) (xy 374.073311 -241.407562)
			(xy 374.043746 -241.446906) (xy 374.008253 -241.480998) (xy 373.96775 -241.508954) (xy 373.923288 -241.530052)
			(xy 373.876017 -241.543744) (xy 373.827162 -241.549676) (xy 373.777987 -241.547695) (xy 373.729768 -241.537851)
			(xy 373.683752 -241.520399) (xy 373.641131 -241.495792) (xy 373.60301 -241.464667) (xy 373.570375 -241.42783)
			(xy 373.544072 -241.386234) (xy 373.524781 -241.340958) (xy 373.513004 -241.293174) (xy 373.509044 -241.24412)
			(xy 373.180102 -241.24412) (xy 373.179607 -241.268727) (xy 373.171712 -241.317304) (xy 373.156128 -241.363985)
			(xy 373.133257 -241.407562) (xy 373.103692 -241.446906) (xy 373.068199 -241.480998) (xy 373.027696 -241.508954)
			(xy 372.983234 -241.530052) (xy 372.935963 -241.543744) (xy 372.887108 -241.549676) (xy 372.837933 -241.547695)
			(xy 372.789714 -241.537851) (xy 372.743698 -241.520399) (xy 372.701077 -241.495792) (xy 372.662956 -241.464667)
			(xy 372.630321 -241.42783) (xy 372.604018 -241.386234) (xy 372.584727 -241.340958) (xy 372.57295 -241.293174)
			(xy 372.56899 -241.24412) (xy 372.240048 -241.24412) (xy 372.239553 -241.268727) (xy 372.231658 -241.317304)
			(xy 372.216074 -241.363985) (xy 372.193203 -241.407562) (xy 372.163638 -241.446906) (xy 372.128145 -241.480998)
			(xy 372.087642 -241.508954) (xy 372.04318 -241.530052) (xy 371.995909 -241.543744) (xy 371.947054 -241.549676)
			(xy 371.897879 -241.547695) (xy 371.84966 -241.537851) (xy 371.803644 -241.520399) (xy 371.761023 -241.495792)
			(xy 371.722902 -241.464667) (xy 371.690267 -241.42783) (xy 371.663964 -241.386234) (xy 371.644673 -241.340958)
			(xy 371.632896 -241.293174) (xy 371.628936 -241.24412) (xy 371.299994 -241.24412) (xy 371.299499 -241.268727)
			(xy 371.291604 -241.317304) (xy 371.27602 -241.363985) (xy 371.253149 -241.407562) (xy 371.223584 -241.446906)
			(xy 371.188091 -241.480998) (xy 371.147588 -241.508954) (xy 371.103126 -241.530052) (xy 371.055855 -241.543744)
			(xy 371.007 -241.549676) (xy 370.957825 -241.547695) (xy 370.909606 -241.537851) (xy 370.86359 -241.520399)
			(xy 370.820969 -241.495792) (xy 370.782848 -241.464667) (xy 370.750213 -241.42783) (xy 370.72391 -241.386234)
			(xy 370.704619 -241.340958) (xy 370.692842 -241.293174) (xy 370.688882 -241.24412) (xy 370.360194 -241.24412)
			(xy 370.359699 -241.268727) (xy 370.351804 -241.317304) (xy 370.33622 -241.363985) (xy 370.313349 -241.407562)
			(xy 370.283784 -241.446906) (xy 370.248291 -241.480998) (xy 370.207788 -241.508954) (xy 370.163326 -241.530052)
			(xy 370.116055 -241.543744) (xy 370.0672 -241.549676) (xy 370.018025 -241.547695) (xy 369.969806 -241.537851)
			(xy 369.92379 -241.520399) (xy 369.881169 -241.495792) (xy 369.843048 -241.464667) (xy 369.810413 -241.42783)
			(xy 369.78411 -241.386234) (xy 369.764819 -241.340958) (xy 369.753042 -241.293174) (xy 369.749082 -241.24412)
			(xy 369.42014 -241.24412) (xy 369.419645 -241.268727) (xy 369.41175 -241.317304) (xy 369.396166 -241.363985)
			(xy 369.373295 -241.407562) (xy 369.34373 -241.446906) (xy 369.308237 -241.480998) (xy 369.267734 -241.508954)
			(xy 369.223272 -241.530052) (xy 369.176001 -241.543744) (xy 369.127146 -241.549676) (xy 369.077971 -241.547695)
			(xy 369.029752 -241.537851) (xy 368.983736 -241.520399) (xy 368.941115 -241.495792) (xy 368.902994 -241.464667)
			(xy 368.870359 -241.42783) (xy 368.844056 -241.386234) (xy 368.824765 -241.340958) (xy 368.812988 -241.293174)
			(xy 368.809028 -241.24412) (xy 368.480086 -241.24412) (xy 368.479591 -241.268727) (xy 368.471696 -241.317304)
			(xy 368.456112 -241.363985) (xy 368.433241 -241.407562) (xy 368.403676 -241.446906) (xy 368.368183 -241.480998)
			(xy 368.32768 -241.508954) (xy 368.283218 -241.530052) (xy 368.235947 -241.543744) (xy 368.187092 -241.549676)
			(xy 368.137917 -241.547695) (xy 368.089698 -241.537851) (xy 368.043682 -241.520399) (xy 368.001061 -241.495792)
			(xy 367.96294 -241.464667) (xy 367.930305 -241.42783) (xy 367.904002 -241.386234) (xy 367.884711 -241.340958)
			(xy 367.872934 -241.293174) (xy 367.868974 -241.24412) (xy 367.540032 -241.24412) (xy 367.539537 -241.268727)
			(xy 367.531642 -241.317304) (xy 367.516058 -241.363985) (xy 367.493187 -241.407562) (xy 367.463622 -241.446906)
			(xy 367.428129 -241.480998) (xy 367.387626 -241.508954) (xy 367.343164 -241.530052) (xy 367.295893 -241.543744)
			(xy 367.247038 -241.549676) (xy 367.197863 -241.547695) (xy 367.149644 -241.537851) (xy 367.103628 -241.520399)
			(xy 367.061007 -241.495792) (xy 367.022886 -241.464667) (xy 366.990251 -241.42783) (xy 366.963948 -241.386234)
			(xy 366.944657 -241.340958) (xy 366.93288 -241.293174) (xy 366.92892 -241.24412) (xy 366.600232 -241.24412)
			(xy 366.599737 -241.268727) (xy 366.591842 -241.317304) (xy 366.576258 -241.363985) (xy 366.553387 -241.407562)
			(xy 366.523822 -241.446906) (xy 366.488329 -241.480998) (xy 366.447826 -241.508954) (xy 366.403364 -241.530052)
			(xy 366.356093 -241.543744) (xy 366.307238 -241.549676) (xy 366.258063 -241.547695) (xy 366.209844 -241.537851)
			(xy 366.163828 -241.520399) (xy 366.121207 -241.495792) (xy 366.083086 -241.464667) (xy 366.050451 -241.42783)
			(xy 366.024148 -241.386234) (xy 366.004857 -241.340958) (xy 365.99308 -241.293174) (xy 365.98912 -241.24412)
			(xy 365.660178 -241.24412) (xy 365.659683 -241.268727) (xy 365.651788 -241.317304) (xy 365.636204 -241.363985)
			(xy 365.613333 -241.407562) (xy 365.583768 -241.446906) (xy 365.548275 -241.480998) (xy 365.507772 -241.508954)
			(xy 365.46331 -241.530052) (xy 365.416039 -241.543744) (xy 365.367184 -241.549676) (xy 365.318009 -241.547695)
			(xy 365.26979 -241.537851) (xy 365.223774 -241.520399) (xy 365.181153 -241.495792) (xy 365.143032 -241.464667)
			(xy 365.110397 -241.42783) (xy 365.084094 -241.386234) (xy 365.064803 -241.340958) (xy 365.053026 -241.293174)
			(xy 365.049066 -241.24412) (xy 364.720124 -241.24412) (xy 364.719629 -241.268727) (xy 364.711734 -241.317304)
			(xy 364.69615 -241.363985) (xy 364.673279 -241.407562) (xy 364.643714 -241.446906) (xy 364.608221 -241.480998)
			(xy 364.567718 -241.508954) (xy 364.523256 -241.530052) (xy 364.475985 -241.543744) (xy 364.42713 -241.549676)
			(xy 364.377955 -241.547695) (xy 364.329736 -241.537851) (xy 364.28372 -241.520399) (xy 364.241099 -241.495792)
			(xy 364.202978 -241.464667) (xy 364.170343 -241.42783) (xy 364.14404 -241.386234) (xy 364.124749 -241.340958)
			(xy 364.112972 -241.293174) (xy 364.109012 -241.24412) (xy 363.78007 -241.24412) (xy 363.779575 -241.268727)
			(xy 363.77168 -241.317304) (xy 363.756096 -241.363985) (xy 363.733225 -241.407562) (xy 363.70366 -241.446906)
			(xy 363.668167 -241.480998) (xy 363.627664 -241.508954) (xy 363.583202 -241.530052) (xy 363.535931 -241.543744)
			(xy 363.487076 -241.549676) (xy 363.437901 -241.547695) (xy 363.389682 -241.537851) (xy 363.343666 -241.520399)
			(xy 363.301045 -241.495792) (xy 363.262924 -241.464667) (xy 363.230289 -241.42783) (xy 363.203986 -241.386234)
			(xy 363.184695 -241.340958) (xy 363.172918 -241.293174) (xy 363.168958 -241.24412) (xy 362.840016 -241.24412)
			(xy 362.839521 -241.268727) (xy 362.831626 -241.317304) (xy 362.816042 -241.363985) (xy 362.793171 -241.407562)
			(xy 362.763606 -241.446906) (xy 362.728113 -241.480998) (xy 362.68761 -241.508954) (xy 362.643148 -241.530052)
			(xy 362.595877 -241.543744) (xy 362.547022 -241.549676) (xy 362.497847 -241.547695) (xy 362.449628 -241.537851)
			(xy 362.403612 -241.520399) (xy 362.360991 -241.495792) (xy 362.32287 -241.464667) (xy 362.290235 -241.42783)
			(xy 362.263932 -241.386234) (xy 362.244641 -241.340958) (xy 362.232864 -241.293174) (xy 362.228904 -241.24412)
			(xy 361.900216 -241.24412) (xy 361.899721 -241.268727) (xy 361.891826 -241.317304) (xy 361.876242 -241.363985)
			(xy 361.853371 -241.407562) (xy 361.823806 -241.446906) (xy 361.788313 -241.480998) (xy 361.74781 -241.508954)
			(xy 361.703348 -241.530052) (xy 361.656077 -241.543744) (xy 361.607222 -241.549676) (xy 361.558047 -241.547695)
			(xy 361.509828 -241.537851) (xy 361.463812 -241.520399) (xy 361.421191 -241.495792) (xy 361.38307 -241.464667)
			(xy 361.350435 -241.42783) (xy 361.324132 -241.386234) (xy 361.304841 -241.340958) (xy 361.293064 -241.293174)
			(xy 361.289104 -241.24412) (xy 358.14635 -241.24412) (xy 358.145855 -241.268727) (xy 358.13796 -241.317304)
			(xy 358.122376 -241.363985) (xy 358.099505 -241.407562) (xy 358.06994 -241.446906) (xy 358.034447 -241.480998)
			(xy 357.993944 -241.508954) (xy 357.949482 -241.530052) (xy 357.902211 -241.543744) (xy 357.853356 -241.549676)
			(xy 357.804181 -241.547695) (xy 357.755962 -241.537851) (xy 357.709946 -241.520399) (xy 357.667325 -241.495792)
			(xy 357.629204 -241.464667) (xy 357.596569 -241.42783) (xy 357.570266 -241.386234) (xy 357.550975 -241.340958)
			(xy 357.539198 -241.293174) (xy 357.535238 -241.24412) (xy 357.20655 -241.24412) (xy 357.206055 -241.268727)
			(xy 357.19816 -241.317304) (xy 357.182576 -241.363985) (xy 357.159705 -241.407562) (xy 357.13014 -241.446906)
			(xy 357.094647 -241.480998) (xy 357.054144 -241.508954) (xy 357.009682 -241.530052) (xy 356.962411 -241.543744)
			(xy 356.913556 -241.549676) (xy 356.864381 -241.547695) (xy 356.816162 -241.537851) (xy 356.770146 -241.520399)
			(xy 356.727525 -241.495792) (xy 356.689404 -241.464667) (xy 356.656769 -241.42783) (xy 356.630466 -241.386234)
			(xy 356.611175 -241.340958) (xy 356.599398 -241.293174) (xy 356.595438 -241.24412) (xy 356.266496 -241.24412)
			(xy 356.266001 -241.268727) (xy 356.258106 -241.317304) (xy 356.242522 -241.363985) (xy 356.219651 -241.407562)
			(xy 356.190086 -241.446906) (xy 356.154593 -241.480998) (xy 356.11409 -241.508954) (xy 356.069628 -241.530052)
			(xy 356.022357 -241.543744) (xy 355.973502 -241.549676) (xy 355.924327 -241.547695) (xy 355.876108 -241.537851)
			(xy 355.830092 -241.520399) (xy 355.787471 -241.495792) (xy 355.74935 -241.464667) (xy 355.716715 -241.42783)
			(xy 355.690412 -241.386234) (xy 355.671121 -241.340958) (xy 355.659344 -241.293174) (xy 355.655384 -241.24412)
			(xy 355.326442 -241.24412) (xy 355.325947 -241.268727) (xy 355.318052 -241.317304) (xy 355.302468 -241.363985)
			(xy 355.279597 -241.407562) (xy 355.250032 -241.446906) (xy 355.214539 -241.480998) (xy 355.174036 -241.508954)
			(xy 355.129574 -241.530052) (xy 355.082303 -241.543744) (xy 355.033448 -241.549676) (xy 354.984273 -241.547695)
			(xy 354.936054 -241.537851) (xy 354.890038 -241.520399) (xy 354.847417 -241.495792) (xy 354.809296 -241.464667)
			(xy 354.776661 -241.42783) (xy 354.750358 -241.386234) (xy 354.731067 -241.340958) (xy 354.71929 -241.293174)
			(xy 354.71533 -241.24412) (xy 354.386388 -241.24412) (xy 354.385893 -241.268727) (xy 354.377998 -241.317304)
			(xy 354.362414 -241.363985) (xy 354.339543 -241.407562) (xy 354.309978 -241.446906) (xy 354.274485 -241.480998)
			(xy 354.233982 -241.508954) (xy 354.18952 -241.530052) (xy 354.142249 -241.543744) (xy 354.093394 -241.549676)
			(xy 354.044219 -241.547695) (xy 353.996 -241.537851) (xy 353.949984 -241.520399) (xy 353.907363 -241.495792)
			(xy 353.869242 -241.464667) (xy 353.836607 -241.42783) (xy 353.810304 -241.386234) (xy 353.791013 -241.340958)
			(xy 353.779236 -241.293174) (xy 353.775276 -241.24412) (xy 353.446334 -241.24412) (xy 353.445839 -241.268727)
			(xy 353.437944 -241.317304) (xy 353.42236 -241.363985) (xy 353.399489 -241.407562) (xy 353.369924 -241.446906)
			(xy 353.334431 -241.480998) (xy 353.293928 -241.508954) (xy 353.249466 -241.530052) (xy 353.202195 -241.543744)
			(xy 353.15334 -241.549676) (xy 353.104165 -241.547695) (xy 353.055946 -241.537851) (xy 353.00993 -241.520399)
			(xy 352.967309 -241.495792) (xy 352.929188 -241.464667) (xy 352.896553 -241.42783) (xy 352.87025 -241.386234)
			(xy 352.850959 -241.340958) (xy 352.839182 -241.293174) (xy 352.835222 -241.24412) (xy 352.506534 -241.24412)
			(xy 352.506039 -241.268727) (xy 352.498144 -241.317304) (xy 352.48256 -241.363985) (xy 352.459689 -241.407562)
			(xy 352.430124 -241.446906) (xy 352.394631 -241.480998) (xy 352.354128 -241.508954) (xy 352.309666 -241.530052)
			(xy 352.262395 -241.543744) (xy 352.21354 -241.549676) (xy 352.164365 -241.547695) (xy 352.116146 -241.537851)
			(xy 352.07013 -241.520399) (xy 352.027509 -241.495792) (xy 351.989388 -241.464667) (xy 351.956753 -241.42783)
			(xy 351.93045 -241.386234) (xy 351.911159 -241.340958) (xy 351.899382 -241.293174) (xy 351.895422 -241.24412)
			(xy 351.56648 -241.24412) (xy 351.565985 -241.268727) (xy 351.55809 -241.317304) (xy 351.542506 -241.363985)
			(xy 351.519635 -241.407562) (xy 351.49007 -241.446906) (xy 351.454577 -241.480998) (xy 351.414074 -241.508954)
			(xy 351.369612 -241.530052) (xy 351.322341 -241.543744) (xy 351.273486 -241.549676) (xy 351.224311 -241.547695)
			(xy 351.176092 -241.537851) (xy 351.130076 -241.520399) (xy 351.087455 -241.495792) (xy 351.049334 -241.464667)
			(xy 351.016699 -241.42783) (xy 350.990396 -241.386234) (xy 350.971105 -241.340958) (xy 350.959328 -241.293174)
			(xy 350.955368 -241.24412) (xy 350.626426 -241.24412) (xy 350.625931 -241.268727) (xy 350.618036 -241.317304)
			(xy 350.602452 -241.363985) (xy 350.579581 -241.407562) (xy 350.550016 -241.446906) (xy 350.514523 -241.480998)
			(xy 350.47402 -241.508954) (xy 350.429558 -241.530052) (xy 350.382287 -241.543744) (xy 350.333432 -241.549676)
			(xy 350.284257 -241.547695) (xy 350.236038 -241.537851) (xy 350.190022 -241.520399) (xy 350.147401 -241.495792)
			(xy 350.10928 -241.464667) (xy 350.076645 -241.42783) (xy 350.050342 -241.386234) (xy 350.031051 -241.340958)
			(xy 350.019274 -241.293174) (xy 350.015314 -241.24412) (xy 349.686372 -241.24412) (xy 349.685877 -241.268727)
			(xy 349.677982 -241.317304) (xy 349.662398 -241.363985) (xy 349.639527 -241.407562) (xy 349.609962 -241.446906)
			(xy 349.574469 -241.480998) (xy 349.533966 -241.508954) (xy 349.489504 -241.530052) (xy 349.442233 -241.543744)
			(xy 349.393378 -241.549676) (xy 349.344203 -241.547695) (xy 349.295984 -241.537851) (xy 349.249968 -241.520399)
			(xy 349.207347 -241.495792) (xy 349.169226 -241.464667) (xy 349.136591 -241.42783) (xy 349.110288 -241.386234)
			(xy 349.090997 -241.340958) (xy 349.07922 -241.293174) (xy 349.07526 -241.24412) (xy 348.746318 -241.24412)
			(xy 348.745823 -241.268727) (xy 348.737928 -241.317304) (xy 348.722344 -241.363985) (xy 348.699473 -241.407562)
			(xy 348.669908 -241.446906) (xy 348.634415 -241.480998) (xy 348.593912 -241.508954) (xy 348.54945 -241.530052)
			(xy 348.502179 -241.543744) (xy 348.453324 -241.549676) (xy 348.404149 -241.547695) (xy 348.35593 -241.537851)
			(xy 348.309914 -241.520399) (xy 348.267293 -241.495792) (xy 348.229172 -241.464667) (xy 348.196537 -241.42783)
			(xy 348.170234 -241.386234) (xy 348.150943 -241.340958) (xy 348.139166 -241.293174) (xy 348.135206 -241.24412)
			(xy 347.806518 -241.24412) (xy 347.806023 -241.268727) (xy 347.798128 -241.317304) (xy 347.782544 -241.363985)
			(xy 347.759673 -241.407562) (xy 347.730108 -241.446906) (xy 347.694615 -241.480998) (xy 347.654112 -241.508954)
			(xy 347.60965 -241.530052) (xy 347.562379 -241.543744) (xy 347.513524 -241.549676) (xy 347.464349 -241.547695)
			(xy 347.41613 -241.537851) (xy 347.370114 -241.520399) (xy 347.327493 -241.495792) (xy 347.289372 -241.464667)
			(xy 347.256737 -241.42783) (xy 347.230434 -241.386234) (xy 347.211143 -241.340958) (xy 347.199366 -241.293174)
			(xy 347.195406 -241.24412) (xy 346.866464 -241.24412) (xy 346.865969 -241.268727) (xy 346.858074 -241.317304)
			(xy 346.84249 -241.363985) (xy 346.819619 -241.407562) (xy 346.790054 -241.446906) (xy 346.754561 -241.480998)
			(xy 346.714058 -241.508954) (xy 346.669596 -241.530052) (xy 346.622325 -241.543744) (xy 346.57347 -241.549676)
			(xy 346.524295 -241.547695) (xy 346.476076 -241.537851) (xy 346.43006 -241.520399) (xy 346.387439 -241.495792)
			(xy 346.349318 -241.464667) (xy 346.316683 -241.42783) (xy 346.29038 -241.386234) (xy 346.271089 -241.340958)
			(xy 346.259312 -241.293174) (xy 346.255352 -241.24412) (xy 345.92641 -241.24412) (xy 345.925915 -241.268727)
			(xy 345.91802 -241.317304) (xy 345.902436 -241.363985) (xy 345.879565 -241.407562) (xy 345.85 -241.446906)
			(xy 345.814507 -241.480998) (xy 345.774004 -241.508954) (xy 345.729542 -241.530052) (xy 345.682271 -241.543744)
			(xy 345.633416 -241.549676) (xy 345.584241 -241.547695) (xy 345.536022 -241.537851) (xy 345.490006 -241.520399)
			(xy 345.447385 -241.495792) (xy 345.409264 -241.464667) (xy 345.376629 -241.42783) (xy 345.350326 -241.386234)
			(xy 345.331035 -241.340958) (xy 345.319258 -241.293174) (xy 345.315298 -241.24412) (xy 344.986356 -241.24412)
			(xy 344.985861 -241.268727) (xy 344.977966 -241.317304) (xy 344.962382 -241.363985) (xy 344.939511 -241.407562)
			(xy 344.909946 -241.446906) (xy 344.874453 -241.480998) (xy 344.83395 -241.508954) (xy 344.789488 -241.530052)
			(xy 344.742217 -241.543744) (xy 344.693362 -241.549676) (xy 344.644187 -241.547695) (xy 344.595968 -241.537851)
			(xy 344.549952 -241.520399) (xy 344.507331 -241.495792) (xy 344.46921 -241.464667) (xy 344.436575 -241.42783)
			(xy 344.410272 -241.386234) (xy 344.390981 -241.340958) (xy 344.379204 -241.293174) (xy 344.375244 -241.24412)
			(xy 344.056716 -241.24412) (xy 344.056204 -241.269566) (xy 344.04804 -241.3198) (xy 344.031924 -241.368074)
			(xy 344.008273 -241.413137) (xy 343.9777 -241.453823) (xy 343.940996 -241.489078) (xy 343.899112 -241.517988)
			(xy 343.853133 -241.539805) (xy 343.804249 -241.553965) (xy 343.753728 -241.560099) (xy 343.702876 -241.55805)
			(xy 343.653012 -241.54787) (xy 343.605426 -241.529823) (xy 343.561352 -241.504377) (xy 343.52193 -241.47219)
			(xy 343.488182 -241.434096) (xy 343.460981 -241.391082) (xy 343.441033 -241.344262) (xy 343.428854 -241.294848)
			(xy 343.424759 -241.24412) (xy 343.106502 -241.24412) (xy 343.106007 -241.268727) (xy 343.098112 -241.317304)
			(xy 343.082528 -241.363985) (xy 343.059657 -241.407562) (xy 343.030092 -241.446906) (xy 342.994599 -241.480998)
			(xy 342.954096 -241.508954) (xy 342.909634 -241.530052) (xy 342.862363 -241.543744) (xy 342.813508 -241.549676)
			(xy 342.764333 -241.547695) (xy 342.716114 -241.537851) (xy 342.670098 -241.520399) (xy 342.627477 -241.495792)
			(xy 342.589356 -241.464667) (xy 342.556721 -241.42783) (xy 342.530418 -241.386234) (xy 342.511127 -241.340958)
			(xy 342.49935 -241.293174) (xy 342.49539 -241.24412) (xy 342.176862 -241.24412) (xy 342.17635 -241.269566)
			(xy 342.168186 -241.3198) (xy 342.15207 -241.368074) (xy 342.128419 -241.413137) (xy 342.097846 -241.453823)
			(xy 342.061142 -241.489078) (xy 342.019258 -241.517988) (xy 341.973279 -241.539805) (xy 341.924395 -241.553965)
			(xy 341.873874 -241.560099) (xy 341.823022 -241.55805) (xy 341.773158 -241.54787) (xy 341.725572 -241.529823)
			(xy 341.681498 -241.504377) (xy 341.642076 -241.47219) (xy 341.608328 -241.434096) (xy 341.581127 -241.391082)
			(xy 341.561179 -241.344262) (xy 341.549 -241.294848) (xy 341.544905 -241.24412) (xy 341.226394 -241.24412)
			(xy 341.226074 -241.263315) (xy 341.22123 -241.3014) (xy 341.216742 -241.320066) (xy 341.215218 -241.326162)
			(xy 341.215218 -241.655346) (xy 341.215795 -241.666548) (xy 341.225268 -241.686852) (xy 341.233506 -241.694462)
			(xy 341.270844 -241.72545) (xy 341.29218 -241.74323) (xy 341.299358 -241.748735) (xy 341.316411 -241.754734)
			(xy 341.325454 -241.754914) (xy 341.330026 -241.754914) (xy 341.345103 -241.75205) (xy 341.375641 -241.748999)
			(xy 341.390986 -241.748818) (xy 341.393018 -241.748818) (xy 341.416905 -241.749439) (xy 341.464052 -241.757194)
			(xy 341.509415 -241.7722) (xy 341.551886 -241.79409) (xy 341.590429 -241.822329) (xy 341.624101 -241.856228)
			(xy 341.652082 -241.894959) (xy 341.673686 -241.937575) (xy 341.688388 -241.983038) (xy 341.695828 -242.030236)
			(xy 341.696294 -242.054126) (xy 342.014805 -242.054126) (xy 342.0189 -242.003398) (xy 342.031079 -241.953984)
			(xy 342.051027 -241.907164) (xy 342.078228 -241.86415) (xy 342.111976 -241.826056) (xy 342.151398 -241.793869)
			(xy 342.195472 -241.768423) (xy 342.243058 -241.750376) (xy 342.292922 -241.740196) (xy 342.343774 -241.738147)
			(xy 342.394295 -241.744281) (xy 342.443179 -241.758441) (xy 342.489158 -241.780258) (xy 342.531042 -241.809168)
			(xy 342.567746 -241.844423) (xy 342.598319 -241.885109) (xy 342.62197 -241.930172) (xy 342.638086 -241.978446)
			(xy 342.64625 -242.02868) (xy 342.646762 -242.054126) (xy 342.954859 -242.054126) (xy 342.958954 -242.003398)
			(xy 342.971133 -241.953984) (xy 342.991081 -241.907164) (xy 343.018282 -241.86415) (xy 343.05203 -241.826056)
			(xy 343.091452 -241.793869) (xy 343.135526 -241.768423) (xy 343.183112 -241.750376) (xy 343.232976 -241.740196)
			(xy 343.283828 -241.738147) (xy 343.334349 -241.744281) (xy 343.383233 -241.758441) (xy 343.429212 -241.780258)
			(xy 343.471096 -241.809168) (xy 343.5078 -241.844423) (xy 343.538373 -241.885109) (xy 343.562024 -241.930172)
			(xy 343.57814 -241.978446) (xy 343.586304 -242.02868) (xy 343.586816 -242.054126) (xy 343.905344 -242.054126)
			(xy 343.909304 -242.005072) (xy 343.921081 -241.957288) (xy 343.940372 -241.912012) (xy 343.966675 -241.870416)
			(xy 343.99931 -241.833579) (xy 344.037431 -241.802454) (xy 344.080052 -241.777847) (xy 344.126068 -241.760395)
			(xy 344.174287 -241.750551) (xy 344.223462 -241.74857) (xy 344.272317 -241.754502) (xy 344.319588 -241.768194)
			(xy 344.36405 -241.789292) (xy 344.404553 -241.817248) (xy 344.440046 -241.85134) (xy 344.469611 -241.890684)
			(xy 344.492482 -241.934261) (xy 344.508066 -241.980942) (xy 344.515961 -242.029519) (xy 344.516456 -242.054126)
			(xy 346.725252 -242.054126) (xy 346.729212 -242.005072) (xy 346.740989 -241.957288) (xy 346.76028 -241.912012)
			(xy 346.786583 -241.870416) (xy 346.819218 -241.833579) (xy 346.857339 -241.802454) (xy 346.89996 -241.777847)
			(xy 346.945976 -241.760395) (xy 346.994195 -241.750551) (xy 347.04337 -241.74857) (xy 347.092225 -241.754502)
			(xy 347.139496 -241.768194) (xy 347.183958 -241.789292) (xy 347.224461 -241.817248) (xy 347.259954 -241.85134)
			(xy 347.289519 -241.890684) (xy 347.31239 -241.934261) (xy 347.327974 -241.980942) (xy 347.335869 -242.029519)
			(xy 347.336364 -242.054126) (xy 349.545414 -242.054126) (xy 349.549374 -242.005072) (xy 349.561151 -241.957288)
			(xy 349.580442 -241.912012) (xy 349.606745 -241.870416) (xy 349.63938 -241.833579) (xy 349.677501 -241.802454)
			(xy 349.720122 -241.777847) (xy 349.766138 -241.760395) (xy 349.814357 -241.750551) (xy 349.863532 -241.74857)
			(xy 349.912387 -241.754502) (xy 349.959658 -241.768194) (xy 350.00412 -241.789292) (xy 350.044623 -241.817248)
			(xy 350.080116 -241.85134) (xy 350.109681 -241.890684) (xy 350.132552 -241.934261) (xy 350.148136 -241.980942)
			(xy 350.156031 -242.029519) (xy 350.156526 -242.054126) (xy 352.365322 -242.054126) (xy 352.369282 -242.005072)
			(xy 352.381059 -241.957288) (xy 352.40035 -241.912012) (xy 352.426653 -241.870416) (xy 352.459288 -241.833579)
			(xy 352.497409 -241.802454) (xy 352.54003 -241.777847) (xy 352.586046 -241.760395) (xy 352.634265 -241.750551)
			(xy 352.68344 -241.74857) (xy 352.732295 -241.754502) (xy 352.779566 -241.768194) (xy 352.824028 -241.789292)
			(xy 352.864531 -241.817248) (xy 352.900024 -241.85134) (xy 352.929589 -241.890684) (xy 352.95246 -241.934261)
			(xy 352.968044 -241.980942) (xy 352.975939 -242.029519) (xy 352.976434 -242.054126) (xy 355.18523 -242.054126)
			(xy 355.18919 -242.005072) (xy 355.200967 -241.957288) (xy 355.220258 -241.912012) (xy 355.246561 -241.870416)
			(xy 355.279196 -241.833579) (xy 355.317317 -241.802454) (xy 355.359938 -241.777847) (xy 355.405954 -241.760395)
			(xy 355.454173 -241.750551) (xy 355.503348 -241.74857) (xy 355.552203 -241.754502) (xy 355.599474 -241.768194)
			(xy 355.643936 -241.789292) (xy 355.684439 -241.817248) (xy 355.719932 -241.85134) (xy 355.749497 -241.890684)
			(xy 355.772368 -241.934261) (xy 355.787952 -241.980942) (xy 355.795847 -242.029519) (xy 355.796342 -242.054126)
			(xy 356.125284 -242.054126) (xy 356.129244 -242.005072) (xy 356.141021 -241.957288) (xy 356.160312 -241.912012)
			(xy 356.186615 -241.870416) (xy 356.21925 -241.833579) (xy 356.257371 -241.802454) (xy 356.299992 -241.777847)
			(xy 356.346008 -241.760395) (xy 356.394227 -241.750551) (xy 356.443402 -241.74857) (xy 356.492257 -241.754502)
			(xy 356.539528 -241.768194) (xy 356.58399 -241.789292) (xy 356.624493 -241.817248) (xy 356.659986 -241.85134)
			(xy 356.689551 -241.890684) (xy 356.712422 -241.934261) (xy 356.728006 -241.980942) (xy 356.735901 -242.029519)
			(xy 356.736396 -242.054126) (xy 357.065338 -242.054126) (xy 357.069298 -242.005072) (xy 357.081075 -241.957288)
			(xy 357.100366 -241.912012) (xy 357.126669 -241.870416) (xy 357.159304 -241.833579) (xy 357.197425 -241.802454)
			(xy 357.240046 -241.777847) (xy 357.286062 -241.760395) (xy 357.334281 -241.750551) (xy 357.383456 -241.74857)
			(xy 357.432311 -241.754502) (xy 357.479582 -241.768194) (xy 357.524044 -241.789292) (xy 357.564547 -241.817248)
			(xy 357.60004 -241.85134) (xy 357.629605 -241.890684) (xy 357.652476 -241.934261) (xy 357.66806 -241.980942)
			(xy 357.675955 -242.029519) (xy 357.67645 -242.054126) (xy 358.005392 -242.054126) (xy 358.009352 -242.005072)
			(xy 358.021129 -241.957288) (xy 358.04042 -241.912012) (xy 358.066723 -241.870416) (xy 358.099358 -241.833579)
			(xy 358.137479 -241.802454) (xy 358.1801 -241.777847) (xy 358.226116 -241.760395) (xy 358.274335 -241.750551)
			(xy 358.32351 -241.74857) (xy 358.372365 -241.754502) (xy 358.419636 -241.768194) (xy 358.464098 -241.789292)
			(xy 358.504601 -241.817248) (xy 358.540094 -241.85134) (xy 358.569659 -241.890684) (xy 358.59253 -241.934261)
			(xy 358.608114 -241.980942) (xy 358.616009 -242.029519) (xy 358.616504 -242.054126) (xy 360.81895 -242.054126)
			(xy 360.82291 -242.005072) (xy 360.834687 -241.957288) (xy 360.853978 -241.912012) (xy 360.880281 -241.870416)
			(xy 360.912916 -241.833579) (xy 360.951037 -241.802454) (xy 360.993658 -241.777847) (xy 361.039674 -241.760395)
			(xy 361.087893 -241.750551) (xy 361.137068 -241.74857) (xy 361.185923 -241.754502) (xy 361.233194 -241.768194)
			(xy 361.277656 -241.789292) (xy 361.318159 -241.817248) (xy 361.353652 -241.85134) (xy 361.383217 -241.890684)
			(xy 361.406088 -241.934261) (xy 361.421672 -241.980942) (xy 361.429567 -242.029519) (xy 361.430062 -242.054126)
			(xy 361.759004 -242.054126) (xy 361.762964 -242.005072) (xy 361.774741 -241.957288) (xy 361.794032 -241.912012)
			(xy 361.820335 -241.870416) (xy 361.85297 -241.833579) (xy 361.891091 -241.802454) (xy 361.933712 -241.777847)
			(xy 361.979728 -241.760395) (xy 362.027947 -241.750551) (xy 362.077122 -241.74857) (xy 362.125977 -241.754502)
			(xy 362.173248 -241.768194) (xy 362.21771 -241.789292) (xy 362.258213 -241.817248) (xy 362.293706 -241.85134)
			(xy 362.323271 -241.890684) (xy 362.346142 -241.934261) (xy 362.361726 -241.980942) (xy 362.369621 -242.029519)
			(xy 362.370116 -242.054126) (xy 362.699058 -242.054126) (xy 362.703018 -242.005072) (xy 362.714795 -241.957288)
			(xy 362.734086 -241.912012) (xy 362.760389 -241.870416) (xy 362.793024 -241.833579) (xy 362.831145 -241.802454)
			(xy 362.873766 -241.777847) (xy 362.919782 -241.760395) (xy 362.968001 -241.750551) (xy 363.017176 -241.74857)
			(xy 363.066031 -241.754502) (xy 363.113302 -241.768194) (xy 363.157764 -241.789292) (xy 363.198267 -241.817248)
			(xy 363.23376 -241.85134) (xy 363.263325 -241.890684) (xy 363.286196 -241.934261) (xy 363.30178 -241.980942)
			(xy 363.309675 -242.029519) (xy 363.31017 -242.054126) (xy 363.639112 -242.054126) (xy 363.643072 -242.005072)
			(xy 363.654849 -241.957288) (xy 363.67414 -241.912012) (xy 363.700443 -241.870416) (xy 363.733078 -241.833579)
			(xy 363.771199 -241.802454) (xy 363.81382 -241.777847) (xy 363.859836 -241.760395) (xy 363.908055 -241.750551)
			(xy 363.95723 -241.74857) (xy 364.006085 -241.754502) (xy 364.053356 -241.768194) (xy 364.097818 -241.789292)
			(xy 364.138321 -241.817248) (xy 364.173814 -241.85134) (xy 364.203379 -241.890684) (xy 364.22625 -241.934261)
			(xy 364.241834 -241.980942) (xy 364.249729 -242.029519) (xy 364.250224 -242.054126) (xy 366.45902 -242.054126)
			(xy 366.46298 -242.005072) (xy 366.474757 -241.957288) (xy 366.494048 -241.912012) (xy 366.520351 -241.870416)
			(xy 366.552986 -241.833579) (xy 366.591107 -241.802454) (xy 366.633728 -241.777847) (xy 366.679744 -241.760395)
			(xy 366.727963 -241.750551) (xy 366.777138 -241.74857) (xy 366.825993 -241.754502) (xy 366.873264 -241.768194)
			(xy 366.917726 -241.789292) (xy 366.958229 -241.817248) (xy 366.993722 -241.85134) (xy 367.023287 -241.890684)
			(xy 367.046158 -241.934261) (xy 367.061742 -241.980942) (xy 367.069637 -242.029519) (xy 367.070132 -242.054126)
			(xy 369.278928 -242.054126) (xy 369.282888 -242.005072) (xy 369.294665 -241.957288) (xy 369.313956 -241.912012)
			(xy 369.340259 -241.870416) (xy 369.372894 -241.833579) (xy 369.411015 -241.802454) (xy 369.453636 -241.777847)
			(xy 369.499652 -241.760395) (xy 369.547871 -241.750551) (xy 369.597046 -241.74857) (xy 369.645901 -241.754502)
			(xy 369.693172 -241.768194) (xy 369.737634 -241.789292) (xy 369.778137 -241.817248) (xy 369.81363 -241.85134)
			(xy 369.843195 -241.890684) (xy 369.866066 -241.934261) (xy 369.88165 -241.980942) (xy 369.889545 -242.029519)
			(xy 369.89004 -242.054126) (xy 372.09909 -242.054126) (xy 372.10305 -242.005072) (xy 372.114827 -241.957288)
			(xy 372.134118 -241.912012) (xy 372.160421 -241.870416) (xy 372.193056 -241.833579) (xy 372.231177 -241.802454)
			(xy 372.273798 -241.777847) (xy 372.319814 -241.760395) (xy 372.368033 -241.750551) (xy 372.417208 -241.74857)
			(xy 372.466063 -241.754502) (xy 372.513334 -241.768194) (xy 372.557796 -241.789292) (xy 372.598299 -241.817248)
			(xy 372.633792 -241.85134) (xy 372.663357 -241.890684) (xy 372.686228 -241.934261) (xy 372.701812 -241.980942)
			(xy 372.709707 -242.029519) (xy 372.710202 -242.054126) (xy 374.918998 -242.054126) (xy 374.922958 -242.005072)
			(xy 374.934735 -241.957288) (xy 374.954026 -241.912012) (xy 374.980329 -241.870416) (xy 375.012964 -241.833579)
			(xy 375.051085 -241.802454) (xy 375.093706 -241.777847) (xy 375.139722 -241.760395) (xy 375.187941 -241.750551)
			(xy 375.237116 -241.74857) (xy 375.285971 -241.754502) (xy 375.333242 -241.768194) (xy 375.377704 -241.789292)
			(xy 375.418207 -241.817248) (xy 375.4537 -241.85134) (xy 375.483265 -241.890684) (xy 375.506136 -241.934261)
			(xy 375.52172 -241.980942) (xy 375.529615 -242.029519) (xy 375.53011 -242.054126) (xy 375.848621 -242.054126)
			(xy 375.852716 -242.003398) (xy 375.864895 -241.953984) (xy 375.884843 -241.907164) (xy 375.912044 -241.86415)
			(xy 375.945792 -241.826056) (xy 375.985214 -241.793869) (xy 376.029288 -241.768423) (xy 376.076874 -241.750376)
			(xy 376.126738 -241.740196) (xy 376.17759 -241.738147) (xy 376.228111 -241.744281) (xy 376.276995 -241.758441)
			(xy 376.322974 -241.780258) (xy 376.364858 -241.809168) (xy 376.401562 -241.844423) (xy 376.432135 -241.885109)
			(xy 376.455786 -241.930172) (xy 376.471902 -241.978446) (xy 376.480066 -242.02868) (xy 376.480578 -242.054126)
			(xy 376.788675 -242.054126) (xy 376.79277 -242.003398) (xy 376.804949 -241.953984) (xy 376.824897 -241.907164)
			(xy 376.852098 -241.86415) (xy 376.885846 -241.826056) (xy 376.925268 -241.793869) (xy 376.969342 -241.768423)
			(xy 377.016928 -241.750376) (xy 377.066792 -241.740196) (xy 377.117644 -241.738147) (xy 377.168165 -241.744281)
			(xy 377.217049 -241.758441) (xy 377.263028 -241.780258) (xy 377.304912 -241.809168) (xy 377.341616 -241.844423)
			(xy 377.372189 -241.885109) (xy 377.39584 -241.930172) (xy 377.411956 -241.978446) (xy 377.42012 -242.02868)
			(xy 377.420632 -242.054126) (xy 377.42012 -242.079572) (xy 377.411956 -242.129806) (xy 377.39584 -242.17808)
			(xy 377.372189 -242.223143) (xy 377.341616 -242.263829) (xy 377.304912 -242.299084) (xy 377.263028 -242.327994)
			(xy 377.217049 -242.349811) (xy 377.168165 -242.363971) (xy 377.117644 -242.370105) (xy 377.066792 -242.368056)
			(xy 377.016928 -242.357876) (xy 376.969342 -242.339829) (xy 376.925268 -242.314383) (xy 376.885846 -242.282196)
			(xy 376.852098 -242.244102) (xy 376.824897 -242.201088) (xy 376.804949 -242.154268) (xy 376.79277 -242.104854)
			(xy 376.788675 -242.054126) (xy 376.480578 -242.054126) (xy 376.480066 -242.079572) (xy 376.471902 -242.129806)
			(xy 376.455786 -242.17808) (xy 376.432135 -242.223143) (xy 376.401562 -242.263829) (xy 376.364858 -242.299084)
			(xy 376.322974 -242.327994) (xy 376.276995 -242.349811) (xy 376.228111 -242.363971) (xy 376.17759 -242.370105)
			(xy 376.126738 -242.368056) (xy 376.076874 -242.357876) (xy 376.029288 -242.339829) (xy 375.985214 -242.314383)
			(xy 375.945792 -242.282196) (xy 375.912044 -242.244102) (xy 375.884843 -242.201088) (xy 375.864895 -242.154268)
			(xy 375.852716 -242.104854) (xy 375.848621 -242.054126) (xy 375.53011 -242.054126) (xy 375.529615 -242.078733)
			(xy 375.52172 -242.12731) (xy 375.506136 -242.173991) (xy 375.483265 -242.217568) (xy 375.4537 -242.256912)
			(xy 375.418207 -242.291004) (xy 375.377704 -242.31896) (xy 375.333242 -242.340058) (xy 375.285971 -242.35375)
			(xy 375.237116 -242.359682) (xy 375.187941 -242.357701) (xy 375.139722 -242.347857) (xy 375.093706 -242.330405)
			(xy 375.051085 -242.305798) (xy 375.012964 -242.274673) (xy 374.980329 -242.237836) (xy 374.954026 -242.19624)
			(xy 374.934735 -242.150964) (xy 374.922958 -242.10318) (xy 374.918998 -242.054126) (xy 372.710202 -242.054126)
			(xy 372.709707 -242.078733) (xy 372.701812 -242.12731) (xy 372.686228 -242.173991) (xy 372.663357 -242.217568)
			(xy 372.633792 -242.256912) (xy 372.598299 -242.291004) (xy 372.557796 -242.31896) (xy 372.513334 -242.340058)
			(xy 372.466063 -242.35375) (xy 372.417208 -242.359682) (xy 372.368033 -242.357701) (xy 372.319814 -242.347857)
			(xy 372.273798 -242.330405) (xy 372.231177 -242.305798) (xy 372.193056 -242.274673) (xy 372.160421 -242.237836)
			(xy 372.134118 -242.19624) (xy 372.114827 -242.150964) (xy 372.10305 -242.10318) (xy 372.09909 -242.054126)
			(xy 369.89004 -242.054126) (xy 369.889545 -242.078733) (xy 369.88165 -242.12731) (xy 369.866066 -242.173991)
			(xy 369.843195 -242.217568) (xy 369.81363 -242.256912) (xy 369.778137 -242.291004) (xy 369.737634 -242.31896)
			(xy 369.693172 -242.340058) (xy 369.645901 -242.35375) (xy 369.597046 -242.359682) (xy 369.547871 -242.357701)
			(xy 369.499652 -242.347857) (xy 369.453636 -242.330405) (xy 369.411015 -242.305798) (xy 369.372894 -242.274673)
			(xy 369.340259 -242.237836) (xy 369.313956 -242.19624) (xy 369.294665 -242.150964) (xy 369.282888 -242.10318)
			(xy 369.278928 -242.054126) (xy 367.070132 -242.054126) (xy 367.069637 -242.078733) (xy 367.061742 -242.12731)
			(xy 367.046158 -242.173991) (xy 367.023287 -242.217568) (xy 366.993722 -242.256912) (xy 366.958229 -242.291004)
			(xy 366.917726 -242.31896) (xy 366.873264 -242.340058) (xy 366.825993 -242.35375) (xy 366.777138 -242.359682)
			(xy 366.727963 -242.357701) (xy 366.679744 -242.347857) (xy 366.633728 -242.330405) (xy 366.591107 -242.305798)
			(xy 366.552986 -242.274673) (xy 366.520351 -242.237836) (xy 366.494048 -242.19624) (xy 366.474757 -242.150964)
			(xy 366.46298 -242.10318) (xy 366.45902 -242.054126) (xy 364.250224 -242.054126) (xy 364.249729 -242.078733)
			(xy 364.241834 -242.12731) (xy 364.22625 -242.173991) (xy 364.203379 -242.217568) (xy 364.173814 -242.256912)
			(xy 364.138321 -242.291004) (xy 364.097818 -242.31896) (xy 364.053356 -242.340058) (xy 364.006085 -242.35375)
			(xy 363.95723 -242.359682) (xy 363.908055 -242.357701) (xy 363.859836 -242.347857) (xy 363.81382 -242.330405)
			(xy 363.771199 -242.305798) (xy 363.733078 -242.274673) (xy 363.700443 -242.237836) (xy 363.67414 -242.19624)
			(xy 363.654849 -242.150964) (xy 363.643072 -242.10318) (xy 363.639112 -242.054126) (xy 363.31017 -242.054126)
			(xy 363.309675 -242.078733) (xy 363.30178 -242.12731) (xy 363.286196 -242.173991) (xy 363.263325 -242.217568)
			(xy 363.23376 -242.256912) (xy 363.198267 -242.291004) (xy 363.157764 -242.31896) (xy 363.113302 -242.340058)
			(xy 363.066031 -242.35375) (xy 363.017176 -242.359682) (xy 362.968001 -242.357701) (xy 362.919782 -242.347857)
			(xy 362.873766 -242.330405) (xy 362.831145 -242.305798) (xy 362.793024 -242.274673) (xy 362.760389 -242.237836)
			(xy 362.734086 -242.19624) (xy 362.714795 -242.150964) (xy 362.703018 -242.10318) (xy 362.699058 -242.054126)
			(xy 362.370116 -242.054126) (xy 362.369621 -242.078733) (xy 362.361726 -242.12731) (xy 362.346142 -242.173991)
			(xy 362.323271 -242.217568) (xy 362.293706 -242.256912) (xy 362.258213 -242.291004) (xy 362.21771 -242.31896)
			(xy 362.173248 -242.340058) (xy 362.125977 -242.35375) (xy 362.077122 -242.359682) (xy 362.027947 -242.357701)
			(xy 361.979728 -242.347857) (xy 361.933712 -242.330405) (xy 361.891091 -242.305798) (xy 361.85297 -242.274673)
			(xy 361.820335 -242.237836) (xy 361.794032 -242.19624) (xy 361.774741 -242.150964) (xy 361.762964 -242.10318)
			(xy 361.759004 -242.054126) (xy 361.430062 -242.054126) (xy 361.429567 -242.078733) (xy 361.421672 -242.12731)
			(xy 361.406088 -242.173991) (xy 361.383217 -242.217568) (xy 361.353652 -242.256912) (xy 361.318159 -242.291004)
			(xy 361.277656 -242.31896) (xy 361.233194 -242.340058) (xy 361.185923 -242.35375) (xy 361.137068 -242.359682)
			(xy 361.087893 -242.357701) (xy 361.039674 -242.347857) (xy 360.993658 -242.330405) (xy 360.951037 -242.305798)
			(xy 360.912916 -242.274673) (xy 360.880281 -242.237836) (xy 360.853978 -242.19624) (xy 360.834687 -242.150964)
			(xy 360.82291 -242.10318) (xy 360.81895 -242.054126) (xy 358.616504 -242.054126) (xy 358.616009 -242.078733)
			(xy 358.608114 -242.12731) (xy 358.59253 -242.173991) (xy 358.569659 -242.217568) (xy 358.540094 -242.256912)
			(xy 358.504601 -242.291004) (xy 358.464098 -242.31896) (xy 358.419636 -242.340058) (xy 358.372365 -242.35375)
			(xy 358.32351 -242.359682) (xy 358.274335 -242.357701) (xy 358.226116 -242.347857) (xy 358.1801 -242.330405)
			(xy 358.137479 -242.305798) (xy 358.099358 -242.274673) (xy 358.066723 -242.237836) (xy 358.04042 -242.19624)
			(xy 358.021129 -242.150964) (xy 358.009352 -242.10318) (xy 358.005392 -242.054126) (xy 357.67645 -242.054126)
			(xy 357.675955 -242.078733) (xy 357.66806 -242.12731) (xy 357.652476 -242.173991) (xy 357.629605 -242.217568)
			(xy 357.60004 -242.256912) (xy 357.564547 -242.291004) (xy 357.524044 -242.31896) (xy 357.479582 -242.340058)
			(xy 357.432311 -242.35375) (xy 357.383456 -242.359682) (xy 357.334281 -242.357701) (xy 357.286062 -242.347857)
			(xy 357.240046 -242.330405) (xy 357.197425 -242.305798) (xy 357.159304 -242.274673) (xy 357.126669 -242.237836)
			(xy 357.100366 -242.19624) (xy 357.081075 -242.150964) (xy 357.069298 -242.10318) (xy 357.065338 -242.054126)
			(xy 356.736396 -242.054126) (xy 356.735901 -242.078733) (xy 356.728006 -242.12731) (xy 356.712422 -242.173991)
			(xy 356.689551 -242.217568) (xy 356.659986 -242.256912) (xy 356.624493 -242.291004) (xy 356.58399 -242.31896)
			(xy 356.539528 -242.340058) (xy 356.492257 -242.35375) (xy 356.443402 -242.359682) (xy 356.394227 -242.357701)
			(xy 356.346008 -242.347857) (xy 356.299992 -242.330405) (xy 356.257371 -242.305798) (xy 356.21925 -242.274673)
			(xy 356.186615 -242.237836) (xy 356.160312 -242.19624) (xy 356.141021 -242.150964) (xy 356.129244 -242.10318)
			(xy 356.125284 -242.054126) (xy 355.796342 -242.054126) (xy 355.795847 -242.078733) (xy 355.787952 -242.12731)
			(xy 355.772368 -242.173991) (xy 355.749497 -242.217568) (xy 355.719932 -242.256912) (xy 355.684439 -242.291004)
			(xy 355.643936 -242.31896) (xy 355.599474 -242.340058) (xy 355.552203 -242.35375) (xy 355.503348 -242.359682)
			(xy 355.454173 -242.357701) (xy 355.405954 -242.347857) (xy 355.359938 -242.330405) (xy 355.317317 -242.305798)
			(xy 355.279196 -242.274673) (xy 355.246561 -242.237836) (xy 355.220258 -242.19624) (xy 355.200967 -242.150964)
			(xy 355.18919 -242.10318) (xy 355.18523 -242.054126) (xy 352.976434 -242.054126) (xy 352.975939 -242.078733)
			(xy 352.968044 -242.12731) (xy 352.95246 -242.173991) (xy 352.929589 -242.217568) (xy 352.900024 -242.256912)
			(xy 352.864531 -242.291004) (xy 352.824028 -242.31896) (xy 352.779566 -242.340058) (xy 352.732295 -242.35375)
			(xy 352.68344 -242.359682) (xy 352.634265 -242.357701) (xy 352.586046 -242.347857) (xy 352.54003 -242.330405)
			(xy 352.497409 -242.305798) (xy 352.459288 -242.274673) (xy 352.426653 -242.237836) (xy 352.40035 -242.19624)
			(xy 352.381059 -242.150964) (xy 352.369282 -242.10318) (xy 352.365322 -242.054126) (xy 350.156526 -242.054126)
			(xy 350.156031 -242.078733) (xy 350.148136 -242.12731) (xy 350.132552 -242.173991) (xy 350.109681 -242.217568)
			(xy 350.080116 -242.256912) (xy 350.044623 -242.291004) (xy 350.00412 -242.31896) (xy 349.959658 -242.340058)
			(xy 349.912387 -242.35375) (xy 349.863532 -242.359682) (xy 349.814357 -242.357701) (xy 349.766138 -242.347857)
			(xy 349.720122 -242.330405) (xy 349.677501 -242.305798) (xy 349.63938 -242.274673) (xy 349.606745 -242.237836)
			(xy 349.580442 -242.19624) (xy 349.561151 -242.150964) (xy 349.549374 -242.10318) (xy 349.545414 -242.054126)
			(xy 347.336364 -242.054126) (xy 347.335869 -242.078733) (xy 347.327974 -242.12731) (xy 347.31239 -242.173991)
			(xy 347.289519 -242.217568) (xy 347.259954 -242.256912) (xy 347.224461 -242.291004) (xy 347.183958 -242.31896)
			(xy 347.139496 -242.340058) (xy 347.092225 -242.35375) (xy 347.04337 -242.359682) (xy 346.994195 -242.357701)
			(xy 346.945976 -242.347857) (xy 346.89996 -242.330405) (xy 346.857339 -242.305798) (xy 346.819218 -242.274673)
			(xy 346.786583 -242.237836) (xy 346.76028 -242.19624) (xy 346.740989 -242.150964) (xy 346.729212 -242.10318)
			(xy 346.725252 -242.054126) (xy 344.516456 -242.054126) (xy 344.515961 -242.078733) (xy 344.508066 -242.12731)
			(xy 344.492482 -242.173991) (xy 344.469611 -242.217568) (xy 344.440046 -242.256912) (xy 344.404553 -242.291004)
			(xy 344.36405 -242.31896) (xy 344.319588 -242.340058) (xy 344.272317 -242.35375) (xy 344.223462 -242.359682)
			(xy 344.174287 -242.357701) (xy 344.126068 -242.347857) (xy 344.080052 -242.330405) (xy 344.037431 -242.305798)
			(xy 343.99931 -242.274673) (xy 343.966675 -242.237836) (xy 343.940372 -242.19624) (xy 343.921081 -242.150964)
			(xy 343.909304 -242.10318) (xy 343.905344 -242.054126) (xy 343.586816 -242.054126) (xy 343.586304 -242.079572)
			(xy 343.57814 -242.129806) (xy 343.562024 -242.17808) (xy 343.538373 -242.223143) (xy 343.5078 -242.263829)
			(xy 343.471096 -242.299084) (xy 343.429212 -242.327994) (xy 343.383233 -242.349811) (xy 343.334349 -242.363971)
			(xy 343.283828 -242.370105) (xy 343.232976 -242.368056) (xy 343.183112 -242.357876) (xy 343.135526 -242.339829)
			(xy 343.091452 -242.314383) (xy 343.05203 -242.282196) (xy 343.018282 -242.244102) (xy 342.991081 -242.201088)
			(xy 342.971133 -242.154268) (xy 342.958954 -242.104854) (xy 342.954859 -242.054126) (xy 342.646762 -242.054126)
			(xy 342.64625 -242.079572) (xy 342.638086 -242.129806) (xy 342.62197 -242.17808) (xy 342.598319 -242.223143)
			(xy 342.567746 -242.263829) (xy 342.531042 -242.299084) (xy 342.489158 -242.327994) (xy 342.443179 -242.349811)
			(xy 342.394295 -242.363971) (xy 342.343774 -242.370105) (xy 342.292922 -242.368056) (xy 342.243058 -242.357876)
			(xy 342.195472 -242.339829) (xy 342.151398 -242.314383) (xy 342.111976 -242.282196) (xy 342.078228 -242.244102)
			(xy 342.051027 -242.201088) (xy 342.031079 -242.154268) (xy 342.0189 -242.104854) (xy 342.014805 -242.054126)
			(xy 341.696294 -242.054126) (xy 341.695821 -242.078115) (xy 341.688312 -242.125503) (xy 341.673482 -242.171133)
			(xy 341.651697 -242.213881) (xy 341.623493 -242.252695) (xy 341.589564 -242.286619) (xy 341.550747 -242.314818)
			(xy 341.507996 -242.336597) (xy 341.462364 -242.351421) (xy 341.414976 -242.358925) (xy 341.390986 -242.359434)
			(xy 341.376676 -242.359264) (xy 341.348182 -242.356589) (xy 341.33409 -242.3541) (xy 341.325454 -242.353338)
			(xy 341.316421 -242.353573) (xy 341.299385 -242.359567) (xy 341.29218 -242.365022) (xy 341.270844 -242.382802)
			(xy 341.233506 -242.41379) (xy 341.225249 -242.421392) (xy 341.215746 -242.441695) (xy 341.215218 -242.452906)
			(xy 341.215218 -242.78209) (xy 341.216742 -242.788186) (xy 341.221255 -242.806847) (xy 341.2261 -242.844935)
			(xy 341.226394 -242.864132) (xy 341.544905 -242.864132) (xy 341.549 -242.813404) (xy 341.561179 -242.76399)
			(xy 341.581127 -242.71717) (xy 341.608328 -242.674156) (xy 341.642076 -242.636062) (xy 341.681498 -242.603875)
			(xy 341.725572 -242.578429) (xy 341.773158 -242.560382) (xy 341.823022 -242.550202) (xy 341.873874 -242.548153)
			(xy 341.924395 -242.554287) (xy 341.973279 -242.568447) (xy 342.019258 -242.590264) (xy 342.061142 -242.619174)
			(xy 342.097846 -242.654429) (xy 342.128419 -242.695115) (xy 342.15207 -242.740178) (xy 342.168186 -242.788452)
			(xy 342.17635 -242.838686) (xy 342.176862 -242.864132) (xy 342.49539 -242.864132) (xy 342.49935 -242.815078)
			(xy 342.511127 -242.767294) (xy 342.530418 -242.722018) (xy 342.556721 -242.680422) (xy 342.589356 -242.643585)
			(xy 342.627477 -242.61246) (xy 342.670098 -242.587853) (xy 342.716114 -242.570401) (xy 342.764333 -242.560557)
			(xy 342.813508 -242.558576) (xy 342.862363 -242.564508) (xy 342.909634 -242.5782) (xy 342.954096 -242.599298)
			(xy 342.994599 -242.627254) (xy 343.030092 -242.661346) (xy 343.059657 -242.70069) (xy 343.082528 -242.744267)
			(xy 343.098112 -242.790948) (xy 343.106007 -242.839525) (xy 343.106502 -242.864132) (xy 343.424759 -242.864132)
			(xy 343.428854 -242.813404) (xy 343.441033 -242.76399) (xy 343.460981 -242.71717) (xy 343.488182 -242.674156)
			(xy 343.52193 -242.636062) (xy 343.561352 -242.603875) (xy 343.605426 -242.578429) (xy 343.653012 -242.560382)
			(xy 343.702876 -242.550202) (xy 343.753728 -242.548153) (xy 343.804249 -242.554287) (xy 343.853133 -242.568447)
			(xy 343.899112 -242.590264) (xy 343.940996 -242.619174) (xy 343.9777 -242.654429) (xy 344.008273 -242.695115)
			(xy 344.031924 -242.740178) (xy 344.04804 -242.788452) (xy 344.056204 -242.838686) (xy 344.056716 -242.864132)
			(xy 344.375244 -242.864132) (xy 344.379204 -242.815078) (xy 344.390981 -242.767294) (xy 344.410272 -242.722018)
			(xy 344.436575 -242.680422) (xy 344.46921 -242.643585) (xy 344.507331 -242.61246) (xy 344.549952 -242.587853)
			(xy 344.595968 -242.570401) (xy 344.644187 -242.560557) (xy 344.693362 -242.558576) (xy 344.742217 -242.564508)
			(xy 344.789488 -242.5782) (xy 344.83395 -242.599298) (xy 344.874453 -242.627254) (xy 344.909946 -242.661346)
			(xy 344.939511 -242.70069) (xy 344.962382 -242.744267) (xy 344.977966 -242.790948) (xy 344.985861 -242.839525)
			(xy 344.986356 -242.864132) (xy 345.315298 -242.864132) (xy 345.319258 -242.815078) (xy 345.331035 -242.767294)
			(xy 345.350326 -242.722018) (xy 345.376629 -242.680422) (xy 345.409264 -242.643585) (xy 345.447385 -242.61246)
			(xy 345.490006 -242.587853) (xy 345.536022 -242.570401) (xy 345.584241 -242.560557) (xy 345.633416 -242.558576)
			(xy 345.682271 -242.564508) (xy 345.729542 -242.5782) (xy 345.774004 -242.599298) (xy 345.814507 -242.627254)
			(xy 345.85 -242.661346) (xy 345.879565 -242.70069) (xy 345.902436 -242.744267) (xy 345.91802 -242.790948)
			(xy 345.925915 -242.839525) (xy 345.92641 -242.864132) (xy 346.255352 -242.864132) (xy 346.259312 -242.815078)
			(xy 346.271089 -242.767294) (xy 346.29038 -242.722018) (xy 346.316683 -242.680422) (xy 346.349318 -242.643585)
			(xy 346.387439 -242.61246) (xy 346.43006 -242.587853) (xy 346.476076 -242.570401) (xy 346.524295 -242.560557)
			(xy 346.57347 -242.558576) (xy 346.622325 -242.564508) (xy 346.669596 -242.5782) (xy 346.714058 -242.599298)
			(xy 346.754561 -242.627254) (xy 346.790054 -242.661346) (xy 346.819619 -242.70069) (xy 346.84249 -242.744267)
			(xy 346.858074 -242.790948) (xy 346.865969 -242.839525) (xy 346.866464 -242.864132) (xy 347.195406 -242.864132)
			(xy 347.199366 -242.815078) (xy 347.211143 -242.767294) (xy 347.230434 -242.722018) (xy 347.256737 -242.680422)
			(xy 347.289372 -242.643585) (xy 347.327493 -242.61246) (xy 347.370114 -242.587853) (xy 347.41613 -242.570401)
			(xy 347.464349 -242.560557) (xy 347.513524 -242.558576) (xy 347.562379 -242.564508) (xy 347.60965 -242.5782)
			(xy 347.654112 -242.599298) (xy 347.694615 -242.627254) (xy 347.730108 -242.661346) (xy 347.759673 -242.70069)
			(xy 347.782544 -242.744267) (xy 347.798128 -242.790948) (xy 347.806023 -242.839525) (xy 347.806518 -242.864132)
			(xy 348.135206 -242.864132) (xy 348.139166 -242.815078) (xy 348.150943 -242.767294) (xy 348.170234 -242.722018)
			(xy 348.196537 -242.680422) (xy 348.229172 -242.643585) (xy 348.267293 -242.61246) (xy 348.309914 -242.587853)
			(xy 348.35593 -242.570401) (xy 348.404149 -242.560557) (xy 348.453324 -242.558576) (xy 348.502179 -242.564508)
			(xy 348.54945 -242.5782) (xy 348.593912 -242.599298) (xy 348.634415 -242.627254) (xy 348.669908 -242.661346)
			(xy 348.699473 -242.70069) (xy 348.722344 -242.744267) (xy 348.737928 -242.790948) (xy 348.745823 -242.839525)
			(xy 348.746318 -242.864132) (xy 349.07526 -242.864132) (xy 349.07922 -242.815078) (xy 349.090997 -242.767294)
			(xy 349.110288 -242.722018) (xy 349.136591 -242.680422) (xy 349.169226 -242.643585) (xy 349.207347 -242.61246)
			(xy 349.249968 -242.587853) (xy 349.295984 -242.570401) (xy 349.344203 -242.560557) (xy 349.393378 -242.558576)
			(xy 349.442233 -242.564508) (xy 349.489504 -242.5782) (xy 349.533966 -242.599298) (xy 349.574469 -242.627254)
			(xy 349.609962 -242.661346) (xy 349.639527 -242.70069) (xy 349.662398 -242.744267) (xy 349.677982 -242.790948)
			(xy 349.685877 -242.839525) (xy 349.686372 -242.864132) (xy 350.015314 -242.864132) (xy 350.019274 -242.815078)
			(xy 350.031051 -242.767294) (xy 350.050342 -242.722018) (xy 350.076645 -242.680422) (xy 350.10928 -242.643585)
			(xy 350.147401 -242.61246) (xy 350.190022 -242.587853) (xy 350.236038 -242.570401) (xy 350.284257 -242.560557)
			(xy 350.333432 -242.558576) (xy 350.382287 -242.564508) (xy 350.429558 -242.5782) (xy 350.47402 -242.599298)
			(xy 350.514523 -242.627254) (xy 350.550016 -242.661346) (xy 350.579581 -242.70069) (xy 350.602452 -242.744267)
			(xy 350.618036 -242.790948) (xy 350.625931 -242.839525) (xy 350.626426 -242.864132) (xy 350.955368 -242.864132)
			(xy 350.959328 -242.815078) (xy 350.971105 -242.767294) (xy 350.990396 -242.722018) (xy 351.016699 -242.680422)
			(xy 351.049334 -242.643585) (xy 351.087455 -242.61246) (xy 351.130076 -242.587853) (xy 351.176092 -242.570401)
			(xy 351.224311 -242.560557) (xy 351.273486 -242.558576) (xy 351.322341 -242.564508) (xy 351.369612 -242.5782)
			(xy 351.414074 -242.599298) (xy 351.454577 -242.627254) (xy 351.49007 -242.661346) (xy 351.519635 -242.70069)
			(xy 351.542506 -242.744267) (xy 351.55809 -242.790948) (xy 351.565985 -242.839525) (xy 351.56648 -242.864132)
			(xy 351.895422 -242.864132) (xy 351.899382 -242.815078) (xy 351.911159 -242.767294) (xy 351.93045 -242.722018)
			(xy 351.956753 -242.680422) (xy 351.989388 -242.643585) (xy 352.027509 -242.61246) (xy 352.07013 -242.587853)
			(xy 352.116146 -242.570401) (xy 352.164365 -242.560557) (xy 352.21354 -242.558576) (xy 352.262395 -242.564508)
			(xy 352.309666 -242.5782) (xy 352.354128 -242.599298) (xy 352.394631 -242.627254) (xy 352.430124 -242.661346)
			(xy 352.459689 -242.70069) (xy 352.48256 -242.744267) (xy 352.498144 -242.790948) (xy 352.506039 -242.839525)
			(xy 352.506534 -242.864132) (xy 352.835222 -242.864132) (xy 352.839182 -242.815078) (xy 352.850959 -242.767294)
			(xy 352.87025 -242.722018) (xy 352.896553 -242.680422) (xy 352.929188 -242.643585) (xy 352.967309 -242.61246)
			(xy 353.00993 -242.587853) (xy 353.055946 -242.570401) (xy 353.104165 -242.560557) (xy 353.15334 -242.558576)
			(xy 353.202195 -242.564508) (xy 353.249466 -242.5782) (xy 353.293928 -242.599298) (xy 353.334431 -242.627254)
			(xy 353.369924 -242.661346) (xy 353.399489 -242.70069) (xy 353.42236 -242.744267) (xy 353.437944 -242.790948)
			(xy 353.445839 -242.839525) (xy 353.446334 -242.864132) (xy 353.775276 -242.864132) (xy 353.779236 -242.815078)
			(xy 353.791013 -242.767294) (xy 353.810304 -242.722018) (xy 353.836607 -242.680422) (xy 353.869242 -242.643585)
			(xy 353.907363 -242.61246) (xy 353.949984 -242.587853) (xy 353.996 -242.570401) (xy 354.044219 -242.560557)
			(xy 354.093394 -242.558576) (xy 354.142249 -242.564508) (xy 354.18952 -242.5782) (xy 354.233982 -242.599298)
			(xy 354.274485 -242.627254) (xy 354.309978 -242.661346) (xy 354.339543 -242.70069) (xy 354.362414 -242.744267)
			(xy 354.377998 -242.790948) (xy 354.385893 -242.839525) (xy 354.386388 -242.864132) (xy 354.71533 -242.864132)
			(xy 354.71929 -242.815078) (xy 354.731067 -242.767294) (xy 354.750358 -242.722018) (xy 354.776661 -242.680422)
			(xy 354.809296 -242.643585) (xy 354.847417 -242.61246) (xy 354.890038 -242.587853) (xy 354.936054 -242.570401)
			(xy 354.984273 -242.560557) (xy 355.033448 -242.558576) (xy 355.082303 -242.564508) (xy 355.129574 -242.5782)
			(xy 355.174036 -242.599298) (xy 355.214539 -242.627254) (xy 355.250032 -242.661346) (xy 355.279597 -242.70069)
			(xy 355.302468 -242.744267) (xy 355.318052 -242.790948) (xy 355.325947 -242.839525) (xy 355.326442 -242.864132)
			(xy 355.655384 -242.864132) (xy 355.659344 -242.815078) (xy 355.671121 -242.767294) (xy 355.690412 -242.722018)
			(xy 355.716715 -242.680422) (xy 355.74935 -242.643585) (xy 355.787471 -242.61246) (xy 355.830092 -242.587853)
			(xy 355.876108 -242.570401) (xy 355.924327 -242.560557) (xy 355.973502 -242.558576) (xy 356.022357 -242.564508)
			(xy 356.069628 -242.5782) (xy 356.11409 -242.599298) (xy 356.154593 -242.627254) (xy 356.190086 -242.661346)
			(xy 356.219651 -242.70069) (xy 356.242522 -242.744267) (xy 356.258106 -242.790948) (xy 356.266001 -242.839525)
			(xy 356.266496 -242.864132) (xy 363.168958 -242.864132) (xy 363.172918 -242.815078) (xy 363.184695 -242.767294)
			(xy 363.203986 -242.722018) (xy 363.230289 -242.680422) (xy 363.262924 -242.643585) (xy 363.301045 -242.61246)
			(xy 363.343666 -242.587853) (xy 363.389682 -242.570401) (xy 363.437901 -242.560557) (xy 363.487076 -242.558576)
			(xy 363.535931 -242.564508) (xy 363.583202 -242.5782) (xy 363.627664 -242.599298) (xy 363.668167 -242.627254)
			(xy 363.70366 -242.661346) (xy 363.733225 -242.70069) (xy 363.756096 -242.744267) (xy 363.77168 -242.790948)
			(xy 363.779575 -242.839525) (xy 363.78007 -242.864132) (xy 364.109012 -242.864132) (xy 364.112972 -242.815078)
			(xy 364.124749 -242.767294) (xy 364.14404 -242.722018) (xy 364.170343 -242.680422) (xy 364.202978 -242.643585)
			(xy 364.241099 -242.61246) (xy 364.28372 -242.587853) (xy 364.329736 -242.570401) (xy 364.377955 -242.560557)
			(xy 364.42713 -242.558576) (xy 364.475985 -242.564508) (xy 364.523256 -242.5782) (xy 364.567718 -242.599298)
			(xy 364.608221 -242.627254) (xy 364.643714 -242.661346) (xy 364.673279 -242.70069) (xy 364.69615 -242.744267)
			(xy 364.711734 -242.790948) (xy 364.719629 -242.839525) (xy 364.720124 -242.864132) (xy 365.049066 -242.864132)
			(xy 365.053026 -242.815078) (xy 365.064803 -242.767294) (xy 365.084094 -242.722018) (xy 365.110397 -242.680422)
			(xy 365.143032 -242.643585) (xy 365.181153 -242.61246) (xy 365.223774 -242.587853) (xy 365.26979 -242.570401)
			(xy 365.318009 -242.560557) (xy 365.367184 -242.558576) (xy 365.416039 -242.564508) (xy 365.46331 -242.5782)
			(xy 365.507772 -242.599298) (xy 365.548275 -242.627254) (xy 365.583768 -242.661346) (xy 365.613333 -242.70069)
			(xy 365.636204 -242.744267) (xy 365.651788 -242.790948) (xy 365.659683 -242.839525) (xy 365.660178 -242.864132)
			(xy 365.98912 -242.864132) (xy 365.99308 -242.815078) (xy 366.004857 -242.767294) (xy 366.024148 -242.722018)
			(xy 366.050451 -242.680422) (xy 366.083086 -242.643585) (xy 366.121207 -242.61246) (xy 366.163828 -242.587853)
			(xy 366.209844 -242.570401) (xy 366.258063 -242.560557) (xy 366.307238 -242.558576) (xy 366.356093 -242.564508)
			(xy 366.403364 -242.5782) (xy 366.447826 -242.599298) (xy 366.488329 -242.627254) (xy 366.523822 -242.661346)
			(xy 366.553387 -242.70069) (xy 366.576258 -242.744267) (xy 366.591842 -242.790948) (xy 366.599737 -242.839525)
			(xy 366.600232 -242.864132) (xy 366.92892 -242.864132) (xy 366.93288 -242.815078) (xy 366.944657 -242.767294)
			(xy 366.963948 -242.722018) (xy 366.990251 -242.680422) (xy 367.022886 -242.643585) (xy 367.061007 -242.61246)
			(xy 367.103628 -242.587853) (xy 367.149644 -242.570401) (xy 367.197863 -242.560557) (xy 367.247038 -242.558576)
			(xy 367.295893 -242.564508) (xy 367.343164 -242.5782) (xy 367.387626 -242.599298) (xy 367.428129 -242.627254)
			(xy 367.463622 -242.661346) (xy 367.493187 -242.70069) (xy 367.516058 -242.744267) (xy 367.531642 -242.790948)
			(xy 367.539537 -242.839525) (xy 367.540032 -242.864132) (xy 367.868974 -242.864132) (xy 367.872934 -242.815078)
			(xy 367.884711 -242.767294) (xy 367.904002 -242.722018) (xy 367.930305 -242.680422) (xy 367.96294 -242.643585)
			(xy 368.001061 -242.61246) (xy 368.043682 -242.587853) (xy 368.089698 -242.570401) (xy 368.137917 -242.560557)
			(xy 368.187092 -242.558576) (xy 368.235947 -242.564508) (xy 368.283218 -242.5782) (xy 368.32768 -242.599298)
			(xy 368.368183 -242.627254) (xy 368.403676 -242.661346) (xy 368.433241 -242.70069) (xy 368.456112 -242.744267)
			(xy 368.471696 -242.790948) (xy 368.479591 -242.839525) (xy 368.480086 -242.864132) (xy 368.809028 -242.864132)
			(xy 368.812988 -242.815078) (xy 368.824765 -242.767294) (xy 368.844056 -242.722018) (xy 368.870359 -242.680422)
			(xy 368.902994 -242.643585) (xy 368.941115 -242.61246) (xy 368.983736 -242.587853) (xy 369.029752 -242.570401)
			(xy 369.077971 -242.560557) (xy 369.127146 -242.558576) (xy 369.176001 -242.564508) (xy 369.223272 -242.5782)
			(xy 369.267734 -242.599298) (xy 369.308237 -242.627254) (xy 369.34373 -242.661346) (xy 369.373295 -242.70069)
			(xy 369.396166 -242.744267) (xy 369.41175 -242.790948) (xy 369.419645 -242.839525) (xy 369.42014 -242.864132)
			(xy 369.749082 -242.864132) (xy 369.753042 -242.815078) (xy 369.764819 -242.767294) (xy 369.78411 -242.722018)
			(xy 369.810413 -242.680422) (xy 369.843048 -242.643585) (xy 369.881169 -242.61246) (xy 369.92379 -242.587853)
			(xy 369.969806 -242.570401) (xy 370.018025 -242.560557) (xy 370.0672 -242.558576) (xy 370.116055 -242.564508)
			(xy 370.163326 -242.5782) (xy 370.207788 -242.599298) (xy 370.248291 -242.627254) (xy 370.283784 -242.661346)
			(xy 370.313349 -242.70069) (xy 370.33622 -242.744267) (xy 370.351804 -242.790948) (xy 370.359699 -242.839525)
			(xy 370.360194 -242.864132) (xy 370.688882 -242.864132) (xy 370.692842 -242.815078) (xy 370.704619 -242.767294)
			(xy 370.72391 -242.722018) (xy 370.750213 -242.680422) (xy 370.782848 -242.643585) (xy 370.820969 -242.61246)
			(xy 370.86359 -242.587853) (xy 370.909606 -242.570401) (xy 370.957825 -242.560557) (xy 371.007 -242.558576)
			(xy 371.055855 -242.564508) (xy 371.103126 -242.5782) (xy 371.147588 -242.599298) (xy 371.188091 -242.627254)
			(xy 371.223584 -242.661346) (xy 371.253149 -242.70069) (xy 371.27602 -242.744267) (xy 371.291604 -242.790948)
			(xy 371.299499 -242.839525) (xy 371.299994 -242.864132) (xy 371.628936 -242.864132) (xy 371.632896 -242.815078)
			(xy 371.644673 -242.767294) (xy 371.663964 -242.722018) (xy 371.690267 -242.680422) (xy 371.722902 -242.643585)
			(xy 371.761023 -242.61246) (xy 371.803644 -242.587853) (xy 371.84966 -242.570401) (xy 371.897879 -242.560557)
			(xy 371.947054 -242.558576) (xy 371.995909 -242.564508) (xy 372.04318 -242.5782) (xy 372.087642 -242.599298)
			(xy 372.128145 -242.627254) (xy 372.163638 -242.661346) (xy 372.193203 -242.70069) (xy 372.216074 -242.744267)
			(xy 372.231658 -242.790948) (xy 372.239553 -242.839525) (xy 372.240048 -242.864132) (xy 372.56899 -242.864132)
			(xy 372.57295 -242.815078) (xy 372.584727 -242.767294) (xy 372.604018 -242.722018) (xy 372.630321 -242.680422)
			(xy 372.662956 -242.643585) (xy 372.701077 -242.61246) (xy 372.743698 -242.587853) (xy 372.789714 -242.570401)
			(xy 372.837933 -242.560557) (xy 372.887108 -242.558576) (xy 372.935963 -242.564508) (xy 372.983234 -242.5782)
			(xy 373.027696 -242.599298) (xy 373.068199 -242.627254) (xy 373.103692 -242.661346) (xy 373.133257 -242.70069)
			(xy 373.156128 -242.744267) (xy 373.171712 -242.790948) (xy 373.179607 -242.839525) (xy 373.180102 -242.864132)
			(xy 373.509044 -242.864132) (xy 373.513004 -242.815078) (xy 373.524781 -242.767294) (xy 373.544072 -242.722018)
			(xy 373.570375 -242.680422) (xy 373.60301 -242.643585) (xy 373.641131 -242.61246) (xy 373.683752 -242.587853)
			(xy 373.729768 -242.570401) (xy 373.777987 -242.560557) (xy 373.827162 -242.558576) (xy 373.876017 -242.564508)
			(xy 373.923288 -242.5782) (xy 373.96775 -242.599298) (xy 374.008253 -242.627254) (xy 374.043746 -242.661346)
			(xy 374.073311 -242.70069) (xy 374.096182 -242.744267) (xy 374.111766 -242.790948) (xy 374.119661 -242.839525)
			(xy 374.120156 -242.864132) (xy 374.449098 -242.864132) (xy 374.453058 -242.815078) (xy 374.464835 -242.767294)
			(xy 374.484126 -242.722018) (xy 374.510429 -242.680422) (xy 374.543064 -242.643585) (xy 374.581185 -242.61246)
			(xy 374.623806 -242.587853) (xy 374.669822 -242.570401) (xy 374.718041 -242.560557) (xy 374.767216 -242.558576)
			(xy 374.816071 -242.564508) (xy 374.863342 -242.5782) (xy 374.907804 -242.599298) (xy 374.948307 -242.627254)
			(xy 374.9838 -242.661346) (xy 375.013365 -242.70069) (xy 375.036236 -242.744267) (xy 375.05182 -242.790948)
			(xy 375.059715 -242.839525) (xy 375.06021 -242.864132) (xy 375.378467 -242.864132) (xy 375.382562 -242.813404)
			(xy 375.394741 -242.76399) (xy 375.414689 -242.71717) (xy 375.44189 -242.674156) (xy 375.475638 -242.636062)
			(xy 375.51506 -242.603875) (xy 375.559134 -242.578429) (xy 375.60672 -242.560382) (xy 375.656584 -242.550202)
			(xy 375.707436 -242.548153) (xy 375.757957 -242.554287) (xy 375.806841 -242.568447) (xy 375.85282 -242.590264)
			(xy 375.894704 -242.619174) (xy 375.931408 -242.654429) (xy 375.961981 -242.695115) (xy 375.985632 -242.740178)
			(xy 376.001748 -242.788452) (xy 376.009912 -242.838686) (xy 376.010424 -242.864132) (xy 376.328952 -242.864132)
			(xy 376.332912 -242.815078) (xy 376.344689 -242.767294) (xy 376.36398 -242.722018) (xy 376.390283 -242.680422)
			(xy 376.422918 -242.643585) (xy 376.461039 -242.61246) (xy 376.50366 -242.587853) (xy 376.549676 -242.570401)
			(xy 376.597895 -242.560557) (xy 376.64707 -242.558576) (xy 376.695925 -242.564508) (xy 376.743196 -242.5782)
			(xy 376.787658 -242.599298) (xy 376.828161 -242.627254) (xy 376.863654 -242.661346) (xy 376.893219 -242.70069)
			(xy 376.91609 -242.744267) (xy 376.931674 -242.790948) (xy 376.939569 -242.839525) (xy 376.940064 -242.864132)
			(xy 376.939569 -242.888739) (xy 376.931674 -242.937316) (xy 376.91609 -242.983997) (xy 376.893219 -243.027574)
			(xy 376.863654 -243.066918) (xy 376.828161 -243.10101) (xy 376.787658 -243.128966) (xy 376.743196 -243.150064)
			(xy 376.695925 -243.163756) (xy 376.64707 -243.169688) (xy 376.597895 -243.167707) (xy 376.549676 -243.157863)
			(xy 376.50366 -243.140411) (xy 376.461039 -243.115804) (xy 376.422918 -243.084679) (xy 376.390283 -243.047842)
			(xy 376.36398 -243.006246) (xy 376.344689 -242.96097) (xy 376.332912 -242.913186) (xy 376.328952 -242.864132)
			(xy 376.010424 -242.864132) (xy 376.009912 -242.889578) (xy 376.001748 -242.939812) (xy 375.985632 -242.988086)
			(xy 375.961981 -243.033149) (xy 375.931408 -243.073835) (xy 375.894704 -243.10909) (xy 375.85282 -243.138)
			(xy 375.806841 -243.159817) (xy 375.757957 -243.173977) (xy 375.707436 -243.180111) (xy 375.656584 -243.178062)
			(xy 375.60672 -243.167882) (xy 375.559134 -243.149835) (xy 375.51506 -243.124389) (xy 375.475638 -243.092202)
			(xy 375.44189 -243.054108) (xy 375.414689 -243.011094) (xy 375.394741 -242.964274) (xy 375.382562 -242.91486)
			(xy 375.378467 -242.864132) (xy 375.06021 -242.864132) (xy 375.059715 -242.888739) (xy 375.05182 -242.937316)
			(xy 375.036236 -242.983997) (xy 375.013365 -243.027574) (xy 374.9838 -243.066918) (xy 374.948307 -243.10101)
			(xy 374.907804 -243.128966) (xy 374.863342 -243.150064) (xy 374.816071 -243.163756) (xy 374.767216 -243.169688)
			(xy 374.718041 -243.167707) (xy 374.669822 -243.157863) (xy 374.623806 -243.140411) (xy 374.581185 -243.115804)
			(xy 374.543064 -243.084679) (xy 374.510429 -243.047842) (xy 374.484126 -243.006246) (xy 374.464835 -242.96097)
			(xy 374.453058 -242.913186) (xy 374.449098 -242.864132) (xy 374.120156 -242.864132) (xy 374.119661 -242.888739)
			(xy 374.111766 -242.937316) (xy 374.096182 -242.983997) (xy 374.073311 -243.027574) (xy 374.043746 -243.066918)
			(xy 374.008253 -243.10101) (xy 373.96775 -243.128966) (xy 373.923288 -243.150064) (xy 373.876017 -243.163756)
			(xy 373.827162 -243.169688) (xy 373.777987 -243.167707) (xy 373.729768 -243.157863) (xy 373.683752 -243.140411)
			(xy 373.641131 -243.115804) (xy 373.60301 -243.084679) (xy 373.570375 -243.047842) (xy 373.544072 -243.006246)
			(xy 373.524781 -242.96097) (xy 373.513004 -242.913186) (xy 373.509044 -242.864132) (xy 373.180102 -242.864132)
			(xy 373.179607 -242.888739) (xy 373.171712 -242.937316) (xy 373.156128 -242.983997) (xy 373.133257 -243.027574)
			(xy 373.103692 -243.066918) (xy 373.068199 -243.10101) (xy 373.027696 -243.128966) (xy 372.983234 -243.150064)
			(xy 372.935963 -243.163756) (xy 372.887108 -243.169688) (xy 372.837933 -243.167707) (xy 372.789714 -243.157863)
			(xy 372.743698 -243.140411) (xy 372.701077 -243.115804) (xy 372.662956 -243.084679) (xy 372.630321 -243.047842)
			(xy 372.604018 -243.006246) (xy 372.584727 -242.96097) (xy 372.57295 -242.913186) (xy 372.56899 -242.864132)
			(xy 372.240048 -242.864132) (xy 372.239553 -242.888739) (xy 372.231658 -242.937316) (xy 372.216074 -242.983997)
			(xy 372.193203 -243.027574) (xy 372.163638 -243.066918) (xy 372.128145 -243.10101) (xy 372.087642 -243.128966)
			(xy 372.04318 -243.150064) (xy 371.995909 -243.163756) (xy 371.947054 -243.169688) (xy 371.897879 -243.167707)
			(xy 371.84966 -243.157863) (xy 371.803644 -243.140411) (xy 371.761023 -243.115804) (xy 371.722902 -243.084679)
			(xy 371.690267 -243.047842) (xy 371.663964 -243.006246) (xy 371.644673 -242.96097) (xy 371.632896 -242.913186)
			(xy 371.628936 -242.864132) (xy 371.299994 -242.864132) (xy 371.299499 -242.888739) (xy 371.291604 -242.937316)
			(xy 371.27602 -242.983997) (xy 371.253149 -243.027574) (xy 371.223584 -243.066918) (xy 371.188091 -243.10101)
			(xy 371.147588 -243.128966) (xy 371.103126 -243.150064) (xy 371.055855 -243.163756) (xy 371.007 -243.169688)
			(xy 370.957825 -243.167707) (xy 370.909606 -243.157863) (xy 370.86359 -243.140411) (xy 370.820969 -243.115804)
			(xy 370.782848 -243.084679) (xy 370.750213 -243.047842) (xy 370.72391 -243.006246) (xy 370.704619 -242.96097)
			(xy 370.692842 -242.913186) (xy 370.688882 -242.864132) (xy 370.360194 -242.864132) (xy 370.359699 -242.888739)
			(xy 370.351804 -242.937316) (xy 370.33622 -242.983997) (xy 370.313349 -243.027574) (xy 370.283784 -243.066918)
			(xy 370.248291 -243.10101) (xy 370.207788 -243.128966) (xy 370.163326 -243.150064) (xy 370.116055 -243.163756)
			(xy 370.0672 -243.169688) (xy 370.018025 -243.167707) (xy 369.969806 -243.157863) (xy 369.92379 -243.140411)
			(xy 369.881169 -243.115804) (xy 369.843048 -243.084679) (xy 369.810413 -243.047842) (xy 369.78411 -243.006246)
			(xy 369.764819 -242.96097) (xy 369.753042 -242.913186) (xy 369.749082 -242.864132) (xy 369.42014 -242.864132)
			(xy 369.419645 -242.888739) (xy 369.41175 -242.937316) (xy 369.396166 -242.983997) (xy 369.373295 -243.027574)
			(xy 369.34373 -243.066918) (xy 369.308237 -243.10101) (xy 369.267734 -243.128966) (xy 369.223272 -243.150064)
			(xy 369.176001 -243.163756) (xy 369.127146 -243.169688) (xy 369.077971 -243.167707) (xy 369.029752 -243.157863)
			(xy 368.983736 -243.140411) (xy 368.941115 -243.115804) (xy 368.902994 -243.084679) (xy 368.870359 -243.047842)
			(xy 368.844056 -243.006246) (xy 368.824765 -242.96097) (xy 368.812988 -242.913186) (xy 368.809028 -242.864132)
			(xy 368.480086 -242.864132) (xy 368.479591 -242.888739) (xy 368.471696 -242.937316) (xy 368.456112 -242.983997)
			(xy 368.433241 -243.027574) (xy 368.403676 -243.066918) (xy 368.368183 -243.10101) (xy 368.32768 -243.128966)
			(xy 368.283218 -243.150064) (xy 368.235947 -243.163756) (xy 368.187092 -243.169688) (xy 368.137917 -243.167707)
			(xy 368.089698 -243.157863) (xy 368.043682 -243.140411) (xy 368.001061 -243.115804) (xy 367.96294 -243.084679)
			(xy 367.930305 -243.047842) (xy 367.904002 -243.006246) (xy 367.884711 -242.96097) (xy 367.872934 -242.913186)
			(xy 367.868974 -242.864132) (xy 367.540032 -242.864132) (xy 367.539537 -242.888739) (xy 367.531642 -242.937316)
			(xy 367.516058 -242.983997) (xy 367.493187 -243.027574) (xy 367.463622 -243.066918) (xy 367.428129 -243.10101)
			(xy 367.387626 -243.128966) (xy 367.343164 -243.150064) (xy 367.295893 -243.163756) (xy 367.247038 -243.169688)
			(xy 367.197863 -243.167707) (xy 367.149644 -243.157863) (xy 367.103628 -243.140411) (xy 367.061007 -243.115804)
			(xy 367.022886 -243.084679) (xy 366.990251 -243.047842) (xy 366.963948 -243.006246) (xy 366.944657 -242.96097)
			(xy 366.93288 -242.913186) (xy 366.92892 -242.864132) (xy 366.600232 -242.864132) (xy 366.599737 -242.888739)
			(xy 366.591842 -242.937316) (xy 366.576258 -242.983997) (xy 366.553387 -243.027574) (xy 366.523822 -243.066918)
			(xy 366.488329 -243.10101) (xy 366.447826 -243.128966) (xy 366.403364 -243.150064) (xy 366.356093 -243.163756)
			(xy 366.307238 -243.169688) (xy 366.258063 -243.167707) (xy 366.209844 -243.157863) (xy 366.163828 -243.140411)
			(xy 366.121207 -243.115804) (xy 366.083086 -243.084679) (xy 366.050451 -243.047842) (xy 366.024148 -243.006246)
			(xy 366.004857 -242.96097) (xy 365.99308 -242.913186) (xy 365.98912 -242.864132) (xy 365.660178 -242.864132)
			(xy 365.659683 -242.888739) (xy 365.651788 -242.937316) (xy 365.636204 -242.983997) (xy 365.613333 -243.027574)
			(xy 365.583768 -243.066918) (xy 365.548275 -243.10101) (xy 365.507772 -243.128966) (xy 365.46331 -243.150064)
			(xy 365.416039 -243.163756) (xy 365.367184 -243.169688) (xy 365.318009 -243.167707) (xy 365.26979 -243.157863)
			(xy 365.223774 -243.140411) (xy 365.181153 -243.115804) (xy 365.143032 -243.084679) (xy 365.110397 -243.047842)
			(xy 365.084094 -243.006246) (xy 365.064803 -242.96097) (xy 365.053026 -242.913186) (xy 365.049066 -242.864132)
			(xy 364.720124 -242.864132) (xy 364.719629 -242.888739) (xy 364.711734 -242.937316) (xy 364.69615 -242.983997)
			(xy 364.673279 -243.027574) (xy 364.643714 -243.066918) (xy 364.608221 -243.10101) (xy 364.567718 -243.128966)
			(xy 364.523256 -243.150064) (xy 364.475985 -243.163756) (xy 364.42713 -243.169688) (xy 364.377955 -243.167707)
			(xy 364.329736 -243.157863) (xy 364.28372 -243.140411) (xy 364.241099 -243.115804) (xy 364.202978 -243.084679)
			(xy 364.170343 -243.047842) (xy 364.14404 -243.006246) (xy 364.124749 -242.96097) (xy 364.112972 -242.913186)
			(xy 364.109012 -242.864132) (xy 363.78007 -242.864132) (xy 363.779575 -242.888739) (xy 363.77168 -242.937316)
			(xy 363.756096 -242.983997) (xy 363.733225 -243.027574) (xy 363.70366 -243.066918) (xy 363.668167 -243.10101)
			(xy 363.627664 -243.128966) (xy 363.583202 -243.150064) (xy 363.535931 -243.163756) (xy 363.487076 -243.169688)
			(xy 363.437901 -243.167707) (xy 363.389682 -243.157863) (xy 363.343666 -243.140411) (xy 363.301045 -243.115804)
			(xy 363.262924 -243.084679) (xy 363.230289 -243.047842) (xy 363.203986 -243.006246) (xy 363.184695 -242.96097)
			(xy 363.172918 -242.913186) (xy 363.168958 -242.864132) (xy 356.266496 -242.864132) (xy 356.266001 -242.888739)
			(xy 356.258106 -242.937316) (xy 356.242522 -242.983997) (xy 356.219651 -243.027574) (xy 356.190086 -243.066918)
			(xy 356.154593 -243.10101) (xy 356.11409 -243.128966) (xy 356.069628 -243.150064) (xy 356.022357 -243.163756)
			(xy 355.973502 -243.169688) (xy 355.924327 -243.167707) (xy 355.876108 -243.157863) (xy 355.830092 -243.140411)
			(xy 355.787471 -243.115804) (xy 355.74935 -243.084679) (xy 355.716715 -243.047842) (xy 355.690412 -243.006246)
			(xy 355.671121 -242.96097) (xy 355.659344 -242.913186) (xy 355.655384 -242.864132) (xy 355.326442 -242.864132)
			(xy 355.325947 -242.888739) (xy 355.318052 -242.937316) (xy 355.302468 -242.983997) (xy 355.279597 -243.027574)
			(xy 355.250032 -243.066918) (xy 355.214539 -243.10101) (xy 355.174036 -243.128966) (xy 355.129574 -243.150064)
			(xy 355.082303 -243.163756) (xy 355.033448 -243.169688) (xy 354.984273 -243.167707) (xy 354.936054 -243.157863)
			(xy 354.890038 -243.140411) (xy 354.847417 -243.115804) (xy 354.809296 -243.084679) (xy 354.776661 -243.047842)
			(xy 354.750358 -243.006246) (xy 354.731067 -242.96097) (xy 354.71929 -242.913186) (xy 354.71533 -242.864132)
			(xy 354.386388 -242.864132) (xy 354.385893 -242.888739) (xy 354.377998 -242.937316) (xy 354.362414 -242.983997)
			(xy 354.339543 -243.027574) (xy 354.309978 -243.066918) (xy 354.274485 -243.10101) (xy 354.233982 -243.128966)
			(xy 354.18952 -243.150064) (xy 354.142249 -243.163756) (xy 354.093394 -243.169688) (xy 354.044219 -243.167707)
			(xy 353.996 -243.157863) (xy 353.949984 -243.140411) (xy 353.907363 -243.115804) (xy 353.869242 -243.084679)
			(xy 353.836607 -243.047842) (xy 353.810304 -243.006246) (xy 353.791013 -242.96097) (xy 353.779236 -242.913186)
			(xy 353.775276 -242.864132) (xy 353.446334 -242.864132) (xy 353.445839 -242.888739) (xy 353.437944 -242.937316)
			(xy 353.42236 -242.983997) (xy 353.399489 -243.027574) (xy 353.369924 -243.066918) (xy 353.334431 -243.10101)
			(xy 353.293928 -243.128966) (xy 353.249466 -243.150064) (xy 353.202195 -243.163756) (xy 353.15334 -243.169688)
			(xy 353.104165 -243.167707) (xy 353.055946 -243.157863) (xy 353.00993 -243.140411) (xy 352.967309 -243.115804)
			(xy 352.929188 -243.084679) (xy 352.896553 -243.047842) (xy 352.87025 -243.006246) (xy 352.850959 -242.96097)
			(xy 352.839182 -242.913186) (xy 352.835222 -242.864132) (xy 352.506534 -242.864132) (xy 352.506039 -242.888739)
			(xy 352.498144 -242.937316) (xy 352.48256 -242.983997) (xy 352.459689 -243.027574) (xy 352.430124 -243.066918)
			(xy 352.394631 -243.10101) (xy 352.354128 -243.128966) (xy 352.309666 -243.150064) (xy 352.262395 -243.163756)
			(xy 352.21354 -243.169688) (xy 352.164365 -243.167707) (xy 352.116146 -243.157863) (xy 352.07013 -243.140411)
			(xy 352.027509 -243.115804) (xy 351.989388 -243.084679) (xy 351.956753 -243.047842) (xy 351.93045 -243.006246)
			(xy 351.911159 -242.96097) (xy 351.899382 -242.913186) (xy 351.895422 -242.864132) (xy 351.56648 -242.864132)
			(xy 351.565985 -242.888739) (xy 351.55809 -242.937316) (xy 351.542506 -242.983997) (xy 351.519635 -243.027574)
			(xy 351.49007 -243.066918) (xy 351.454577 -243.10101) (xy 351.414074 -243.128966) (xy 351.369612 -243.150064)
			(xy 351.322341 -243.163756) (xy 351.273486 -243.169688) (xy 351.224311 -243.167707) (xy 351.176092 -243.157863)
			(xy 351.130076 -243.140411) (xy 351.087455 -243.115804) (xy 351.049334 -243.084679) (xy 351.016699 -243.047842)
			(xy 350.990396 -243.006246) (xy 350.971105 -242.96097) (xy 350.959328 -242.913186) (xy 350.955368 -242.864132)
			(xy 350.626426 -242.864132) (xy 350.625931 -242.888739) (xy 350.618036 -242.937316) (xy 350.602452 -242.983997)
			(xy 350.579581 -243.027574) (xy 350.550016 -243.066918) (xy 350.514523 -243.10101) (xy 350.47402 -243.128966)
			(xy 350.429558 -243.150064) (xy 350.382287 -243.163756) (xy 350.333432 -243.169688) (xy 350.284257 -243.167707)
			(xy 350.236038 -243.157863) (xy 350.190022 -243.140411) (xy 350.147401 -243.115804) (xy 350.10928 -243.084679)
			(xy 350.076645 -243.047842) (xy 350.050342 -243.006246) (xy 350.031051 -242.96097) (xy 350.019274 -242.913186)
			(xy 350.015314 -242.864132) (xy 349.686372 -242.864132) (xy 349.685877 -242.888739) (xy 349.677982 -242.937316)
			(xy 349.662398 -242.983997) (xy 349.639527 -243.027574) (xy 349.609962 -243.066918) (xy 349.574469 -243.10101)
			(xy 349.533966 -243.128966) (xy 349.489504 -243.150064) (xy 349.442233 -243.163756) (xy 349.393378 -243.169688)
			(xy 349.344203 -243.167707) (xy 349.295984 -243.157863) (xy 349.249968 -243.140411) (xy 349.207347 -243.115804)
			(xy 349.169226 -243.084679) (xy 349.136591 -243.047842) (xy 349.110288 -243.006246) (xy 349.090997 -242.96097)
			(xy 349.07922 -242.913186) (xy 349.07526 -242.864132) (xy 348.746318 -242.864132) (xy 348.745823 -242.888739)
			(xy 348.737928 -242.937316) (xy 348.722344 -242.983997) (xy 348.699473 -243.027574) (xy 348.669908 -243.066918)
			(xy 348.634415 -243.10101) (xy 348.593912 -243.128966) (xy 348.54945 -243.150064) (xy 348.502179 -243.163756)
			(xy 348.453324 -243.169688) (xy 348.404149 -243.167707) (xy 348.35593 -243.157863) (xy 348.309914 -243.140411)
			(xy 348.267293 -243.115804) (xy 348.229172 -243.084679) (xy 348.196537 -243.047842) (xy 348.170234 -243.006246)
			(xy 348.150943 -242.96097) (xy 348.139166 -242.913186) (xy 348.135206 -242.864132) (xy 347.806518 -242.864132)
			(xy 347.806023 -242.888739) (xy 347.798128 -242.937316) (xy 347.782544 -242.983997) (xy 347.759673 -243.027574)
			(xy 347.730108 -243.066918) (xy 347.694615 -243.10101) (xy 347.654112 -243.128966) (xy 347.60965 -243.150064)
			(xy 347.562379 -243.163756) (xy 347.513524 -243.169688) (xy 347.464349 -243.167707) (xy 347.41613 -243.157863)
			(xy 347.370114 -243.140411) (xy 347.327493 -243.115804) (xy 347.289372 -243.084679) (xy 347.256737 -243.047842)
			(xy 347.230434 -243.006246) (xy 347.211143 -242.96097) (xy 347.199366 -242.913186) (xy 347.195406 -242.864132)
			(xy 346.866464 -242.864132) (xy 346.865969 -242.888739) (xy 346.858074 -242.937316) (xy 346.84249 -242.983997)
			(xy 346.819619 -243.027574) (xy 346.790054 -243.066918) (xy 346.754561 -243.10101) (xy 346.714058 -243.128966)
			(xy 346.669596 -243.150064) (xy 346.622325 -243.163756) (xy 346.57347 -243.169688) (xy 346.524295 -243.167707)
			(xy 346.476076 -243.157863) (xy 346.43006 -243.140411) (xy 346.387439 -243.115804) (xy 346.349318 -243.084679)
			(xy 346.316683 -243.047842) (xy 346.29038 -243.006246) (xy 346.271089 -242.96097) (xy 346.259312 -242.913186)
			(xy 346.255352 -242.864132) (xy 345.92641 -242.864132) (xy 345.925915 -242.888739) (xy 345.91802 -242.937316)
			(xy 345.902436 -242.983997) (xy 345.879565 -243.027574) (xy 345.85 -243.066918) (xy 345.814507 -243.10101)
			(xy 345.774004 -243.128966) (xy 345.729542 -243.150064) (xy 345.682271 -243.163756) (xy 345.633416 -243.169688)
			(xy 345.584241 -243.167707) (xy 345.536022 -243.157863) (xy 345.490006 -243.140411) (xy 345.447385 -243.115804)
			(xy 345.409264 -243.084679) (xy 345.376629 -243.047842) (xy 345.350326 -243.006246) (xy 345.331035 -242.96097)
			(xy 345.319258 -242.913186) (xy 345.315298 -242.864132) (xy 344.986356 -242.864132) (xy 344.985861 -242.888739)
			(xy 344.977966 -242.937316) (xy 344.962382 -242.983997) (xy 344.939511 -243.027574) (xy 344.909946 -243.066918)
			(xy 344.874453 -243.10101) (xy 344.83395 -243.128966) (xy 344.789488 -243.150064) (xy 344.742217 -243.163756)
			(xy 344.693362 -243.169688) (xy 344.644187 -243.167707) (xy 344.595968 -243.157863) (xy 344.549952 -243.140411)
			(xy 344.507331 -243.115804) (xy 344.46921 -243.084679) (xy 344.436575 -243.047842) (xy 344.410272 -243.006246)
			(xy 344.390981 -242.96097) (xy 344.379204 -242.913186) (xy 344.375244 -242.864132) (xy 344.056716 -242.864132)
			(xy 344.056204 -242.889578) (xy 344.04804 -242.939812) (xy 344.031924 -242.988086) (xy 344.008273 -243.033149)
			(xy 343.9777 -243.073835) (xy 343.940996 -243.10909) (xy 343.899112 -243.138) (xy 343.853133 -243.159817)
			(xy 343.804249 -243.173977) (xy 343.753728 -243.180111) (xy 343.702876 -243.178062) (xy 343.653012 -243.167882)
			(xy 343.605426 -243.149835) (xy 343.561352 -243.124389) (xy 343.52193 -243.092202) (xy 343.488182 -243.054108)
			(xy 343.460981 -243.011094) (xy 343.441033 -242.964274) (xy 343.428854 -242.91486) (xy 343.424759 -242.864132)
			(xy 343.106502 -242.864132) (xy 343.106007 -242.888739) (xy 343.098112 -242.937316) (xy 343.082528 -242.983997)
			(xy 343.059657 -243.027574) (xy 343.030092 -243.066918) (xy 342.994599 -243.10101) (xy 342.954096 -243.128966)
			(xy 342.909634 -243.150064) (xy 342.862363 -243.163756) (xy 342.813508 -243.169688) (xy 342.764333 -243.167707)
			(xy 342.716114 -243.157863) (xy 342.670098 -243.140411) (xy 342.627477 -243.115804) (xy 342.589356 -243.084679)
			(xy 342.556721 -243.047842) (xy 342.530418 -243.006246) (xy 342.511127 -242.96097) (xy 342.49935 -242.913186)
			(xy 342.49539 -242.864132) (xy 342.176862 -242.864132) (xy 342.17635 -242.889578) (xy 342.168186 -242.939812)
			(xy 342.15207 -242.988086) (xy 342.128419 -243.033149) (xy 342.097846 -243.073835) (xy 342.061142 -243.10909)
			(xy 342.019258 -243.138) (xy 341.973279 -243.159817) (xy 341.924395 -243.173977) (xy 341.873874 -243.180111)
			(xy 341.823022 -243.178062) (xy 341.773158 -243.167882) (xy 341.725572 -243.149835) (xy 341.681498 -243.124389)
			(xy 341.642076 -243.092202) (xy 341.608328 -243.054108) (xy 341.581127 -243.011094) (xy 341.561179 -242.964274)
			(xy 341.549 -242.91486) (xy 341.544905 -242.864132) (xy 341.226394 -242.864132) (xy 341.226073 -242.883327)
			(xy 341.221228 -242.921411) (xy 341.216742 -242.940078) (xy 341.215218 -242.946174) (xy 341.215218 -243.275358)
			(xy 341.215797 -243.286559) (xy 341.225273 -243.306859) (xy 341.233506 -243.314474) (xy 341.270844 -243.345462)
			(xy 341.29218 -243.363242) (xy 341.299358 -243.368746) (xy 341.316411 -243.374743) (xy 341.325454 -243.374926)
			(xy 341.330026 -243.374926) (xy 341.345103 -243.372062) (xy 341.375641 -243.369011) (xy 341.390986 -243.36883)
			(xy 341.393018 -243.36883) (xy 341.416904 -243.369451) (xy 341.464051 -243.377206) (xy 341.509413 -243.392212)
			(xy 341.551883 -243.414102) (xy 341.590425 -243.442342) (xy 341.624096 -243.476241) (xy 341.652075 -243.514971)
			(xy 341.673679 -243.557588) (xy 341.688379 -243.603051) (xy 341.695817 -243.650248) (xy 341.696294 -243.674138)
			(xy 342.014805 -243.674138) (xy 342.0189 -243.62341) (xy 342.031079 -243.573996) (xy 342.051027 -243.527176)
			(xy 342.078228 -243.484162) (xy 342.111976 -243.446068) (xy 342.151398 -243.413881) (xy 342.195472 -243.388435)
			(xy 342.243058 -243.370388) (xy 342.292922 -243.360208) (xy 342.343774 -243.358159) (xy 342.394295 -243.364293)
			(xy 342.443179 -243.378453) (xy 342.489158 -243.40027) (xy 342.531042 -243.42918) (xy 342.567746 -243.464435)
			(xy 342.598319 -243.505121) (xy 342.62197 -243.550184) (xy 342.638086 -243.598458) (xy 342.64625 -243.648692)
			(xy 342.646762 -243.674138) (xy 342.954859 -243.674138) (xy 342.958954 -243.62341) (xy 342.971133 -243.573996)
			(xy 342.991081 -243.527176) (xy 343.018282 -243.484162) (xy 343.05203 -243.446068) (xy 343.091452 -243.413881)
			(xy 343.135526 -243.388435) (xy 343.183112 -243.370388) (xy 343.232976 -243.360208) (xy 343.283828 -243.358159)
			(xy 343.334349 -243.364293) (xy 343.383233 -243.378453) (xy 343.429212 -243.40027) (xy 343.471096 -243.42918)
			(xy 343.5078 -243.464435) (xy 343.538373 -243.505121) (xy 343.562024 -243.550184) (xy 343.57814 -243.598458)
			(xy 343.586304 -243.648692) (xy 343.586816 -243.674138) (xy 343.905344 -243.674138) (xy 343.909304 -243.625084)
			(xy 343.921081 -243.5773) (xy 343.940372 -243.532024) (xy 343.966675 -243.490428) (xy 343.99931 -243.453591)
			(xy 344.037431 -243.422466) (xy 344.080052 -243.397859) (xy 344.126068 -243.380407) (xy 344.174287 -243.370563)
			(xy 344.223462 -243.368582) (xy 344.272317 -243.374514) (xy 344.319588 -243.388206) (xy 344.36405 -243.409304)
			(xy 344.404553 -243.43726) (xy 344.440046 -243.471352) (xy 344.469611 -243.510696) (xy 344.492482 -243.554273)
			(xy 344.508066 -243.600954) (xy 344.515961 -243.649531) (xy 344.516456 -243.674138) (xy 344.845398 -243.674138)
			(xy 344.849358 -243.625084) (xy 344.861135 -243.5773) (xy 344.880426 -243.532024) (xy 344.906729 -243.490428)
			(xy 344.939364 -243.453591) (xy 344.977485 -243.422466) (xy 345.020106 -243.397859) (xy 345.066122 -243.380407)
			(xy 345.114341 -243.370563) (xy 345.163516 -243.368582) (xy 345.212371 -243.374514) (xy 345.259642 -243.388206)
			(xy 345.304104 -243.409304) (xy 345.344607 -243.43726) (xy 345.3801 -243.471352) (xy 345.409665 -243.510696)
			(xy 345.432536 -243.554273) (xy 345.44812 -243.600954) (xy 345.456015 -243.649531) (xy 345.45651 -243.674138)
			(xy 345.785198 -243.674138) (xy 345.789158 -243.625084) (xy 345.800935 -243.5773) (xy 345.820226 -243.532024)
			(xy 345.846529 -243.490428) (xy 345.879164 -243.453591) (xy 345.917285 -243.422466) (xy 345.959906 -243.397859)
			(xy 346.005922 -243.380407) (xy 346.054141 -243.370563) (xy 346.103316 -243.368582) (xy 346.152171 -243.374514)
			(xy 346.199442 -243.388206) (xy 346.243904 -243.409304) (xy 346.284407 -243.43726) (xy 346.3199 -243.471352)
			(xy 346.349465 -243.510696) (xy 346.372336 -243.554273) (xy 346.38792 -243.600954) (xy 346.395815 -243.649531)
			(xy 346.39631 -243.674138) (xy 346.725252 -243.674138) (xy 346.729212 -243.625084) (xy 346.740989 -243.5773)
			(xy 346.76028 -243.532024) (xy 346.786583 -243.490428) (xy 346.819218 -243.453591) (xy 346.857339 -243.422466)
			(xy 346.89996 -243.397859) (xy 346.945976 -243.380407) (xy 346.994195 -243.370563) (xy 347.04337 -243.368582)
			(xy 347.092225 -243.374514) (xy 347.139496 -243.388206) (xy 347.183958 -243.409304) (xy 347.224461 -243.43726)
			(xy 347.259954 -243.471352) (xy 347.289519 -243.510696) (xy 347.31239 -243.554273) (xy 347.327974 -243.600954)
			(xy 347.335869 -243.649531) (xy 347.336364 -243.674138) (xy 347.665306 -243.674138) (xy 347.669266 -243.625084)
			(xy 347.681043 -243.5773) (xy 347.700334 -243.532024) (xy 347.726637 -243.490428) (xy 347.759272 -243.453591)
			(xy 347.797393 -243.422466) (xy 347.840014 -243.397859) (xy 347.88603 -243.380407) (xy 347.934249 -243.370563)
			(xy 347.983424 -243.368582) (xy 348.032279 -243.374514) (xy 348.07955 -243.388206) (xy 348.124012 -243.409304)
			(xy 348.164515 -243.43726) (xy 348.200008 -243.471352) (xy 348.229573 -243.510696) (xy 348.252444 -243.554273)
			(xy 348.268028 -243.600954) (xy 348.275923 -243.649531) (xy 348.276418 -243.674138) (xy 348.60536 -243.674138)
			(xy 348.60932 -243.625084) (xy 348.621097 -243.5773) (xy 348.640388 -243.532024) (xy 348.666691 -243.490428)
			(xy 348.699326 -243.453591) (xy 348.737447 -243.422466) (xy 348.780068 -243.397859) (xy 348.826084 -243.380407)
			(xy 348.874303 -243.370563) (xy 348.923478 -243.368582) (xy 348.972333 -243.374514) (xy 349.019604 -243.388206)
			(xy 349.064066 -243.409304) (xy 349.104569 -243.43726) (xy 349.140062 -243.471352) (xy 349.169627 -243.510696)
			(xy 349.192498 -243.554273) (xy 349.208082 -243.600954) (xy 349.215977 -243.649531) (xy 349.216472 -243.674138)
			(xy 349.545414 -243.674138) (xy 349.549374 -243.625084) (xy 349.561151 -243.5773) (xy 349.580442 -243.532024)
			(xy 349.606745 -243.490428) (xy 349.63938 -243.453591) (xy 349.677501 -243.422466) (xy 349.720122 -243.397859)
			(xy 349.766138 -243.380407) (xy 349.814357 -243.370563) (xy 349.863532 -243.368582) (xy 349.912387 -243.374514)
			(xy 349.959658 -243.388206) (xy 350.00412 -243.409304) (xy 350.044623 -243.43726) (xy 350.080116 -243.471352)
			(xy 350.109681 -243.510696) (xy 350.132552 -243.554273) (xy 350.148136 -243.600954) (xy 350.156031 -243.649531)
			(xy 350.156526 -243.674138) (xy 350.485214 -243.674138) (xy 350.489174 -243.625084) (xy 350.500951 -243.5773)
			(xy 350.520242 -243.532024) (xy 350.546545 -243.490428) (xy 350.57918 -243.453591) (xy 350.617301 -243.422466)
			(xy 350.659922 -243.397859) (xy 350.705938 -243.380407) (xy 350.754157 -243.370563) (xy 350.803332 -243.368582)
			(xy 350.852187 -243.374514) (xy 350.899458 -243.388206) (xy 350.94392 -243.409304) (xy 350.984423 -243.43726)
			(xy 351.019916 -243.471352) (xy 351.049481 -243.510696) (xy 351.072352 -243.554273) (xy 351.087936 -243.600954)
			(xy 351.095831 -243.649531) (xy 351.096326 -243.674138) (xy 351.425268 -243.674138) (xy 351.429228 -243.625084)
			(xy 351.441005 -243.5773) (xy 351.460296 -243.532024) (xy 351.486599 -243.490428) (xy 351.519234 -243.453591)
			(xy 351.557355 -243.422466) (xy 351.599976 -243.397859) (xy 351.645992 -243.380407) (xy 351.694211 -243.370563)
			(xy 351.743386 -243.368582) (xy 351.792241 -243.374514) (xy 351.839512 -243.388206) (xy 351.883974 -243.409304)
			(xy 351.924477 -243.43726) (xy 351.95997 -243.471352) (xy 351.989535 -243.510696) (xy 352.012406 -243.554273)
			(xy 352.02799 -243.600954) (xy 352.035885 -243.649531) (xy 352.03638 -243.674138) (xy 352.365322 -243.674138)
			(xy 352.369282 -243.625084) (xy 352.381059 -243.5773) (xy 352.40035 -243.532024) (xy 352.426653 -243.490428)
			(xy 352.459288 -243.453591) (xy 352.497409 -243.422466) (xy 352.54003 -243.397859) (xy 352.586046 -243.380407)
			(xy 352.634265 -243.370563) (xy 352.68344 -243.368582) (xy 352.732295 -243.374514) (xy 352.779566 -243.388206)
			(xy 352.824028 -243.409304) (xy 352.864531 -243.43726) (xy 352.900024 -243.471352) (xy 352.929589 -243.510696)
			(xy 352.95246 -243.554273) (xy 352.968044 -243.600954) (xy 352.975939 -243.649531) (xy 352.976434 -243.674138)
			(xy 353.305376 -243.674138) (xy 353.309336 -243.625084) (xy 353.321113 -243.5773) (xy 353.340404 -243.532024)
			(xy 353.366707 -243.490428) (xy 353.399342 -243.453591) (xy 353.437463 -243.422466) (xy 353.480084 -243.397859)
			(xy 353.5261 -243.380407) (xy 353.574319 -243.370563) (xy 353.623494 -243.368582) (xy 353.672349 -243.374514)
			(xy 353.71962 -243.388206) (xy 353.764082 -243.409304) (xy 353.804585 -243.43726) (xy 353.840078 -243.471352)
			(xy 353.869643 -243.510696) (xy 353.892514 -243.554273) (xy 353.908098 -243.600954) (xy 353.915993 -243.649531)
			(xy 353.916488 -243.674138) (xy 354.24543 -243.674138) (xy 354.24939 -243.625084) (xy 354.261167 -243.5773)
			(xy 354.280458 -243.532024) (xy 354.306761 -243.490428) (xy 354.339396 -243.453591) (xy 354.377517 -243.422466)
			(xy 354.420138 -243.397859) (xy 354.466154 -243.380407) (xy 354.514373 -243.370563) (xy 354.563548 -243.368582)
			(xy 354.612403 -243.374514) (xy 354.659674 -243.388206) (xy 354.704136 -243.409304) (xy 354.744639 -243.43726)
			(xy 354.780132 -243.471352) (xy 354.809697 -243.510696) (xy 354.832568 -243.554273) (xy 354.848152 -243.600954)
			(xy 354.856047 -243.649531) (xy 354.856542 -243.674138) (xy 355.18523 -243.674138) (xy 355.18919 -243.625084)
			(xy 355.200967 -243.5773) (xy 355.220258 -243.532024) (xy 355.246561 -243.490428) (xy 355.279196 -243.453591)
			(xy 355.317317 -243.422466) (xy 355.359938 -243.397859) (xy 355.405954 -243.380407) (xy 355.454173 -243.370563)
			(xy 355.503348 -243.368582) (xy 355.552203 -243.374514) (xy 355.599474 -243.388206) (xy 355.643936 -243.409304)
			(xy 355.684439 -243.43726) (xy 355.719932 -243.471352) (xy 355.749497 -243.510696) (xy 355.772368 -243.554273)
			(xy 355.787952 -243.600954) (xy 355.795847 -243.649531) (xy 355.796342 -243.674138) (xy 356.125284 -243.674138)
			(xy 356.129244 -243.625084) (xy 356.141021 -243.5773) (xy 356.160312 -243.532024) (xy 356.186615 -243.490428)
			(xy 356.21925 -243.453591) (xy 356.257371 -243.422466) (xy 356.299992 -243.397859) (xy 356.346008 -243.380407)
			(xy 356.394227 -243.370563) (xy 356.443402 -243.368582) (xy 356.492257 -243.374514) (xy 356.539528 -243.388206)
			(xy 356.58399 -243.409304) (xy 356.624493 -243.43726) (xy 356.659986 -243.471352) (xy 356.689551 -243.510696)
			(xy 356.712422 -243.554273) (xy 356.728006 -243.600954) (xy 356.735901 -243.649531) (xy 356.736396 -243.674138)
			(xy 357.065338 -243.674138) (xy 357.069298 -243.625084) (xy 357.081075 -243.5773) (xy 357.100366 -243.532024)
			(xy 357.126669 -243.490428) (xy 357.159304 -243.453591) (xy 357.197425 -243.422466) (xy 357.240046 -243.397859)
			(xy 357.286062 -243.380407) (xy 357.334281 -243.370563) (xy 357.383456 -243.368582) (xy 357.432311 -243.374514)
			(xy 357.479582 -243.388206) (xy 357.524044 -243.409304) (xy 357.564547 -243.43726) (xy 357.60004 -243.471352)
			(xy 357.629605 -243.510696) (xy 357.652476 -243.554273) (xy 357.66806 -243.600954) (xy 357.675955 -243.649531)
			(xy 357.67645 -243.674138) (xy 358.005392 -243.674138) (xy 358.009352 -243.625084) (xy 358.021129 -243.5773)
			(xy 358.04042 -243.532024) (xy 358.066723 -243.490428) (xy 358.099358 -243.453591) (xy 358.137479 -243.422466)
			(xy 358.1801 -243.397859) (xy 358.226116 -243.380407) (xy 358.274335 -243.370563) (xy 358.32351 -243.368582)
			(xy 358.372365 -243.374514) (xy 358.419636 -243.388206) (xy 358.464098 -243.409304) (xy 358.504601 -243.43726)
			(xy 358.540094 -243.471352) (xy 358.569659 -243.510696) (xy 358.59253 -243.554273) (xy 358.608114 -243.600954)
			(xy 358.616009 -243.649531) (xy 358.616504 -243.674138) (xy 360.81895 -243.674138) (xy 360.82291 -243.625084)
			(xy 360.834687 -243.5773) (xy 360.853978 -243.532024) (xy 360.880281 -243.490428) (xy 360.912916 -243.453591)
			(xy 360.951037 -243.422466) (xy 360.993658 -243.397859) (xy 361.039674 -243.380407) (xy 361.087893 -243.370563)
			(xy 361.137068 -243.368582) (xy 361.185923 -243.374514) (xy 361.233194 -243.388206) (xy 361.277656 -243.409304)
			(xy 361.318159 -243.43726) (xy 361.353652 -243.471352) (xy 361.383217 -243.510696) (xy 361.406088 -243.554273)
			(xy 361.421672 -243.600954) (xy 361.429567 -243.649531) (xy 361.430061 -243.6741) (xy 361.758723 -243.6741)
			(xy 361.762898 -243.623721) (xy 361.775308 -243.574716) (xy 361.795615 -243.528421) (xy 361.823265 -243.486101)
			(xy 361.857503 -243.448909) (xy 361.897396 -243.41786) (xy 361.941856 -243.393801) (xy 361.989669 -243.377388)
			(xy 362.039532 -243.369068) (xy 362.064808 -243.368576) (xy 363.004862 -243.368576) (xy 363.030146 -243.36899)
			(xy 363.080025 -243.377308) (xy 363.127854 -243.393722) (xy 363.172329 -243.417786) (xy 363.212237 -243.448843)
			(xy 363.246487 -243.486045) (xy 363.274147 -243.528377) (xy 363.294462 -243.574685) (xy 363.306876 -243.623705)
			(xy 363.311053 -243.6741) (xy 363.31105 -243.674138) (xy 363.639112 -243.674138) (xy 363.643072 -243.625084)
			(xy 363.654849 -243.5773) (xy 363.67414 -243.532024) (xy 363.700443 -243.490428) (xy 363.733078 -243.453591)
			(xy 363.771199 -243.422466) (xy 363.81382 -243.397859) (xy 363.859836 -243.380407) (xy 363.908055 -243.370563)
			(xy 363.95723 -243.368582) (xy 364.006085 -243.374514) (xy 364.053356 -243.388206) (xy 364.097818 -243.409304)
			(xy 364.138321 -243.43726) (xy 364.173814 -243.471352) (xy 364.203379 -243.510696) (xy 364.22625 -243.554273)
			(xy 364.241834 -243.600954) (xy 364.249729 -243.649531) (xy 364.250224 -243.674138) (xy 364.578912 -243.674138)
			(xy 364.582872 -243.625084) (xy 364.594649 -243.5773) (xy 364.61394 -243.532024) (xy 364.640243 -243.490428)
			(xy 364.672878 -243.453591) (xy 364.710999 -243.422466) (xy 364.75362 -243.397859) (xy 364.799636 -243.380407)
			(xy 364.847855 -243.370563) (xy 364.89703 -243.368582) (xy 364.945885 -243.374514) (xy 364.993156 -243.388206)
			(xy 365.037618 -243.409304) (xy 365.078121 -243.43726) (xy 365.113614 -243.471352) (xy 365.143179 -243.510696)
			(xy 365.16605 -243.554273) (xy 365.181634 -243.600954) (xy 365.189529 -243.649531) (xy 365.190024 -243.674138)
			(xy 365.518966 -243.674138) (xy 365.522926 -243.625084) (xy 365.534703 -243.5773) (xy 365.553994 -243.532024)
			(xy 365.580297 -243.490428) (xy 365.612932 -243.453591) (xy 365.651053 -243.422466) (xy 365.693674 -243.397859)
			(xy 365.73969 -243.380407) (xy 365.787909 -243.370563) (xy 365.837084 -243.368582) (xy 365.885939 -243.374514)
			(xy 365.93321 -243.388206) (xy 365.977672 -243.409304) (xy 366.018175 -243.43726) (xy 366.053668 -243.471352)
			(xy 366.083233 -243.510696) (xy 366.106104 -243.554273) (xy 366.121688 -243.600954) (xy 366.129583 -243.649531)
			(xy 366.130078 -243.674138) (xy 366.45902 -243.674138) (xy 366.46298 -243.625084) (xy 366.474757 -243.5773)
			(xy 366.494048 -243.532024) (xy 366.520351 -243.490428) (xy 366.552986 -243.453591) (xy 366.591107 -243.422466)
			(xy 366.633728 -243.397859) (xy 366.679744 -243.380407) (xy 366.727963 -243.370563) (xy 366.777138 -243.368582)
			(xy 366.825993 -243.374514) (xy 366.873264 -243.388206) (xy 366.917726 -243.409304) (xy 366.958229 -243.43726)
			(xy 366.993722 -243.471352) (xy 367.023287 -243.510696) (xy 367.046158 -243.554273) (xy 367.061742 -243.600954)
			(xy 367.069637 -243.649531) (xy 367.070132 -243.674138) (xy 367.399074 -243.674138) (xy 367.403034 -243.625084)
			(xy 367.414811 -243.5773) (xy 367.434102 -243.532024) (xy 367.460405 -243.490428) (xy 367.49304 -243.453591)
			(xy 367.531161 -243.422466) (xy 367.573782 -243.397859) (xy 367.619798 -243.380407) (xy 367.668017 -243.370563)
			(xy 367.717192 -243.368582) (xy 367.766047 -243.374514) (xy 367.813318 -243.388206) (xy 367.85778 -243.409304)
			(xy 367.898283 -243.43726) (xy 367.933776 -243.471352) (xy 367.963341 -243.510696) (xy 367.986212 -243.554273)
			(xy 368.001796 -243.600954) (xy 368.009691 -243.649531) (xy 368.010186 -243.674138) (xy 368.338874 -243.674138)
			(xy 368.342834 -243.625084) (xy 368.354611 -243.5773) (xy 368.373902 -243.532024) (xy 368.400205 -243.490428)
			(xy 368.43284 -243.453591) (xy 368.470961 -243.422466) (xy 368.513582 -243.397859) (xy 368.559598 -243.380407)
			(xy 368.607817 -243.370563) (xy 368.656992 -243.368582) (xy 368.705847 -243.374514) (xy 368.753118 -243.388206)
			(xy 368.79758 -243.409304) (xy 368.838083 -243.43726) (xy 368.873576 -243.471352) (xy 368.903141 -243.510696)
			(xy 368.926012 -243.554273) (xy 368.941596 -243.600954) (xy 368.949491 -243.649531) (xy 368.949986 -243.674138)
			(xy 369.278928 -243.674138) (xy 369.282888 -243.625084) (xy 369.294665 -243.5773) (xy 369.313956 -243.532024)
			(xy 369.340259 -243.490428) (xy 369.372894 -243.453591) (xy 369.411015 -243.422466) (xy 369.453636 -243.397859)
			(xy 369.499652 -243.380407) (xy 369.547871 -243.370563) (xy 369.597046 -243.368582) (xy 369.645901 -243.374514)
			(xy 369.693172 -243.388206) (xy 369.737634 -243.409304) (xy 369.778137 -243.43726) (xy 369.81363 -243.471352)
			(xy 369.843195 -243.510696) (xy 369.866066 -243.554273) (xy 369.88165 -243.600954) (xy 369.889545 -243.649531)
			(xy 369.89004 -243.674138) (xy 370.218982 -243.674138) (xy 370.222942 -243.625084) (xy 370.234719 -243.5773)
			(xy 370.25401 -243.532024) (xy 370.280313 -243.490428) (xy 370.312948 -243.453591) (xy 370.351069 -243.422466)
			(xy 370.39369 -243.397859) (xy 370.439706 -243.380407) (xy 370.487925 -243.370563) (xy 370.5371 -243.368582)
			(xy 370.585955 -243.374514) (xy 370.633226 -243.388206) (xy 370.677688 -243.409304) (xy 370.718191 -243.43726)
			(xy 370.753684 -243.471352) (xy 370.783249 -243.510696) (xy 370.80612 -243.554273) (xy 370.821704 -243.600954)
			(xy 370.829599 -243.649531) (xy 370.830094 -243.674138) (xy 371.159036 -243.674138) (xy 371.162996 -243.625084)
			(xy 371.174773 -243.5773) (xy 371.194064 -243.532024) (xy 371.220367 -243.490428) (xy 371.253002 -243.453591)
			(xy 371.291123 -243.422466) (xy 371.333744 -243.397859) (xy 371.37976 -243.380407) (xy 371.427979 -243.370563)
			(xy 371.477154 -243.368582) (xy 371.526009 -243.374514) (xy 371.57328 -243.388206) (xy 371.617742 -243.409304)
			(xy 371.658245 -243.43726) (xy 371.693738 -243.471352) (xy 371.723303 -243.510696) (xy 371.746174 -243.554273)
			(xy 371.761758 -243.600954) (xy 371.769653 -243.649531) (xy 371.770148 -243.674138) (xy 372.09909 -243.674138)
			(xy 372.10305 -243.625084) (xy 372.114827 -243.5773) (xy 372.134118 -243.532024) (xy 372.160421 -243.490428)
			(xy 372.193056 -243.453591) (xy 372.231177 -243.422466) (xy 372.273798 -243.397859) (xy 372.319814 -243.380407)
			(xy 372.368033 -243.370563) (xy 372.417208 -243.368582) (xy 372.466063 -243.374514) (xy 372.513334 -243.388206)
			(xy 372.557796 -243.409304) (xy 372.598299 -243.43726) (xy 372.633792 -243.471352) (xy 372.663357 -243.510696)
			(xy 372.686228 -243.554273) (xy 372.701812 -243.600954) (xy 372.709707 -243.649531) (xy 372.710202 -243.674138)
			(xy 373.03889 -243.674138) (xy 373.04285 -243.625084) (xy 373.054627 -243.5773) (xy 373.073918 -243.532024)
			(xy 373.100221 -243.490428) (xy 373.132856 -243.453591) (xy 373.170977 -243.422466) (xy 373.213598 -243.397859)
			(xy 373.259614 -243.380407) (xy 373.307833 -243.370563) (xy 373.357008 -243.368582) (xy 373.405863 -243.374514)
			(xy 373.453134 -243.388206) (xy 373.497596 -243.409304) (xy 373.538099 -243.43726) (xy 373.573592 -243.471352)
			(xy 373.603157 -243.510696) (xy 373.626028 -243.554273) (xy 373.641612 -243.600954) (xy 373.649507 -243.649531)
			(xy 373.650002 -243.674138) (xy 373.978944 -243.674138) (xy 373.982904 -243.625084) (xy 373.994681 -243.5773)
			(xy 374.013972 -243.532024) (xy 374.040275 -243.490428) (xy 374.07291 -243.453591) (xy 374.111031 -243.422466)
			(xy 374.153652 -243.397859) (xy 374.199668 -243.380407) (xy 374.247887 -243.370563) (xy 374.297062 -243.368582)
			(xy 374.345917 -243.374514) (xy 374.393188 -243.388206) (xy 374.43765 -243.409304) (xy 374.478153 -243.43726)
			(xy 374.513646 -243.471352) (xy 374.543211 -243.510696) (xy 374.566082 -243.554273) (xy 374.581666 -243.600954)
			(xy 374.589561 -243.649531) (xy 374.590056 -243.674138) (xy 374.918998 -243.674138) (xy 374.922958 -243.625084)
			(xy 374.934735 -243.5773) (xy 374.954026 -243.532024) (xy 374.980329 -243.490428) (xy 375.012964 -243.453591)
			(xy 375.051085 -243.422466) (xy 375.093706 -243.397859) (xy 375.139722 -243.380407) (xy 375.187941 -243.370563)
			(xy 375.237116 -243.368582) (xy 375.285971 -243.374514) (xy 375.333242 -243.388206) (xy 375.377704 -243.409304)
			(xy 375.418207 -243.43726) (xy 375.4537 -243.471352) (xy 375.483265 -243.510696) (xy 375.506136 -243.554273)
			(xy 375.52172 -243.600954) (xy 375.529615 -243.649531) (xy 375.53011 -243.674138) (xy 375.848621 -243.674138)
			(xy 375.852716 -243.62341) (xy 375.864895 -243.573996) (xy 375.884843 -243.527176) (xy 375.912044 -243.484162)
			(xy 375.945792 -243.446068) (xy 375.985214 -243.413881) (xy 376.029288 -243.388435) (xy 376.076874 -243.370388)
			(xy 376.126738 -243.360208) (xy 376.17759 -243.358159) (xy 376.228111 -243.364293) (xy 376.276995 -243.378453)
			(xy 376.322974 -243.40027) (xy 376.364858 -243.42918) (xy 376.401562 -243.464435) (xy 376.432135 -243.505121)
			(xy 376.455786 -243.550184) (xy 376.471902 -243.598458) (xy 376.480066 -243.648692) (xy 376.480578 -243.674138)
			(xy 376.788675 -243.674138) (xy 376.79277 -243.62341) (xy 376.804949 -243.573996) (xy 376.824897 -243.527176)
			(xy 376.852098 -243.484162) (xy 376.885846 -243.446068) (xy 376.925268 -243.413881) (xy 376.969342 -243.388435)
			(xy 377.016928 -243.370388) (xy 377.066792 -243.360208) (xy 377.117644 -243.358159) (xy 377.168165 -243.364293)
			(xy 377.217049 -243.378453) (xy 377.263028 -243.40027) (xy 377.304912 -243.42918) (xy 377.341616 -243.464435)
			(xy 377.372189 -243.505121) (xy 377.39584 -243.550184) (xy 377.411956 -243.598458) (xy 377.42012 -243.648692)
			(xy 377.420632 -243.674138) (xy 377.42012 -243.699584) (xy 377.411956 -243.749818) (xy 377.39584 -243.798092)
			(xy 377.372189 -243.843155) (xy 377.341616 -243.883841) (xy 377.304912 -243.919096) (xy 377.263028 -243.948006)
			(xy 377.217049 -243.969823) (xy 377.168165 -243.983983) (xy 377.117644 -243.990117) (xy 377.066792 -243.988068)
			(xy 377.016928 -243.977888) (xy 376.969342 -243.959841) (xy 376.925268 -243.934395) (xy 376.885846 -243.902208)
			(xy 376.852098 -243.864114) (xy 376.824897 -243.8211) (xy 376.804949 -243.77428) (xy 376.79277 -243.724866)
			(xy 376.788675 -243.674138) (xy 376.480578 -243.674138) (xy 376.480066 -243.699584) (xy 376.471902 -243.749818)
			(xy 376.455786 -243.798092) (xy 376.432135 -243.843155) (xy 376.401562 -243.883841) (xy 376.364858 -243.919096)
			(xy 376.322974 -243.948006) (xy 376.276995 -243.969823) (xy 376.228111 -243.983983) (xy 376.17759 -243.990117)
			(xy 376.126738 -243.988068) (xy 376.076874 -243.977888) (xy 376.029288 -243.959841) (xy 375.985214 -243.934395)
			(xy 375.945792 -243.902208) (xy 375.912044 -243.864114) (xy 375.884843 -243.8211) (xy 375.864895 -243.77428)
			(xy 375.852716 -243.724866) (xy 375.848621 -243.674138) (xy 375.53011 -243.674138) (xy 375.529615 -243.698745)
			(xy 375.52172 -243.747322) (xy 375.506136 -243.794003) (xy 375.483265 -243.83758) (xy 375.4537 -243.876924)
			(xy 375.418207 -243.911016) (xy 375.377704 -243.938972) (xy 375.333242 -243.96007) (xy 375.285971 -243.973762)
			(xy 375.237116 -243.979694) (xy 375.187941 -243.977713) (xy 375.139722 -243.967869) (xy 375.093706 -243.950417)
			(xy 375.051085 -243.92581) (xy 375.012964 -243.894685) (xy 374.980329 -243.857848) (xy 374.954026 -243.816252)
			(xy 374.934735 -243.770976) (xy 374.922958 -243.723192) (xy 374.918998 -243.674138) (xy 374.590056 -243.674138)
			(xy 374.589561 -243.698745) (xy 374.581666 -243.747322) (xy 374.566082 -243.794003) (xy 374.543211 -243.83758)
			(xy 374.513646 -243.876924) (xy 374.478153 -243.911016) (xy 374.43765 -243.938972) (xy 374.393188 -243.96007)
			(xy 374.345917 -243.973762) (xy 374.297062 -243.979694) (xy 374.247887 -243.977713) (xy 374.199668 -243.967869)
			(xy 374.153652 -243.950417) (xy 374.111031 -243.92581) (xy 374.07291 -243.894685) (xy 374.040275 -243.857848)
			(xy 374.013972 -243.816252) (xy 373.994681 -243.770976) (xy 373.982904 -243.723192) (xy 373.978944 -243.674138)
			(xy 373.650002 -243.674138) (xy 373.649507 -243.698745) (xy 373.641612 -243.747322) (xy 373.626028 -243.794003)
			(xy 373.603157 -243.83758) (xy 373.573592 -243.876924) (xy 373.538099 -243.911016) (xy 373.497596 -243.938972)
			(xy 373.453134 -243.96007) (xy 373.405863 -243.973762) (xy 373.357008 -243.979694) (xy 373.307833 -243.977713)
			(xy 373.259614 -243.967869) (xy 373.213598 -243.950417) (xy 373.170977 -243.92581) (xy 373.132856 -243.894685)
			(xy 373.100221 -243.857848) (xy 373.073918 -243.816252) (xy 373.054627 -243.770976) (xy 373.04285 -243.723192)
			(xy 373.03889 -243.674138) (xy 372.710202 -243.674138) (xy 372.709707 -243.698745) (xy 372.701812 -243.747322)
			(xy 372.686228 -243.794003) (xy 372.663357 -243.83758) (xy 372.633792 -243.876924) (xy 372.598299 -243.911016)
			(xy 372.557796 -243.938972) (xy 372.513334 -243.96007) (xy 372.466063 -243.973762) (xy 372.417208 -243.979694)
			(xy 372.368033 -243.977713) (xy 372.319814 -243.967869) (xy 372.273798 -243.950417) (xy 372.231177 -243.92581)
			(xy 372.193056 -243.894685) (xy 372.160421 -243.857848) (xy 372.134118 -243.816252) (xy 372.114827 -243.770976)
			(xy 372.10305 -243.723192) (xy 372.09909 -243.674138) (xy 371.770148 -243.674138) (xy 371.769653 -243.698745)
			(xy 371.761758 -243.747322) (xy 371.746174 -243.794003) (xy 371.723303 -243.83758) (xy 371.693738 -243.876924)
			(xy 371.658245 -243.911016) (xy 371.617742 -243.938972) (xy 371.57328 -243.96007) (xy 371.526009 -243.973762)
			(xy 371.477154 -243.979694) (xy 371.427979 -243.977713) (xy 371.37976 -243.967869) (xy 371.333744 -243.950417)
			(xy 371.291123 -243.92581) (xy 371.253002 -243.894685) (xy 371.220367 -243.857848) (xy 371.194064 -243.816252)
			(xy 371.174773 -243.770976) (xy 371.162996 -243.723192) (xy 371.159036 -243.674138) (xy 370.830094 -243.674138)
			(xy 370.829599 -243.698745) (xy 370.821704 -243.747322) (xy 370.80612 -243.794003) (xy 370.783249 -243.83758)
			(xy 370.753684 -243.876924) (xy 370.718191 -243.911016) (xy 370.677688 -243.938972) (xy 370.633226 -243.96007)
			(xy 370.585955 -243.973762) (xy 370.5371 -243.979694) (xy 370.487925 -243.977713) (xy 370.439706 -243.967869)
			(xy 370.39369 -243.950417) (xy 370.351069 -243.92581) (xy 370.312948 -243.894685) (xy 370.280313 -243.857848)
			(xy 370.25401 -243.816252) (xy 370.234719 -243.770976) (xy 370.222942 -243.723192) (xy 370.218982 -243.674138)
			(xy 369.89004 -243.674138) (xy 369.889545 -243.698745) (xy 369.88165 -243.747322) (xy 369.866066 -243.794003)
			(xy 369.843195 -243.83758) (xy 369.81363 -243.876924) (xy 369.778137 -243.911016) (xy 369.737634 -243.938972)
			(xy 369.693172 -243.96007) (xy 369.645901 -243.973762) (xy 369.597046 -243.979694) (xy 369.547871 -243.977713)
			(xy 369.499652 -243.967869) (xy 369.453636 -243.950417) (xy 369.411015 -243.92581) (xy 369.372894 -243.894685)
			(xy 369.340259 -243.857848) (xy 369.313956 -243.816252) (xy 369.294665 -243.770976) (xy 369.282888 -243.723192)
			(xy 369.278928 -243.674138) (xy 368.949986 -243.674138) (xy 368.949491 -243.698745) (xy 368.941596 -243.747322)
			(xy 368.926012 -243.794003) (xy 368.903141 -243.83758) (xy 368.873576 -243.876924) (xy 368.838083 -243.911016)
			(xy 368.79758 -243.938972) (xy 368.753118 -243.96007) (xy 368.705847 -243.973762) (xy 368.656992 -243.979694)
			(xy 368.607817 -243.977713) (xy 368.559598 -243.967869) (xy 368.513582 -243.950417) (xy 368.470961 -243.92581)
			(xy 368.43284 -243.894685) (xy 368.400205 -243.857848) (xy 368.373902 -243.816252) (xy 368.354611 -243.770976)
			(xy 368.342834 -243.723192) (xy 368.338874 -243.674138) (xy 368.010186 -243.674138) (xy 368.009691 -243.698745)
			(xy 368.001796 -243.747322) (xy 367.986212 -243.794003) (xy 367.963341 -243.83758) (xy 367.933776 -243.876924)
			(xy 367.898283 -243.911016) (xy 367.85778 -243.938972) (xy 367.813318 -243.96007) (xy 367.766047 -243.973762)
			(xy 367.717192 -243.979694) (xy 367.668017 -243.977713) (xy 367.619798 -243.967869) (xy 367.573782 -243.950417)
			(xy 367.531161 -243.92581) (xy 367.49304 -243.894685) (xy 367.460405 -243.857848) (xy 367.434102 -243.816252)
			(xy 367.414811 -243.770976) (xy 367.403034 -243.723192) (xy 367.399074 -243.674138) (xy 367.070132 -243.674138)
			(xy 367.069637 -243.698745) (xy 367.061742 -243.747322) (xy 367.046158 -243.794003) (xy 367.023287 -243.83758)
			(xy 366.993722 -243.876924) (xy 366.958229 -243.911016) (xy 366.917726 -243.938972) (xy 366.873264 -243.96007)
			(xy 366.825993 -243.973762) (xy 366.777138 -243.979694) (xy 366.727963 -243.977713) (xy 366.679744 -243.967869)
			(xy 366.633728 -243.950417) (xy 366.591107 -243.92581) (xy 366.552986 -243.894685) (xy 366.520351 -243.857848)
			(xy 366.494048 -243.816252) (xy 366.474757 -243.770976) (xy 366.46298 -243.723192) (xy 366.45902 -243.674138)
			(xy 366.130078 -243.674138) (xy 366.129583 -243.698745) (xy 366.121688 -243.747322) (xy 366.106104 -243.794003)
			(xy 366.083233 -243.83758) (xy 366.053668 -243.876924) (xy 366.018175 -243.911016) (xy 365.977672 -243.938972)
			(xy 365.93321 -243.96007) (xy 365.885939 -243.973762) (xy 365.837084 -243.979694) (xy 365.787909 -243.977713)
			(xy 365.73969 -243.967869) (xy 365.693674 -243.950417) (xy 365.651053 -243.92581) (xy 365.612932 -243.894685)
			(xy 365.580297 -243.857848) (xy 365.553994 -243.816252) (xy 365.534703 -243.770976) (xy 365.522926 -243.723192)
			(xy 365.518966 -243.674138) (xy 365.190024 -243.674138) (xy 365.189529 -243.698745) (xy 365.181634 -243.747322)
			(xy 365.16605 -243.794003) (xy 365.143179 -243.83758) (xy 365.113614 -243.876924) (xy 365.078121 -243.911016)
			(xy 365.037618 -243.938972) (xy 364.993156 -243.96007) (xy 364.945885 -243.973762) (xy 364.89703 -243.979694)
			(xy 364.847855 -243.977713) (xy 364.799636 -243.967869) (xy 364.75362 -243.950417) (xy 364.710999 -243.92581)
			(xy 364.672878 -243.894685) (xy 364.640243 -243.857848) (xy 364.61394 -243.816252) (xy 364.594649 -243.770976)
			(xy 364.582872 -243.723192) (xy 364.578912 -243.674138) (xy 364.250224 -243.674138) (xy 364.249729 -243.698745)
			(xy 364.241834 -243.747322) (xy 364.22625 -243.794003) (xy 364.203379 -243.83758) (xy 364.173814 -243.876924)
			(xy 364.138321 -243.911016) (xy 364.097818 -243.938972) (xy 364.053356 -243.96007) (xy 364.006085 -243.973762)
			(xy 363.95723 -243.979694) (xy 363.908055 -243.977713) (xy 363.859836 -243.967869) (xy 363.81382 -243.950417)
			(xy 363.771199 -243.92581) (xy 363.733078 -243.894685) (xy 363.700443 -243.857848) (xy 363.67414 -243.816252)
			(xy 363.654849 -243.770976) (xy 363.643072 -243.723192) (xy 363.639112 -243.674138) (xy 363.31105 -243.674138)
			(xy 363.306876 -243.724495) (xy 363.294462 -243.773515) (xy 363.274147 -243.819823) (xy 363.246487 -243.862155)
			(xy 363.212237 -243.899357) (xy 363.172329 -243.930414) (xy 363.127854 -243.954478) (xy 363.080025 -243.970892)
			(xy 363.030146 -243.97921) (xy 363.004862 -243.9797) (xy 362.064808 -243.9797) (xy 362.039532 -243.979132)
			(xy 361.989669 -243.970812) (xy 361.941856 -243.954399) (xy 361.897396 -243.93034) (xy 361.857503 -243.899291)
			(xy 361.823265 -243.862099) (xy 361.795615 -243.819779) (xy 361.775308 -243.773484) (xy 361.762898 -243.724479)
			(xy 361.758723 -243.6741) (xy 361.430061 -243.6741) (xy 361.430062 -243.674138) (xy 361.429567 -243.698745)
			(xy 361.421672 -243.747322) (xy 361.406088 -243.794003) (xy 361.383217 -243.83758) (xy 361.353652 -243.876924)
			(xy 361.318159 -243.911016) (xy 361.277656 -243.938972) (xy 361.233194 -243.96007) (xy 361.185923 -243.973762)
			(xy 361.137068 -243.979694) (xy 361.087893 -243.977713) (xy 361.039674 -243.967869) (xy 360.993658 -243.950417)
			(xy 360.951037 -243.92581) (xy 360.912916 -243.894685) (xy 360.880281 -243.857848) (xy 360.853978 -243.816252)
			(xy 360.834687 -243.770976) (xy 360.82291 -243.723192) (xy 360.81895 -243.674138) (xy 358.616504 -243.674138)
			(xy 358.616009 -243.698745) (xy 358.608114 -243.747322) (xy 358.59253 -243.794003) (xy 358.569659 -243.83758)
			(xy 358.540094 -243.876924) (xy 358.504601 -243.911016) (xy 358.464098 -243.938972) (xy 358.419636 -243.96007)
			(xy 358.372365 -243.973762) (xy 358.32351 -243.979694) (xy 358.274335 -243.977713) (xy 358.226116 -243.967869)
			(xy 358.1801 -243.950417) (xy 358.137479 -243.92581) (xy 358.099358 -243.894685) (xy 358.066723 -243.857848)
			(xy 358.04042 -243.816252) (xy 358.021129 -243.770976) (xy 358.009352 -243.723192) (xy 358.005392 -243.674138)
			(xy 357.67645 -243.674138) (xy 357.675955 -243.698745) (xy 357.66806 -243.747322) (xy 357.652476 -243.794003)
			(xy 357.629605 -243.83758) (xy 357.60004 -243.876924) (xy 357.564547 -243.911016) (xy 357.524044 -243.938972)
			(xy 357.479582 -243.96007) (xy 357.432311 -243.973762) (xy 357.383456 -243.979694) (xy 357.334281 -243.977713)
			(xy 357.286062 -243.967869) (xy 357.240046 -243.950417) (xy 357.197425 -243.92581) (xy 357.159304 -243.894685)
			(xy 357.126669 -243.857848) (xy 357.100366 -243.816252) (xy 357.081075 -243.770976) (xy 357.069298 -243.723192)
			(xy 357.065338 -243.674138) (xy 356.736396 -243.674138) (xy 356.735901 -243.698745) (xy 356.728006 -243.747322)
			(xy 356.712422 -243.794003) (xy 356.689551 -243.83758) (xy 356.659986 -243.876924) (xy 356.624493 -243.911016)
			(xy 356.58399 -243.938972) (xy 356.539528 -243.96007) (xy 356.492257 -243.973762) (xy 356.443402 -243.979694)
			(xy 356.394227 -243.977713) (xy 356.346008 -243.967869) (xy 356.299992 -243.950417) (xy 356.257371 -243.92581)
			(xy 356.21925 -243.894685) (xy 356.186615 -243.857848) (xy 356.160312 -243.816252) (xy 356.141021 -243.770976)
			(xy 356.129244 -243.723192) (xy 356.125284 -243.674138) (xy 355.796342 -243.674138) (xy 355.795847 -243.698745)
			(xy 355.787952 -243.747322) (xy 355.772368 -243.794003) (xy 355.749497 -243.83758) (xy 355.719932 -243.876924)
			(xy 355.684439 -243.911016) (xy 355.643936 -243.938972) (xy 355.599474 -243.96007) (xy 355.552203 -243.973762)
			(xy 355.503348 -243.979694) (xy 355.454173 -243.977713) (xy 355.405954 -243.967869) (xy 355.359938 -243.950417)
			(xy 355.317317 -243.92581) (xy 355.279196 -243.894685) (xy 355.246561 -243.857848) (xy 355.220258 -243.816252)
			(xy 355.200967 -243.770976) (xy 355.18919 -243.723192) (xy 355.18523 -243.674138) (xy 354.856542 -243.674138)
			(xy 354.856047 -243.698745) (xy 354.848152 -243.747322) (xy 354.832568 -243.794003) (xy 354.809697 -243.83758)
			(xy 354.780132 -243.876924) (xy 354.744639 -243.911016) (xy 354.704136 -243.938972) (xy 354.659674 -243.96007)
			(xy 354.612403 -243.973762) (xy 354.563548 -243.979694) (xy 354.514373 -243.977713) (xy 354.466154 -243.967869)
			(xy 354.420138 -243.950417) (xy 354.377517 -243.92581) (xy 354.339396 -243.894685) (xy 354.306761 -243.857848)
			(xy 354.280458 -243.816252) (xy 354.261167 -243.770976) (xy 354.24939 -243.723192) (xy 354.24543 -243.674138)
			(xy 353.916488 -243.674138) (xy 353.915993 -243.698745) (xy 353.908098 -243.747322) (xy 353.892514 -243.794003)
			(xy 353.869643 -243.83758) (xy 353.840078 -243.876924) (xy 353.804585 -243.911016) (xy 353.764082 -243.938972)
			(xy 353.71962 -243.96007) (xy 353.672349 -243.973762) (xy 353.623494 -243.979694) (xy 353.574319 -243.977713)
			(xy 353.5261 -243.967869) (xy 353.480084 -243.950417) (xy 353.437463 -243.92581) (xy 353.399342 -243.894685)
			(xy 353.366707 -243.857848) (xy 353.340404 -243.816252) (xy 353.321113 -243.770976) (xy 353.309336 -243.723192)
			(xy 353.305376 -243.674138) (xy 352.976434 -243.674138) (xy 352.975939 -243.698745) (xy 352.968044 -243.747322)
			(xy 352.95246 -243.794003) (xy 352.929589 -243.83758) (xy 352.900024 -243.876924) (xy 352.864531 -243.911016)
			(xy 352.824028 -243.938972) (xy 352.779566 -243.96007) (xy 352.732295 -243.973762) (xy 352.68344 -243.979694)
			(xy 352.634265 -243.977713) (xy 352.586046 -243.967869) (xy 352.54003 -243.950417) (xy 352.497409 -243.92581)
			(xy 352.459288 -243.894685) (xy 352.426653 -243.857848) (xy 352.40035 -243.816252) (xy 352.381059 -243.770976)
			(xy 352.369282 -243.723192) (xy 352.365322 -243.674138) (xy 352.03638 -243.674138) (xy 352.035885 -243.698745)
			(xy 352.02799 -243.747322) (xy 352.012406 -243.794003) (xy 351.989535 -243.83758) (xy 351.95997 -243.876924)
			(xy 351.924477 -243.911016) (xy 351.883974 -243.938972) (xy 351.839512 -243.96007) (xy 351.792241 -243.973762)
			(xy 351.743386 -243.979694) (xy 351.694211 -243.977713) (xy 351.645992 -243.967869) (xy 351.599976 -243.950417)
			(xy 351.557355 -243.92581) (xy 351.519234 -243.894685) (xy 351.486599 -243.857848) (xy 351.460296 -243.816252)
			(xy 351.441005 -243.770976) (xy 351.429228 -243.723192) (xy 351.425268 -243.674138) (xy 351.096326 -243.674138)
			(xy 351.095831 -243.698745) (xy 351.087936 -243.747322) (xy 351.072352 -243.794003) (xy 351.049481 -243.83758)
			(xy 351.019916 -243.876924) (xy 350.984423 -243.911016) (xy 350.94392 -243.938972) (xy 350.899458 -243.96007)
			(xy 350.852187 -243.973762) (xy 350.803332 -243.979694) (xy 350.754157 -243.977713) (xy 350.705938 -243.967869)
			(xy 350.659922 -243.950417) (xy 350.617301 -243.92581) (xy 350.57918 -243.894685) (xy 350.546545 -243.857848)
			(xy 350.520242 -243.816252) (xy 350.500951 -243.770976) (xy 350.489174 -243.723192) (xy 350.485214 -243.674138)
			(xy 350.156526 -243.674138) (xy 350.156031 -243.698745) (xy 350.148136 -243.747322) (xy 350.132552 -243.794003)
			(xy 350.109681 -243.83758) (xy 350.080116 -243.876924) (xy 350.044623 -243.911016) (xy 350.00412 -243.938972)
			(xy 349.959658 -243.96007) (xy 349.912387 -243.973762) (xy 349.863532 -243.979694) (xy 349.814357 -243.977713)
			(xy 349.766138 -243.967869) (xy 349.720122 -243.950417) (xy 349.677501 -243.92581) (xy 349.63938 -243.894685)
			(xy 349.606745 -243.857848) (xy 349.580442 -243.816252) (xy 349.561151 -243.770976) (xy 349.549374 -243.723192)
			(xy 349.545414 -243.674138) (xy 349.216472 -243.674138) (xy 349.215977 -243.698745) (xy 349.208082 -243.747322)
			(xy 349.192498 -243.794003) (xy 349.169627 -243.83758) (xy 349.140062 -243.876924) (xy 349.104569 -243.911016)
			(xy 349.064066 -243.938972) (xy 349.019604 -243.96007) (xy 348.972333 -243.973762) (xy 348.923478 -243.979694)
			(xy 348.874303 -243.977713) (xy 348.826084 -243.967869) (xy 348.780068 -243.950417) (xy 348.737447 -243.92581)
			(xy 348.699326 -243.894685) (xy 348.666691 -243.857848) (xy 348.640388 -243.816252) (xy 348.621097 -243.770976)
			(xy 348.60932 -243.723192) (xy 348.60536 -243.674138) (xy 348.276418 -243.674138) (xy 348.275923 -243.698745)
			(xy 348.268028 -243.747322) (xy 348.252444 -243.794003) (xy 348.229573 -243.83758) (xy 348.200008 -243.876924)
			(xy 348.164515 -243.911016) (xy 348.124012 -243.938972) (xy 348.07955 -243.96007) (xy 348.032279 -243.973762)
			(xy 347.983424 -243.979694) (xy 347.934249 -243.977713) (xy 347.88603 -243.967869) (xy 347.840014 -243.950417)
			(xy 347.797393 -243.92581) (xy 347.759272 -243.894685) (xy 347.726637 -243.857848) (xy 347.700334 -243.816252)
			(xy 347.681043 -243.770976) (xy 347.669266 -243.723192) (xy 347.665306 -243.674138) (xy 347.336364 -243.674138)
			(xy 347.335869 -243.698745) (xy 347.327974 -243.747322) (xy 347.31239 -243.794003) (xy 347.289519 -243.83758)
			(xy 347.259954 -243.876924) (xy 347.224461 -243.911016) (xy 347.183958 -243.938972) (xy 347.139496 -243.96007)
			(xy 347.092225 -243.973762) (xy 347.04337 -243.979694) (xy 346.994195 -243.977713) (xy 346.945976 -243.967869)
			(xy 346.89996 -243.950417) (xy 346.857339 -243.92581) (xy 346.819218 -243.894685) (xy 346.786583 -243.857848)
			(xy 346.76028 -243.816252) (xy 346.740989 -243.770976) (xy 346.729212 -243.723192) (xy 346.725252 -243.674138)
			(xy 346.39631 -243.674138) (xy 346.395815 -243.698745) (xy 346.38792 -243.747322) (xy 346.372336 -243.794003)
			(xy 346.349465 -243.83758) (xy 346.3199 -243.876924) (xy 346.284407 -243.911016) (xy 346.243904 -243.938972)
			(xy 346.199442 -243.96007) (xy 346.152171 -243.973762) (xy 346.103316 -243.979694) (xy 346.054141 -243.977713)
			(xy 346.005922 -243.967869) (xy 345.959906 -243.950417) (xy 345.917285 -243.92581) (xy 345.879164 -243.894685)
			(xy 345.846529 -243.857848) (xy 345.820226 -243.816252) (xy 345.800935 -243.770976) (xy 345.789158 -243.723192)
			(xy 345.785198 -243.674138) (xy 345.45651 -243.674138) (xy 345.456015 -243.698745) (xy 345.44812 -243.747322)
			(xy 345.432536 -243.794003) (xy 345.409665 -243.83758) (xy 345.3801 -243.876924) (xy 345.344607 -243.911016)
			(xy 345.304104 -243.938972) (xy 345.259642 -243.96007) (xy 345.212371 -243.973762) (xy 345.163516 -243.979694)
			(xy 345.114341 -243.977713) (xy 345.066122 -243.967869) (xy 345.020106 -243.950417) (xy 344.977485 -243.92581)
			(xy 344.939364 -243.894685) (xy 344.906729 -243.857848) (xy 344.880426 -243.816252) (xy 344.861135 -243.770976)
			(xy 344.849358 -243.723192) (xy 344.845398 -243.674138) (xy 344.516456 -243.674138) (xy 344.515961 -243.698745)
			(xy 344.508066 -243.747322) (xy 344.492482 -243.794003) (xy 344.469611 -243.83758) (xy 344.440046 -243.876924)
			(xy 344.404553 -243.911016) (xy 344.36405 -243.938972) (xy 344.319588 -243.96007) (xy 344.272317 -243.973762)
			(xy 344.223462 -243.979694) (xy 344.174287 -243.977713) (xy 344.126068 -243.967869) (xy 344.080052 -243.950417)
			(xy 344.037431 -243.92581) (xy 343.99931 -243.894685) (xy 343.966675 -243.857848) (xy 343.940372 -243.816252)
			(xy 343.921081 -243.770976) (xy 343.909304 -243.723192) (xy 343.905344 -243.674138) (xy 343.586816 -243.674138)
			(xy 343.586304 -243.699584) (xy 343.57814 -243.749818) (xy 343.562024 -243.798092) (xy 343.538373 -243.843155)
			(xy 343.5078 -243.883841) (xy 343.471096 -243.919096) (xy 343.429212 -243.948006) (xy 343.383233 -243.969823)
			(xy 343.334349 -243.983983) (xy 343.283828 -243.990117) (xy 343.232976 -243.988068) (xy 343.183112 -243.977888)
			(xy 343.135526 -243.959841) (xy 343.091452 -243.934395) (xy 343.05203 -243.902208) (xy 343.018282 -243.864114)
			(xy 342.991081 -243.8211) (xy 342.971133 -243.77428) (xy 342.958954 -243.724866) (xy 342.954859 -243.674138)
			(xy 342.646762 -243.674138) (xy 342.64625 -243.699584) (xy 342.638086 -243.749818) (xy 342.62197 -243.798092)
			(xy 342.598319 -243.843155) (xy 342.567746 -243.883841) (xy 342.531042 -243.919096) (xy 342.489158 -243.948006)
			(xy 342.443179 -243.969823) (xy 342.394295 -243.983983) (xy 342.343774 -243.990117) (xy 342.292922 -243.988068)
			(xy 342.243058 -243.977888) (xy 342.195472 -243.959841) (xy 342.151398 -243.934395) (xy 342.111976 -243.902208)
			(xy 342.078228 -243.864114) (xy 342.051027 -243.8211) (xy 342.031079 -243.77428) (xy 342.0189 -243.724866)
			(xy 342.014805 -243.674138) (xy 341.696294 -243.674138) (xy 341.695821 -243.698127) (xy 341.68831 -243.745513)
			(xy 341.673479 -243.791141) (xy 341.651693 -243.833888) (xy 341.623489 -243.8727) (xy 341.58956 -243.906622)
			(xy 341.550743 -243.93482) (xy 341.507993 -243.956599) (xy 341.462363 -243.971422) (xy 341.414975 -243.978925)
			(xy 341.390986 -243.979446) (xy 341.376676 -243.979276) (xy 341.348182 -243.976601) (xy 341.33409 -243.974112)
			(xy 341.325454 -243.97335) (xy 341.316421 -243.973585) (xy 341.299386 -243.97958) (xy 341.29218 -243.985034)
			(xy 341.270844 -244.002814) (xy 341.233506 -244.033802) (xy 341.225251 -244.041405) (xy 341.215754 -244.061708)
			(xy 341.215218 -244.072918) (xy 341.215218 -244.402102) (xy 341.216742 -244.408198) (xy 341.221255 -244.426859)
			(xy 341.226098 -244.464947) (xy 341.226394 -244.484144) (xy 341.544905 -244.484144) (xy 341.549 -244.433416)
			(xy 341.561179 -244.384002) (xy 341.581127 -244.337182) (xy 341.608328 -244.294168) (xy 341.642076 -244.256074)
			(xy 341.681498 -244.223887) (xy 341.725572 -244.198441) (xy 341.773158 -244.180394) (xy 341.823022 -244.170214)
			(xy 341.873874 -244.168165) (xy 341.924395 -244.174299) (xy 341.973279 -244.188459) (xy 342.019258 -244.210276)
			(xy 342.061142 -244.239186) (xy 342.097846 -244.274441) (xy 342.128419 -244.315127) (xy 342.15207 -244.36019)
			(xy 342.168186 -244.408464) (xy 342.17635 -244.458698) (xy 342.176862 -244.484144) (xy 342.49539 -244.484144)
			(xy 342.49935 -244.43509) (xy 342.511127 -244.387306) (xy 342.530418 -244.34203) (xy 342.556721 -244.300434)
			(xy 342.589356 -244.263597) (xy 342.627477 -244.232472) (xy 342.670098 -244.207865) (xy 342.716114 -244.190413)
			(xy 342.764333 -244.180569) (xy 342.813508 -244.178588) (xy 342.862363 -244.18452) (xy 342.909634 -244.198212)
			(xy 342.954096 -244.21931) (xy 342.994599 -244.247266) (xy 343.030092 -244.281358) (xy 343.059657 -244.320702)
			(xy 343.082528 -244.364279) (xy 343.098112 -244.41096) (xy 343.106007 -244.459537) (xy 343.106502 -244.484144)
			(xy 343.424759 -244.484144) (xy 343.428854 -244.433416) (xy 343.441033 -244.384002) (xy 343.460981 -244.337182)
			(xy 343.488182 -244.294168) (xy 343.52193 -244.256074) (xy 343.561352 -244.223887) (xy 343.605426 -244.198441)
			(xy 343.653012 -244.180394) (xy 343.702876 -244.170214) (xy 343.753728 -244.168165) (xy 343.804249 -244.174299)
			(xy 343.853133 -244.188459) (xy 343.899112 -244.210276) (xy 343.940996 -244.239186) (xy 343.9777 -244.274441)
			(xy 344.008273 -244.315127) (xy 344.031924 -244.36019) (xy 344.04804 -244.408464) (xy 344.056204 -244.458698)
			(xy 344.056716 -244.484144) (xy 344.375244 -244.484144) (xy 344.379204 -244.43509) (xy 344.390981 -244.387306)
			(xy 344.410272 -244.34203) (xy 344.436575 -244.300434) (xy 344.46921 -244.263597) (xy 344.507331 -244.232472)
			(xy 344.549952 -244.207865) (xy 344.595968 -244.190413) (xy 344.644187 -244.180569) (xy 344.693362 -244.178588)
			(xy 344.742217 -244.18452) (xy 344.789488 -244.198212) (xy 344.83395 -244.21931) (xy 344.874453 -244.247266)
			(xy 344.909946 -244.281358) (xy 344.939511 -244.320702) (xy 344.962382 -244.364279) (xy 344.977966 -244.41096)
			(xy 344.985861 -244.459537) (xy 344.986356 -244.484144) (xy 345.315298 -244.484144) (xy 345.319258 -244.43509)
			(xy 345.331035 -244.387306) (xy 345.350326 -244.34203) (xy 345.376629 -244.300434) (xy 345.409264 -244.263597)
			(xy 345.447385 -244.232472) (xy 345.490006 -244.207865) (xy 345.536022 -244.190413) (xy 345.584241 -244.180569)
			(xy 345.633416 -244.178588) (xy 345.682271 -244.18452) (xy 345.729542 -244.198212) (xy 345.774004 -244.21931)
			(xy 345.814507 -244.247266) (xy 345.85 -244.281358) (xy 345.879565 -244.320702) (xy 345.902436 -244.364279)
			(xy 345.91802 -244.41096) (xy 345.925915 -244.459537) (xy 345.92641 -244.484144) (xy 346.255352 -244.484144)
			(xy 346.259312 -244.43509) (xy 346.271089 -244.387306) (xy 346.29038 -244.34203) (xy 346.316683 -244.300434)
			(xy 346.349318 -244.263597) (xy 346.387439 -244.232472) (xy 346.43006 -244.207865) (xy 346.476076 -244.190413)
			(xy 346.524295 -244.180569) (xy 346.57347 -244.178588) (xy 346.622325 -244.18452) (xy 346.669596 -244.198212)
			(xy 346.714058 -244.21931) (xy 346.754561 -244.247266) (xy 346.790054 -244.281358) (xy 346.819619 -244.320702)
			(xy 346.84249 -244.364279) (xy 346.858074 -244.41096) (xy 346.865969 -244.459537) (xy 346.866464 -244.484144)
			(xy 347.195406 -244.484144) (xy 347.199366 -244.43509) (xy 347.211143 -244.387306) (xy 347.230434 -244.34203)
			(xy 347.256737 -244.300434) (xy 347.289372 -244.263597) (xy 347.327493 -244.232472) (xy 347.370114 -244.207865)
			(xy 347.41613 -244.190413) (xy 347.464349 -244.180569) (xy 347.513524 -244.178588) (xy 347.562379 -244.18452)
			(xy 347.60965 -244.198212) (xy 347.654112 -244.21931) (xy 347.694615 -244.247266) (xy 347.730108 -244.281358)
			(xy 347.759673 -244.320702) (xy 347.782544 -244.364279) (xy 347.798128 -244.41096) (xy 347.806023 -244.459537)
			(xy 347.806518 -244.484144) (xy 348.135206 -244.484144) (xy 348.139166 -244.43509) (xy 348.150943 -244.387306)
			(xy 348.170234 -244.34203) (xy 348.196537 -244.300434) (xy 348.229172 -244.263597) (xy 348.267293 -244.232472)
			(xy 348.309914 -244.207865) (xy 348.35593 -244.190413) (xy 348.404149 -244.180569) (xy 348.453324 -244.178588)
			(xy 348.502179 -244.18452) (xy 348.54945 -244.198212) (xy 348.593912 -244.21931) (xy 348.634415 -244.247266)
			(xy 348.669908 -244.281358) (xy 348.699473 -244.320702) (xy 348.722344 -244.364279) (xy 348.737928 -244.41096)
			(xy 348.745823 -244.459537) (xy 348.746318 -244.484144) (xy 349.07526 -244.484144) (xy 349.07922 -244.43509)
			(xy 349.090997 -244.387306) (xy 349.110288 -244.34203) (xy 349.136591 -244.300434) (xy 349.169226 -244.263597)
			(xy 349.207347 -244.232472) (xy 349.249968 -244.207865) (xy 349.295984 -244.190413) (xy 349.344203 -244.180569)
			(xy 349.393378 -244.178588) (xy 349.442233 -244.18452) (xy 349.489504 -244.198212) (xy 349.533966 -244.21931)
			(xy 349.574469 -244.247266) (xy 349.609962 -244.281358) (xy 349.639527 -244.320702) (xy 349.662398 -244.364279)
			(xy 349.677982 -244.41096) (xy 349.685877 -244.459537) (xy 349.686372 -244.484144) (xy 350.015314 -244.484144)
			(xy 350.019274 -244.43509) (xy 350.031051 -244.387306) (xy 350.050342 -244.34203) (xy 350.076645 -244.300434)
			(xy 350.10928 -244.263597) (xy 350.147401 -244.232472) (xy 350.190022 -244.207865) (xy 350.236038 -244.190413)
			(xy 350.284257 -244.180569) (xy 350.333432 -244.178588) (xy 350.382287 -244.18452) (xy 350.429558 -244.198212)
			(xy 350.47402 -244.21931) (xy 350.514523 -244.247266) (xy 350.550016 -244.281358) (xy 350.579581 -244.320702)
			(xy 350.602452 -244.364279) (xy 350.618036 -244.41096) (xy 350.625931 -244.459537) (xy 350.626426 -244.484144)
			(xy 350.955368 -244.484144) (xy 350.959328 -244.43509) (xy 350.971105 -244.387306) (xy 350.990396 -244.34203)
			(xy 351.016699 -244.300434) (xy 351.049334 -244.263597) (xy 351.087455 -244.232472) (xy 351.130076 -244.207865)
			(xy 351.176092 -244.190413) (xy 351.224311 -244.180569) (xy 351.273486 -244.178588) (xy 351.322341 -244.18452)
			(xy 351.369612 -244.198212) (xy 351.414074 -244.21931) (xy 351.454577 -244.247266) (xy 351.49007 -244.281358)
			(xy 351.519635 -244.320702) (xy 351.542506 -244.364279) (xy 351.55809 -244.41096) (xy 351.565985 -244.459537)
			(xy 351.56648 -244.484144) (xy 351.895422 -244.484144) (xy 351.899382 -244.43509) (xy 351.911159 -244.387306)
			(xy 351.93045 -244.34203) (xy 351.956753 -244.300434) (xy 351.989388 -244.263597) (xy 352.027509 -244.232472)
			(xy 352.07013 -244.207865) (xy 352.116146 -244.190413) (xy 352.164365 -244.180569) (xy 352.21354 -244.178588)
			(xy 352.262395 -244.18452) (xy 352.309666 -244.198212) (xy 352.354128 -244.21931) (xy 352.394631 -244.247266)
			(xy 352.430124 -244.281358) (xy 352.459689 -244.320702) (xy 352.48256 -244.364279) (xy 352.498144 -244.41096)
			(xy 352.506039 -244.459537) (xy 352.506534 -244.484144) (xy 352.835222 -244.484144) (xy 352.839182 -244.43509)
			(xy 352.850959 -244.387306) (xy 352.87025 -244.34203) (xy 352.896553 -244.300434) (xy 352.929188 -244.263597)
			(xy 352.967309 -244.232472) (xy 353.00993 -244.207865) (xy 353.055946 -244.190413) (xy 353.104165 -244.180569)
			(xy 353.15334 -244.178588) (xy 353.202195 -244.18452) (xy 353.249466 -244.198212) (xy 353.293928 -244.21931)
			(xy 353.334431 -244.247266) (xy 353.369924 -244.281358) (xy 353.399489 -244.320702) (xy 353.42236 -244.364279)
			(xy 353.437944 -244.41096) (xy 353.445839 -244.459537) (xy 353.446334 -244.484144) (xy 353.775276 -244.484144)
			(xy 353.779236 -244.43509) (xy 353.791013 -244.387306) (xy 353.810304 -244.34203) (xy 353.836607 -244.300434)
			(xy 353.869242 -244.263597) (xy 353.907363 -244.232472) (xy 353.949984 -244.207865) (xy 353.996 -244.190413)
			(xy 354.044219 -244.180569) (xy 354.093394 -244.178588) (xy 354.142249 -244.18452) (xy 354.18952 -244.198212)
			(xy 354.233982 -244.21931) (xy 354.274485 -244.247266) (xy 354.309978 -244.281358) (xy 354.339543 -244.320702)
			(xy 354.362414 -244.364279) (xy 354.377998 -244.41096) (xy 354.385893 -244.459537) (xy 354.386388 -244.484144)
			(xy 354.71533 -244.484144) (xy 354.71929 -244.43509) (xy 354.731067 -244.387306) (xy 354.750358 -244.34203)
			(xy 354.776661 -244.300434) (xy 354.809296 -244.263597) (xy 354.847417 -244.232472) (xy 354.890038 -244.207865)
			(xy 354.936054 -244.190413) (xy 354.984273 -244.180569) (xy 355.033448 -244.178588) (xy 355.082303 -244.18452)
			(xy 355.129574 -244.198212) (xy 355.174036 -244.21931) (xy 355.214539 -244.247266) (xy 355.250032 -244.281358)
			(xy 355.279597 -244.320702) (xy 355.302468 -244.364279) (xy 355.318052 -244.41096) (xy 355.325947 -244.459537)
			(xy 355.326442 -244.484144) (xy 355.655384 -244.484144) (xy 355.659344 -244.43509) (xy 355.671121 -244.387306)
			(xy 355.690412 -244.34203) (xy 355.716715 -244.300434) (xy 355.74935 -244.263597) (xy 355.787471 -244.232472)
			(xy 355.830092 -244.207865) (xy 355.876108 -244.190413) (xy 355.924327 -244.180569) (xy 355.973502 -244.178588)
			(xy 356.022357 -244.18452) (xy 356.069628 -244.198212) (xy 356.11409 -244.21931) (xy 356.154593 -244.247266)
			(xy 356.190086 -244.281358) (xy 356.219651 -244.320702) (xy 356.242522 -244.364279) (xy 356.258106 -244.41096)
			(xy 356.266001 -244.459537) (xy 356.266496 -244.484144) (xy 356.595438 -244.484144) (xy 356.599398 -244.43509)
			(xy 356.611175 -244.387306) (xy 356.630466 -244.34203) (xy 356.656769 -244.300434) (xy 356.689404 -244.263597)
			(xy 356.727525 -244.232472) (xy 356.770146 -244.207865) (xy 356.816162 -244.190413) (xy 356.864381 -244.180569)
			(xy 356.913556 -244.178588) (xy 356.962411 -244.18452) (xy 357.009682 -244.198212) (xy 357.054144 -244.21931)
			(xy 357.094647 -244.247266) (xy 357.13014 -244.281358) (xy 357.159705 -244.320702) (xy 357.182576 -244.364279)
			(xy 357.19816 -244.41096) (xy 357.206055 -244.459537) (xy 357.20655 -244.484144) (xy 357.535238 -244.484144)
			(xy 357.539198 -244.43509) (xy 357.550975 -244.387306) (xy 357.570266 -244.34203) (xy 357.596569 -244.300434)
			(xy 357.629204 -244.263597) (xy 357.667325 -244.232472) (xy 357.709946 -244.207865) (xy 357.755962 -244.190413)
			(xy 357.804181 -244.180569) (xy 357.853356 -244.178588) (xy 357.902211 -244.18452) (xy 357.949482 -244.198212)
			(xy 357.993944 -244.21931) (xy 358.034447 -244.247266) (xy 358.06994 -244.281358) (xy 358.099505 -244.320702)
			(xy 358.122376 -244.364279) (xy 358.13796 -244.41096) (xy 358.145855 -244.459537) (xy 358.14635 -244.484144)
			(xy 361.289104 -244.484144) (xy 361.293064 -244.43509) (xy 361.304841 -244.387306) (xy 361.324132 -244.34203)
			(xy 361.350435 -244.300434) (xy 361.38307 -244.263597) (xy 361.421191 -244.232472) (xy 361.463812 -244.207865)
			(xy 361.509828 -244.190413) (xy 361.558047 -244.180569) (xy 361.607222 -244.178588) (xy 361.656077 -244.18452)
			(xy 361.703348 -244.198212) (xy 361.74781 -244.21931) (xy 361.788313 -244.247266) (xy 361.823806 -244.281358)
			(xy 361.853371 -244.320702) (xy 361.876242 -244.364279) (xy 361.891826 -244.41096) (xy 361.899721 -244.459537)
			(xy 361.900216 -244.484144) (xy 362.228904 -244.484144) (xy 362.232864 -244.43509) (xy 362.244641 -244.387306)
			(xy 362.263932 -244.34203) (xy 362.290235 -244.300434) (xy 362.32287 -244.263597) (xy 362.360991 -244.232472)
			(xy 362.403612 -244.207865) (xy 362.449628 -244.190413) (xy 362.497847 -244.180569) (xy 362.547022 -244.178588)
			(xy 362.595877 -244.18452) (xy 362.643148 -244.198212) (xy 362.68761 -244.21931) (xy 362.728113 -244.247266)
			(xy 362.763606 -244.281358) (xy 362.793171 -244.320702) (xy 362.816042 -244.364279) (xy 362.831626 -244.41096)
			(xy 362.839521 -244.459537) (xy 362.840016 -244.484144) (xy 363.168958 -244.484144) (xy 363.172918 -244.43509)
			(xy 363.184695 -244.387306) (xy 363.203986 -244.34203) (xy 363.230289 -244.300434) (xy 363.262924 -244.263597)
			(xy 363.301045 -244.232472) (xy 363.343666 -244.207865) (xy 363.389682 -244.190413) (xy 363.437901 -244.180569)
			(xy 363.487076 -244.178588) (xy 363.535931 -244.18452) (xy 363.583202 -244.198212) (xy 363.627664 -244.21931)
			(xy 363.668167 -244.247266) (xy 363.70366 -244.281358) (xy 363.733225 -244.320702) (xy 363.756096 -244.364279)
			(xy 363.77168 -244.41096) (xy 363.779575 -244.459537) (xy 363.780069 -244.4841) (xy 364.108984 -244.4841)
			(xy 364.113155 -244.433763) (xy 364.125555 -244.384799) (xy 364.145845 -244.338543) (xy 364.173472 -244.296259)
			(xy 364.207683 -244.259098) (xy 364.247543 -244.228076) (xy 364.291966 -244.204037) (xy 364.33974 -244.187639)
			(xy 364.389561 -244.179327) (xy 364.414816 -244.178836) (xy 365.35487 -244.178836) (xy 365.380133 -244.179238)
			(xy 365.42997 -244.18755) (xy 365.47776 -244.203952) (xy 365.522198 -244.227997) (xy 365.562072 -244.259028)
			(xy 365.596293 -244.2962) (xy 365.62393 -244.338497) (xy 365.644227 -244.384767) (xy 365.656631 -244.433747)
			(xy 365.660804 -244.4841) (xy 365.6608 -244.484144) (xy 365.98912 -244.484144) (xy 365.99308 -244.43509)
			(xy 366.004857 -244.387306) (xy 366.024148 -244.34203) (xy 366.050451 -244.300434) (xy 366.083086 -244.263597)
			(xy 366.121207 -244.232472) (xy 366.163828 -244.207865) (xy 366.209844 -244.190413) (xy 366.258063 -244.180569)
			(xy 366.307238 -244.178588) (xy 366.356093 -244.18452) (xy 366.403364 -244.198212) (xy 366.447826 -244.21931)
			(xy 366.488329 -244.247266) (xy 366.523822 -244.281358) (xy 366.553387 -244.320702) (xy 366.576258 -244.364279)
			(xy 366.591842 -244.41096) (xy 366.599737 -244.459537) (xy 366.600231 -244.4841) (xy 366.928884 -244.4841)
			(xy 366.933055 -244.433762) (xy 366.945456 -244.384797) (xy 366.965746 -244.338541) (xy 366.993374 -244.296256)
			(xy 367.027586 -244.259095) (xy 367.067447 -244.228073) (xy 367.111871 -244.204035) (xy 367.159646 -244.187637)
			(xy 367.209469 -244.179327) (xy 367.234724 -244.178836) (xy 368.174778 -244.178836) (xy 368.200041 -244.179239)
			(xy 368.249877 -244.187552) (xy 368.297665 -244.203955) (xy 368.342102 -244.228) (xy 368.381975 -244.259031)
			(xy 368.416196 -244.296203) (xy 368.443831 -244.3385) (xy 368.464128 -244.384769) (xy 368.476531 -244.433748)
			(xy 368.480704 -244.4841) (xy 368.4807 -244.484144) (xy 368.809028 -244.484144) (xy 368.812988 -244.43509)
			(xy 368.824765 -244.387306) (xy 368.844056 -244.34203) (xy 368.870359 -244.300434) (xy 368.902994 -244.263597)
			(xy 368.941115 -244.232472) (xy 368.983736 -244.207865) (xy 369.029752 -244.190413) (xy 369.077971 -244.180569)
			(xy 369.127146 -244.178588) (xy 369.176001 -244.18452) (xy 369.223272 -244.198212) (xy 369.267734 -244.21931)
			(xy 369.308237 -244.247266) (xy 369.34373 -244.281358) (xy 369.373295 -244.320702) (xy 369.396166 -244.364279)
			(xy 369.41175 -244.41096) (xy 369.419645 -244.459537) (xy 369.420139 -244.4841) (xy 369.749113 -244.4841)
			(xy 369.753283 -244.433771) (xy 369.76568 -244.384814) (xy 369.785966 -244.338565) (xy 369.813587 -244.296286)
			(xy 369.847791 -244.25913) (xy 369.887643 -244.22811) (xy 369.932057 -244.204073) (xy 369.979822 -244.187673)
			(xy 370.029635 -244.179359) (xy 370.054886 -244.178836) (xy 370.99494 -244.178836) (xy 371.020197 -244.179272)
			(xy 371.070021 -244.187592) (xy 371.117796 -244.203999) (xy 371.162219 -244.228045) (xy 371.202079 -244.259074)
			(xy 371.236289 -244.296241) (xy 371.263916 -244.33853) (xy 371.284205 -244.38479) (xy 371.296604 -244.433759)
			(xy 371.300776 -244.4841) (xy 371.300772 -244.484144) (xy 371.628936 -244.484144) (xy 371.632896 -244.43509)
			(xy 371.644673 -244.387306) (xy 371.663964 -244.34203) (xy 371.690267 -244.300434) (xy 371.722902 -244.263597)
			(xy 371.761023 -244.232472) (xy 371.803644 -244.207865) (xy 371.84966 -244.190413) (xy 371.897879 -244.180569)
			(xy 371.947054 -244.178588) (xy 371.995909 -244.18452) (xy 372.04318 -244.198212) (xy 372.087642 -244.21931)
			(xy 372.128145 -244.247266) (xy 372.163638 -244.281358) (xy 372.193203 -244.320702) (xy 372.216074 -244.364279)
			(xy 372.231658 -244.41096) (xy 372.239553 -244.459537) (xy 372.240047 -244.4841) (xy 372.569013 -244.4841)
			(xy 372.573183 -244.43377) (xy 372.585581 -244.384812) (xy 372.605867 -244.338563) (xy 372.63349 -244.296284)
			(xy 372.667694 -244.259127) (xy 372.707547 -244.228107) (xy 372.751963 -244.20407) (xy 372.799729 -244.187671)
			(xy 372.849543 -244.179358) (xy 372.874794 -244.178836) (xy 373.814848 -244.178836) (xy 373.840104 -244.179273)
			(xy 373.889927 -244.187594) (xy 373.937701 -244.204002) (xy 373.982123 -244.228048) (xy 374.021982 -244.259077)
			(xy 374.056191 -244.296243) (xy 374.083817 -244.338533) (xy 374.104106 -244.384792) (xy 374.116505 -244.43376)
			(xy 374.120676 -244.4841) (xy 374.120672 -244.484144) (xy 374.449098 -244.484144) (xy 374.453058 -244.43509)
			(xy 374.464835 -244.387306) (xy 374.484126 -244.34203) (xy 374.510429 -244.300434) (xy 374.543064 -244.263597)
			(xy 374.581185 -244.232472) (xy 374.623806 -244.207865) (xy 374.669822 -244.190413) (xy 374.718041 -244.180569)
			(xy 374.767216 -244.178588) (xy 374.816071 -244.18452) (xy 374.863342 -244.198212) (xy 374.907804 -244.21931)
			(xy 374.948307 -244.247266) (xy 374.9838 -244.281358) (xy 375.013365 -244.320702) (xy 375.036236 -244.364279)
			(xy 375.05182 -244.41096) (xy 375.059715 -244.459537) (xy 375.06021 -244.484144) (xy 375.378467 -244.484144)
			(xy 375.382562 -244.433416) (xy 375.394741 -244.384002) (xy 375.414689 -244.337182) (xy 375.44189 -244.294168)
			(xy 375.475638 -244.256074) (xy 375.51506 -244.223887) (xy 375.559134 -244.198441) (xy 375.60672 -244.180394)
			(xy 375.656584 -244.170214) (xy 375.707436 -244.168165) (xy 375.757957 -244.174299) (xy 375.806841 -244.188459)
			(xy 375.85282 -244.210276) (xy 375.894704 -244.239186) (xy 375.931408 -244.274441) (xy 375.961981 -244.315127)
			(xy 375.985632 -244.36019) (xy 376.001748 -244.408464) (xy 376.009912 -244.458698) (xy 376.010424 -244.484144)
			(xy 376.328952 -244.484144) (xy 376.332912 -244.43509) (xy 376.344689 -244.387306) (xy 376.36398 -244.34203)
			(xy 376.390283 -244.300434) (xy 376.422918 -244.263597) (xy 376.461039 -244.232472) (xy 376.50366 -244.207865)
			(xy 376.549676 -244.190413) (xy 376.597895 -244.180569) (xy 376.64707 -244.178588) (xy 376.695925 -244.18452)
			(xy 376.743196 -244.198212) (xy 376.787658 -244.21931) (xy 376.828161 -244.247266) (xy 376.863654 -244.281358)
			(xy 376.893219 -244.320702) (xy 376.91609 -244.364279) (xy 376.931674 -244.41096) (xy 376.939569 -244.459537)
			(xy 376.940064 -244.484144) (xy 376.939569 -244.508751) (xy 376.931674 -244.557328) (xy 376.91609 -244.604009)
			(xy 376.893219 -244.647586) (xy 376.863654 -244.68693) (xy 376.828161 -244.721022) (xy 376.787658 -244.748978)
			(xy 376.743196 -244.770076) (xy 376.695925 -244.783768) (xy 376.64707 -244.7897) (xy 376.597895 -244.787719)
			(xy 376.549676 -244.777875) (xy 376.50366 -244.760423) (xy 376.461039 -244.735816) (xy 376.422918 -244.704691)
			(xy 376.390283 -244.667854) (xy 376.36398 -244.626258) (xy 376.344689 -244.580982) (xy 376.332912 -244.533198)
			(xy 376.328952 -244.484144) (xy 376.010424 -244.484144) (xy 376.009912 -244.50959) (xy 376.001748 -244.559824)
			(xy 375.985632 -244.608098) (xy 375.961981 -244.653161) (xy 375.931408 -244.693847) (xy 375.894704 -244.729102)
			(xy 375.85282 -244.758012) (xy 375.806841 -244.779829) (xy 375.757957 -244.793989) (xy 375.707436 -244.800123)
			(xy 375.656584 -244.798074) (xy 375.60672 -244.787894) (xy 375.559134 -244.769847) (xy 375.51506 -244.744401)
			(xy 375.475638 -244.712214) (xy 375.44189 -244.67412) (xy 375.414689 -244.631106) (xy 375.394741 -244.584286)
			(xy 375.382562 -244.534872) (xy 375.378467 -244.484144) (xy 375.06021 -244.484144) (xy 375.059715 -244.508751)
			(xy 375.05182 -244.557328) (xy 375.036236 -244.604009) (xy 375.013365 -244.647586) (xy 374.9838 -244.68693)
			(xy 374.948307 -244.721022) (xy 374.907804 -244.748978) (xy 374.863342 -244.770076) (xy 374.816071 -244.783768)
			(xy 374.767216 -244.7897) (xy 374.718041 -244.787719) (xy 374.669822 -244.777875) (xy 374.623806 -244.760423)
			(xy 374.581185 -244.735816) (xy 374.543064 -244.704691) (xy 374.510429 -244.667854) (xy 374.484126 -244.626258)
			(xy 374.464835 -244.580982) (xy 374.453058 -244.533198) (xy 374.449098 -244.484144) (xy 374.120672 -244.484144)
			(xy 374.116505 -244.53444) (xy 374.104106 -244.583408) (xy 374.083817 -244.629667) (xy 374.056191 -244.671957)
			(xy 374.021982 -244.709123) (xy 373.982123 -244.740152) (xy 373.937701 -244.764198) (xy 373.889927 -244.780606)
			(xy 373.840104 -244.788927) (xy 373.814848 -244.789452) (xy 372.874794 -244.789452) (xy 372.849543 -244.788842)
			(xy 372.799729 -244.780529) (xy 372.751963 -244.76413) (xy 372.707547 -244.740093) (xy 372.667694 -244.709073)
			(xy 372.63349 -244.671916) (xy 372.605867 -244.629637) (xy 372.585581 -244.583388) (xy 372.573183 -244.53443)
			(xy 372.569013 -244.4841) (xy 372.240047 -244.4841) (xy 372.240048 -244.484144) (xy 372.239553 -244.508751)
			(xy 372.231658 -244.557328) (xy 372.216074 -244.604009) (xy 372.193203 -244.647586) (xy 372.163638 -244.68693)
			(xy 372.128145 -244.721022) (xy 372.087642 -244.748978) (xy 372.04318 -244.770076) (xy 371.995909 -244.783768)
			(xy 371.947054 -244.7897) (xy 371.897879 -244.787719) (xy 371.84966 -244.777875) (xy 371.803644 -244.760423)
			(xy 371.761023 -244.735816) (xy 371.722902 -244.704691) (xy 371.690267 -244.667854) (xy 371.663964 -244.626258)
			(xy 371.644673 -244.580982) (xy 371.632896 -244.533198) (xy 371.628936 -244.484144) (xy 371.300772 -244.484144)
			(xy 371.296604 -244.534441) (xy 371.284205 -244.58341) (xy 371.263915 -244.62967) (xy 371.236289 -244.671959)
			(xy 371.202079 -244.709126) (xy 371.162219 -244.740155) (xy 371.117796 -244.764201) (xy 371.070021 -244.780608)
			(xy 371.020197 -244.788928) (xy 370.99494 -244.789452) (xy 370.054886 -244.789452) (xy 370.029635 -244.788841)
			(xy 369.979822 -244.780527) (xy 369.932057 -244.764127) (xy 369.887643 -244.74009) (xy 369.847791 -244.70907)
			(xy 369.813587 -244.671914) (xy 369.785966 -244.629635) (xy 369.76568 -244.583386) (xy 369.753283 -244.534429)
			(xy 369.749113 -244.4841) (xy 369.420139 -244.4841) (xy 369.42014 -244.484144) (xy 369.419645 -244.508751)
			(xy 369.41175 -244.557328) (xy 369.396166 -244.604009) (xy 369.373295 -244.647586) (xy 369.34373 -244.68693)
			(xy 369.308237 -244.721022) (xy 369.267734 -244.748978) (xy 369.223272 -244.770076) (xy 369.176001 -244.783768)
			(xy 369.127146 -244.7897) (xy 369.077971 -244.787719) (xy 369.029752 -244.777875) (xy 368.983736 -244.760423)
			(xy 368.941115 -244.735816) (xy 368.902994 -244.704691) (xy 368.870359 -244.667854) (xy 368.844056 -244.626258)
			(xy 368.824765 -244.580982) (xy 368.812988 -244.533198) (xy 368.809028 -244.484144) (xy 368.4807 -244.484144)
			(xy 368.476531 -244.534452) (xy 368.464128 -244.583431) (xy 368.443831 -244.6297) (xy 368.416196 -244.671997)
			(xy 368.381975 -244.709169) (xy 368.342102 -244.7402) (xy 368.297665 -244.764245) (xy 368.249877 -244.780648)
			(xy 368.200041 -244.788961) (xy 368.174778 -244.789452) (xy 367.234724 -244.789452) (xy 367.209469 -244.788873)
			(xy 367.159646 -244.780563) (xy 367.111871 -244.764165) (xy 367.067447 -244.740127) (xy 367.027586 -244.709105)
			(xy 366.993374 -244.671944) (xy 366.965746 -244.629659) (xy 366.945456 -244.583403) (xy 366.933055 -244.534438)
			(xy 366.928884 -244.4841) (xy 366.600231 -244.4841) (xy 366.600232 -244.484144) (xy 366.599737 -244.508751)
			(xy 366.591842 -244.557328) (xy 366.576258 -244.604009) (xy 366.553387 -244.647586) (xy 366.523822 -244.68693)
			(xy 366.488329 -244.721022) (xy 366.447826 -244.748978) (xy 366.403364 -244.770076) (xy 366.356093 -244.783768)
			(xy 366.307238 -244.7897) (xy 366.258063 -244.787719) (xy 366.209844 -244.777875) (xy 366.163828 -244.760423)
			(xy 366.121207 -244.735816) (xy 366.083086 -244.704691) (xy 366.050451 -244.667854) (xy 366.024148 -244.626258)
			(xy 366.004857 -244.580982) (xy 365.99308 -244.533198) (xy 365.98912 -244.484144) (xy 365.6608 -244.484144)
			(xy 365.656631 -244.534453) (xy 365.644227 -244.583433) (xy 365.62393 -244.629703) (xy 365.596293 -244.672)
			(xy 365.562072 -244.709172) (xy 365.522198 -244.740203) (xy 365.47776 -244.764248) (xy 365.42997 -244.78065)
			(xy 365.380133 -244.788962) (xy 365.35487 -244.789452) (xy 364.414816 -244.789452) (xy 364.389561 -244.788873)
			(xy 364.33974 -244.780561) (xy 364.291966 -244.764163) (xy 364.247543 -244.740124) (xy 364.207683 -244.709102)
			(xy 364.173472 -244.671941) (xy 364.145845 -244.629657) (xy 364.125555 -244.583401) (xy 364.113155 -244.534437)
			(xy 364.108984 -244.4841) (xy 363.780069 -244.4841) (xy 363.78007 -244.484144) (xy 363.779575 -244.508751)
			(xy 363.77168 -244.557328) (xy 363.756096 -244.604009) (xy 363.733225 -244.647586) (xy 363.70366 -244.68693)
			(xy 363.668167 -244.721022) (xy 363.627664 -244.748978) (xy 363.583202 -244.770076) (xy 363.535931 -244.783768)
			(xy 363.487076 -244.7897) (xy 363.437901 -244.787719) (xy 363.389682 -244.777875) (xy 363.343666 -244.760423)
			(xy 363.301045 -244.735816) (xy 363.262924 -244.704691) (xy 363.230289 -244.667854) (xy 363.203986 -244.626258)
			(xy 363.184695 -244.580982) (xy 363.172918 -244.533198) (xy 363.168958 -244.484144) (xy 362.840016 -244.484144)
			(xy 362.839521 -244.508751) (xy 362.831626 -244.557328) (xy 362.816042 -244.604009) (xy 362.793171 -244.647586)
			(xy 362.763606 -244.68693) (xy 362.728113 -244.721022) (xy 362.68761 -244.748978) (xy 362.643148 -244.770076)
			(xy 362.595877 -244.783768) (xy 362.547022 -244.7897) (xy 362.497847 -244.787719) (xy 362.449628 -244.777875)
			(xy 362.403612 -244.760423) (xy 362.360991 -244.735816) (xy 362.32287 -244.704691) (xy 362.290235 -244.667854)
			(xy 362.263932 -244.626258) (xy 362.244641 -244.580982) (xy 362.232864 -244.533198) (xy 362.228904 -244.484144)
			(xy 361.900216 -244.484144) (xy 361.899721 -244.508751) (xy 361.891826 -244.557328) (xy 361.876242 -244.604009)
			(xy 361.853371 -244.647586) (xy 361.823806 -244.68693) (xy 361.788313 -244.721022) (xy 361.74781 -244.748978)
			(xy 361.703348 -244.770076) (xy 361.656077 -244.783768) (xy 361.607222 -244.7897) (xy 361.558047 -244.787719)
			(xy 361.509828 -244.777875) (xy 361.463812 -244.760423) (xy 361.421191 -244.735816) (xy 361.38307 -244.704691)
			(xy 361.350435 -244.667854) (xy 361.324132 -244.626258) (xy 361.304841 -244.580982) (xy 361.293064 -244.533198)
			(xy 361.289104 -244.484144) (xy 358.14635 -244.484144) (xy 358.145855 -244.508751) (xy 358.13796 -244.557328)
			(xy 358.122376 -244.604009) (xy 358.099505 -244.647586) (xy 358.06994 -244.68693) (xy 358.034447 -244.721022)
			(xy 357.993944 -244.748978) (xy 357.949482 -244.770076) (xy 357.902211 -244.783768) (xy 357.853356 -244.7897)
			(xy 357.804181 -244.787719) (xy 357.755962 -244.777875) (xy 357.709946 -244.760423) (xy 357.667325 -244.735816)
			(xy 357.629204 -244.704691) (xy 357.596569 -244.667854) (xy 357.570266 -244.626258) (xy 357.550975 -244.580982)
			(xy 357.539198 -244.533198) (xy 357.535238 -244.484144) (xy 357.20655 -244.484144) (xy 357.206055 -244.508751)
			(xy 357.19816 -244.557328) (xy 357.182576 -244.604009) (xy 357.159705 -244.647586) (xy 357.13014 -244.68693)
			(xy 357.094647 -244.721022) (xy 357.054144 -244.748978) (xy 357.009682 -244.770076) (xy 356.962411 -244.783768)
			(xy 356.913556 -244.7897) (xy 356.864381 -244.787719) (xy 356.816162 -244.777875) (xy 356.770146 -244.760423)
			(xy 356.727525 -244.735816) (xy 356.689404 -244.704691) (xy 356.656769 -244.667854) (xy 356.630466 -244.626258)
			(xy 356.611175 -244.580982) (xy 356.599398 -244.533198) (xy 356.595438 -244.484144) (xy 356.266496 -244.484144)
			(xy 356.266001 -244.508751) (xy 356.258106 -244.557328) (xy 356.242522 -244.604009) (xy 356.219651 -244.647586)
			(xy 356.190086 -244.68693) (xy 356.154593 -244.721022) (xy 356.11409 -244.748978) (xy 356.069628 -244.770076)
			(xy 356.022357 -244.783768) (xy 355.973502 -244.7897) (xy 355.924327 -244.787719) (xy 355.876108 -244.777875)
			(xy 355.830092 -244.760423) (xy 355.787471 -244.735816) (xy 355.74935 -244.704691) (xy 355.716715 -244.667854)
			(xy 355.690412 -244.626258) (xy 355.671121 -244.580982) (xy 355.659344 -244.533198) (xy 355.655384 -244.484144)
			(xy 355.326442 -244.484144) (xy 355.325947 -244.508751) (xy 355.318052 -244.557328) (xy 355.302468 -244.604009)
			(xy 355.279597 -244.647586) (xy 355.250032 -244.68693) (xy 355.214539 -244.721022) (xy 355.174036 -244.748978)
			(xy 355.129574 -244.770076) (xy 355.082303 -244.783768) (xy 355.033448 -244.7897) (xy 354.984273 -244.787719)
			(xy 354.936054 -244.777875) (xy 354.890038 -244.760423) (xy 354.847417 -244.735816) (xy 354.809296 -244.704691)
			(xy 354.776661 -244.667854) (xy 354.750358 -244.626258) (xy 354.731067 -244.580982) (xy 354.71929 -244.533198)
			(xy 354.71533 -244.484144) (xy 354.386388 -244.484144) (xy 354.385893 -244.508751) (xy 354.377998 -244.557328)
			(xy 354.362414 -244.604009) (xy 354.339543 -244.647586) (xy 354.309978 -244.68693) (xy 354.274485 -244.721022)
			(xy 354.233982 -244.748978) (xy 354.18952 -244.770076) (xy 354.142249 -244.783768) (xy 354.093394 -244.7897)
			(xy 354.044219 -244.787719) (xy 353.996 -244.777875) (xy 353.949984 -244.760423) (xy 353.907363 -244.735816)
			(xy 353.869242 -244.704691) (xy 353.836607 -244.667854) (xy 353.810304 -244.626258) (xy 353.791013 -244.580982)
			(xy 353.779236 -244.533198) (xy 353.775276 -244.484144) (xy 353.446334 -244.484144) (xy 353.445839 -244.508751)
			(xy 353.437944 -244.557328) (xy 353.42236 -244.604009) (xy 353.399489 -244.647586) (xy 353.369924 -244.68693)
			(xy 353.334431 -244.721022) (xy 353.293928 -244.748978) (xy 353.249466 -244.770076) (xy 353.202195 -244.783768)
			(xy 353.15334 -244.7897) (xy 353.104165 -244.787719) (xy 353.055946 -244.777875) (xy 353.00993 -244.760423)
			(xy 352.967309 -244.735816) (xy 352.929188 -244.704691) (xy 352.896553 -244.667854) (xy 352.87025 -244.626258)
			(xy 352.850959 -244.580982) (xy 352.839182 -244.533198) (xy 352.835222 -244.484144) (xy 352.506534 -244.484144)
			(xy 352.506039 -244.508751) (xy 352.498144 -244.557328) (xy 352.48256 -244.604009) (xy 352.459689 -244.647586)
			(xy 352.430124 -244.68693) (xy 352.394631 -244.721022) (xy 352.354128 -244.748978) (xy 352.309666 -244.770076)
			(xy 352.262395 -244.783768) (xy 352.21354 -244.7897) (xy 352.164365 -244.787719) (xy 352.116146 -244.777875)
			(xy 352.07013 -244.760423) (xy 352.027509 -244.735816) (xy 351.989388 -244.704691) (xy 351.956753 -244.667854)
			(xy 351.93045 -244.626258) (xy 351.911159 -244.580982) (xy 351.899382 -244.533198) (xy 351.895422 -244.484144)
			(xy 351.56648 -244.484144) (xy 351.565985 -244.508751) (xy 351.55809 -244.557328) (xy 351.542506 -244.604009)
			(xy 351.519635 -244.647586) (xy 351.49007 -244.68693) (xy 351.454577 -244.721022) (xy 351.414074 -244.748978)
			(xy 351.369612 -244.770076) (xy 351.322341 -244.783768) (xy 351.273486 -244.7897) (xy 351.224311 -244.787719)
			(xy 351.176092 -244.777875) (xy 351.130076 -244.760423) (xy 351.087455 -244.735816) (xy 351.049334 -244.704691)
			(xy 351.016699 -244.667854) (xy 350.990396 -244.626258) (xy 350.971105 -244.580982) (xy 350.959328 -244.533198)
			(xy 350.955368 -244.484144) (xy 350.626426 -244.484144) (xy 350.625931 -244.508751) (xy 350.618036 -244.557328)
			(xy 350.602452 -244.604009) (xy 350.579581 -244.647586) (xy 350.550016 -244.68693) (xy 350.514523 -244.721022)
			(xy 350.47402 -244.748978) (xy 350.429558 -244.770076) (xy 350.382287 -244.783768) (xy 350.333432 -244.7897)
			(xy 350.284257 -244.787719) (xy 350.236038 -244.777875) (xy 350.190022 -244.760423) (xy 350.147401 -244.735816)
			(xy 350.10928 -244.704691) (xy 350.076645 -244.667854) (xy 350.050342 -244.626258) (xy 350.031051 -244.580982)
			(xy 350.019274 -244.533198) (xy 350.015314 -244.484144) (xy 349.686372 -244.484144) (xy 349.685877 -244.508751)
			(xy 349.677982 -244.557328) (xy 349.662398 -244.604009) (xy 349.639527 -244.647586) (xy 349.609962 -244.68693)
			(xy 349.574469 -244.721022) (xy 349.533966 -244.748978) (xy 349.489504 -244.770076) (xy 349.442233 -244.783768)
			(xy 349.393378 -244.7897) (xy 349.344203 -244.787719) (xy 349.295984 -244.777875) (xy 349.249968 -244.760423)
			(xy 349.207347 -244.735816) (xy 349.169226 -244.704691) (xy 349.136591 -244.667854) (xy 349.110288 -244.626258)
			(xy 349.090997 -244.580982) (xy 349.07922 -244.533198) (xy 349.07526 -244.484144) (xy 348.746318 -244.484144)
			(xy 348.745823 -244.508751) (xy 348.737928 -244.557328) (xy 348.722344 -244.604009) (xy 348.699473 -244.647586)
			(xy 348.669908 -244.68693) (xy 348.634415 -244.721022) (xy 348.593912 -244.748978) (xy 348.54945 -244.770076)
			(xy 348.502179 -244.783768) (xy 348.453324 -244.7897) (xy 348.404149 -244.787719) (xy 348.35593 -244.777875)
			(xy 348.309914 -244.760423) (xy 348.267293 -244.735816) (xy 348.229172 -244.704691) (xy 348.196537 -244.667854)
			(xy 348.170234 -244.626258) (xy 348.150943 -244.580982) (xy 348.139166 -244.533198) (xy 348.135206 -244.484144)
			(xy 347.806518 -244.484144) (xy 347.806023 -244.508751) (xy 347.798128 -244.557328) (xy 347.782544 -244.604009)
			(xy 347.759673 -244.647586) (xy 347.730108 -244.68693) (xy 347.694615 -244.721022) (xy 347.654112 -244.748978)
			(xy 347.60965 -244.770076) (xy 347.562379 -244.783768) (xy 347.513524 -244.7897) (xy 347.464349 -244.787719)
			(xy 347.41613 -244.777875) (xy 347.370114 -244.760423) (xy 347.327493 -244.735816) (xy 347.289372 -244.704691)
			(xy 347.256737 -244.667854) (xy 347.230434 -244.626258) (xy 347.211143 -244.580982) (xy 347.199366 -244.533198)
			(xy 347.195406 -244.484144) (xy 346.866464 -244.484144) (xy 346.865969 -244.508751) (xy 346.858074 -244.557328)
			(xy 346.84249 -244.604009) (xy 346.819619 -244.647586) (xy 346.790054 -244.68693) (xy 346.754561 -244.721022)
			(xy 346.714058 -244.748978) (xy 346.669596 -244.770076) (xy 346.622325 -244.783768) (xy 346.57347 -244.7897)
			(xy 346.524295 -244.787719) (xy 346.476076 -244.777875) (xy 346.43006 -244.760423) (xy 346.387439 -244.735816)
			(xy 346.349318 -244.704691) (xy 346.316683 -244.667854) (xy 346.29038 -244.626258) (xy 346.271089 -244.580982)
			(xy 346.259312 -244.533198) (xy 346.255352 -244.484144) (xy 345.92641 -244.484144) (xy 345.925915 -244.508751)
			(xy 345.91802 -244.557328) (xy 345.902436 -244.604009) (xy 345.879565 -244.647586) (xy 345.85 -244.68693)
			(xy 345.814507 -244.721022) (xy 345.774004 -244.748978) (xy 345.729542 -244.770076) (xy 345.682271 -244.783768)
			(xy 345.633416 -244.7897) (xy 345.584241 -244.787719) (xy 345.536022 -244.777875) (xy 345.490006 -244.760423)
			(xy 345.447385 -244.735816) (xy 345.409264 -244.704691) (xy 345.376629 -244.667854) (xy 345.350326 -244.626258)
			(xy 345.331035 -244.580982) (xy 345.319258 -244.533198) (xy 345.315298 -244.484144) (xy 344.986356 -244.484144)
			(xy 344.985861 -244.508751) (xy 344.977966 -244.557328) (xy 344.962382 -244.604009) (xy 344.939511 -244.647586)
			(xy 344.909946 -244.68693) (xy 344.874453 -244.721022) (xy 344.83395 -244.748978) (xy 344.789488 -244.770076)
			(xy 344.742217 -244.783768) (xy 344.693362 -244.7897) (xy 344.644187 -244.787719) (xy 344.595968 -244.777875)
			(xy 344.549952 -244.760423) (xy 344.507331 -244.735816) (xy 344.46921 -244.704691) (xy 344.436575 -244.667854)
			(xy 344.410272 -244.626258) (xy 344.390981 -244.580982) (xy 344.379204 -244.533198) (xy 344.375244 -244.484144)
			(xy 344.056716 -244.484144) (xy 344.056204 -244.50959) (xy 344.04804 -244.559824) (xy 344.031924 -244.608098)
			(xy 344.008273 -244.653161) (xy 343.9777 -244.693847) (xy 343.940996 -244.729102) (xy 343.899112 -244.758012)
			(xy 343.853133 -244.779829) (xy 343.804249 -244.793989) (xy 343.753728 -244.800123) (xy 343.702876 -244.798074)
			(xy 343.653012 -244.787894) (xy 343.605426 -244.769847) (xy 343.561352 -244.744401) (xy 343.52193 -244.712214)
			(xy 343.488182 -244.67412) (xy 343.460981 -244.631106) (xy 343.441033 -244.584286) (xy 343.428854 -244.534872)
			(xy 343.424759 -244.484144) (xy 343.106502 -244.484144) (xy 343.106007 -244.508751) (xy 343.098112 -244.557328)
			(xy 343.082528 -244.604009) (xy 343.059657 -244.647586) (xy 343.030092 -244.68693) (xy 342.994599 -244.721022)
			(xy 342.954096 -244.748978) (xy 342.909634 -244.770076) (xy 342.862363 -244.783768) (xy 342.813508 -244.7897)
			(xy 342.764333 -244.787719) (xy 342.716114 -244.777875) (xy 342.670098 -244.760423) (xy 342.627477 -244.735816)
			(xy 342.589356 -244.704691) (xy 342.556721 -244.667854) (xy 342.530418 -244.626258) (xy 342.511127 -244.580982)
			(xy 342.49935 -244.533198) (xy 342.49539 -244.484144) (xy 342.176862 -244.484144) (xy 342.17635 -244.50959)
			(xy 342.168186 -244.559824) (xy 342.15207 -244.608098) (xy 342.128419 -244.653161) (xy 342.097846 -244.693847)
			(xy 342.061142 -244.729102) (xy 342.019258 -244.758012) (xy 341.973279 -244.779829) (xy 341.924395 -244.793989)
			(xy 341.873874 -244.800123) (xy 341.823022 -244.798074) (xy 341.773158 -244.787894) (xy 341.725572 -244.769847)
			(xy 341.681498 -244.744401) (xy 341.642076 -244.712214) (xy 341.608328 -244.67412) (xy 341.581127 -244.631106)
			(xy 341.561179 -244.584286) (xy 341.549 -244.534872) (xy 341.544905 -244.484144) (xy 341.226394 -244.484144)
			(xy 341.226073 -244.503339) (xy 341.221226 -244.541423) (xy 341.216742 -244.56009) (xy 341.215218 -244.566186)
			(xy 341.215218 -244.89537) (xy 341.2158 -244.90657) (xy 341.225279 -244.926866) (xy 341.233506 -244.934486)
			(xy 341.270844 -244.965474) (xy 341.29218 -244.983254) (xy 341.299359 -244.988757) (xy 341.316411 -244.994753)
			(xy 341.325454 -244.994938) (xy 341.330026 -244.994938) (xy 341.345103 -244.992074) (xy 341.375641 -244.989023)
			(xy 341.390986 -244.988842) (xy 341.393018 -244.988842) (xy 341.416904 -244.989463) (xy 341.464049 -244.997218)
			(xy 341.509411 -245.012225) (xy 341.551881 -245.034115) (xy 341.590421 -245.062354) (xy 341.624091 -245.096253)
			(xy 341.652069 -245.134984) (xy 341.673671 -245.177601) (xy 341.68837 -245.223063) (xy 341.695806 -245.27026)
			(xy 341.696294 -245.29415) (xy 342.014805 -245.29415) (xy 342.0189 -245.243422) (xy 342.031079 -245.194008)
			(xy 342.051027 -245.147188) (xy 342.078228 -245.104174) (xy 342.111976 -245.06608) (xy 342.151398 -245.033893)
			(xy 342.195472 -245.008447) (xy 342.243058 -244.9904) (xy 342.292922 -244.98022) (xy 342.343774 -244.978171)
			(xy 342.394295 -244.984305) (xy 342.443179 -244.998465) (xy 342.489158 -245.020282) (xy 342.531042 -245.049192)
			(xy 342.567746 -245.084447) (xy 342.598319 -245.125133) (xy 342.62197 -245.170196) (xy 342.638086 -245.21847)
			(xy 342.64625 -245.268704) (xy 342.646762 -245.29415) (xy 342.954859 -245.29415) (xy 342.958954 -245.243422)
			(xy 342.971133 -245.194008) (xy 342.991081 -245.147188) (xy 343.018282 -245.104174) (xy 343.05203 -245.06608)
			(xy 343.091452 -245.033893) (xy 343.135526 -245.008447) (xy 343.183112 -244.9904) (xy 343.232976 -244.98022)
			(xy 343.283828 -244.978171) (xy 343.334349 -244.984305) (xy 343.383233 -244.998465) (xy 343.429212 -245.020282)
			(xy 343.471096 -245.049192) (xy 343.5078 -245.084447) (xy 343.538373 -245.125133) (xy 343.562024 -245.170196)
			(xy 343.57814 -245.21847) (xy 343.586304 -245.268704) (xy 343.586816 -245.29415) (xy 343.905344 -245.29415)
			(xy 343.909304 -245.245096) (xy 343.921081 -245.197312) (xy 343.940372 -245.152036) (xy 343.966675 -245.11044)
			(xy 343.99931 -245.073603) (xy 344.037431 -245.042478) (xy 344.080052 -245.017871) (xy 344.126068 -245.000419)
			(xy 344.174287 -244.990575) (xy 344.223462 -244.988594) (xy 344.272317 -244.994526) (xy 344.319588 -245.008218)
			(xy 344.36405 -245.029316) (xy 344.404553 -245.057272) (xy 344.440046 -245.091364) (xy 344.469611 -245.130708)
			(xy 344.492482 -245.174285) (xy 344.508066 -245.220966) (xy 344.515961 -245.269543) (xy 344.516456 -245.29415)
			(xy 346.725252 -245.29415) (xy 346.729212 -245.245096) (xy 346.740989 -245.197312) (xy 346.76028 -245.152036)
			(xy 346.786583 -245.11044) (xy 346.819218 -245.073603) (xy 346.857339 -245.042478) (xy 346.89996 -245.017871)
			(xy 346.945976 -245.000419) (xy 346.994195 -244.990575) (xy 347.04337 -244.988594) (xy 347.092225 -244.994526)
			(xy 347.139496 -245.008218) (xy 347.183958 -245.029316) (xy 347.224461 -245.057272) (xy 347.259954 -245.091364)
			(xy 347.289519 -245.130708) (xy 347.31239 -245.174285) (xy 347.327974 -245.220966) (xy 347.335869 -245.269543)
			(xy 347.336364 -245.29415) (xy 349.545414 -245.29415) (xy 349.549374 -245.245096) (xy 349.561151 -245.197312)
			(xy 349.580442 -245.152036) (xy 349.606745 -245.11044) (xy 349.63938 -245.073603) (xy 349.677501 -245.042478)
			(xy 349.720122 -245.017871) (xy 349.766138 -245.000419) (xy 349.814357 -244.990575) (xy 349.863532 -244.988594)
			(xy 349.912387 -244.994526) (xy 349.959658 -245.008218) (xy 350.00412 -245.029316) (xy 350.044623 -245.057272)
			(xy 350.080116 -245.091364) (xy 350.109681 -245.130708) (xy 350.132552 -245.174285) (xy 350.148136 -245.220966)
			(xy 350.156031 -245.269543) (xy 350.156526 -245.29415) (xy 352.365322 -245.29415) (xy 352.369282 -245.245096)
			(xy 352.381059 -245.197312) (xy 352.40035 -245.152036) (xy 352.426653 -245.11044) (xy 352.459288 -245.073603)
			(xy 352.497409 -245.042478) (xy 352.54003 -245.017871) (xy 352.586046 -245.000419) (xy 352.634265 -244.990575)
			(xy 352.68344 -244.988594) (xy 352.732295 -244.994526) (xy 352.779566 -245.008218) (xy 352.824028 -245.029316)
			(xy 352.864531 -245.057272) (xy 352.900024 -245.091364) (xy 352.929589 -245.130708) (xy 352.95246 -245.174285)
			(xy 352.968044 -245.220966) (xy 352.975939 -245.269543) (xy 352.976434 -245.29415) (xy 355.18523 -245.29415)
			(xy 355.18919 -245.245096) (xy 355.200967 -245.197312) (xy 355.220258 -245.152036) (xy 355.246561 -245.11044)
			(xy 355.279196 -245.073603) (xy 355.317317 -245.042478) (xy 355.359938 -245.017871) (xy 355.405954 -245.000419)
			(xy 355.454173 -244.990575) (xy 355.503348 -244.988594) (xy 355.552203 -244.994526) (xy 355.599474 -245.008218)
			(xy 355.643936 -245.029316) (xy 355.684439 -245.057272) (xy 355.719932 -245.091364) (xy 355.749497 -245.130708)
			(xy 355.772368 -245.174285) (xy 355.787952 -245.220966) (xy 355.795847 -245.269543) (xy 355.796342 -245.29415)
			(xy 356.125284 -245.29415) (xy 356.129244 -245.245096) (xy 356.141021 -245.197312) (xy 356.160312 -245.152036)
			(xy 356.186615 -245.11044) (xy 356.21925 -245.073603) (xy 356.257371 -245.042478) (xy 356.299992 -245.017871)
			(xy 356.346008 -245.000419) (xy 356.394227 -244.990575) (xy 356.443402 -244.988594) (xy 356.492257 -244.994526)
			(xy 356.539528 -245.008218) (xy 356.58399 -245.029316) (xy 356.624493 -245.057272) (xy 356.659986 -245.091364)
			(xy 356.689551 -245.130708) (xy 356.712422 -245.174285) (xy 356.728006 -245.220966) (xy 356.735901 -245.269543)
			(xy 356.736396 -245.29415) (xy 357.065338 -245.29415) (xy 357.069298 -245.245096) (xy 357.081075 -245.197312)
			(xy 357.100366 -245.152036) (xy 357.126669 -245.11044) (xy 357.159304 -245.073603) (xy 357.197425 -245.042478)
			(xy 357.240046 -245.017871) (xy 357.286062 -245.000419) (xy 357.334281 -244.990575) (xy 357.383456 -244.988594)
			(xy 357.432311 -244.994526) (xy 357.479582 -245.008218) (xy 357.524044 -245.029316) (xy 357.564547 -245.057272)
			(xy 357.60004 -245.091364) (xy 357.629605 -245.130708) (xy 357.652476 -245.174285) (xy 357.66806 -245.220966)
			(xy 357.675955 -245.269543) (xy 357.67645 -245.29415) (xy 358.005392 -245.29415) (xy 358.009352 -245.245096)
			(xy 358.021129 -245.197312) (xy 358.04042 -245.152036) (xy 358.066723 -245.11044) (xy 358.099358 -245.073603)
			(xy 358.137479 -245.042478) (xy 358.1801 -245.017871) (xy 358.226116 -245.000419) (xy 358.274335 -244.990575)
			(xy 358.32351 -244.988594) (xy 358.372365 -244.994526) (xy 358.419636 -245.008218) (xy 358.464098 -245.029316)
			(xy 358.504601 -245.057272) (xy 358.540094 -245.091364) (xy 358.569659 -245.130708) (xy 358.59253 -245.174285)
			(xy 358.608114 -245.220966) (xy 358.616009 -245.269543) (xy 358.616504 -245.29415) (xy 358.616009 -245.318757)
			(xy 358.608114 -245.367334) (xy 358.59253 -245.414015) (xy 358.569659 -245.457592) (xy 358.540094 -245.496936)
			(xy 358.504601 -245.531028) (xy 358.474274 -245.55196) (xy 359.396541 -245.55196) (xy 359.400571 -245.499462)
			(xy 359.412568 -245.448194) (xy 359.432251 -245.399359) (xy 359.459157 -245.3541) (xy 359.492657 -245.313479)
			(xy 359.531965 -245.278448) (xy 359.57616 -245.249828) (xy 359.624205 -245.228289) (xy 359.674976 -245.214337)
			(xy 359.727281 -245.208299) (xy 359.779895 -245.210316) (xy 359.831585 -245.22034) (xy 359.881138 -245.238138)
			(xy 359.927394 -245.263291) (xy 359.967877 -245.29415) (xy 360.81895 -245.29415) (xy 360.82291 -245.245096)
			(xy 360.834687 -245.197312) (xy 360.853978 -245.152036) (xy 360.880281 -245.11044) (xy 360.912916 -245.073603)
			(xy 360.951037 -245.042478) (xy 360.993658 -245.017871) (xy 361.039674 -245.000419) (xy 361.087893 -244.990575)
			(xy 361.137068 -244.988594) (xy 361.185923 -244.994526) (xy 361.233194 -245.008218) (xy 361.277656 -245.029316)
			(xy 361.318159 -245.057272) (xy 361.353652 -245.091364) (xy 361.383217 -245.130708) (xy 361.406088 -245.174285)
			(xy 361.421672 -245.220966) (xy 361.429567 -245.269543) (xy 361.430061 -245.2941) (xy 361.758735 -245.2941)
			(xy 361.76291 -245.243723) (xy 361.775319 -245.194719) (xy 361.795626 -245.148427) (xy 361.823274 -245.106109)
			(xy 361.857511 -245.068918) (xy 361.897403 -245.03787) (xy 361.941861 -245.013812) (xy 361.989672 -244.997399)
			(xy 362.039533 -244.98908) (xy 362.064808 -244.988588) (xy 363.004862 -244.988588) (xy 363.030147 -244.988978)
			(xy 363.080028 -244.997296) (xy 363.127859 -245.013711) (xy 363.172336 -245.037776) (xy 363.212245 -245.068834)
			(xy 363.246497 -245.106037) (xy 363.274158 -245.148371) (xy 363.294473 -245.194681) (xy 363.306888 -245.243703)
			(xy 363.311065 -245.2941) (xy 363.311061 -245.29415) (xy 363.639112 -245.29415) (xy 363.643072 -245.245096)
			(xy 363.654849 -245.197312) (xy 363.67414 -245.152036) (xy 363.700443 -245.11044) (xy 363.733078 -245.073603)
			(xy 363.771199 -245.042478) (xy 363.81382 -245.017871) (xy 363.859836 -245.000419) (xy 363.908055 -244.990575)
			(xy 363.95723 -244.988594) (xy 364.006085 -244.994526) (xy 364.053356 -245.008218) (xy 364.097818 -245.029316)
			(xy 364.138321 -245.057272) (xy 364.173814 -245.091364) (xy 364.203379 -245.130708) (xy 364.22625 -245.174285)
			(xy 364.241834 -245.220966) (xy 364.249729 -245.269543) (xy 364.250224 -245.29415) (xy 366.45902 -245.29415)
			(xy 366.46298 -245.245096) (xy 366.474757 -245.197312) (xy 366.494048 -245.152036) (xy 366.520351 -245.11044)
			(xy 366.552986 -245.073603) (xy 366.591107 -245.042478) (xy 366.633728 -245.017871) (xy 366.679744 -245.000419)
			(xy 366.727963 -244.990575) (xy 366.777138 -244.988594) (xy 366.825993 -244.994526) (xy 366.873264 -245.008218)
			(xy 366.917726 -245.029316) (xy 366.958229 -245.057272) (xy 366.993722 -245.091364) (xy 367.023287 -245.130708)
			(xy 367.046158 -245.174285) (xy 367.061742 -245.220966) (xy 367.069637 -245.269543) (xy 367.070132 -245.29415)
			(xy 369.278928 -245.29415) (xy 369.282888 -245.245096) (xy 369.294665 -245.197312) (xy 369.313956 -245.152036)
			(xy 369.340259 -245.11044) (xy 369.372894 -245.073603) (xy 369.411015 -245.042478) (xy 369.453636 -245.017871)
			(xy 369.499652 -245.000419) (xy 369.547871 -244.990575) (xy 369.597046 -244.988594) (xy 369.645901 -244.994526)
			(xy 369.693172 -245.008218) (xy 369.737634 -245.029316) (xy 369.778137 -245.057272) (xy 369.81363 -245.091364)
			(xy 369.843195 -245.130708) (xy 369.866066 -245.174285) (xy 369.88165 -245.220966) (xy 369.889545 -245.269543)
			(xy 369.89004 -245.29415) (xy 372.09909 -245.29415) (xy 372.10305 -245.245096) (xy 372.114827 -245.197312)
			(xy 372.134118 -245.152036) (xy 372.160421 -245.11044) (xy 372.193056 -245.073603) (xy 372.231177 -245.042478)
			(xy 372.273798 -245.017871) (xy 372.319814 -245.000419) (xy 372.368033 -244.990575) (xy 372.417208 -244.988594)
			(xy 372.466063 -244.994526) (xy 372.513334 -245.008218) (xy 372.557796 -245.029316) (xy 372.598299 -245.057272)
			(xy 372.633792 -245.091364) (xy 372.663357 -245.130708) (xy 372.686228 -245.174285) (xy 372.701812 -245.220966)
			(xy 372.709707 -245.269543) (xy 372.710202 -245.29415) (xy 374.918998 -245.29415) (xy 374.922958 -245.245096)
			(xy 374.934735 -245.197312) (xy 374.954026 -245.152036) (xy 374.980329 -245.11044) (xy 375.012964 -245.073603)
			(xy 375.051085 -245.042478) (xy 375.093706 -245.017871) (xy 375.139722 -245.000419) (xy 375.187941 -244.990575)
			(xy 375.237116 -244.988594) (xy 375.285971 -244.994526) (xy 375.333242 -245.008218) (xy 375.377704 -245.029316)
			(xy 375.418207 -245.057272) (xy 375.4537 -245.091364) (xy 375.483265 -245.130708) (xy 375.506136 -245.174285)
			(xy 375.52172 -245.220966) (xy 375.529615 -245.269543) (xy 375.53011 -245.29415) (xy 375.848621 -245.29415)
			(xy 375.852716 -245.243422) (xy 375.864895 -245.194008) (xy 375.884843 -245.147188) (xy 375.912044 -245.104174)
			(xy 375.945792 -245.06608) (xy 375.985214 -245.033893) (xy 376.029288 -245.008447) (xy 376.076874 -244.9904)
			(xy 376.126738 -244.98022) (xy 376.17759 -244.978171) (xy 376.228111 -244.984305) (xy 376.276995 -244.998465)
			(xy 376.322974 -245.020282) (xy 376.364858 -245.049192) (xy 376.401562 -245.084447) (xy 376.432135 -245.125133)
			(xy 376.455786 -245.170196) (xy 376.471902 -245.21847) (xy 376.480066 -245.268704) (xy 376.480578 -245.29415)
			(xy 376.788675 -245.29415) (xy 376.79277 -245.243422) (xy 376.804949 -245.194008) (xy 376.824897 -245.147188)
			(xy 376.852098 -245.104174) (xy 376.885846 -245.06608) (xy 376.925268 -245.033893) (xy 376.969342 -245.008447)
			(xy 377.016928 -244.9904) (xy 377.066792 -244.98022) (xy 377.117644 -244.978171) (xy 377.168165 -244.984305)
			(xy 377.217049 -244.998465) (xy 377.263028 -245.020282) (xy 377.304912 -245.049192) (xy 377.341616 -245.084447)
			(xy 377.372189 -245.125133) (xy 377.39584 -245.170196) (xy 377.411956 -245.21847) (xy 377.42012 -245.268704)
			(xy 377.420632 -245.29415) (xy 377.42012 -245.319596) (xy 377.411956 -245.36983) (xy 377.39584 -245.418104)
			(xy 377.372189 -245.463167) (xy 377.341616 -245.503853) (xy 377.304912 -245.539108) (xy 377.263028 -245.568018)
			(xy 377.217049 -245.589835) (xy 377.168165 -245.603995) (xy 377.117644 -245.610129) (xy 377.066792 -245.60808)
			(xy 377.016928 -245.5979) (xy 376.969342 -245.579853) (xy 376.925268 -245.554407) (xy 376.885846 -245.52222)
			(xy 376.852098 -245.484126) (xy 376.824897 -245.441112) (xy 376.804949 -245.394292) (xy 376.79277 -245.344878)
			(xy 376.788675 -245.29415) (xy 376.480578 -245.29415) (xy 376.480066 -245.319596) (xy 376.471902 -245.36983)
			(xy 376.455786 -245.418104) (xy 376.432135 -245.463167) (xy 376.401562 -245.503853) (xy 376.364858 -245.539108)
			(xy 376.322974 -245.568018) (xy 376.276995 -245.589835) (xy 376.228111 -245.603995) (xy 376.17759 -245.610129)
			(xy 376.126738 -245.60808) (xy 376.076874 -245.5979) (xy 376.029288 -245.579853) (xy 375.985214 -245.554407)
			(xy 375.945792 -245.52222) (xy 375.912044 -245.484126) (xy 375.884843 -245.441112) (xy 375.864895 -245.394292)
			(xy 375.852716 -245.344878) (xy 375.848621 -245.29415) (xy 375.53011 -245.29415) (xy 375.529615 -245.318757)
			(xy 375.52172 -245.367334) (xy 375.506136 -245.414015) (xy 375.483265 -245.457592) (xy 375.4537 -245.496936)
			(xy 375.418207 -245.531028) (xy 375.377704 -245.558984) (xy 375.333242 -245.580082) (xy 375.285971 -245.593774)
			(xy 375.237116 -245.599706) (xy 375.187941 -245.597725) (xy 375.139722 -245.587881) (xy 375.093706 -245.570429)
			(xy 375.051085 -245.545822) (xy 375.012964 -245.514697) (xy 374.980329 -245.47786) (xy 374.954026 -245.436264)
			(xy 374.934735 -245.390988) (xy 374.922958 -245.343204) (xy 374.918998 -245.29415) (xy 372.710202 -245.29415)
			(xy 372.709707 -245.318757) (xy 372.701812 -245.367334) (xy 372.686228 -245.414015) (xy 372.663357 -245.457592)
			(xy 372.633792 -245.496936) (xy 372.598299 -245.531028) (xy 372.557796 -245.558984) (xy 372.513334 -245.580082)
			(xy 372.466063 -245.593774) (xy 372.417208 -245.599706) (xy 372.368033 -245.597725) (xy 372.319814 -245.587881)
			(xy 372.273798 -245.570429) (xy 372.231177 -245.545822) (xy 372.193056 -245.514697) (xy 372.160421 -245.47786)
			(xy 372.134118 -245.436264) (xy 372.114827 -245.390988) (xy 372.10305 -245.343204) (xy 372.09909 -245.29415)
			(xy 369.89004 -245.29415) (xy 369.889545 -245.318757) (xy 369.88165 -245.367334) (xy 369.866066 -245.414015)
			(xy 369.843195 -245.457592) (xy 369.81363 -245.496936) (xy 369.778137 -245.531028) (xy 369.737634 -245.558984)
			(xy 369.693172 -245.580082) (xy 369.645901 -245.593774) (xy 369.597046 -245.599706) (xy 369.547871 -245.597725)
			(xy 369.499652 -245.587881) (xy 369.453636 -245.570429) (xy 369.411015 -245.545822) (xy 369.372894 -245.514697)
			(xy 369.340259 -245.47786) (xy 369.313956 -245.436264) (xy 369.294665 -245.390988) (xy 369.282888 -245.343204)
			(xy 369.278928 -245.29415) (xy 367.070132 -245.29415) (xy 367.069637 -245.318757) (xy 367.061742 -245.367334)
			(xy 367.046158 -245.414015) (xy 367.023287 -245.457592) (xy 366.993722 -245.496936) (xy 366.958229 -245.531028)
			(xy 366.917726 -245.558984) (xy 366.873264 -245.580082) (xy 366.825993 -245.593774) (xy 366.777138 -245.599706)
			(xy 366.727963 -245.597725) (xy 366.679744 -245.587881) (xy 366.633728 -245.570429) (xy 366.591107 -245.545822)
			(xy 366.552986 -245.514697) (xy 366.520351 -245.47786) (xy 366.494048 -245.436264) (xy 366.474757 -245.390988)
			(xy 366.46298 -245.343204) (xy 366.45902 -245.29415) (xy 364.250224 -245.29415) (xy 364.249729 -245.318757)
			(xy 364.241834 -245.367334) (xy 364.22625 -245.414015) (xy 364.203379 -245.457592) (xy 364.173814 -245.496936)
			(xy 364.138321 -245.531028) (xy 364.097818 -245.558984) (xy 364.053356 -245.580082) (xy 364.006085 -245.593774)
			(xy 363.95723 -245.599706) (xy 363.908055 -245.597725) (xy 363.859836 -245.587881) (xy 363.81382 -245.570429)
			(xy 363.771199 -245.545822) (xy 363.733078 -245.514697) (xy 363.700443 -245.47786) (xy 363.67414 -245.436264)
			(xy 363.654849 -245.390988) (xy 363.643072 -245.343204) (xy 363.639112 -245.29415) (xy 363.311061 -245.29415)
			(xy 363.306888 -245.344497) (xy 363.294473 -245.393519) (xy 363.274158 -245.439829) (xy 363.246497 -245.482163)
			(xy 363.212245 -245.519366) (xy 363.172336 -245.550424) (xy 363.127859 -245.574489) (xy 363.080028 -245.590904)
			(xy 363.030147 -245.599222) (xy 363.004862 -245.599712) (xy 362.064808 -245.599712) (xy 362.039533 -245.59912)
			(xy 361.989672 -245.590801) (xy 361.941861 -245.574388) (xy 361.897403 -245.55033) (xy 361.857511 -245.519282)
			(xy 361.823274 -245.482091) (xy 361.795626 -245.439773) (xy 361.775319 -245.393481) (xy 361.76291 -245.344477)
			(xy 361.758735 -245.2941) (xy 361.430061 -245.2941) (xy 361.430062 -245.29415) (xy 361.429567 -245.318757)
			(xy 361.421672 -245.367334) (xy 361.406088 -245.414015) (xy 361.383217 -245.457592) (xy 361.353652 -245.496936)
			(xy 361.318159 -245.531028) (xy 361.277656 -245.558984) (xy 361.233194 -245.580082) (xy 361.185923 -245.593774)
			(xy 361.137068 -245.599706) (xy 361.087893 -245.597725) (xy 361.039674 -245.587881) (xy 360.993658 -245.570429)
			(xy 360.951037 -245.545822) (xy 360.912916 -245.514697) (xy 360.880281 -245.47786) (xy 360.853978 -245.436264)
			(xy 360.834687 -245.390988) (xy 360.82291 -245.343204) (xy 360.81895 -245.29415) (xy 359.967877 -245.29415)
			(xy 359.969268 -245.29521) (xy 360.00578 -245.333148) (xy 360.036072 -245.376214) (xy 360.059435 -245.423399)
			(xy 360.075321 -245.473598) (xy 360.083358 -245.525634) (xy 360.083862 -245.55196) (xy 360.083358 -245.578286)
			(xy 360.075321 -245.630322) (xy 360.059435 -245.680521) (xy 360.036072 -245.727706) (xy 360.00578 -245.770772)
			(xy 359.969268 -245.80871) (xy 359.927394 -245.840629) (xy 359.881138 -245.865782) (xy 359.831585 -245.88358)
			(xy 359.779895 -245.893604) (xy 359.727281 -245.895621) (xy 359.674976 -245.889583) (xy 359.624205 -245.875631)
			(xy 359.57616 -245.854092) (xy 359.531965 -245.825472) (xy 359.492657 -245.790441) (xy 359.459157 -245.74982)
			(xy 359.432251 -245.704561) (xy 359.412568 -245.655726) (xy 359.400571 -245.604458) (xy 359.396541 -245.55196)
			(xy 358.474274 -245.55196) (xy 358.464098 -245.558984) (xy 358.419636 -245.580082) (xy 358.372365 -245.593774)
			(xy 358.32351 -245.599706) (xy 358.274335 -245.597725) (xy 358.226116 -245.587881) (xy 358.1801 -245.570429)
			(xy 358.137479 -245.545822) (xy 358.099358 -245.514697) (xy 358.066723 -245.47786) (xy 358.04042 -245.436264)
			(xy 358.021129 -245.390988) (xy 358.009352 -245.343204) (xy 358.005392 -245.29415) (xy 357.67645 -245.29415)
			(xy 357.675955 -245.318757) (xy 357.66806 -245.367334) (xy 357.652476 -245.414015) (xy 357.629605 -245.457592)
			(xy 357.60004 -245.496936) (xy 357.564547 -245.531028) (xy 357.524044 -245.558984) (xy 357.479582 -245.580082)
			(xy 357.432311 -245.593774) (xy 357.383456 -245.599706) (xy 357.334281 -245.597725) (xy 357.286062 -245.587881)
			(xy 357.240046 -245.570429) (xy 357.197425 -245.545822) (xy 357.159304 -245.514697) (xy 357.126669 -245.47786)
			(xy 357.100366 -245.436264) (xy 357.081075 -245.390988) (xy 357.069298 -245.343204) (xy 357.065338 -245.29415)
			(xy 356.736396 -245.29415) (xy 356.735901 -245.318757) (xy 356.728006 -245.367334) (xy 356.712422 -245.414015)
			(xy 356.689551 -245.457592) (xy 356.659986 -245.496936) (xy 356.624493 -245.531028) (xy 356.58399 -245.558984)
			(xy 356.539528 -245.580082) (xy 356.492257 -245.593774) (xy 356.443402 -245.599706) (xy 356.394227 -245.597725)
			(xy 356.346008 -245.587881) (xy 356.299992 -245.570429) (xy 356.257371 -245.545822) (xy 356.21925 -245.514697)
			(xy 356.186615 -245.47786) (xy 356.160312 -245.436264) (xy 356.141021 -245.390988) (xy 356.129244 -245.343204)
			(xy 356.125284 -245.29415) (xy 355.796342 -245.29415) (xy 355.795847 -245.318757) (xy 355.787952 -245.367334)
			(xy 355.772368 -245.414015) (xy 355.749497 -245.457592) (xy 355.719932 -245.496936) (xy 355.684439 -245.531028)
			(xy 355.643936 -245.558984) (xy 355.599474 -245.580082) (xy 355.552203 -245.593774) (xy 355.503348 -245.599706)
			(xy 355.454173 -245.597725) (xy 355.405954 -245.587881) (xy 355.359938 -245.570429) (xy 355.317317 -245.545822)
			(xy 355.279196 -245.514697) (xy 355.246561 -245.47786) (xy 355.220258 -245.436264) (xy 355.200967 -245.390988)
			(xy 355.18919 -245.343204) (xy 355.18523 -245.29415) (xy 352.976434 -245.29415) (xy 352.975939 -245.318757)
			(xy 352.968044 -245.367334) (xy 352.95246 -245.414015) (xy 352.929589 -245.457592) (xy 352.900024 -245.496936)
			(xy 352.864531 -245.531028) (xy 352.824028 -245.558984) (xy 352.779566 -245.580082) (xy 352.732295 -245.593774)
			(xy 352.68344 -245.599706) (xy 352.634265 -245.597725) (xy 352.586046 -245.587881) (xy 352.54003 -245.570429)
			(xy 352.497409 -245.545822) (xy 352.459288 -245.514697) (xy 352.426653 -245.47786) (xy 352.40035 -245.436264)
			(xy 352.381059 -245.390988) (xy 352.369282 -245.343204) (xy 352.365322 -245.29415) (xy 350.156526 -245.29415)
			(xy 350.156031 -245.318757) (xy 350.148136 -245.367334) (xy 350.132552 -245.414015) (xy 350.109681 -245.457592)
			(xy 350.080116 -245.496936) (xy 350.044623 -245.531028) (xy 350.00412 -245.558984) (xy 349.959658 -245.580082)
			(xy 349.912387 -245.593774) (xy 349.863532 -245.599706) (xy 349.814357 -245.597725) (xy 349.766138 -245.587881)
			(xy 349.720122 -245.570429) (xy 349.677501 -245.545822) (xy 349.63938 -245.514697) (xy 349.606745 -245.47786)
			(xy 349.580442 -245.436264) (xy 349.561151 -245.390988) (xy 349.549374 -245.343204) (xy 349.545414 -245.29415)
			(xy 347.336364 -245.29415) (xy 347.335869 -245.318757) (xy 347.327974 -245.367334) (xy 347.31239 -245.414015)
			(xy 347.289519 -245.457592) (xy 347.259954 -245.496936) (xy 347.224461 -245.531028) (xy 347.183958 -245.558984)
			(xy 347.139496 -245.580082) (xy 347.092225 -245.593774) (xy 347.04337 -245.599706) (xy 346.994195 -245.597725)
			(xy 346.945976 -245.587881) (xy 346.89996 -245.570429) (xy 346.857339 -245.545822) (xy 346.819218 -245.514697)
			(xy 346.786583 -245.47786) (xy 346.76028 -245.436264) (xy 346.740989 -245.390988) (xy 346.729212 -245.343204)
			(xy 346.725252 -245.29415) (xy 344.516456 -245.29415) (xy 344.515961 -245.318757) (xy 344.508066 -245.367334)
			(xy 344.492482 -245.414015) (xy 344.469611 -245.457592) (xy 344.440046 -245.496936) (xy 344.404553 -245.531028)
			(xy 344.36405 -245.558984) (xy 344.319588 -245.580082) (xy 344.272317 -245.593774) (xy 344.223462 -245.599706)
			(xy 344.174287 -245.597725) (xy 344.126068 -245.587881) (xy 344.080052 -245.570429) (xy 344.037431 -245.545822)
			(xy 343.99931 -245.514697) (xy 343.966675 -245.47786) (xy 343.940372 -245.436264) (xy 343.921081 -245.390988)
			(xy 343.909304 -245.343204) (xy 343.905344 -245.29415) (xy 343.586816 -245.29415) (xy 343.586304 -245.319596)
			(xy 343.57814 -245.36983) (xy 343.562024 -245.418104) (xy 343.538373 -245.463167) (xy 343.5078 -245.503853)
			(xy 343.471096 -245.539108) (xy 343.429212 -245.568018) (xy 343.383233 -245.589835) (xy 343.334349 -245.603995)
			(xy 343.283828 -245.610129) (xy 343.232976 -245.60808) (xy 343.183112 -245.5979) (xy 343.135526 -245.579853)
			(xy 343.091452 -245.554407) (xy 343.05203 -245.52222) (xy 343.018282 -245.484126) (xy 342.991081 -245.441112)
			(xy 342.971133 -245.394292) (xy 342.958954 -245.344878) (xy 342.954859 -245.29415) (xy 342.646762 -245.29415)
			(xy 342.64625 -245.319596) (xy 342.638086 -245.36983) (xy 342.62197 -245.418104) (xy 342.598319 -245.463167)
			(xy 342.567746 -245.503853) (xy 342.531042 -245.539108) (xy 342.489158 -245.568018) (xy 342.443179 -245.589835)
			(xy 342.394295 -245.603995) (xy 342.343774 -245.610129) (xy 342.292922 -245.60808) (xy 342.243058 -245.5979)
			(xy 342.195472 -245.579853) (xy 342.151398 -245.554407) (xy 342.111976 -245.52222) (xy 342.078228 -245.484126)
			(xy 342.051027 -245.441112) (xy 342.031079 -245.394292) (xy 342.0189 -245.344878) (xy 342.014805 -245.29415)
			(xy 341.696294 -245.29415) (xy 341.69582 -245.318138) (xy 341.688307 -245.365523) (xy 341.673475 -245.41115)
			(xy 341.651689 -245.453894) (xy 341.623484 -245.492705) (xy 341.589556 -245.526626) (xy 341.55074 -245.554822)
			(xy 341.50799 -245.5766) (xy 341.462361 -245.591422) (xy 341.414974 -245.598925) (xy 341.390986 -245.599458)
			(xy 341.376676 -245.599288) (xy 341.348182 -245.596614) (xy 341.33409 -245.594124) (xy 341.325454 -245.593362)
			(xy 341.316421 -245.593598) (xy 341.299387 -245.599593) (xy 341.29218 -245.605046) (xy 341.270844 -245.622826)
			(xy 341.233506 -245.653814) (xy 341.225253 -245.661418) (xy 341.21576 -245.681721) (xy 341.215218 -245.69293)
			(xy 341.215218 -246.022114) (xy 341.216742 -246.02821) (xy 341.221254 -246.046872) (xy 341.226095 -246.084959)
			(xy 341.226394 -246.104156) (xy 341.544905 -246.104156) (xy 341.549 -246.053428) (xy 341.561179 -246.004014)
			(xy 341.581127 -245.957194) (xy 341.608328 -245.91418) (xy 341.642076 -245.876086) (xy 341.681498 -245.843899)
			(xy 341.725572 -245.818453) (xy 341.773158 -245.800406) (xy 341.823022 -245.790226) (xy 341.873874 -245.788177)
			(xy 341.924395 -245.794311) (xy 341.973279 -245.808471) (xy 342.019258 -245.830288) (xy 342.061142 -245.859198)
			(xy 342.097846 -245.894453) (xy 342.128419 -245.935139) (xy 342.15207 -245.980202) (xy 342.168186 -246.028476)
			(xy 342.17635 -246.07871) (xy 342.176862 -246.104156) (xy 342.49539 -246.104156) (xy 342.49935 -246.055102)
			(xy 342.511127 -246.007318) (xy 342.530418 -245.962042) (xy 342.556721 -245.920446) (xy 342.589356 -245.883609)
			(xy 342.627477 -245.852484) (xy 342.670098 -245.827877) (xy 342.716114 -245.810425) (xy 342.764333 -245.800581)
			(xy 342.813508 -245.7986) (xy 342.862363 -245.804532) (xy 342.909634 -245.818224) (xy 342.954096 -245.839322)
			(xy 342.994599 -245.867278) (xy 343.030092 -245.90137) (xy 343.059657 -245.940714) (xy 343.082528 -245.984291)
			(xy 343.098112 -246.030972) (xy 343.106007 -246.079549) (xy 343.106502 -246.104156) (xy 343.424759 -246.104156)
			(xy 343.428854 -246.053428) (xy 343.441033 -246.004014) (xy 343.460981 -245.957194) (xy 343.488182 -245.91418)
			(xy 343.52193 -245.876086) (xy 343.561352 -245.843899) (xy 343.605426 -245.818453) (xy 343.653012 -245.800406)
			(xy 343.702876 -245.790226) (xy 343.753728 -245.788177) (xy 343.804249 -245.794311) (xy 343.853133 -245.808471)
			(xy 343.899112 -245.830288) (xy 343.940996 -245.859198) (xy 343.9777 -245.894453) (xy 344.008273 -245.935139)
			(xy 344.031924 -245.980202) (xy 344.04804 -246.028476) (xy 344.056204 -246.07871) (xy 344.056716 -246.104156)
			(xy 344.375244 -246.104156) (xy 344.379204 -246.055102) (xy 344.390981 -246.007318) (xy 344.410272 -245.962042)
			(xy 344.436575 -245.920446) (xy 344.46921 -245.883609) (xy 344.507331 -245.852484) (xy 344.549952 -245.827877)
			(xy 344.595968 -245.810425) (xy 344.644187 -245.800581) (xy 344.693362 -245.7986) (xy 344.742217 -245.804532)
			(xy 344.789488 -245.818224) (xy 344.83395 -245.839322) (xy 344.874453 -245.867278) (xy 344.909946 -245.90137)
			(xy 344.939511 -245.940714) (xy 344.962382 -245.984291) (xy 344.977966 -246.030972) (xy 344.985861 -246.079549)
			(xy 344.986356 -246.104156) (xy 345.315298 -246.104156) (xy 345.319258 -246.055102) (xy 345.331035 -246.007318)
			(xy 345.350326 -245.962042) (xy 345.376629 -245.920446) (xy 345.409264 -245.883609) (xy 345.447385 -245.852484)
			(xy 345.490006 -245.827877) (xy 345.536022 -245.810425) (xy 345.584241 -245.800581) (xy 345.633416 -245.7986)
			(xy 345.682271 -245.804532) (xy 345.729542 -245.818224) (xy 345.774004 -245.839322) (xy 345.814507 -245.867278)
			(xy 345.85 -245.90137) (xy 345.879565 -245.940714) (xy 345.902436 -245.984291) (xy 345.91802 -246.030972)
			(xy 345.925915 -246.079549) (xy 345.92641 -246.104156) (xy 346.255352 -246.104156) (xy 346.259312 -246.055102)
			(xy 346.271089 -246.007318) (xy 346.29038 -245.962042) (xy 346.316683 -245.920446) (xy 346.349318 -245.883609)
			(xy 346.387439 -245.852484) (xy 346.43006 -245.827877) (xy 346.476076 -245.810425) (xy 346.524295 -245.800581)
			(xy 346.57347 -245.7986) (xy 346.622325 -245.804532) (xy 346.669596 -245.818224) (xy 346.714058 -245.839322)
			(xy 346.754561 -245.867278) (xy 346.790054 -245.90137) (xy 346.819619 -245.940714) (xy 346.84249 -245.984291)
			(xy 346.858074 -246.030972) (xy 346.865969 -246.079549) (xy 346.866464 -246.104156) (xy 347.195406 -246.104156)
			(xy 347.199366 -246.055102) (xy 347.211143 -246.007318) (xy 347.230434 -245.962042) (xy 347.256737 -245.920446)
			(xy 347.289372 -245.883609) (xy 347.327493 -245.852484) (xy 347.370114 -245.827877) (xy 347.41613 -245.810425)
			(xy 347.464349 -245.800581) (xy 347.513524 -245.7986) (xy 347.562379 -245.804532) (xy 347.60965 -245.818224)
			(xy 347.654112 -245.839322) (xy 347.694615 -245.867278) (xy 347.730108 -245.90137) (xy 347.759673 -245.940714)
			(xy 347.782544 -245.984291) (xy 347.798128 -246.030972) (xy 347.806023 -246.079549) (xy 347.806518 -246.104156)
			(xy 348.135206 -246.104156) (xy 348.139166 -246.055102) (xy 348.150943 -246.007318) (xy 348.170234 -245.962042)
			(xy 348.196537 -245.920446) (xy 348.229172 -245.883609) (xy 348.267293 -245.852484) (xy 348.309914 -245.827877)
			(xy 348.35593 -245.810425) (xy 348.404149 -245.800581) (xy 348.453324 -245.7986) (xy 348.502179 -245.804532)
			(xy 348.54945 -245.818224) (xy 348.593912 -245.839322) (xy 348.634415 -245.867278) (xy 348.669908 -245.90137)
			(xy 348.699473 -245.940714) (xy 348.722344 -245.984291) (xy 348.737928 -246.030972) (xy 348.745823 -246.079549)
			(xy 348.746318 -246.104156) (xy 349.07526 -246.104156) (xy 349.07922 -246.055102) (xy 349.090997 -246.007318)
			(xy 349.110288 -245.962042) (xy 349.136591 -245.920446) (xy 349.169226 -245.883609) (xy 349.207347 -245.852484)
			(xy 349.249968 -245.827877) (xy 349.295984 -245.810425) (xy 349.344203 -245.800581) (xy 349.393378 -245.7986)
			(xy 349.442233 -245.804532) (xy 349.489504 -245.818224) (xy 349.533966 -245.839322) (xy 349.574469 -245.867278)
			(xy 349.609962 -245.90137) (xy 349.639527 -245.940714) (xy 349.662398 -245.984291) (xy 349.677982 -246.030972)
			(xy 349.685877 -246.079549) (xy 349.686372 -246.104156) (xy 350.015314 -246.104156) (xy 350.019274 -246.055102)
			(xy 350.031051 -246.007318) (xy 350.050342 -245.962042) (xy 350.076645 -245.920446) (xy 350.10928 -245.883609)
			(xy 350.147401 -245.852484) (xy 350.190022 -245.827877) (xy 350.236038 -245.810425) (xy 350.284257 -245.800581)
			(xy 350.333432 -245.7986) (xy 350.382287 -245.804532) (xy 350.429558 -245.818224) (xy 350.47402 -245.839322)
			(xy 350.514523 -245.867278) (xy 350.550016 -245.90137) (xy 350.579581 -245.940714) (xy 350.602452 -245.984291)
			(xy 350.618036 -246.030972) (xy 350.625931 -246.079549) (xy 350.626426 -246.104156) (xy 350.955368 -246.104156)
			(xy 350.959328 -246.055102) (xy 350.971105 -246.007318) (xy 350.990396 -245.962042) (xy 351.016699 -245.920446)
			(xy 351.049334 -245.883609) (xy 351.087455 -245.852484) (xy 351.130076 -245.827877) (xy 351.176092 -245.810425)
			(xy 351.224311 -245.800581) (xy 351.273486 -245.7986) (xy 351.322341 -245.804532) (xy 351.369612 -245.818224)
			(xy 351.414074 -245.839322) (xy 351.454577 -245.867278) (xy 351.49007 -245.90137) (xy 351.519635 -245.940714)
			(xy 351.542506 -245.984291) (xy 351.55809 -246.030972) (xy 351.565985 -246.079549) (xy 351.56648 -246.104156)
			(xy 351.895422 -246.104156) (xy 351.899382 -246.055102) (xy 351.911159 -246.007318) (xy 351.93045 -245.962042)
			(xy 351.956753 -245.920446) (xy 351.989388 -245.883609) (xy 352.027509 -245.852484) (xy 352.07013 -245.827877)
			(xy 352.116146 -245.810425) (xy 352.164365 -245.800581) (xy 352.21354 -245.7986) (xy 352.262395 -245.804532)
			(xy 352.309666 -245.818224) (xy 352.354128 -245.839322) (xy 352.394631 -245.867278) (xy 352.430124 -245.90137)
			(xy 352.459689 -245.940714) (xy 352.48256 -245.984291) (xy 352.498144 -246.030972) (xy 352.506039 -246.079549)
			(xy 352.506534 -246.104156) (xy 352.835222 -246.104156) (xy 352.839182 -246.055102) (xy 352.850959 -246.007318)
			(xy 352.87025 -245.962042) (xy 352.896553 -245.920446) (xy 352.929188 -245.883609) (xy 352.967309 -245.852484)
			(xy 353.00993 -245.827877) (xy 353.055946 -245.810425) (xy 353.104165 -245.800581) (xy 353.15334 -245.7986)
			(xy 353.202195 -245.804532) (xy 353.249466 -245.818224) (xy 353.293928 -245.839322) (xy 353.334431 -245.867278)
			(xy 353.369924 -245.90137) (xy 353.399489 -245.940714) (xy 353.42236 -245.984291) (xy 353.437944 -246.030972)
			(xy 353.445839 -246.079549) (xy 353.446334 -246.104156) (xy 353.775276 -246.104156) (xy 353.779236 -246.055102)
			(xy 353.791013 -246.007318) (xy 353.810304 -245.962042) (xy 353.836607 -245.920446) (xy 353.869242 -245.883609)
			(xy 353.907363 -245.852484) (xy 353.949984 -245.827877) (xy 353.996 -245.810425) (xy 354.044219 -245.800581)
			(xy 354.093394 -245.7986) (xy 354.142249 -245.804532) (xy 354.18952 -245.818224) (xy 354.233982 -245.839322)
			(xy 354.274485 -245.867278) (xy 354.309978 -245.90137) (xy 354.339543 -245.940714) (xy 354.362414 -245.984291)
			(xy 354.377998 -246.030972) (xy 354.385893 -246.079549) (xy 354.386388 -246.104156) (xy 354.71533 -246.104156)
			(xy 354.71929 -246.055102) (xy 354.731067 -246.007318) (xy 354.750358 -245.962042) (xy 354.776661 -245.920446)
			(xy 354.809296 -245.883609) (xy 354.847417 -245.852484) (xy 354.890038 -245.827877) (xy 354.936054 -245.810425)
			(xy 354.984273 -245.800581) (xy 355.033448 -245.7986) (xy 355.082303 -245.804532) (xy 355.129574 -245.818224)
			(xy 355.174036 -245.839322) (xy 355.214539 -245.867278) (xy 355.250032 -245.90137) (xy 355.279597 -245.940714)
			(xy 355.302468 -245.984291) (xy 355.318052 -246.030972) (xy 355.325947 -246.079549) (xy 355.326442 -246.104156)
			(xy 355.655384 -246.104156) (xy 355.659344 -246.055102) (xy 355.671121 -246.007318) (xy 355.690412 -245.962042)
			(xy 355.716715 -245.920446) (xy 355.74935 -245.883609) (xy 355.787471 -245.852484) (xy 355.830092 -245.827877)
			(xy 355.876108 -245.810425) (xy 355.924327 -245.800581) (xy 355.973502 -245.7986) (xy 356.022357 -245.804532)
			(xy 356.069628 -245.818224) (xy 356.11409 -245.839322) (xy 356.154593 -245.867278) (xy 356.190086 -245.90137)
			(xy 356.219651 -245.940714) (xy 356.242522 -245.984291) (xy 356.258106 -246.030972) (xy 356.266001 -246.079549)
			(xy 356.266496 -246.104156) (xy 363.168958 -246.104156) (xy 363.172918 -246.055102) (xy 363.184695 -246.007318)
			(xy 363.203986 -245.962042) (xy 363.230289 -245.920446) (xy 363.262924 -245.883609) (xy 363.301045 -245.852484)
			(xy 363.343666 -245.827877) (xy 363.389682 -245.810425) (xy 363.437901 -245.800581) (xy 363.487076 -245.7986)
			(xy 363.535931 -245.804532) (xy 363.583202 -245.818224) (xy 363.627664 -245.839322) (xy 363.668167 -245.867278)
			(xy 363.70366 -245.90137) (xy 363.733225 -245.940714) (xy 363.756096 -245.984291) (xy 363.77168 -246.030972)
			(xy 363.779575 -246.079549) (xy 363.78007 -246.104156) (xy 363.780069 -246.1042) (xy 364.108896 -246.1042)
			(xy 364.113068 -246.053848) (xy 364.125472 -246.00487) (xy 364.145768 -245.958601) (xy 364.173403 -245.916305)
			(xy 364.207623 -245.879133) (xy 364.247495 -245.848102) (xy 364.291931 -245.824057) (xy 364.339718 -245.807653)
			(xy 364.389554 -245.79934) (xy 364.414816 -245.798848) (xy 365.35487 -245.798848) (xy 365.380126 -245.799426)
			(xy 365.429949 -245.807736) (xy 365.477725 -245.824133) (xy 365.52215 -245.848171) (xy 365.562012 -245.879193)
			(xy 365.596224 -245.916354) (xy 365.623853 -245.958639) (xy 365.644144 -246.004896) (xy 365.656545 -246.053861)
			(xy 365.660712 -246.104156) (xy 365.98912 -246.104156) (xy 365.99308 -246.055102) (xy 366.004857 -246.007318)
			(xy 366.024148 -245.962042) (xy 366.050451 -245.920446) (xy 366.083086 -245.883609) (xy 366.121207 -245.852484)
			(xy 366.163828 -245.827877) (xy 366.209844 -245.810425) (xy 366.258063 -245.800581) (xy 366.307238 -245.7986)
			(xy 366.356093 -245.804532) (xy 366.403364 -245.818224) (xy 366.447826 -245.839322) (xy 366.488329 -245.867278)
			(xy 366.523822 -245.90137) (xy 366.553387 -245.940714) (xy 366.576258 -245.984291) (xy 366.591842 -246.030972)
			(xy 366.599737 -246.079549) (xy 366.600232 -246.104156) (xy 366.600231 -246.1042) (xy 366.928796 -246.1042)
			(xy 366.932969 -246.053847) (xy 366.945372 -246.004868) (xy 366.965669 -245.958599) (xy 366.993305 -245.916302)
			(xy 367.027526 -245.879131) (xy 367.067399 -245.848099) (xy 367.111836 -245.824054) (xy 367.159625 -245.807652)
			(xy 367.209461 -245.799339) (xy 367.234724 -245.798848) (xy 368.174778 -245.798848) (xy 368.200033 -245.799427)
			(xy 368.249855 -245.807737) (xy 368.29763 -245.824135) (xy 368.342054 -245.848173) (xy 368.381915 -245.879196)
			(xy 368.416126 -245.916357) (xy 368.443754 -245.958642) (xy 368.464045 -246.004897) (xy 368.476445 -246.053862)
			(xy 368.480612 -246.104156) (xy 368.809028 -246.104156) (xy 368.812988 -246.055102) (xy 368.824765 -246.007318)
			(xy 368.844056 -245.962042) (xy 368.870359 -245.920446) (xy 368.902994 -245.883609) (xy 368.941115 -245.852484)
			(xy 368.983736 -245.827877) (xy 369.029752 -245.810425) (xy 369.077971 -245.800581) (xy 369.127146 -245.7986)
			(xy 369.176001 -245.804532) (xy 369.223272 -245.818224) (xy 369.267734 -245.839322) (xy 369.308237 -245.867278)
			(xy 369.34373 -245.90137) (xy 369.373295 -245.940714) (xy 369.396166 -245.984291) (xy 369.41175 -246.030972)
			(xy 369.419645 -246.079549) (xy 369.42014 -246.104156) (xy 369.420139 -246.1042) (xy 369.749024 -246.1042)
			(xy 369.753196 -246.053856) (xy 369.765597 -246.004885) (xy 369.785888 -245.958623) (xy 369.813518 -245.916332)
			(xy 369.847731 -245.879165) (xy 369.887595 -245.848136) (xy 369.932022 -245.824092) (xy 369.979801 -245.807687)
			(xy 370.029628 -245.79937) (xy 370.054886 -245.798848) (xy 370.99494 -245.798848) (xy 371.02019 -245.799461)
			(xy 371.069999 -245.807778) (xy 371.11776 -245.82418) (xy 371.162171 -245.848219) (xy 371.202019 -245.879239)
			(xy 371.236219 -245.916395) (xy 371.263838 -245.958673) (xy 371.284121 -246.004919) (xy 371.296517 -246.053873)
			(xy 371.300683 -246.104156) (xy 371.628936 -246.104156) (xy 371.632896 -246.055102) (xy 371.644673 -246.007318)
			(xy 371.663964 -245.962042) (xy 371.690267 -245.920446) (xy 371.722902 -245.883609) (xy 371.761023 -245.852484)
			(xy 371.803644 -245.827877) (xy 371.84966 -245.810425) (xy 371.897879 -245.800581) (xy 371.947054 -245.7986)
			(xy 371.995909 -245.804532) (xy 372.04318 -245.818224) (xy 372.087642 -245.839322) (xy 372.128145 -245.867278)
			(xy 372.163638 -245.90137) (xy 372.193203 -245.940714) (xy 372.216074 -245.984291) (xy 372.231658 -246.030972)
			(xy 372.239553 -246.079549) (xy 372.240048 -246.104156) (xy 372.240047 -246.1042) (xy 372.568924 -246.1042)
			(xy 372.573096 -246.053855) (xy 372.585497 -246.004884) (xy 372.60579 -245.958621) (xy 372.63342 -245.916329)
			(xy 372.667634 -245.879162) (xy 372.707499 -245.848133) (xy 372.751927 -245.824089) (xy 372.799707 -245.807685)
			(xy 372.849535 -245.79937) (xy 372.874794 -245.798848) (xy 373.814848 -245.798848) (xy 373.840097 -245.799461)
			(xy 373.889906 -245.80778) (xy 373.937666 -245.824183) (xy 373.982075 -245.848222) (xy 374.021923 -245.879242)
			(xy 374.056121 -245.916398) (xy 374.083739 -245.958675) (xy 374.104022 -246.004921) (xy 374.116417 -246.053874)
			(xy 374.120583 -246.104156) (xy 374.449098 -246.104156) (xy 374.453058 -246.055102) (xy 374.464835 -246.007318)
			(xy 374.484126 -245.962042) (xy 374.510429 -245.920446) (xy 374.543064 -245.883609) (xy 374.581185 -245.852484)
			(xy 374.623806 -245.827877) (xy 374.669822 -245.810425) (xy 374.718041 -245.800581) (xy 374.767216 -245.7986)
			(xy 374.816071 -245.804532) (xy 374.863342 -245.818224) (xy 374.907804 -245.839322) (xy 374.948307 -245.867278)
			(xy 374.9838 -245.90137) (xy 375.013365 -245.940714) (xy 375.036236 -245.984291) (xy 375.05182 -246.030972)
			(xy 375.059715 -246.079549) (xy 375.06021 -246.104156) (xy 375.378467 -246.104156) (xy 375.382562 -246.053428)
			(xy 375.394741 -246.004014) (xy 375.414689 -245.957194) (xy 375.44189 -245.91418) (xy 375.475638 -245.876086)
			(xy 375.51506 -245.843899) (xy 375.559134 -245.818453) (xy 375.60672 -245.800406) (xy 375.656584 -245.790226)
			(xy 375.707436 -245.788177) (xy 375.757957 -245.794311) (xy 375.806841 -245.808471) (xy 375.85282 -245.830288)
			(xy 375.894704 -245.859198) (xy 375.931408 -245.894453) (xy 375.961981 -245.935139) (xy 375.985632 -245.980202)
			(xy 376.001748 -246.028476) (xy 376.009912 -246.07871) (xy 376.010424 -246.104156) (xy 376.328952 -246.104156)
			(xy 376.332912 -246.055102) (xy 376.344689 -246.007318) (xy 376.36398 -245.962042) (xy 376.390283 -245.920446)
			(xy 376.422918 -245.883609) (xy 376.461039 -245.852484) (xy 376.50366 -245.827877) (xy 376.549676 -245.810425)
			(xy 376.597895 -245.800581) (xy 376.64707 -245.7986) (xy 376.695925 -245.804532) (xy 376.743196 -245.818224)
			(xy 376.787658 -245.839322) (xy 376.828161 -245.867278) (xy 376.863654 -245.90137) (xy 376.893219 -245.940714)
			(xy 376.91609 -245.984291) (xy 376.931674 -246.030972) (xy 376.939569 -246.079549) (xy 376.940064 -246.104156)
			(xy 376.939569 -246.128763) (xy 376.931674 -246.17734) (xy 376.91609 -246.224021) (xy 376.893219 -246.267598)
			(xy 376.863654 -246.306942) (xy 376.828161 -246.341034) (xy 376.787658 -246.36899) (xy 376.743196 -246.390088)
			(xy 376.695925 -246.40378) (xy 376.64707 -246.409712) (xy 376.597895 -246.407731) (xy 376.549676 -246.397887)
			(xy 376.50366 -246.380435) (xy 376.461039 -246.355828) (xy 376.422918 -246.324703) (xy 376.390283 -246.287866)
			(xy 376.36398 -246.24627) (xy 376.344689 -246.200994) (xy 376.332912 -246.15321) (xy 376.328952 -246.104156)
			(xy 376.010424 -246.104156) (xy 376.009912 -246.129602) (xy 376.001748 -246.179836) (xy 375.985632 -246.22811)
			(xy 375.961981 -246.273173) (xy 375.931408 -246.313859) (xy 375.894704 -246.349114) (xy 375.85282 -246.378024)
			(xy 375.806841 -246.399841) (xy 375.757957 -246.414001) (xy 375.707436 -246.420135) (xy 375.656584 -246.418086)
			(xy 375.60672 -246.407906) (xy 375.559134 -246.389859) (xy 375.51506 -246.364413) (xy 375.475638 -246.332226)
			(xy 375.44189 -246.294132) (xy 375.414689 -246.251118) (xy 375.394741 -246.204298) (xy 375.382562 -246.154884)
			(xy 375.378467 -246.104156) (xy 375.06021 -246.104156) (xy 375.059715 -246.128763) (xy 375.05182 -246.17734)
			(xy 375.036236 -246.224021) (xy 375.013365 -246.267598) (xy 374.9838 -246.306942) (xy 374.948307 -246.341034)
			(xy 374.907804 -246.36899) (xy 374.863342 -246.390088) (xy 374.816071 -246.40378) (xy 374.767216 -246.409712)
			(xy 374.718041 -246.407731) (xy 374.669822 -246.397887) (xy 374.623806 -246.380435) (xy 374.581185 -246.355828)
			(xy 374.543064 -246.324703) (xy 374.510429 -246.287866) (xy 374.484126 -246.24627) (xy 374.464835 -246.200994)
			(xy 374.453058 -246.15321) (xy 374.449098 -246.104156) (xy 374.120583 -246.104156) (xy 374.120587 -246.1042)
			(xy 374.116417 -246.154526) (xy 374.104022 -246.203479) (xy 374.083739 -246.249725) (xy 374.056121 -246.292002)
			(xy 374.021923 -246.329158) (xy 373.982075 -246.360178) (xy 373.937666 -246.384217) (xy 373.889906 -246.40062)
			(xy 373.840097 -246.408939) (xy 373.814848 -246.409464) (xy 372.874794 -246.409464) (xy 372.849535 -246.40903)
			(xy 372.799707 -246.400715) (xy 372.751927 -246.384311) (xy 372.707499 -246.360267) (xy 372.667634 -246.329238)
			(xy 372.63342 -246.292071) (xy 372.60579 -246.249779) (xy 372.585497 -246.203516) (xy 372.573096 -246.154545)
			(xy 372.568924 -246.1042) (xy 372.240047 -246.1042) (xy 372.239553 -246.128763) (xy 372.231658 -246.17734)
			(xy 372.216074 -246.224021) (xy 372.193203 -246.267598) (xy 372.163638 -246.306942) (xy 372.128145 -246.341034)
			(xy 372.087642 -246.36899) (xy 372.04318 -246.390088) (xy 371.995909 -246.40378) (xy 371.947054 -246.409712)
			(xy 371.897879 -246.407731) (xy 371.84966 -246.397887) (xy 371.803644 -246.380435) (xy 371.761023 -246.355828)
			(xy 371.722902 -246.324703) (xy 371.690267 -246.287866) (xy 371.663964 -246.24627) (xy 371.644673 -246.200994)
			(xy 371.632896 -246.15321) (xy 371.628936 -246.104156) (xy 371.300683 -246.104156) (xy 371.300687 -246.1042)
			(xy 371.296517 -246.154527) (xy 371.284121 -246.203481) (xy 371.263838 -246.249727) (xy 371.236219 -246.292005)
			(xy 371.202019 -246.329161) (xy 371.162171 -246.360181) (xy 371.11776 -246.38422) (xy 371.069999 -246.400622)
			(xy 371.02019 -246.408939) (xy 370.99494 -246.409464) (xy 370.054886 -246.409464) (xy 370.029628 -246.40903)
			(xy 369.979801 -246.400713) (xy 369.932022 -246.384308) (xy 369.887595 -246.360264) (xy 369.847731 -246.329235)
			(xy 369.813518 -246.292068) (xy 369.785888 -246.249777) (xy 369.765597 -246.203515) (xy 369.753196 -246.154544)
			(xy 369.749024 -246.1042) (xy 369.420139 -246.1042) (xy 369.419645 -246.128763) (xy 369.41175 -246.17734)
			(xy 369.396166 -246.224021) (xy 369.373295 -246.267598) (xy 369.34373 -246.306942) (xy 369.308237 -246.341034)
			(xy 369.267734 -246.36899) (xy 369.223272 -246.390088) (xy 369.176001 -246.40378) (xy 369.127146 -246.409712)
			(xy 369.077971 -246.407731) (xy 369.029752 -246.397887) (xy 368.983736 -246.380435) (xy 368.941115 -246.355828)
			(xy 368.902994 -246.324703) (xy 368.870359 -246.287866) (xy 368.844056 -246.24627) (xy 368.824765 -246.200994)
			(xy 368.812988 -246.15321) (xy 368.809028 -246.104156) (xy 368.480612 -246.104156) (xy 368.480616 -246.1042)
			(xy 368.476445 -246.154538) (xy 368.464045 -246.203503) (xy 368.443754 -246.249758) (xy 368.416126 -246.292043)
			(xy 368.381915 -246.329204) (xy 368.342054 -246.360227) (xy 368.29763 -246.384265) (xy 368.249855 -246.400663)
			(xy 368.200033 -246.408973) (xy 368.174778 -246.409464) (xy 367.234724 -246.409464) (xy 367.209461 -246.409061)
			(xy 367.159625 -246.400748) (xy 367.111836 -246.384346) (xy 367.067399 -246.360301) (xy 367.027526 -246.329269)
			(xy 366.993305 -246.292098) (xy 366.965669 -246.249801) (xy 366.945372 -246.203532) (xy 366.932969 -246.154553)
			(xy 366.928796 -246.1042) (xy 366.600231 -246.1042) (xy 366.599737 -246.128763) (xy 366.591842 -246.17734)
			(xy 366.576258 -246.224021) (xy 366.553387 -246.267598) (xy 366.523822 -246.306942) (xy 366.488329 -246.341034)
			(xy 366.447826 -246.36899) (xy 366.403364 -246.390088) (xy 366.356093 -246.40378) (xy 366.307238 -246.409712)
			(xy 366.258063 -246.407731) (xy 366.209844 -246.397887) (xy 366.163828 -246.380435) (xy 366.121207 -246.355828)
			(xy 366.083086 -246.324703) (xy 366.050451 -246.287866) (xy 366.024148 -246.24627) (xy 366.004857 -246.200994)
			(xy 365.99308 -246.15321) (xy 365.98912 -246.104156) (xy 365.660712 -246.104156) (xy 365.660716 -246.1042)
			(xy 365.656545 -246.154539) (xy 365.644144 -246.203504) (xy 365.623853 -246.249761) (xy 365.596224 -246.292046)
			(xy 365.562012 -246.329207) (xy 365.52215 -246.360229) (xy 365.477725 -246.384267) (xy 365.429949 -246.400664)
			(xy 365.380126 -246.408974) (xy 365.35487 -246.409464) (xy 364.414816 -246.409464) (xy 364.389554 -246.40906)
			(xy 364.339718 -246.400747) (xy 364.291931 -246.384343) (xy 364.247495 -246.360298) (xy 364.207623 -246.329267)
			(xy 364.173403 -246.292095) (xy 364.145768 -246.249799) (xy 364.125472 -246.20353) (xy 364.113068 -246.154552)
			(xy 364.108896 -246.1042) (xy 363.780069 -246.1042) (xy 363.779575 -246.128763) (xy 363.77168 -246.17734)
			(xy 363.756096 -246.224021) (xy 363.733225 -246.267598) (xy 363.70366 -246.306942) (xy 363.668167 -246.341034)
			(xy 363.627664 -246.36899) (xy 363.583202 -246.390088) (xy 363.535931 -246.40378) (xy 363.487076 -246.409712)
			(xy 363.437901 -246.407731) (xy 363.389682 -246.397887) (xy 363.343666 -246.380435) (xy 363.301045 -246.355828)
			(xy 363.262924 -246.324703) (xy 363.230289 -246.287866) (xy 363.203986 -246.24627) (xy 363.184695 -246.200994)
			(xy 363.172918 -246.15321) (xy 363.168958 -246.104156) (xy 356.266496 -246.104156) (xy 356.266001 -246.128763)
			(xy 356.258106 -246.17734) (xy 356.242522 -246.224021) (xy 356.219651 -246.267598) (xy 356.190086 -246.306942)
			(xy 356.154593 -246.341034) (xy 356.11409 -246.36899) (xy 356.069628 -246.390088) (xy 356.022357 -246.40378)
			(xy 355.973502 -246.409712) (xy 355.924327 -246.407731) (xy 355.876108 -246.397887) (xy 355.830092 -246.380435)
			(xy 355.787471 -246.355828) (xy 355.74935 -246.324703) (xy 355.716715 -246.287866) (xy 355.690412 -246.24627)
			(xy 355.671121 -246.200994) (xy 355.659344 -246.15321) (xy 355.655384 -246.104156) (xy 355.326442 -246.104156)
			(xy 355.325947 -246.128763) (xy 355.318052 -246.17734) (xy 355.302468 -246.224021) (xy 355.279597 -246.267598)
			(xy 355.250032 -246.306942) (xy 355.214539 -246.341034) (xy 355.174036 -246.36899) (xy 355.129574 -246.390088)
			(xy 355.082303 -246.40378) (xy 355.033448 -246.409712) (xy 354.984273 -246.407731) (xy 354.936054 -246.397887)
			(xy 354.890038 -246.380435) (xy 354.847417 -246.355828) (xy 354.809296 -246.324703) (xy 354.776661 -246.287866)
			(xy 354.750358 -246.24627) (xy 354.731067 -246.200994) (xy 354.71929 -246.15321) (xy 354.71533 -246.104156)
			(xy 354.386388 -246.104156) (xy 354.385893 -246.128763) (xy 354.377998 -246.17734) (xy 354.362414 -246.224021)
			(xy 354.339543 -246.267598) (xy 354.309978 -246.306942) (xy 354.274485 -246.341034) (xy 354.233982 -246.36899)
			(xy 354.18952 -246.390088) (xy 354.142249 -246.40378) (xy 354.093394 -246.409712) (xy 354.044219 -246.407731)
			(xy 353.996 -246.397887) (xy 353.949984 -246.380435) (xy 353.907363 -246.355828) (xy 353.869242 -246.324703)
			(xy 353.836607 -246.287866) (xy 353.810304 -246.24627) (xy 353.791013 -246.200994) (xy 353.779236 -246.15321)
			(xy 353.775276 -246.104156) (xy 353.446334 -246.104156) (xy 353.445839 -246.128763) (xy 353.437944 -246.17734)
			(xy 353.42236 -246.224021) (xy 353.399489 -246.267598) (xy 353.369924 -246.306942) (xy 353.334431 -246.341034)
			(xy 353.293928 -246.36899) (xy 353.249466 -246.390088) (xy 353.202195 -246.40378) (xy 353.15334 -246.409712)
			(xy 353.104165 -246.407731) (xy 353.055946 -246.397887) (xy 353.00993 -246.380435) (xy 352.967309 -246.355828)
			(xy 352.929188 -246.324703) (xy 352.896553 -246.287866) (xy 352.87025 -246.24627) (xy 352.850959 -246.200994)
			(xy 352.839182 -246.15321) (xy 352.835222 -246.104156) (xy 352.506534 -246.104156) (xy 352.506039 -246.128763)
			(xy 352.498144 -246.17734) (xy 352.48256 -246.224021) (xy 352.459689 -246.267598) (xy 352.430124 -246.306942)
			(xy 352.394631 -246.341034) (xy 352.354128 -246.36899) (xy 352.309666 -246.390088) (xy 352.262395 -246.40378)
			(xy 352.21354 -246.409712) (xy 352.164365 -246.407731) (xy 352.116146 -246.397887) (xy 352.07013 -246.380435)
			(xy 352.027509 -246.355828) (xy 351.989388 -246.324703) (xy 351.956753 -246.287866) (xy 351.93045 -246.24627)
			(xy 351.911159 -246.200994) (xy 351.899382 -246.15321) (xy 351.895422 -246.104156) (xy 351.56648 -246.104156)
			(xy 351.565985 -246.128763) (xy 351.55809 -246.17734) (xy 351.542506 -246.224021) (xy 351.519635 -246.267598)
			(xy 351.49007 -246.306942) (xy 351.454577 -246.341034) (xy 351.414074 -246.36899) (xy 351.369612 -246.390088)
			(xy 351.322341 -246.40378) (xy 351.273486 -246.409712) (xy 351.224311 -246.407731) (xy 351.176092 -246.397887)
			(xy 351.130076 -246.380435) (xy 351.087455 -246.355828) (xy 351.049334 -246.324703) (xy 351.016699 -246.287866)
			(xy 350.990396 -246.24627) (xy 350.971105 -246.200994) (xy 350.959328 -246.15321) (xy 350.955368 -246.104156)
			(xy 350.626426 -246.104156) (xy 350.625931 -246.128763) (xy 350.618036 -246.17734) (xy 350.602452 -246.224021)
			(xy 350.579581 -246.267598) (xy 350.550016 -246.306942) (xy 350.514523 -246.341034) (xy 350.47402 -246.36899)
			(xy 350.429558 -246.390088) (xy 350.382287 -246.40378) (xy 350.333432 -246.409712) (xy 350.284257 -246.407731)
			(xy 350.236038 -246.397887) (xy 350.190022 -246.380435) (xy 350.147401 -246.355828) (xy 350.10928 -246.324703)
			(xy 350.076645 -246.287866) (xy 350.050342 -246.24627) (xy 350.031051 -246.200994) (xy 350.019274 -246.15321)
			(xy 350.015314 -246.104156) (xy 349.686372 -246.104156) (xy 349.685877 -246.128763) (xy 349.677982 -246.17734)
			(xy 349.662398 -246.224021) (xy 349.639527 -246.267598) (xy 349.609962 -246.306942) (xy 349.574469 -246.341034)
			(xy 349.533966 -246.36899) (xy 349.489504 -246.390088) (xy 349.442233 -246.40378) (xy 349.393378 -246.409712)
			(xy 349.344203 -246.407731) (xy 349.295984 -246.397887) (xy 349.249968 -246.380435) (xy 349.207347 -246.355828)
			(xy 349.169226 -246.324703) (xy 349.136591 -246.287866) (xy 349.110288 -246.24627) (xy 349.090997 -246.200994)
			(xy 349.07922 -246.15321) (xy 349.07526 -246.104156) (xy 348.746318 -246.104156) (xy 348.745823 -246.128763)
			(xy 348.737928 -246.17734) (xy 348.722344 -246.224021) (xy 348.699473 -246.267598) (xy 348.669908 -246.306942)
			(xy 348.634415 -246.341034) (xy 348.593912 -246.36899) (xy 348.54945 -246.390088) (xy 348.502179 -246.40378)
			(xy 348.453324 -246.409712) (xy 348.404149 -246.407731) (xy 348.35593 -246.397887) (xy 348.309914 -246.380435)
			(xy 348.267293 -246.355828) (xy 348.229172 -246.324703) (xy 348.196537 -246.287866) (xy 348.170234 -246.24627)
			(xy 348.150943 -246.200994) (xy 348.139166 -246.15321) (xy 348.135206 -246.104156) (xy 347.806518 -246.104156)
			(xy 347.806023 -246.128763) (xy 347.798128 -246.17734) (xy 347.782544 -246.224021) (xy 347.759673 -246.267598)
			(xy 347.730108 -246.306942) (xy 347.694615 -246.341034) (xy 347.654112 -246.36899) (xy 347.60965 -246.390088)
			(xy 347.562379 -246.40378) (xy 347.513524 -246.409712) (xy 347.464349 -246.407731) (xy 347.41613 -246.397887)
			(xy 347.370114 -246.380435) (xy 347.327493 -246.355828) (xy 347.289372 -246.324703) (xy 347.256737 -246.287866)
			(xy 347.230434 -246.24627) (xy 347.211143 -246.200994) (xy 347.199366 -246.15321) (xy 347.195406 -246.104156)
			(xy 346.866464 -246.104156) (xy 346.865969 -246.128763) (xy 346.858074 -246.17734) (xy 346.84249 -246.224021)
			(xy 346.819619 -246.267598) (xy 346.790054 -246.306942) (xy 346.754561 -246.341034) (xy 346.714058 -246.36899)
			(xy 346.669596 -246.390088) (xy 346.622325 -246.40378) (xy 346.57347 -246.409712) (xy 346.524295 -246.407731)
			(xy 346.476076 -246.397887) (xy 346.43006 -246.380435) (xy 346.387439 -246.355828) (xy 346.349318 -246.324703)
			(xy 346.316683 -246.287866) (xy 346.29038 -246.24627) (xy 346.271089 -246.200994) (xy 346.259312 -246.15321)
			(xy 346.255352 -246.104156) (xy 345.92641 -246.104156) (xy 345.925915 -246.128763) (xy 345.91802 -246.17734)
			(xy 345.902436 -246.224021) (xy 345.879565 -246.267598) (xy 345.85 -246.306942) (xy 345.814507 -246.341034)
			(xy 345.774004 -246.36899) (xy 345.729542 -246.390088) (xy 345.682271 -246.40378) (xy 345.633416 -246.409712)
			(xy 345.584241 -246.407731) (xy 345.536022 -246.397887) (xy 345.490006 -246.380435) (xy 345.447385 -246.355828)
			(xy 345.409264 -246.324703) (xy 345.376629 -246.287866) (xy 345.350326 -246.24627) (xy 345.331035 -246.200994)
			(xy 345.319258 -246.15321) (xy 345.315298 -246.104156) (xy 344.986356 -246.104156) (xy 344.985861 -246.128763)
			(xy 344.977966 -246.17734) (xy 344.962382 -246.224021) (xy 344.939511 -246.267598) (xy 344.909946 -246.306942)
			(xy 344.874453 -246.341034) (xy 344.83395 -246.36899) (xy 344.789488 -246.390088) (xy 344.742217 -246.40378)
			(xy 344.693362 -246.409712) (xy 344.644187 -246.407731) (xy 344.595968 -246.397887) (xy 344.549952 -246.380435)
			(xy 344.507331 -246.355828) (xy 344.46921 -246.324703) (xy 344.436575 -246.287866) (xy 344.410272 -246.24627)
			(xy 344.390981 -246.200994) (xy 344.379204 -246.15321) (xy 344.375244 -246.104156) (xy 344.056716 -246.104156)
			(xy 344.056204 -246.129602) (xy 344.04804 -246.179836) (xy 344.031924 -246.22811) (xy 344.008273 -246.273173)
			(xy 343.9777 -246.313859) (xy 343.940996 -246.349114) (xy 343.899112 -246.378024) (xy 343.853133 -246.399841)
			(xy 343.804249 -246.414001) (xy 343.753728 -246.420135) (xy 343.702876 -246.418086) (xy 343.653012 -246.407906)
			(xy 343.605426 -246.389859) (xy 343.561352 -246.364413) (xy 343.52193 -246.332226) (xy 343.488182 -246.294132)
			(xy 343.460981 -246.251118) (xy 343.441033 -246.204298) (xy 343.428854 -246.154884) (xy 343.424759 -246.104156)
			(xy 343.106502 -246.104156) (xy 343.106007 -246.128763) (xy 343.098112 -246.17734) (xy 343.082528 -246.224021)
			(xy 343.059657 -246.267598) (xy 343.030092 -246.306942) (xy 342.994599 -246.341034) (xy 342.954096 -246.36899)
			(xy 342.909634 -246.390088) (xy 342.862363 -246.40378) (xy 342.813508 -246.409712) (xy 342.764333 -246.407731)
			(xy 342.716114 -246.397887) (xy 342.670098 -246.380435) (xy 342.627477 -246.355828) (xy 342.589356 -246.324703)
			(xy 342.556721 -246.287866) (xy 342.530418 -246.24627) (xy 342.511127 -246.200994) (xy 342.49935 -246.15321)
			(xy 342.49539 -246.104156) (xy 342.176862 -246.104156) (xy 342.17635 -246.129602) (xy 342.168186 -246.179836)
			(xy 342.15207 -246.22811) (xy 342.128419 -246.273173) (xy 342.097846 -246.313859) (xy 342.061142 -246.349114)
			(xy 342.019258 -246.378024) (xy 341.973279 -246.399841) (xy 341.924395 -246.414001) (xy 341.873874 -246.420135)
			(xy 341.823022 -246.418086) (xy 341.773158 -246.407906) (xy 341.725572 -246.389859) (xy 341.681498 -246.364413)
			(xy 341.642076 -246.332226) (xy 341.608328 -246.294132) (xy 341.581127 -246.251118) (xy 341.561179 -246.204298)
			(xy 341.549 -246.154884) (xy 341.544905 -246.104156) (xy 341.226394 -246.104156) (xy 341.226078 -246.123352)
			(xy 341.221242 -246.161438) (xy 341.216742 -246.180102) (xy 341.215218 -246.186198) (xy 341.215218 -246.515382)
			(xy 341.215802 -246.52658) (xy 341.225284 -246.546873) (xy 341.233506 -246.554498) (xy 341.270844 -246.585486)
			(xy 341.29218 -246.603266) (xy 341.299356 -246.608777) (xy 341.316409 -246.614783) (xy 341.325454 -246.61495)
			(xy 341.330026 -246.61495) (xy 341.345103 -246.612087) (xy 341.375641 -246.609036) (xy 341.390986 -246.608854)
			(xy 341.393018 -246.608854) (xy 341.416907 -246.609475) (xy 341.464057 -246.61723) (xy 341.509424 -246.632235)
			(xy 341.5519 -246.654123) (xy 341.590448 -246.682361) (xy 341.624127 -246.716259) (xy 341.652114 -246.75499)
			(xy 341.673727 -246.797607) (xy 341.688438 -246.84307) (xy 341.695887 -246.89027) (xy 341.696294 -246.914162)
			(xy 342.014805 -246.914162) (xy 342.0189 -246.863434) (xy 342.031079 -246.81402) (xy 342.051027 -246.7672)
			(xy 342.078228 -246.724186) (xy 342.111976 -246.686092) (xy 342.151398 -246.653905) (xy 342.195472 -246.628459)
			(xy 342.243058 -246.610412) (xy 342.292922 -246.600232) (xy 342.343774 -246.598183) (xy 342.394295 -246.604317)
			(xy 342.443179 -246.618477) (xy 342.489158 -246.640294) (xy 342.531042 -246.669204) (xy 342.567746 -246.704459)
			(xy 342.598319 -246.745145) (xy 342.62197 -246.790208) (xy 342.638086 -246.838482) (xy 342.64625 -246.888716)
			(xy 342.646762 -246.914162) (xy 342.954859 -246.914162) (xy 342.958954 -246.863434) (xy 342.971133 -246.81402)
			(xy 342.991081 -246.7672) (xy 343.018282 -246.724186) (xy 343.05203 -246.686092) (xy 343.091452 -246.653905)
			(xy 343.135526 -246.628459) (xy 343.183112 -246.610412) (xy 343.232976 -246.600232) (xy 343.283828 -246.598183)
			(xy 343.334349 -246.604317) (xy 343.383233 -246.618477) (xy 343.429212 -246.640294) (xy 343.471096 -246.669204)
			(xy 343.5078 -246.704459) (xy 343.538373 -246.745145) (xy 343.562024 -246.790208) (xy 343.57814 -246.838482)
			(xy 343.586304 -246.888716) (xy 343.586816 -246.914162) (xy 343.905344 -246.914162) (xy 343.909304 -246.865108)
			(xy 343.921081 -246.817324) (xy 343.940372 -246.772048) (xy 343.966675 -246.730452) (xy 343.99931 -246.693615)
			(xy 344.037431 -246.66249) (xy 344.080052 -246.637883) (xy 344.126068 -246.620431) (xy 344.174287 -246.610587)
			(xy 344.223462 -246.608606) (xy 344.272317 -246.614538) (xy 344.319588 -246.62823) (xy 344.36405 -246.649328)
			(xy 344.404553 -246.677284) (xy 344.440046 -246.711376) (xy 344.469611 -246.75072) (xy 344.492482 -246.794297)
			(xy 344.508066 -246.840978) (xy 344.515961 -246.889555) (xy 344.516456 -246.914162) (xy 344.845398 -246.914162)
			(xy 344.849358 -246.865108) (xy 344.861135 -246.817324) (xy 344.880426 -246.772048) (xy 344.906729 -246.730452)
			(xy 344.939364 -246.693615) (xy 344.977485 -246.66249) (xy 345.020106 -246.637883) (xy 345.066122 -246.620431)
			(xy 345.114341 -246.610587) (xy 345.163516 -246.608606) (xy 345.212371 -246.614538) (xy 345.259642 -246.62823)
			(xy 345.304104 -246.649328) (xy 345.344607 -246.677284) (xy 345.3801 -246.711376) (xy 345.409665 -246.75072)
			(xy 345.432536 -246.794297) (xy 345.44812 -246.840978) (xy 345.456015 -246.889555) (xy 345.45651 -246.914162)
			(xy 345.785198 -246.914162) (xy 345.789158 -246.865108) (xy 345.800935 -246.817324) (xy 345.820226 -246.772048)
			(xy 345.846529 -246.730452) (xy 345.879164 -246.693615) (xy 345.917285 -246.66249) (xy 345.959906 -246.637883)
			(xy 346.005922 -246.620431) (xy 346.054141 -246.610587) (xy 346.103316 -246.608606) (xy 346.152171 -246.614538)
			(xy 346.199442 -246.62823) (xy 346.243904 -246.649328) (xy 346.284407 -246.677284) (xy 346.3199 -246.711376)
			(xy 346.349465 -246.75072) (xy 346.372336 -246.794297) (xy 346.38792 -246.840978) (xy 346.395815 -246.889555)
			(xy 346.39631 -246.914162) (xy 346.725252 -246.914162) (xy 346.729212 -246.865108) (xy 346.740989 -246.817324)
			(xy 346.76028 -246.772048) (xy 346.786583 -246.730452) (xy 346.819218 -246.693615) (xy 346.857339 -246.66249)
			(xy 346.89996 -246.637883) (xy 346.945976 -246.620431) (xy 346.994195 -246.610587) (xy 347.04337 -246.608606)
			(xy 347.092225 -246.614538) (xy 347.139496 -246.62823) (xy 347.183958 -246.649328) (xy 347.224461 -246.677284)
			(xy 347.259954 -246.711376) (xy 347.289519 -246.75072) (xy 347.31239 -246.794297) (xy 347.327974 -246.840978)
			(xy 347.335869 -246.889555) (xy 347.336364 -246.914162) (xy 347.665306 -246.914162) (xy 347.669266 -246.865108)
			(xy 347.681043 -246.817324) (xy 347.700334 -246.772048) (xy 347.726637 -246.730452) (xy 347.759272 -246.693615)
			(xy 347.797393 -246.66249) (xy 347.840014 -246.637883) (xy 347.88603 -246.620431) (xy 347.934249 -246.610587)
			(xy 347.983424 -246.608606) (xy 348.032279 -246.614538) (xy 348.07955 -246.62823) (xy 348.124012 -246.649328)
			(xy 348.164515 -246.677284) (xy 348.200008 -246.711376) (xy 348.229573 -246.75072) (xy 348.252444 -246.794297)
			(xy 348.268028 -246.840978) (xy 348.275923 -246.889555) (xy 348.276418 -246.914162) (xy 348.60536 -246.914162)
			(xy 348.60932 -246.865108) (xy 348.621097 -246.817324) (xy 348.640388 -246.772048) (xy 348.666691 -246.730452)
			(xy 348.699326 -246.693615) (xy 348.737447 -246.66249) (xy 348.780068 -246.637883) (xy 348.826084 -246.620431)
			(xy 348.874303 -246.610587) (xy 348.923478 -246.608606) (xy 348.972333 -246.614538) (xy 349.019604 -246.62823)
			(xy 349.064066 -246.649328) (xy 349.104569 -246.677284) (xy 349.140062 -246.711376) (xy 349.169627 -246.75072)
			(xy 349.192498 -246.794297) (xy 349.208082 -246.840978) (xy 349.215977 -246.889555) (xy 349.216472 -246.914162)
			(xy 349.545414 -246.914162) (xy 349.549374 -246.865108) (xy 349.561151 -246.817324) (xy 349.580442 -246.772048)
			(xy 349.606745 -246.730452) (xy 349.63938 -246.693615) (xy 349.677501 -246.66249) (xy 349.720122 -246.637883)
			(xy 349.766138 -246.620431) (xy 349.814357 -246.610587) (xy 349.863532 -246.608606) (xy 349.912387 -246.614538)
			(xy 349.959658 -246.62823) (xy 350.00412 -246.649328) (xy 350.044623 -246.677284) (xy 350.080116 -246.711376)
			(xy 350.109681 -246.75072) (xy 350.132552 -246.794297) (xy 350.148136 -246.840978) (xy 350.156031 -246.889555)
			(xy 350.156526 -246.914162) (xy 350.485214 -246.914162) (xy 350.489174 -246.865108) (xy 350.500951 -246.817324)
			(xy 350.520242 -246.772048) (xy 350.546545 -246.730452) (xy 350.57918 -246.693615) (xy 350.617301 -246.66249)
			(xy 350.659922 -246.637883) (xy 350.705938 -246.620431) (xy 350.754157 -246.610587) (xy 350.803332 -246.608606)
			(xy 350.852187 -246.614538) (xy 350.899458 -246.62823) (xy 350.94392 -246.649328) (xy 350.984423 -246.677284)
			(xy 351.019916 -246.711376) (xy 351.049481 -246.75072) (xy 351.072352 -246.794297) (xy 351.087936 -246.840978)
			(xy 351.095831 -246.889555) (xy 351.096326 -246.914162) (xy 351.425268 -246.914162) (xy 351.429228 -246.865108)
			(xy 351.441005 -246.817324) (xy 351.460296 -246.772048) (xy 351.486599 -246.730452) (xy 351.519234 -246.693615)
			(xy 351.557355 -246.66249) (xy 351.599976 -246.637883) (xy 351.645992 -246.620431) (xy 351.694211 -246.610587)
			(xy 351.743386 -246.608606) (xy 351.792241 -246.614538) (xy 351.839512 -246.62823) (xy 351.883974 -246.649328)
			(xy 351.924477 -246.677284) (xy 351.95997 -246.711376) (xy 351.989535 -246.75072) (xy 352.012406 -246.794297)
			(xy 352.02799 -246.840978) (xy 352.035885 -246.889555) (xy 352.03638 -246.914162) (xy 352.365322 -246.914162)
			(xy 352.369282 -246.865108) (xy 352.381059 -246.817324) (xy 352.40035 -246.772048) (xy 352.426653 -246.730452)
			(xy 352.459288 -246.693615) (xy 352.497409 -246.66249) (xy 352.54003 -246.637883) (xy 352.586046 -246.620431)
			(xy 352.634265 -246.610587) (xy 352.68344 -246.608606) (xy 352.732295 -246.614538) (xy 352.779566 -246.62823)
			(xy 352.824028 -246.649328) (xy 352.864531 -246.677284) (xy 352.900024 -246.711376) (xy 352.929589 -246.75072)
			(xy 352.95246 -246.794297) (xy 352.968044 -246.840978) (xy 352.975939 -246.889555) (xy 352.976434 -246.914162)
			(xy 353.305376 -246.914162) (xy 353.309336 -246.865108) (xy 353.321113 -246.817324) (xy 353.340404 -246.772048)
			(xy 353.366707 -246.730452) (xy 353.399342 -246.693615) (xy 353.437463 -246.66249) (xy 353.480084 -246.637883)
			(xy 353.5261 -246.620431) (xy 353.574319 -246.610587) (xy 353.623494 -246.608606) (xy 353.672349 -246.614538)
			(xy 353.71962 -246.62823) (xy 353.764082 -246.649328) (xy 353.804585 -246.677284) (xy 353.840078 -246.711376)
			(xy 353.869643 -246.75072) (xy 353.892514 -246.794297) (xy 353.908098 -246.840978) (xy 353.915993 -246.889555)
			(xy 353.916488 -246.914162) (xy 354.24543 -246.914162) (xy 354.24939 -246.865108) (xy 354.261167 -246.817324)
			(xy 354.280458 -246.772048) (xy 354.306761 -246.730452) (xy 354.339396 -246.693615) (xy 354.377517 -246.66249)
			(xy 354.420138 -246.637883) (xy 354.466154 -246.620431) (xy 354.514373 -246.610587) (xy 354.563548 -246.608606)
			(xy 354.612403 -246.614538) (xy 354.659674 -246.62823) (xy 354.704136 -246.649328) (xy 354.744639 -246.677284)
			(xy 354.780132 -246.711376) (xy 354.809697 -246.75072) (xy 354.832568 -246.794297) (xy 354.848152 -246.840978)
			(xy 354.856047 -246.889555) (xy 354.856542 -246.914162) (xy 355.18523 -246.914162) (xy 355.18919 -246.865108)
			(xy 355.200967 -246.817324) (xy 355.220258 -246.772048) (xy 355.246561 -246.730452) (xy 355.279196 -246.693615)
			(xy 355.317317 -246.66249) (xy 355.359938 -246.637883) (xy 355.405954 -246.620431) (xy 355.454173 -246.610587)
			(xy 355.503348 -246.608606) (xy 355.552203 -246.614538) (xy 355.599474 -246.62823) (xy 355.643936 -246.649328)
			(xy 355.684439 -246.677284) (xy 355.719932 -246.711376) (xy 355.749497 -246.75072) (xy 355.772368 -246.794297)
			(xy 355.787952 -246.840978) (xy 355.795847 -246.889555) (xy 355.796342 -246.914162) (xy 356.125284 -246.914162)
			(xy 356.129244 -246.865108) (xy 356.141021 -246.817324) (xy 356.160312 -246.772048) (xy 356.186615 -246.730452)
			(xy 356.21925 -246.693615) (xy 356.257371 -246.66249) (xy 356.299992 -246.637883) (xy 356.346008 -246.620431)
			(xy 356.394227 -246.610587) (xy 356.443402 -246.608606) (xy 356.492257 -246.614538) (xy 356.539528 -246.62823)
			(xy 356.58399 -246.649328) (xy 356.624493 -246.677284) (xy 356.659986 -246.711376) (xy 356.689551 -246.75072)
			(xy 356.712422 -246.794297) (xy 356.728006 -246.840978) (xy 356.735901 -246.889555) (xy 356.736396 -246.914162)
			(xy 357.065338 -246.914162) (xy 357.069298 -246.865108) (xy 357.081075 -246.817324) (xy 357.100366 -246.772048)
			(xy 357.126669 -246.730452) (xy 357.159304 -246.693615) (xy 357.197425 -246.66249) (xy 357.240046 -246.637883)
			(xy 357.286062 -246.620431) (xy 357.334281 -246.610587) (xy 357.383456 -246.608606) (xy 357.432311 -246.614538)
			(xy 357.479582 -246.62823) (xy 357.524044 -246.649328) (xy 357.564547 -246.677284) (xy 357.60004 -246.711376)
			(xy 357.629605 -246.75072) (xy 357.652476 -246.794297) (xy 357.66806 -246.840978) (xy 357.675955 -246.889555)
			(xy 357.67645 -246.914162) (xy 358.005392 -246.914162) (xy 358.009352 -246.865108) (xy 358.021129 -246.817324)
			(xy 358.04042 -246.772048) (xy 358.066723 -246.730452) (xy 358.099358 -246.693615) (xy 358.137479 -246.66249)
			(xy 358.1801 -246.637883) (xy 358.226116 -246.620431) (xy 358.274335 -246.610587) (xy 358.32351 -246.608606)
			(xy 358.372365 -246.614538) (xy 358.419636 -246.62823) (xy 358.464098 -246.649328) (xy 358.504601 -246.677284)
			(xy 358.540094 -246.711376) (xy 358.569659 -246.75072) (xy 358.59253 -246.794297) (xy 358.608114 -246.840978)
			(xy 358.616009 -246.889555) (xy 358.616504 -246.914162) (xy 360.81895 -246.914162) (xy 360.82291 -246.865108)
			(xy 360.834687 -246.817324) (xy 360.853978 -246.772048) (xy 360.880281 -246.730452) (xy 360.912916 -246.693615)
			(xy 360.951037 -246.66249) (xy 360.993658 -246.637883) (xy 361.039674 -246.620431) (xy 361.087893 -246.610587)
			(xy 361.137068 -246.608606) (xy 361.185923 -246.614538) (xy 361.233194 -246.62823) (xy 361.277656 -246.649328)
			(xy 361.318159 -246.677284) (xy 361.353652 -246.711376) (xy 361.383217 -246.75072) (xy 361.406088 -246.794297)
			(xy 361.421672 -246.840978) (xy 361.429567 -246.889555) (xy 361.430062 -246.914162) (xy 361.430061 -246.9142)
			(xy 361.758647 -246.9142) (xy 361.762823 -246.863808) (xy 361.775236 -246.814791) (xy 361.795548 -246.768485)
			(xy 361.823205 -246.726155) (xy 361.857452 -246.688953) (xy 361.897355 -246.657897) (xy 361.941825 -246.633831)
			(xy 361.989651 -246.617414) (xy 362.039526 -246.609093) (xy 362.064808 -246.6086) (xy 363.004862 -246.6086)
			(xy 363.03014 -246.609166) (xy 363.080006 -246.617481) (xy 363.127824 -246.633892) (xy 363.172288 -246.65795)
			(xy 363.212185 -246.688999) (xy 363.246428 -246.726191) (xy 363.274081 -246.768513) (xy 363.29439 -246.81481)
			(xy 363.306801 -246.863818) (xy 363.310974 -246.914162) (xy 363.639112 -246.914162) (xy 363.643072 -246.865108)
			(xy 363.654849 -246.817324) (xy 363.67414 -246.772048) (xy 363.700443 -246.730452) (xy 363.733078 -246.693615)
			(xy 363.771199 -246.66249) (xy 363.81382 -246.637883) (xy 363.859836 -246.620431) (xy 363.908055 -246.610587)
			(xy 363.95723 -246.608606) (xy 364.006085 -246.614538) (xy 364.053356 -246.62823) (xy 364.097818 -246.649328)
			(xy 364.138321 -246.677284) (xy 364.173814 -246.711376) (xy 364.203379 -246.75072) (xy 364.22625 -246.794297)
			(xy 364.241834 -246.840978) (xy 364.249729 -246.889555) (xy 364.250224 -246.914162) (xy 364.578912 -246.914162)
			(xy 364.582872 -246.865108) (xy 364.594649 -246.817324) (xy 364.61394 -246.772048) (xy 364.640243 -246.730452)
			(xy 364.672878 -246.693615) (xy 364.710999 -246.66249) (xy 364.75362 -246.637883) (xy 364.799636 -246.620431)
			(xy 364.847855 -246.610587) (xy 364.89703 -246.608606) (xy 364.945885 -246.614538) (xy 364.993156 -246.62823)
			(xy 365.037618 -246.649328) (xy 365.078121 -246.677284) (xy 365.113614 -246.711376) (xy 365.143179 -246.75072)
			(xy 365.16605 -246.794297) (xy 365.181634 -246.840978) (xy 365.189529 -246.889555) (xy 365.190024 -246.914162)
			(xy 365.518966 -246.914162) (xy 365.522926 -246.865108) (xy 365.534703 -246.817324) (xy 365.553994 -246.772048)
			(xy 365.580297 -246.730452) (xy 365.612932 -246.693615) (xy 365.651053 -246.66249) (xy 365.693674 -246.637883)
			(xy 365.73969 -246.620431) (xy 365.787909 -246.610587) (xy 365.837084 -246.608606) (xy 365.885939 -246.614538)
			(xy 365.93321 -246.62823) (xy 365.977672 -246.649328) (xy 366.018175 -246.677284) (xy 366.053668 -246.711376)
			(xy 366.083233 -246.75072) (xy 366.106104 -246.794297) (xy 366.121688 -246.840978) (xy 366.129583 -246.889555)
			(xy 366.130078 -246.914162) (xy 366.45902 -246.914162) (xy 366.46298 -246.865108) (xy 366.474757 -246.817324)
			(xy 366.494048 -246.772048) (xy 366.520351 -246.730452) (xy 366.552986 -246.693615) (xy 366.591107 -246.66249)
			(xy 366.633728 -246.637883) (xy 366.679744 -246.620431) (xy 366.727963 -246.610587) (xy 366.777138 -246.608606)
			(xy 366.825993 -246.614538) (xy 366.873264 -246.62823) (xy 366.917726 -246.649328) (xy 366.958229 -246.677284)
			(xy 366.993722 -246.711376) (xy 367.023287 -246.75072) (xy 367.046158 -246.794297) (xy 367.061742 -246.840978)
			(xy 367.069637 -246.889555) (xy 367.070132 -246.914162) (xy 367.399074 -246.914162) (xy 367.403034 -246.865108)
			(xy 367.414811 -246.817324) (xy 367.434102 -246.772048) (xy 367.460405 -246.730452) (xy 367.49304 -246.693615)
			(xy 367.531161 -246.66249) (xy 367.573782 -246.637883) (xy 367.619798 -246.620431) (xy 367.668017 -246.610587)
			(xy 367.717192 -246.608606) (xy 367.766047 -246.614538) (xy 367.813318 -246.62823) (xy 367.85778 -246.649328)
			(xy 367.898283 -246.677284) (xy 367.933776 -246.711376) (xy 367.963341 -246.75072) (xy 367.986212 -246.794297)
			(xy 368.001796 -246.840978) (xy 368.009691 -246.889555) (xy 368.010186 -246.914162) (xy 368.338874 -246.914162)
			(xy 368.342834 -246.865108) (xy 368.354611 -246.817324) (xy 368.373902 -246.772048) (xy 368.400205 -246.730452)
			(xy 368.43284 -246.693615) (xy 368.470961 -246.66249) (xy 368.513582 -246.637883) (xy 368.559598 -246.620431)
			(xy 368.607817 -246.610587) (xy 368.656992 -246.608606) (xy 368.705847 -246.614538) (xy 368.753118 -246.62823)
			(xy 368.79758 -246.649328) (xy 368.838083 -246.677284) (xy 368.873576 -246.711376) (xy 368.903141 -246.75072)
			(xy 368.926012 -246.794297) (xy 368.941596 -246.840978) (xy 368.949491 -246.889555) (xy 368.949986 -246.914162)
			(xy 369.278928 -246.914162) (xy 369.282888 -246.865108) (xy 369.294665 -246.817324) (xy 369.313956 -246.772048)
			(xy 369.340259 -246.730452) (xy 369.372894 -246.693615) (xy 369.411015 -246.66249) (xy 369.453636 -246.637883)
			(xy 369.499652 -246.620431) (xy 369.547871 -246.610587) (xy 369.597046 -246.608606) (xy 369.645901 -246.614538)
			(xy 369.693172 -246.62823) (xy 369.737634 -246.649328) (xy 369.778137 -246.677284) (xy 369.81363 -246.711376)
			(xy 369.843195 -246.75072) (xy 369.866066 -246.794297) (xy 369.88165 -246.840978) (xy 369.889545 -246.889555)
			(xy 369.89004 -246.914162) (xy 370.218982 -246.914162) (xy 370.222942 -246.865108) (xy 370.234719 -246.817324)
			(xy 370.25401 -246.772048) (xy 370.280313 -246.730452) (xy 370.312948 -246.693615) (xy 370.351069 -246.66249)
			(xy 370.39369 -246.637883) (xy 370.439706 -246.620431) (xy 370.487925 -246.610587) (xy 370.5371 -246.608606)
			(xy 370.585955 -246.614538) (xy 370.633226 -246.62823) (xy 370.677688 -246.649328) (xy 370.718191 -246.677284)
			(xy 370.753684 -246.711376) (xy 370.783249 -246.75072) (xy 370.80612 -246.794297) (xy 370.821704 -246.840978)
			(xy 370.829599 -246.889555) (xy 370.830094 -246.914162) (xy 371.159036 -246.914162) (xy 371.162996 -246.865108)
			(xy 371.174773 -246.817324) (xy 371.194064 -246.772048) (xy 371.220367 -246.730452) (xy 371.253002 -246.693615)
			(xy 371.291123 -246.66249) (xy 371.333744 -246.637883) (xy 371.37976 -246.620431) (xy 371.427979 -246.610587)
			(xy 371.477154 -246.608606) (xy 371.526009 -246.614538) (xy 371.57328 -246.62823) (xy 371.617742 -246.649328)
			(xy 371.658245 -246.677284) (xy 371.693738 -246.711376) (xy 371.723303 -246.75072) (xy 371.746174 -246.794297)
			(xy 371.761758 -246.840978) (xy 371.769653 -246.889555) (xy 371.770148 -246.914162) (xy 372.09909 -246.914162)
			(xy 372.10305 -246.865108) (xy 372.114827 -246.817324) (xy 372.134118 -246.772048) (xy 372.160421 -246.730452)
			(xy 372.193056 -246.693615) (xy 372.231177 -246.66249) (xy 372.273798 -246.637883) (xy 372.319814 -246.620431)
			(xy 372.368033 -246.610587) (xy 372.417208 -246.608606) (xy 372.466063 -246.614538) (xy 372.513334 -246.62823)
			(xy 372.557796 -246.649328) (xy 372.598299 -246.677284) (xy 372.633792 -246.711376) (xy 372.663357 -246.75072)
			(xy 372.686228 -246.794297) (xy 372.701812 -246.840978) (xy 372.709707 -246.889555) (xy 372.710202 -246.914162)
			(xy 373.03889 -246.914162) (xy 373.04285 -246.865108) (xy 373.054627 -246.817324) (xy 373.073918 -246.772048)
			(xy 373.100221 -246.730452) (xy 373.132856 -246.693615) (xy 373.170977 -246.66249) (xy 373.213598 -246.637883)
			(xy 373.259614 -246.620431) (xy 373.307833 -246.610587) (xy 373.357008 -246.608606) (xy 373.405863 -246.614538)
			(xy 373.453134 -246.62823) (xy 373.497596 -246.649328) (xy 373.538099 -246.677284) (xy 373.573592 -246.711376)
			(xy 373.603157 -246.75072) (xy 373.626028 -246.794297) (xy 373.641612 -246.840978) (xy 373.649507 -246.889555)
			(xy 373.650002 -246.914162) (xy 373.978944 -246.914162) (xy 373.982904 -246.865108) (xy 373.994681 -246.817324)
			(xy 374.013972 -246.772048) (xy 374.040275 -246.730452) (xy 374.07291 -246.693615) (xy 374.111031 -246.66249)
			(xy 374.153652 -246.637883) (xy 374.199668 -246.620431) (xy 374.247887 -246.610587) (xy 374.297062 -246.608606)
			(xy 374.345917 -246.614538) (xy 374.393188 -246.62823) (xy 374.43765 -246.649328) (xy 374.478153 -246.677284)
			(xy 374.513646 -246.711376) (xy 374.543211 -246.75072) (xy 374.566082 -246.794297) (xy 374.581666 -246.840978)
			(xy 374.589561 -246.889555) (xy 374.590056 -246.914162) (xy 374.918998 -246.914162) (xy 374.922958 -246.865108)
			(xy 374.934735 -246.817324) (xy 374.954026 -246.772048) (xy 374.980329 -246.730452) (xy 375.012964 -246.693615)
			(xy 375.051085 -246.66249) (xy 375.093706 -246.637883) (xy 375.139722 -246.620431) (xy 375.187941 -246.610587)
			(xy 375.237116 -246.608606) (xy 375.285971 -246.614538) (xy 375.333242 -246.62823) (xy 375.377704 -246.649328)
			(xy 375.418207 -246.677284) (xy 375.4537 -246.711376) (xy 375.483265 -246.75072) (xy 375.506136 -246.794297)
			(xy 375.52172 -246.840978) (xy 375.529615 -246.889555) (xy 375.53011 -246.914162) (xy 375.848621 -246.914162)
			(xy 375.852716 -246.863434) (xy 375.864895 -246.81402) (xy 375.884843 -246.7672) (xy 375.912044 -246.724186)
			(xy 375.945792 -246.686092) (xy 375.985214 -246.653905) (xy 376.029288 -246.628459) (xy 376.076874 -246.610412)
			(xy 376.126738 -246.600232) (xy 376.17759 -246.598183) (xy 376.228111 -246.604317) (xy 376.276995 -246.618477)
			(xy 376.322974 -246.640294) (xy 376.364858 -246.669204) (xy 376.401562 -246.704459) (xy 376.432135 -246.745145)
			(xy 376.455786 -246.790208) (xy 376.471902 -246.838482) (xy 376.480066 -246.888716) (xy 376.480578 -246.914162)
			(xy 376.788675 -246.914162) (xy 376.79277 -246.863434) (xy 376.804949 -246.81402) (xy 376.824897 -246.7672)
			(xy 376.852098 -246.724186) (xy 376.885846 -246.686092) (xy 376.925268 -246.653905) (xy 376.969342 -246.628459)
			(xy 377.016928 -246.610412) (xy 377.066792 -246.600232) (xy 377.117644 -246.598183) (xy 377.168165 -246.604317)
			(xy 377.217049 -246.618477) (xy 377.263028 -246.640294) (xy 377.304912 -246.669204) (xy 377.341616 -246.704459)
			(xy 377.372189 -246.745145) (xy 377.39584 -246.790208) (xy 377.411956 -246.838482) (xy 377.42012 -246.888716)
			(xy 377.420632 -246.914162) (xy 377.42012 -246.939608) (xy 377.411956 -246.989842) (xy 377.39584 -247.038116)
			(xy 377.372189 -247.083179) (xy 377.341616 -247.123865) (xy 377.304912 -247.15912) (xy 377.263028 -247.18803)
			(xy 377.217049 -247.209847) (xy 377.168165 -247.224007) (xy 377.117644 -247.230141) (xy 377.066792 -247.228092)
			(xy 377.016928 -247.217912) (xy 376.969342 -247.199865) (xy 376.925268 -247.174419) (xy 376.885846 -247.142232)
			(xy 376.852098 -247.104138) (xy 376.824897 -247.061124) (xy 376.804949 -247.014304) (xy 376.79277 -246.96489)
			(xy 376.788675 -246.914162) (xy 376.480578 -246.914162) (xy 376.480066 -246.939608) (xy 376.471902 -246.989842)
			(xy 376.455786 -247.038116) (xy 376.432135 -247.083179) (xy 376.401562 -247.123865) (xy 376.364858 -247.15912)
			(xy 376.322974 -247.18803) (xy 376.276995 -247.209847) (xy 376.228111 -247.224007) (xy 376.17759 -247.230141)
			(xy 376.126738 -247.228092) (xy 376.076874 -247.217912) (xy 376.029288 -247.199865) (xy 375.985214 -247.174419)
			(xy 375.945792 -247.142232) (xy 375.912044 -247.104138) (xy 375.884843 -247.061124) (xy 375.864895 -247.014304)
			(xy 375.852716 -246.96489) (xy 375.848621 -246.914162) (xy 375.53011 -246.914162) (xy 375.529615 -246.938769)
			(xy 375.52172 -246.987346) (xy 375.506136 -247.034027) (xy 375.483265 -247.077604) (xy 375.4537 -247.116948)
			(xy 375.418207 -247.15104) (xy 375.377704 -247.178996) (xy 375.333242 -247.200094) (xy 375.285971 -247.213786)
			(xy 375.237116 -247.219718) (xy 375.187941 -247.217737) (xy 375.139722 -247.207893) (xy 375.093706 -247.190441)
			(xy 375.051085 -247.165834) (xy 375.012964 -247.134709) (xy 374.980329 -247.097872) (xy 374.954026 -247.056276)
			(xy 374.934735 -247.011) (xy 374.922958 -246.963216) (xy 374.918998 -246.914162) (xy 374.590056 -246.914162)
			(xy 374.589561 -246.938769) (xy 374.581666 -246.987346) (xy 374.566082 -247.034027) (xy 374.543211 -247.077604)
			(xy 374.513646 -247.116948) (xy 374.478153 -247.15104) (xy 374.43765 -247.178996) (xy 374.393188 -247.200094)
			(xy 374.345917 -247.213786) (xy 374.297062 -247.219718) (xy 374.247887 -247.217737) (xy 374.199668 -247.207893)
			(xy 374.153652 -247.190441) (xy 374.111031 -247.165834) (xy 374.07291 -247.134709) (xy 374.040275 -247.097872)
			(xy 374.013972 -247.056276) (xy 373.994681 -247.011) (xy 373.982904 -246.963216) (xy 373.978944 -246.914162)
			(xy 373.650002 -246.914162) (xy 373.649507 -246.938769) (xy 373.641612 -246.987346) (xy 373.626028 -247.034027)
			(xy 373.603157 -247.077604) (xy 373.573592 -247.116948) (xy 373.538099 -247.15104) (xy 373.497596 -247.178996)
			(xy 373.453134 -247.200094) (xy 373.405863 -247.213786) (xy 373.357008 -247.219718) (xy 373.307833 -247.217737)
			(xy 373.259614 -247.207893) (xy 373.213598 -247.190441) (xy 373.170977 -247.165834) (xy 373.132856 -247.134709)
			(xy 373.100221 -247.097872) (xy 373.073918 -247.056276) (xy 373.054627 -247.011) (xy 373.04285 -246.963216)
			(xy 373.03889 -246.914162) (xy 372.710202 -246.914162) (xy 372.709707 -246.938769) (xy 372.701812 -246.987346)
			(xy 372.686228 -247.034027) (xy 372.663357 -247.077604) (xy 372.633792 -247.116948) (xy 372.598299 -247.15104)
			(xy 372.557796 -247.178996) (xy 372.513334 -247.200094) (xy 372.466063 -247.213786) (xy 372.417208 -247.219718)
			(xy 372.368033 -247.217737) (xy 372.319814 -247.207893) (xy 372.273798 -247.190441) (xy 372.231177 -247.165834)
			(xy 372.193056 -247.134709) (xy 372.160421 -247.097872) (xy 372.134118 -247.056276) (xy 372.114827 -247.011)
			(xy 372.10305 -246.963216) (xy 372.09909 -246.914162) (xy 371.770148 -246.914162) (xy 371.769653 -246.938769)
			(xy 371.761758 -246.987346) (xy 371.746174 -247.034027) (xy 371.723303 -247.077604) (xy 371.693738 -247.116948)
			(xy 371.658245 -247.15104) (xy 371.617742 -247.178996) (xy 371.57328 -247.200094) (xy 371.526009 -247.213786)
			(xy 371.477154 -247.219718) (xy 371.427979 -247.217737) (xy 371.37976 -247.207893) (xy 371.333744 -247.190441)
			(xy 371.291123 -247.165834) (xy 371.253002 -247.134709) (xy 371.220367 -247.097872) (xy 371.194064 -247.056276)
			(xy 371.174773 -247.011) (xy 371.162996 -246.963216) (xy 371.159036 -246.914162) (xy 370.830094 -246.914162)
			(xy 370.829599 -246.938769) (xy 370.821704 -246.987346) (xy 370.80612 -247.034027) (xy 370.783249 -247.077604)
			(xy 370.753684 -247.116948) (xy 370.718191 -247.15104) (xy 370.677688 -247.178996) (xy 370.633226 -247.200094)
			(xy 370.585955 -247.213786) (xy 370.5371 -247.219718) (xy 370.487925 -247.217737) (xy 370.439706 -247.207893)
			(xy 370.39369 -247.190441) (xy 370.351069 -247.165834) (xy 370.312948 -247.134709) (xy 370.280313 -247.097872)
			(xy 370.25401 -247.056276) (xy 370.234719 -247.011) (xy 370.222942 -246.963216) (xy 370.218982 -246.914162)
			(xy 369.89004 -246.914162) (xy 369.889545 -246.938769) (xy 369.88165 -246.987346) (xy 369.866066 -247.034027)
			(xy 369.843195 -247.077604) (xy 369.81363 -247.116948) (xy 369.778137 -247.15104) (xy 369.737634 -247.178996)
			(xy 369.693172 -247.200094) (xy 369.645901 -247.213786) (xy 369.597046 -247.219718) (xy 369.547871 -247.217737)
			(xy 369.499652 -247.207893) (xy 369.453636 -247.190441) (xy 369.411015 -247.165834) (xy 369.372894 -247.134709)
			(xy 369.340259 -247.097872) (xy 369.313956 -247.056276) (xy 369.294665 -247.011) (xy 369.282888 -246.963216)
			(xy 369.278928 -246.914162) (xy 368.949986 -246.914162) (xy 368.949491 -246.938769) (xy 368.941596 -246.987346)
			(xy 368.926012 -247.034027) (xy 368.903141 -247.077604) (xy 368.873576 -247.116948) (xy 368.838083 -247.15104)
			(xy 368.79758 -247.178996) (xy 368.753118 -247.200094) (xy 368.705847 -247.213786) (xy 368.656992 -247.219718)
			(xy 368.607817 -247.217737) (xy 368.559598 -247.207893) (xy 368.513582 -247.190441) (xy 368.470961 -247.165834)
			(xy 368.43284 -247.134709) (xy 368.400205 -247.097872) (xy 368.373902 -247.056276) (xy 368.354611 -247.011)
			(xy 368.342834 -246.963216) (xy 368.338874 -246.914162) (xy 368.010186 -246.914162) (xy 368.009691 -246.938769)
			(xy 368.001796 -246.987346) (xy 367.986212 -247.034027) (xy 367.963341 -247.077604) (xy 367.933776 -247.116948)
			(xy 367.898283 -247.15104) (xy 367.85778 -247.178996) (xy 367.813318 -247.200094) (xy 367.766047 -247.213786)
			(xy 367.717192 -247.219718) (xy 367.668017 -247.217737) (xy 367.619798 -247.207893) (xy 367.573782 -247.190441)
			(xy 367.531161 -247.165834) (xy 367.49304 -247.134709) (xy 367.460405 -247.097872) (xy 367.434102 -247.056276)
			(xy 367.414811 -247.011) (xy 367.403034 -246.963216) (xy 367.399074 -246.914162) (xy 367.070132 -246.914162)
			(xy 367.069637 -246.938769) (xy 367.061742 -246.987346) (xy 367.046158 -247.034027) (xy 367.023287 -247.077604)
			(xy 366.993722 -247.116948) (xy 366.958229 -247.15104) (xy 366.917726 -247.178996) (xy 366.873264 -247.200094)
			(xy 366.825993 -247.213786) (xy 366.777138 -247.219718) (xy 366.727963 -247.217737) (xy 366.679744 -247.207893)
			(xy 366.633728 -247.190441) (xy 366.591107 -247.165834) (xy 366.552986 -247.134709) (xy 366.520351 -247.097872)
			(xy 366.494048 -247.056276) (xy 366.474757 -247.011) (xy 366.46298 -246.963216) (xy 366.45902 -246.914162)
			(xy 366.130078 -246.914162) (xy 366.129583 -246.938769) (xy 366.121688 -246.987346) (xy 366.106104 -247.034027)
			(xy 366.083233 -247.077604) (xy 366.053668 -247.116948) (xy 366.018175 -247.15104) (xy 365.977672 -247.178996)
			(xy 365.93321 -247.200094) (xy 365.885939 -247.213786) (xy 365.837084 -247.219718) (xy 365.787909 -247.217737)
			(xy 365.73969 -247.207893) (xy 365.693674 -247.190441) (xy 365.651053 -247.165834) (xy 365.612932 -247.134709)
			(xy 365.580297 -247.097872) (xy 365.553994 -247.056276) (xy 365.534703 -247.011) (xy 365.522926 -246.963216)
			(xy 365.518966 -246.914162) (xy 365.190024 -246.914162) (xy 365.189529 -246.938769) (xy 365.181634 -246.987346)
			(xy 365.16605 -247.034027) (xy 365.143179 -247.077604) (xy 365.113614 -247.116948) (xy 365.078121 -247.15104)
			(xy 365.037618 -247.178996) (xy 364.993156 -247.200094) (xy 364.945885 -247.213786) (xy 364.89703 -247.219718)
			(xy 364.847855 -247.217737) (xy 364.799636 -247.207893) (xy 364.75362 -247.190441) (xy 364.710999 -247.165834)
			(xy 364.672878 -247.134709) (xy 364.640243 -247.097872) (xy 364.61394 -247.056276) (xy 364.594649 -247.011)
			(xy 364.582872 -246.963216) (xy 364.578912 -246.914162) (xy 364.250224 -246.914162) (xy 364.249729 -246.938769)
			(xy 364.241834 -246.987346) (xy 364.22625 -247.034027) (xy 364.203379 -247.077604) (xy 364.173814 -247.116948)
			(xy 364.138321 -247.15104) (xy 364.097818 -247.178996) (xy 364.053356 -247.200094) (xy 364.006085 -247.213786)
			(xy 363.95723 -247.219718) (xy 363.908055 -247.217737) (xy 363.859836 -247.207893) (xy 363.81382 -247.190441)
			(xy 363.771199 -247.165834) (xy 363.733078 -247.134709) (xy 363.700443 -247.097872) (xy 363.67414 -247.056276)
			(xy 363.654849 -247.011) (xy 363.643072 -246.963216) (xy 363.639112 -246.914162) (xy 363.310974 -246.914162)
			(xy 363.310977 -246.9142) (xy 363.306801 -246.964582) (xy 363.29439 -247.01359) (xy 363.274081 -247.059887)
			(xy 363.246428 -247.102209) (xy 363.212185 -247.139401) (xy 363.172288 -247.17045) (xy 363.127824 -247.194508)
			(xy 363.080006 -247.210919) (xy 363.03014 -247.219234) (xy 363.004862 -247.219724) (xy 362.064808 -247.219724)
			(xy 362.039526 -247.219307) (xy 361.989651 -247.210986) (xy 361.941825 -247.194569) (xy 361.897355 -247.170503)
			(xy 361.857452 -247.139447) (xy 361.823205 -247.102245) (xy 361.795548 -247.059915) (xy 361.775236 -247.013609)
			(xy 361.762823 -246.964592) (xy 361.758647 -246.9142) (xy 361.430061 -246.9142) (xy 361.429567 -246.938769)
			(xy 361.421672 -246.987346) (xy 361.406088 -247.034027) (xy 361.383217 -247.077604) (xy 361.353652 -247.116948)
			(xy 361.318159 -247.15104) (xy 361.277656 -247.178996) (xy 361.233194 -247.200094) (xy 361.185923 -247.213786)
			(xy 361.137068 -247.219718) (xy 361.087893 -247.217737) (xy 361.039674 -247.207893) (xy 360.993658 -247.190441)
			(xy 360.951037 -247.165834) (xy 360.912916 -247.134709) (xy 360.880281 -247.097872) (xy 360.853978 -247.056276)
			(xy 360.834687 -247.011) (xy 360.82291 -246.963216) (xy 360.81895 -246.914162) (xy 358.616504 -246.914162)
			(xy 358.616009 -246.938769) (xy 358.608114 -246.987346) (xy 358.59253 -247.034027) (xy 358.569659 -247.077604)
			(xy 358.540094 -247.116948) (xy 358.504601 -247.15104) (xy 358.464098 -247.178996) (xy 358.419636 -247.200094)
			(xy 358.372365 -247.213786) (xy 358.32351 -247.219718) (xy 358.274335 -247.217737) (xy 358.226116 -247.207893)
			(xy 358.1801 -247.190441) (xy 358.137479 -247.165834) (xy 358.099358 -247.134709) (xy 358.066723 -247.097872)
			(xy 358.04042 -247.056276) (xy 358.021129 -247.011) (xy 358.009352 -246.963216) (xy 358.005392 -246.914162)
			(xy 357.67645 -246.914162) (xy 357.675955 -246.938769) (xy 357.66806 -246.987346) (xy 357.652476 -247.034027)
			(xy 357.629605 -247.077604) (xy 357.60004 -247.116948) (xy 357.564547 -247.15104) (xy 357.524044 -247.178996)
			(xy 357.479582 -247.200094) (xy 357.432311 -247.213786) (xy 357.383456 -247.219718) (xy 357.334281 -247.217737)
			(xy 357.286062 -247.207893) (xy 357.240046 -247.190441) (xy 357.197425 -247.165834) (xy 357.159304 -247.134709)
			(xy 357.126669 -247.097872) (xy 357.100366 -247.056276) (xy 357.081075 -247.011) (xy 357.069298 -246.963216)
			(xy 357.065338 -246.914162) (xy 356.736396 -246.914162) (xy 356.735901 -246.938769) (xy 356.728006 -246.987346)
			(xy 356.712422 -247.034027) (xy 356.689551 -247.077604) (xy 356.659986 -247.116948) (xy 356.624493 -247.15104)
			(xy 356.58399 -247.178996) (xy 356.539528 -247.200094) (xy 356.492257 -247.213786) (xy 356.443402 -247.219718)
			(xy 356.394227 -247.217737) (xy 356.346008 -247.207893) (xy 356.299992 -247.190441) (xy 356.257371 -247.165834)
			(xy 356.21925 -247.134709) (xy 356.186615 -247.097872) (xy 356.160312 -247.056276) (xy 356.141021 -247.011)
			(xy 356.129244 -246.963216) (xy 356.125284 -246.914162) (xy 355.796342 -246.914162) (xy 355.795847 -246.938769)
			(xy 355.787952 -246.987346) (xy 355.772368 -247.034027) (xy 355.749497 -247.077604) (xy 355.719932 -247.116948)
			(xy 355.684439 -247.15104) (xy 355.643936 -247.178996) (xy 355.599474 -247.200094) (xy 355.552203 -247.213786)
			(xy 355.503348 -247.219718) (xy 355.454173 -247.217737) (xy 355.405954 -247.207893) (xy 355.359938 -247.190441)
			(xy 355.317317 -247.165834) (xy 355.279196 -247.134709) (xy 355.246561 -247.097872) (xy 355.220258 -247.056276)
			(xy 355.200967 -247.011) (xy 355.18919 -246.963216) (xy 355.18523 -246.914162) (xy 354.856542 -246.914162)
			(xy 354.856047 -246.938769) (xy 354.848152 -246.987346) (xy 354.832568 -247.034027) (xy 354.809697 -247.077604)
			(xy 354.780132 -247.116948) (xy 354.744639 -247.15104) (xy 354.704136 -247.178996) (xy 354.659674 -247.200094)
			(xy 354.612403 -247.213786) (xy 354.563548 -247.219718) (xy 354.514373 -247.217737) (xy 354.466154 -247.207893)
			(xy 354.420138 -247.190441) (xy 354.377517 -247.165834) (xy 354.339396 -247.134709) (xy 354.306761 -247.097872)
			(xy 354.280458 -247.056276) (xy 354.261167 -247.011) (xy 354.24939 -246.963216) (xy 354.24543 -246.914162)
			(xy 353.916488 -246.914162) (xy 353.915993 -246.938769) (xy 353.908098 -246.987346) (xy 353.892514 -247.034027)
			(xy 353.869643 -247.077604) (xy 353.840078 -247.116948) (xy 353.804585 -247.15104) (xy 353.764082 -247.178996)
			(xy 353.71962 -247.200094) (xy 353.672349 -247.213786) (xy 353.623494 -247.219718) (xy 353.574319 -247.217737)
			(xy 353.5261 -247.207893) (xy 353.480084 -247.190441) (xy 353.437463 -247.165834) (xy 353.399342 -247.134709)
			(xy 353.366707 -247.097872) (xy 353.340404 -247.056276) (xy 353.321113 -247.011) (xy 353.309336 -246.963216)
			(xy 353.305376 -246.914162) (xy 352.976434 -246.914162) (xy 352.975939 -246.938769) (xy 352.968044 -246.987346)
			(xy 352.95246 -247.034027) (xy 352.929589 -247.077604) (xy 352.900024 -247.116948) (xy 352.864531 -247.15104)
			(xy 352.824028 -247.178996) (xy 352.779566 -247.200094) (xy 352.732295 -247.213786) (xy 352.68344 -247.219718)
			(xy 352.634265 -247.217737) (xy 352.586046 -247.207893) (xy 352.54003 -247.190441) (xy 352.497409 -247.165834)
			(xy 352.459288 -247.134709) (xy 352.426653 -247.097872) (xy 352.40035 -247.056276) (xy 352.381059 -247.011)
			(xy 352.369282 -246.963216) (xy 352.365322 -246.914162) (xy 352.03638 -246.914162) (xy 352.035885 -246.938769)
			(xy 352.02799 -246.987346) (xy 352.012406 -247.034027) (xy 351.989535 -247.077604) (xy 351.95997 -247.116948)
			(xy 351.924477 -247.15104) (xy 351.883974 -247.178996) (xy 351.839512 -247.200094) (xy 351.792241 -247.213786)
			(xy 351.743386 -247.219718) (xy 351.694211 -247.217737) (xy 351.645992 -247.207893) (xy 351.599976 -247.190441)
			(xy 351.557355 -247.165834) (xy 351.519234 -247.134709) (xy 351.486599 -247.097872) (xy 351.460296 -247.056276)
			(xy 351.441005 -247.011) (xy 351.429228 -246.963216) (xy 351.425268 -246.914162) (xy 351.096326 -246.914162)
			(xy 351.095831 -246.938769) (xy 351.087936 -246.987346) (xy 351.072352 -247.034027) (xy 351.049481 -247.077604)
			(xy 351.019916 -247.116948) (xy 350.984423 -247.15104) (xy 350.94392 -247.178996) (xy 350.899458 -247.200094)
			(xy 350.852187 -247.213786) (xy 350.803332 -247.219718) (xy 350.754157 -247.217737) (xy 350.705938 -247.207893)
			(xy 350.659922 -247.190441) (xy 350.617301 -247.165834) (xy 350.57918 -247.134709) (xy 350.546545 -247.097872)
			(xy 350.520242 -247.056276) (xy 350.500951 -247.011) (xy 350.489174 -246.963216) (xy 350.485214 -246.914162)
			(xy 350.156526 -246.914162) (xy 350.156031 -246.938769) (xy 350.148136 -246.987346) (xy 350.132552 -247.034027)
			(xy 350.109681 -247.077604) (xy 350.080116 -247.116948) (xy 350.044623 -247.15104) (xy 350.00412 -247.178996)
			(xy 349.959658 -247.200094) (xy 349.912387 -247.213786) (xy 349.863532 -247.219718) (xy 349.814357 -247.217737)
			(xy 349.766138 -247.207893) (xy 349.720122 -247.190441) (xy 349.677501 -247.165834) (xy 349.63938 -247.134709)
			(xy 349.606745 -247.097872) (xy 349.580442 -247.056276) (xy 349.561151 -247.011) (xy 349.549374 -246.963216)
			(xy 349.545414 -246.914162) (xy 349.216472 -246.914162) (xy 349.215977 -246.938769) (xy 349.208082 -246.987346)
			(xy 349.192498 -247.034027) (xy 349.169627 -247.077604) (xy 349.140062 -247.116948) (xy 349.104569 -247.15104)
			(xy 349.064066 -247.178996) (xy 349.019604 -247.200094) (xy 348.972333 -247.213786) (xy 348.923478 -247.219718)
			(xy 348.874303 -247.217737) (xy 348.826084 -247.207893) (xy 348.780068 -247.190441) (xy 348.737447 -247.165834)
			(xy 348.699326 -247.134709) (xy 348.666691 -247.097872) (xy 348.640388 -247.056276) (xy 348.621097 -247.011)
			(xy 348.60932 -246.963216) (xy 348.60536 -246.914162) (xy 348.276418 -246.914162) (xy 348.275923 -246.938769)
			(xy 348.268028 -246.987346) (xy 348.252444 -247.034027) (xy 348.229573 -247.077604) (xy 348.200008 -247.116948)
			(xy 348.164515 -247.15104) (xy 348.124012 -247.178996) (xy 348.07955 -247.200094) (xy 348.032279 -247.213786)
			(xy 347.983424 -247.219718) (xy 347.934249 -247.217737) (xy 347.88603 -247.207893) (xy 347.840014 -247.190441)
			(xy 347.797393 -247.165834) (xy 347.759272 -247.134709) (xy 347.726637 -247.097872) (xy 347.700334 -247.056276)
			(xy 347.681043 -247.011) (xy 347.669266 -246.963216) (xy 347.665306 -246.914162) (xy 347.336364 -246.914162)
			(xy 347.335869 -246.938769) (xy 347.327974 -246.987346) (xy 347.31239 -247.034027) (xy 347.289519 -247.077604)
			(xy 347.259954 -247.116948) (xy 347.224461 -247.15104) (xy 347.183958 -247.178996) (xy 347.139496 -247.200094)
			(xy 347.092225 -247.213786) (xy 347.04337 -247.219718) (xy 346.994195 -247.217737) (xy 346.945976 -247.207893)
			(xy 346.89996 -247.190441) (xy 346.857339 -247.165834) (xy 346.819218 -247.134709) (xy 346.786583 -247.097872)
			(xy 346.76028 -247.056276) (xy 346.740989 -247.011) (xy 346.729212 -246.963216) (xy 346.725252 -246.914162)
			(xy 346.39631 -246.914162) (xy 346.395815 -246.938769) (xy 346.38792 -246.987346) (xy 346.372336 -247.034027)
			(xy 346.349465 -247.077604) (xy 346.3199 -247.116948) (xy 346.284407 -247.15104) (xy 346.243904 -247.178996)
			(xy 346.199442 -247.200094) (xy 346.152171 -247.213786) (xy 346.103316 -247.219718) (xy 346.054141 -247.217737)
			(xy 346.005922 -247.207893) (xy 345.959906 -247.190441) (xy 345.917285 -247.165834) (xy 345.879164 -247.134709)
			(xy 345.846529 -247.097872) (xy 345.820226 -247.056276) (xy 345.800935 -247.011) (xy 345.789158 -246.963216)
			(xy 345.785198 -246.914162) (xy 345.45651 -246.914162) (xy 345.456015 -246.938769) (xy 345.44812 -246.987346)
			(xy 345.432536 -247.034027) (xy 345.409665 -247.077604) (xy 345.3801 -247.116948) (xy 345.344607 -247.15104)
			(xy 345.304104 -247.178996) (xy 345.259642 -247.200094) (xy 345.212371 -247.213786) (xy 345.163516 -247.219718)
			(xy 345.114341 -247.217737) (xy 345.066122 -247.207893) (xy 345.020106 -247.190441) (xy 344.977485 -247.165834)
			(xy 344.939364 -247.134709) (xy 344.906729 -247.097872) (xy 344.880426 -247.056276) (xy 344.861135 -247.011)
			(xy 344.849358 -246.963216) (xy 344.845398 -246.914162) (xy 344.516456 -246.914162) (xy 344.515961 -246.938769)
			(xy 344.508066 -246.987346) (xy 344.492482 -247.034027) (xy 344.469611 -247.077604) (xy 344.440046 -247.116948)
			(xy 344.404553 -247.15104) (xy 344.36405 -247.178996) (xy 344.319588 -247.200094) (xy 344.272317 -247.213786)
			(xy 344.223462 -247.219718) (xy 344.174287 -247.217737) (xy 344.126068 -247.207893) (xy 344.080052 -247.190441)
			(xy 344.037431 -247.165834) (xy 343.99931 -247.134709) (xy 343.966675 -247.097872) (xy 343.940372 -247.056276)
			(xy 343.921081 -247.011) (xy 343.909304 -246.963216) (xy 343.905344 -246.914162) (xy 343.586816 -246.914162)
			(xy 343.586304 -246.939608) (xy 343.57814 -246.989842) (xy 343.562024 -247.038116) (xy 343.538373 -247.083179)
			(xy 343.5078 -247.123865) (xy 343.471096 -247.15912) (xy 343.429212 -247.18803) (xy 343.383233 -247.209847)
			(xy 343.334349 -247.224007) (xy 343.283828 -247.230141) (xy 343.232976 -247.228092) (xy 343.183112 -247.217912)
			(xy 343.135526 -247.199865) (xy 343.091452 -247.174419) (xy 343.05203 -247.142232) (xy 343.018282 -247.104138)
			(xy 342.991081 -247.061124) (xy 342.971133 -247.014304) (xy 342.958954 -246.96489) (xy 342.954859 -246.914162)
			(xy 342.646762 -246.914162) (xy 342.64625 -246.939608) (xy 342.638086 -246.989842) (xy 342.62197 -247.038116)
			(xy 342.598319 -247.083179) (xy 342.567746 -247.123865) (xy 342.531042 -247.15912) (xy 342.489158 -247.18803)
			(xy 342.443179 -247.209847) (xy 342.394295 -247.224007) (xy 342.343774 -247.230141) (xy 342.292922 -247.228092)
			(xy 342.243058 -247.217912) (xy 342.195472 -247.199865) (xy 342.151398 -247.174419) (xy 342.111976 -247.142232)
			(xy 342.078228 -247.104138) (xy 342.051027 -247.061124) (xy 342.031079 -247.014304) (xy 342.0189 -246.96489)
			(xy 342.014805 -246.914162) (xy 341.696294 -246.914162) (xy 341.695851 -246.938157) (xy 341.688349 -246.985556)
			(xy 341.673523 -247.031198) (xy 341.65174 -247.073958) (xy 341.623534 -247.112784) (xy 341.589602 -247.146719)
			(xy 341.550779 -247.174927) (xy 341.50802 -247.196714) (xy 341.462379 -247.211543) (xy 341.414981 -247.219049)
			(xy 341.390986 -247.21947) (xy 341.376676 -247.2193) (xy 341.348182 -247.216626) (xy 341.33409 -247.214136)
			(xy 341.325454 -247.213374) (xy 341.31642 -247.213608) (xy 341.29938 -247.219595) (xy 341.29218 -247.225058)
			(xy 341.270844 -247.242838) (xy 341.233506 -247.273826) (xy 341.225255 -247.281431) (xy 341.215767 -247.301734)
			(xy 341.215218 -247.312942) (xy 341.215218 -247.642126) (xy 341.216742 -247.648222) (xy 341.221253 -247.666884)
			(xy 341.226093 -247.704971) (xy 341.226394 -247.724168) (xy 341.544905 -247.724168) (xy 341.549 -247.67344)
			(xy 341.561179 -247.624026) (xy 341.581127 -247.577206) (xy 341.608328 -247.534192) (xy 341.642076 -247.496098)
			(xy 341.681498 -247.463911) (xy 341.725572 -247.438465) (xy 341.773158 -247.420418) (xy 341.823022 -247.410238)
			(xy 341.873874 -247.408189) (xy 341.924395 -247.414323) (xy 341.973279 -247.428483) (xy 342.019258 -247.4503)
			(xy 342.061142 -247.47921) (xy 342.097846 -247.514465) (xy 342.128419 -247.555151) (xy 342.15207 -247.600214)
			(xy 342.168186 -247.648488) (xy 342.17635 -247.698722) (xy 342.176862 -247.724168) (xy 342.49539 -247.724168)
			(xy 342.49935 -247.675114) (xy 342.511127 -247.62733) (xy 342.530418 -247.582054) (xy 342.556721 -247.540458)
			(xy 342.589356 -247.503621) (xy 342.627477 -247.472496) (xy 342.670098 -247.447889) (xy 342.716114 -247.430437)
			(xy 342.764333 -247.420593) (xy 342.813508 -247.418612) (xy 342.862363 -247.424544) (xy 342.909634 -247.438236)
			(xy 342.954096 -247.459334) (xy 342.994599 -247.48729) (xy 343.030092 -247.521382) (xy 343.059657 -247.560726)
			(xy 343.082528 -247.604303) (xy 343.098112 -247.650984) (xy 343.106007 -247.699561) (xy 343.106502 -247.724168)
			(xy 343.424759 -247.724168) (xy 343.428854 -247.67344) (xy 343.441033 -247.624026) (xy 343.460981 -247.577206)
			(xy 343.488182 -247.534192) (xy 343.52193 -247.496098) (xy 343.561352 -247.463911) (xy 343.605426 -247.438465)
			(xy 343.653012 -247.420418) (xy 343.702876 -247.410238) (xy 343.753728 -247.408189) (xy 343.804249 -247.414323)
			(xy 343.853133 -247.428483) (xy 343.899112 -247.4503) (xy 343.940996 -247.47921) (xy 343.9777 -247.514465)
			(xy 344.008273 -247.555151) (xy 344.031924 -247.600214) (xy 344.04804 -247.648488) (xy 344.056204 -247.698722)
			(xy 344.056716 -247.724168) (xy 344.375244 -247.724168) (xy 344.379204 -247.675114) (xy 344.390981 -247.62733)
			(xy 344.410272 -247.582054) (xy 344.436575 -247.540458) (xy 344.46921 -247.503621) (xy 344.507331 -247.472496)
			(xy 344.549952 -247.447889) (xy 344.595968 -247.430437) (xy 344.644187 -247.420593) (xy 344.693362 -247.418612)
			(xy 344.742217 -247.424544) (xy 344.789488 -247.438236) (xy 344.83395 -247.459334) (xy 344.874453 -247.48729)
			(xy 344.909946 -247.521382) (xy 344.939511 -247.560726) (xy 344.962382 -247.604303) (xy 344.977966 -247.650984)
			(xy 344.985861 -247.699561) (xy 344.986356 -247.724168) (xy 345.315298 -247.724168) (xy 345.319258 -247.675114)
			(xy 345.331035 -247.62733) (xy 345.350326 -247.582054) (xy 345.376629 -247.540458) (xy 345.409264 -247.503621)
			(xy 345.447385 -247.472496) (xy 345.490006 -247.447889) (xy 345.536022 -247.430437) (xy 345.584241 -247.420593)
			(xy 345.633416 -247.418612) (xy 345.682271 -247.424544) (xy 345.729542 -247.438236) (xy 345.774004 -247.459334)
			(xy 345.814507 -247.48729) (xy 345.85 -247.521382) (xy 345.879565 -247.560726) (xy 345.902436 -247.604303)
			(xy 345.91802 -247.650984) (xy 345.925915 -247.699561) (xy 345.92641 -247.724168) (xy 346.255352 -247.724168)
			(xy 346.259312 -247.675114) (xy 346.271089 -247.62733) (xy 346.29038 -247.582054) (xy 346.316683 -247.540458)
			(xy 346.349318 -247.503621) (xy 346.387439 -247.472496) (xy 346.43006 -247.447889) (xy 346.476076 -247.430437)
			(xy 346.524295 -247.420593) (xy 346.57347 -247.418612) (xy 346.622325 -247.424544) (xy 346.669596 -247.438236)
			(xy 346.714058 -247.459334) (xy 346.754561 -247.48729) (xy 346.790054 -247.521382) (xy 346.819619 -247.560726)
			(xy 346.84249 -247.604303) (xy 346.858074 -247.650984) (xy 346.865969 -247.699561) (xy 346.866464 -247.724168)
			(xy 347.195406 -247.724168) (xy 347.199366 -247.675114) (xy 347.211143 -247.62733) (xy 347.230434 -247.582054)
			(xy 347.256737 -247.540458) (xy 347.289372 -247.503621) (xy 347.327493 -247.472496) (xy 347.370114 -247.447889)
			(xy 347.41613 -247.430437) (xy 347.464349 -247.420593) (xy 347.513524 -247.418612) (xy 347.562379 -247.424544)
			(xy 347.60965 -247.438236) (xy 347.654112 -247.459334) (xy 347.694615 -247.48729) (xy 347.730108 -247.521382)
			(xy 347.759673 -247.560726) (xy 347.782544 -247.604303) (xy 347.798128 -247.650984) (xy 347.806023 -247.699561)
			(xy 347.806518 -247.724168) (xy 348.135206 -247.724168) (xy 348.139166 -247.675114) (xy 348.150943 -247.62733)
			(xy 348.170234 -247.582054) (xy 348.196537 -247.540458) (xy 348.229172 -247.503621) (xy 348.267293 -247.472496)
			(xy 348.309914 -247.447889) (xy 348.35593 -247.430437) (xy 348.404149 -247.420593) (xy 348.453324 -247.418612)
			(xy 348.502179 -247.424544) (xy 348.54945 -247.438236) (xy 348.593912 -247.459334) (xy 348.634415 -247.48729)
			(xy 348.669908 -247.521382) (xy 348.699473 -247.560726) (xy 348.722344 -247.604303) (xy 348.737928 -247.650984)
			(xy 348.745823 -247.699561) (xy 348.746318 -247.724168) (xy 349.07526 -247.724168) (xy 349.07922 -247.675114)
			(xy 349.090997 -247.62733) (xy 349.110288 -247.582054) (xy 349.136591 -247.540458) (xy 349.169226 -247.503621)
			(xy 349.207347 -247.472496) (xy 349.249968 -247.447889) (xy 349.295984 -247.430437) (xy 349.344203 -247.420593)
			(xy 349.393378 -247.418612) (xy 349.442233 -247.424544) (xy 349.489504 -247.438236) (xy 349.533966 -247.459334)
			(xy 349.574469 -247.48729) (xy 349.609962 -247.521382) (xy 349.639527 -247.560726) (xy 349.662398 -247.604303)
			(xy 349.677982 -247.650984) (xy 349.685877 -247.699561) (xy 349.686372 -247.724168) (xy 350.015314 -247.724168)
			(xy 350.019274 -247.675114) (xy 350.031051 -247.62733) (xy 350.050342 -247.582054) (xy 350.076645 -247.540458)
			(xy 350.10928 -247.503621) (xy 350.147401 -247.472496) (xy 350.190022 -247.447889) (xy 350.236038 -247.430437)
			(xy 350.284257 -247.420593) (xy 350.333432 -247.418612) (xy 350.382287 -247.424544) (xy 350.429558 -247.438236)
			(xy 350.47402 -247.459334) (xy 350.514523 -247.48729) (xy 350.550016 -247.521382) (xy 350.579581 -247.560726)
			(xy 350.602452 -247.604303) (xy 350.618036 -247.650984) (xy 350.625931 -247.699561) (xy 350.626426 -247.724168)
			(xy 350.955368 -247.724168) (xy 350.959328 -247.675114) (xy 350.971105 -247.62733) (xy 350.990396 -247.582054)
			(xy 351.016699 -247.540458) (xy 351.049334 -247.503621) (xy 351.087455 -247.472496) (xy 351.130076 -247.447889)
			(xy 351.176092 -247.430437) (xy 351.224311 -247.420593) (xy 351.273486 -247.418612) (xy 351.322341 -247.424544)
			(xy 351.369612 -247.438236) (xy 351.414074 -247.459334) (xy 351.454577 -247.48729) (xy 351.49007 -247.521382)
			(xy 351.519635 -247.560726) (xy 351.542506 -247.604303) (xy 351.55809 -247.650984) (xy 351.565985 -247.699561)
			(xy 351.56648 -247.724168) (xy 351.895422 -247.724168) (xy 351.899382 -247.675114) (xy 351.911159 -247.62733)
			(xy 351.93045 -247.582054) (xy 351.956753 -247.540458) (xy 351.989388 -247.503621) (xy 352.027509 -247.472496)
			(xy 352.07013 -247.447889) (xy 352.116146 -247.430437) (xy 352.164365 -247.420593) (xy 352.21354 -247.418612)
			(xy 352.262395 -247.424544) (xy 352.309666 -247.438236) (xy 352.354128 -247.459334) (xy 352.394631 -247.48729)
			(xy 352.430124 -247.521382) (xy 352.459689 -247.560726) (xy 352.48256 -247.604303) (xy 352.498144 -247.650984)
			(xy 352.506039 -247.699561) (xy 352.506534 -247.724168) (xy 352.835222 -247.724168) (xy 352.839182 -247.675114)
			(xy 352.850959 -247.62733) (xy 352.87025 -247.582054) (xy 352.896553 -247.540458) (xy 352.929188 -247.503621)
			(xy 352.967309 -247.472496) (xy 353.00993 -247.447889) (xy 353.055946 -247.430437) (xy 353.104165 -247.420593)
			(xy 353.15334 -247.418612) (xy 353.202195 -247.424544) (xy 353.249466 -247.438236) (xy 353.293928 -247.459334)
			(xy 353.334431 -247.48729) (xy 353.369924 -247.521382) (xy 353.399489 -247.560726) (xy 353.42236 -247.604303)
			(xy 353.437944 -247.650984) (xy 353.445839 -247.699561) (xy 353.446334 -247.724168) (xy 353.775276 -247.724168)
			(xy 353.779236 -247.675114) (xy 353.791013 -247.62733) (xy 353.810304 -247.582054) (xy 353.836607 -247.540458)
			(xy 353.869242 -247.503621) (xy 353.907363 -247.472496) (xy 353.949984 -247.447889) (xy 353.996 -247.430437)
			(xy 354.044219 -247.420593) (xy 354.093394 -247.418612) (xy 354.142249 -247.424544) (xy 354.18952 -247.438236)
			(xy 354.233982 -247.459334) (xy 354.274485 -247.48729) (xy 354.309978 -247.521382) (xy 354.339543 -247.560726)
			(xy 354.362414 -247.604303) (xy 354.377998 -247.650984) (xy 354.385893 -247.699561) (xy 354.386388 -247.724168)
			(xy 354.71533 -247.724168) (xy 354.71929 -247.675114) (xy 354.731067 -247.62733) (xy 354.750358 -247.582054)
			(xy 354.776661 -247.540458) (xy 354.809296 -247.503621) (xy 354.847417 -247.472496) (xy 354.890038 -247.447889)
			(xy 354.936054 -247.430437) (xy 354.984273 -247.420593) (xy 355.033448 -247.418612) (xy 355.082303 -247.424544)
			(xy 355.129574 -247.438236) (xy 355.174036 -247.459334) (xy 355.214539 -247.48729) (xy 355.250032 -247.521382)
			(xy 355.279597 -247.560726) (xy 355.302468 -247.604303) (xy 355.318052 -247.650984) (xy 355.325947 -247.699561)
			(xy 355.326442 -247.724168) (xy 355.655384 -247.724168) (xy 355.659344 -247.675114) (xy 355.671121 -247.62733)
			(xy 355.690412 -247.582054) (xy 355.716715 -247.540458) (xy 355.74935 -247.503621) (xy 355.787471 -247.472496)
			(xy 355.830092 -247.447889) (xy 355.876108 -247.430437) (xy 355.924327 -247.420593) (xy 355.973502 -247.418612)
			(xy 356.022357 -247.424544) (xy 356.069628 -247.438236) (xy 356.11409 -247.459334) (xy 356.154593 -247.48729)
			(xy 356.190086 -247.521382) (xy 356.219651 -247.560726) (xy 356.242522 -247.604303) (xy 356.258106 -247.650984)
			(xy 356.266001 -247.699561) (xy 356.266496 -247.724168) (xy 356.595438 -247.724168) (xy 356.599398 -247.675114)
			(xy 356.611175 -247.62733) (xy 356.630466 -247.582054) (xy 356.656769 -247.540458) (xy 356.689404 -247.503621)
			(xy 356.727525 -247.472496) (xy 356.770146 -247.447889) (xy 356.816162 -247.430437) (xy 356.864381 -247.420593)
			(xy 356.913556 -247.418612) (xy 356.962411 -247.424544) (xy 357.009682 -247.438236) (xy 357.054144 -247.459334)
			(xy 357.094647 -247.48729) (xy 357.13014 -247.521382) (xy 357.159705 -247.560726) (xy 357.182576 -247.604303)
			(xy 357.19816 -247.650984) (xy 357.206055 -247.699561) (xy 357.20655 -247.724168) (xy 357.535238 -247.724168)
			(xy 357.539198 -247.675114) (xy 357.550975 -247.62733) (xy 357.570266 -247.582054) (xy 357.596569 -247.540458)
			(xy 357.629204 -247.503621) (xy 357.667325 -247.472496) (xy 357.709946 -247.447889) (xy 357.755962 -247.430437)
			(xy 357.804181 -247.420593) (xy 357.853356 -247.418612) (xy 357.902211 -247.424544) (xy 357.949482 -247.438236)
			(xy 357.988941 -247.45696) (xy 359.396541 -247.45696) (xy 359.400571 -247.404462) (xy 359.412568 -247.353194)
			(xy 359.432251 -247.304359) (xy 359.459157 -247.2591) (xy 359.492657 -247.218479) (xy 359.531965 -247.183448)
			(xy 359.57616 -247.154828) (xy 359.624205 -247.133289) (xy 359.674976 -247.119337) (xy 359.727281 -247.113299)
			(xy 359.779895 -247.115316) (xy 359.831585 -247.12534) (xy 359.881138 -247.143138) (xy 359.927394 -247.168291)
			(xy 359.969268 -247.20021) (xy 360.00578 -247.238148) (xy 360.036072 -247.281214) (xy 360.059435 -247.328399)
			(xy 360.075321 -247.378598) (xy 360.083358 -247.430634) (xy 360.083862 -247.45696) (xy 360.083358 -247.483286)
			(xy 360.075321 -247.535322) (xy 360.059435 -247.585521) (xy 360.036072 -247.632706) (xy 360.00578 -247.675772)
			(xy 359.969268 -247.71371) (xy 359.955548 -247.724168) (xy 361.289104 -247.724168) (xy 361.293064 -247.675114)
			(xy 361.304841 -247.62733) (xy 361.324132 -247.582054) (xy 361.350435 -247.540458) (xy 361.38307 -247.503621)
			(xy 361.421191 -247.472496) (xy 361.463812 -247.447889) (xy 361.509828 -247.430437) (xy 361.558047 -247.420593)
			(xy 361.607222 -247.418612) (xy 361.656077 -247.424544) (xy 361.703348 -247.438236) (xy 361.74781 -247.459334)
			(xy 361.788313 -247.48729) (xy 361.823806 -247.521382) (xy 361.853371 -247.560726) (xy 361.876242 -247.604303)
			(xy 361.891826 -247.650984) (xy 361.899721 -247.699561) (xy 361.900216 -247.724168) (xy 362.228904 -247.724168)
			(xy 362.232864 -247.675114) (xy 362.244641 -247.62733) (xy 362.263932 -247.582054) (xy 362.290235 -247.540458)
			(xy 362.32287 -247.503621) (xy 362.360991 -247.472496) (xy 362.403612 -247.447889) (xy 362.449628 -247.430437)
			(xy 362.497847 -247.420593) (xy 362.547022 -247.418612) (xy 362.595877 -247.424544) (xy 362.643148 -247.438236)
			(xy 362.68761 -247.459334) (xy 362.728113 -247.48729) (xy 362.763606 -247.521382) (xy 362.793171 -247.560726)
			(xy 362.816042 -247.604303) (xy 362.831626 -247.650984) (xy 362.839521 -247.699561) (xy 362.840016 -247.724168)
			(xy 363.168958 -247.724168) (xy 363.172918 -247.675114) (xy 363.184695 -247.62733) (xy 363.203986 -247.582054)
			(xy 363.230289 -247.540458) (xy 363.262924 -247.503621) (xy 363.301045 -247.472496) (xy 363.343666 -247.447889)
			(xy 363.389682 -247.430437) (xy 363.437901 -247.420593) (xy 363.487076 -247.418612) (xy 363.535931 -247.424544)
			(xy 363.583202 -247.438236) (xy 363.627664 -247.459334) (xy 363.668167 -247.48729) (xy 363.70366 -247.521382)
			(xy 363.733225 -247.560726) (xy 363.756096 -247.604303) (xy 363.77168 -247.650984) (xy 363.779575 -247.699561)
			(xy 363.78007 -247.724168) (xy 363.780069 -247.7242) (xy 364.108908 -247.7242) (xy 364.11308 -247.67385)
			(xy 364.125483 -247.624874) (xy 364.145778 -247.578607) (xy 364.173412 -247.536312) (xy 364.207631 -247.499142)
			(xy 364.247501 -247.468112) (xy 364.291935 -247.444068) (xy 364.339721 -247.427665) (xy 364.389555 -247.419352)
			(xy 364.414816 -247.41886) (xy 365.35487 -247.41886) (xy 365.380127 -247.419414) (xy 365.429952 -247.427724)
			(xy 365.477729 -247.444122) (xy 365.522156 -247.468161) (xy 365.56202 -247.499184) (xy 365.596233 -247.536347)
			(xy 365.623863 -247.578634) (xy 365.644155 -247.624892) (xy 365.656556 -247.673859) (xy 365.660725 -247.724168)
			(xy 365.98912 -247.724168) (xy 365.99308 -247.675114) (xy 366.004857 -247.62733) (xy 366.024148 -247.582054)
			(xy 366.050451 -247.540458) (xy 366.083086 -247.503621) (xy 366.121207 -247.472496) (xy 366.163828 -247.447889)
			(xy 366.209844 -247.430437) (xy 366.258063 -247.420593) (xy 366.307238 -247.418612) (xy 366.356093 -247.424544)
			(xy 366.403364 -247.438236) (xy 366.447826 -247.459334) (xy 366.488329 -247.48729) (xy 366.523822 -247.521382)
			(xy 366.553387 -247.560726) (xy 366.576258 -247.604303) (xy 366.591842 -247.650984) (xy 366.599737 -247.699561)
			(xy 366.600232 -247.724168) (xy 366.600231 -247.7242) (xy 366.928808 -247.7242) (xy 366.93298 -247.673849)
			(xy 366.945384 -247.624872) (xy 366.96568 -247.578605) (xy 366.993314 -247.536309) (xy 367.027534 -247.499139)
			(xy 367.067406 -247.468109) (xy 367.111841 -247.444065) (xy 367.159628 -247.427663) (xy 367.209462 -247.419351)
			(xy 367.234724 -247.41886) (xy 368.174778 -247.41886) (xy 368.200034 -247.419415) (xy 368.249858 -247.427726)
			(xy 368.297635 -247.444124) (xy 368.34206 -247.468163) (xy 368.381923 -247.499187) (xy 368.416136 -247.536349)
			(xy 368.443764 -247.578636) (xy 368.464056 -247.624893) (xy 368.476457 -247.67386) (xy 368.480625 -247.724168)
			(xy 368.809028 -247.724168) (xy 368.812988 -247.675114) (xy 368.824765 -247.62733) (xy 368.844056 -247.582054)
			(xy 368.870359 -247.540458) (xy 368.902994 -247.503621) (xy 368.941115 -247.472496) (xy 368.983736 -247.447889)
			(xy 369.029752 -247.430437) (xy 369.077971 -247.420593) (xy 369.127146 -247.418612) (xy 369.176001 -247.424544)
			(xy 369.223272 -247.438236) (xy 369.267734 -247.459334) (xy 369.308237 -247.48729) (xy 369.34373 -247.521382)
			(xy 369.373295 -247.560726) (xy 369.396166 -247.604303) (xy 369.41175 -247.650984) (xy 369.419645 -247.699561)
			(xy 369.42014 -247.724168) (xy 369.420139 -247.7242) (xy 369.749037 -247.7242) (xy 369.753208 -247.673858)
			(xy 369.765609 -247.624889) (xy 369.785899 -247.578629) (xy 369.813527 -247.53634) (xy 369.847739 -247.499174)
			(xy 369.887601 -247.468147) (xy 369.932027 -247.444103) (xy 369.979804 -247.427699) (xy 370.029629 -247.419383)
			(xy 370.054886 -247.41886) (xy 370.99494 -247.41886) (xy 371.020191 -247.419449) (xy 371.070002 -247.427767)
			(xy 371.117765 -247.444169) (xy 371.162177 -247.468209) (xy 371.202028 -247.499231) (xy 371.236229 -247.536388)
			(xy 371.263848 -247.578667) (xy 371.284133 -247.624915) (xy 371.296529 -247.673871) (xy 371.300696 -247.724168)
			(xy 371.628936 -247.724168) (xy 371.632896 -247.675114) (xy 371.644673 -247.62733) (xy 371.663964 -247.582054)
			(xy 371.690267 -247.540458) (xy 371.722902 -247.503621) (xy 371.761023 -247.472496) (xy 371.803644 -247.447889)
			(xy 371.84966 -247.430437) (xy 371.897879 -247.420593) (xy 371.947054 -247.418612) (xy 371.995909 -247.424544)
			(xy 372.04318 -247.438236) (xy 372.087642 -247.459334) (xy 372.128145 -247.48729) (xy 372.163638 -247.521382)
			(xy 372.193203 -247.560726) (xy 372.216074 -247.604303) (xy 372.231658 -247.650984) (xy 372.239553 -247.699561)
			(xy 372.240048 -247.724168) (xy 372.240047 -247.7242) (xy 372.568937 -247.7242) (xy 372.573108 -247.673857)
			(xy 372.585509 -247.624888) (xy 372.605801 -247.578627) (xy 372.63343 -247.536337) (xy 372.667642 -247.499171)
			(xy 372.707506 -247.468144) (xy 372.751932 -247.444101) (xy 372.79971 -247.427698) (xy 372.849536 -247.419382)
			(xy 372.874794 -247.41886) (xy 373.814848 -247.41886) (xy 373.840098 -247.419449) (xy 373.889908 -247.427768)
			(xy 373.93767 -247.444172) (xy 373.982082 -247.468212) (xy 374.021931 -247.499233) (xy 374.056131 -247.53639)
			(xy 374.083749 -247.578669) (xy 374.104033 -247.624917) (xy 374.116429 -247.673872) (xy 374.120596 -247.724168)
			(xy 374.449098 -247.724168) (xy 374.453058 -247.675114) (xy 374.464835 -247.62733) (xy 374.484126 -247.582054)
			(xy 374.510429 -247.540458) (xy 374.543064 -247.503621) (xy 374.581185 -247.472496) (xy 374.623806 -247.447889)
			(xy 374.669822 -247.430437) (xy 374.718041 -247.420593) (xy 374.767216 -247.418612) (xy 374.816071 -247.424544)
			(xy 374.863342 -247.438236) (xy 374.907804 -247.459334) (xy 374.948307 -247.48729) (xy 374.9838 -247.521382)
			(xy 375.013365 -247.560726) (xy 375.036236 -247.604303) (xy 375.05182 -247.650984) (xy 375.059715 -247.699561)
			(xy 375.06021 -247.724168) (xy 375.378467 -247.724168) (xy 375.382562 -247.67344) (xy 375.394741 -247.624026)
			(xy 375.414689 -247.577206) (xy 375.44189 -247.534192) (xy 375.475638 -247.496098) (xy 375.51506 -247.463911)
			(xy 375.559134 -247.438465) (xy 375.60672 -247.420418) (xy 375.656584 -247.410238) (xy 375.707436 -247.408189)
			(xy 375.757957 -247.414323) (xy 375.806841 -247.428483) (xy 375.85282 -247.4503) (xy 375.894704 -247.47921)
			(xy 375.931408 -247.514465) (xy 375.961981 -247.555151) (xy 375.985632 -247.600214) (xy 376.001748 -247.648488)
			(xy 376.009912 -247.698722) (xy 376.010424 -247.724168) (xy 376.328952 -247.724168) (xy 376.332912 -247.675114)
			(xy 376.344689 -247.62733) (xy 376.36398 -247.582054) (xy 376.390283 -247.540458) (xy 376.422918 -247.503621)
			(xy 376.461039 -247.472496) (xy 376.50366 -247.447889) (xy 376.549676 -247.430437) (xy 376.597895 -247.420593)
			(xy 376.64707 -247.418612) (xy 376.695925 -247.424544) (xy 376.743196 -247.438236) (xy 376.787658 -247.459334)
			(xy 376.828161 -247.48729) (xy 376.863654 -247.521382) (xy 376.893219 -247.560726) (xy 376.91609 -247.604303)
			(xy 376.931674 -247.650984) (xy 376.939569 -247.699561) (xy 376.940064 -247.724168) (xy 376.939569 -247.748775)
			(xy 376.931674 -247.797352) (xy 376.91609 -247.844033) (xy 376.893219 -247.88761) (xy 376.863654 -247.926954)
			(xy 376.828161 -247.961046) (xy 376.787658 -247.989002) (xy 376.743196 -248.0101) (xy 376.695925 -248.023792)
			(xy 376.64707 -248.029724) (xy 376.597895 -248.027743) (xy 376.549676 -248.017899) (xy 376.50366 -248.000447)
			(xy 376.461039 -247.97584) (xy 376.422918 -247.944715) (xy 376.390283 -247.907878) (xy 376.36398 -247.866282)
			(xy 376.344689 -247.821006) (xy 376.332912 -247.773222) (xy 376.328952 -247.724168) (xy 376.010424 -247.724168)
			(xy 376.009912 -247.749614) (xy 376.001748 -247.799848) (xy 375.985632 -247.848122) (xy 375.961981 -247.893185)
			(xy 375.931408 -247.933871) (xy 375.894704 -247.969126) (xy 375.85282 -247.998036) (xy 375.806841 -248.019853)
			(xy 375.757957 -248.034013) (xy 375.707436 -248.040147) (xy 375.656584 -248.038098) (xy 375.60672 -248.027918)
			(xy 375.559134 -248.009871) (xy 375.51506 -247.984425) (xy 375.475638 -247.952238) (xy 375.44189 -247.914144)
			(xy 375.414689 -247.87113) (xy 375.394741 -247.82431) (xy 375.382562 -247.774896) (xy 375.378467 -247.724168)
			(xy 375.06021 -247.724168) (xy 375.059715 -247.748775) (xy 375.05182 -247.797352) (xy 375.036236 -247.844033)
			(xy 375.013365 -247.88761) (xy 374.9838 -247.926954) (xy 374.948307 -247.961046) (xy 374.907804 -247.989002)
			(xy 374.863342 -248.0101) (xy 374.816071 -248.023792) (xy 374.767216 -248.029724) (xy 374.718041 -248.027743)
			(xy 374.669822 -248.017899) (xy 374.623806 -248.000447) (xy 374.581185 -247.97584) (xy 374.543064 -247.944715)
			(xy 374.510429 -247.907878) (xy 374.484126 -247.866282) (xy 374.464835 -247.821006) (xy 374.453058 -247.773222)
			(xy 374.449098 -247.724168) (xy 374.120596 -247.724168) (xy 374.120599 -247.7242) (xy 374.116429 -247.774528)
			(xy 374.104033 -247.823483) (xy 374.083749 -247.869731) (xy 374.056131 -247.91201) (xy 374.021931 -247.949166)
			(xy 373.982082 -247.980188) (xy 373.937671 -248.004228) (xy 373.889908 -248.020632) (xy 373.840098 -248.028951)
			(xy 373.814848 -248.029476) (xy 372.874794 -248.029476) (xy 372.849536 -248.029018) (xy 372.79971 -248.020702)
			(xy 372.751932 -248.004299) (xy 372.707506 -247.980256) (xy 372.667642 -247.949229) (xy 372.63343 -247.912063)
			(xy 372.605801 -247.869773) (xy 372.585509 -247.823512) (xy 372.573108 -247.774543) (xy 372.568937 -247.7242)
			(xy 372.240047 -247.7242) (xy 372.239553 -247.748775) (xy 372.231658 -247.797352) (xy 372.216074 -247.844033)
			(xy 372.193203 -247.88761) (xy 372.163638 -247.926954) (xy 372.128145 -247.961046) (xy 372.087642 -247.989002)
			(xy 372.04318 -248.0101) (xy 371.995909 -248.023792) (xy 371.947054 -248.029724) (xy 371.897879 -248.027743)
			(xy 371.84966 -248.017899) (xy 371.803644 -248.000447) (xy 371.761023 -247.97584) (xy 371.722902 -247.944715)
			(xy 371.690267 -247.907878) (xy 371.663964 -247.866282) (xy 371.644673 -247.821006) (xy 371.632896 -247.773222)
			(xy 371.628936 -247.724168) (xy 371.300696 -247.724168) (xy 371.300699 -247.7242) (xy 371.296529 -247.774529)
			(xy 371.284133 -247.823485) (xy 371.263848 -247.869733) (xy 371.236229 -247.912012) (xy 371.202028 -247.949169)
			(xy 371.162177 -247.980191) (xy 371.117765 -248.004231) (xy 371.070002 -248.020633) (xy 371.020191 -248.028951)
			(xy 370.99494 -248.029476) (xy 370.054886 -248.029476) (xy 370.029629 -248.029017) (xy 369.979804 -248.020701)
			(xy 369.932027 -248.004297) (xy 369.887601 -247.980253) (xy 369.847739 -247.949226) (xy 369.813527 -247.91206)
			(xy 369.785899 -247.869771) (xy 369.765609 -247.823511) (xy 369.753208 -247.774542) (xy 369.749037 -247.7242)
			(xy 369.420139 -247.7242) (xy 369.419645 -247.748775) (xy 369.41175 -247.797352) (xy 369.396166 -247.844033)
			(xy 369.373295 -247.88761) (xy 369.34373 -247.926954) (xy 369.308237 -247.961046) (xy 369.267734 -247.989002)
			(xy 369.223272 -248.0101) (xy 369.176001 -248.023792) (xy 369.127146 -248.029724) (xy 369.077971 -248.027743)
			(xy 369.029752 -248.017899) (xy 368.983736 -248.000447) (xy 368.941115 -247.97584) (xy 368.902994 -247.944715)
			(xy 368.870359 -247.907878) (xy 368.844056 -247.866282) (xy 368.824765 -247.821006) (xy 368.812988 -247.773222)
			(xy 368.809028 -247.724168) (xy 368.480625 -247.724168) (xy 368.480628 -247.7242) (xy 368.476457 -247.77454)
			(xy 368.464056 -247.823507) (xy 368.443764 -247.869764) (xy 368.416136 -247.912051) (xy 368.381923 -247.949213)
			(xy 368.34206 -247.980237) (xy 368.297635 -248.004276) (xy 368.249858 -248.020674) (xy 368.200034 -248.028985)
			(xy 368.174778 -248.029476) (xy 367.234724 -248.029476) (xy 367.209462 -248.029049) (xy 367.159628 -248.020737)
			(xy 367.111841 -248.004335) (xy 367.067406 -247.980291) (xy 367.027534 -247.949261) (xy 366.993314 -247.912091)
			(xy 366.96568 -247.869795) (xy 366.945384 -247.823528) (xy 366.93298 -247.774551) (xy 366.928808 -247.7242)
			(xy 366.600231 -247.7242) (xy 366.599737 -247.748775) (xy 366.591842 -247.797352) (xy 366.576258 -247.844033)
			(xy 366.553387 -247.88761) (xy 366.523822 -247.926954) (xy 366.488329 -247.961046) (xy 366.447826 -247.989002)
			(xy 366.403364 -248.0101) (xy 366.356093 -248.023792) (xy 366.307238 -248.029724) (xy 366.258063 -248.027743)
			(xy 366.209844 -248.017899) (xy 366.163828 -248.000447) (xy 366.121207 -247.97584) (xy 366.083086 -247.944715)
			(xy 366.050451 -247.907878) (xy 366.024148 -247.866282) (xy 366.004857 -247.821006) (xy 365.99308 -247.773222)
			(xy 365.98912 -247.724168) (xy 365.660725 -247.724168) (xy 365.660728 -247.7242) (xy 365.656556 -247.774541)
			(xy 365.644155 -247.823508) (xy 365.623863 -247.869766) (xy 365.596233 -247.912053) (xy 365.56202 -247.949216)
			(xy 365.522156 -247.980239) (xy 365.477729 -248.004278) (xy 365.429952 -248.020676) (xy 365.380127 -248.028986)
			(xy 365.35487 -248.029476) (xy 364.414816 -248.029476) (xy 364.389555 -248.029048) (xy 364.339721 -248.020735)
			(xy 364.291935 -248.004332) (xy 364.247501 -247.980288) (xy 364.207631 -247.949258) (xy 364.173412 -247.912088)
			(xy 364.145778 -247.869793) (xy 364.125483 -247.823526) (xy 364.11308 -247.77455) (xy 364.108908 -247.7242)
			(xy 363.780069 -247.7242) (xy 363.779575 -247.748775) (xy 363.77168 -247.797352) (xy 363.756096 -247.844033)
			(xy 363.733225 -247.88761) (xy 363.70366 -247.926954) (xy 363.668167 -247.961046) (xy 363.627664 -247.989002)
			(xy 363.583202 -248.0101) (xy 363.535931 -248.023792) (xy 363.487076 -248.029724) (xy 363.437901 -248.027743)
			(xy 363.389682 -248.017899) (xy 363.343666 -248.000447) (xy 363.301045 -247.97584) (xy 363.262924 -247.944715)
			(xy 363.230289 -247.907878) (xy 363.203986 -247.866282) (xy 363.184695 -247.821006) (xy 363.172918 -247.773222)
			(xy 363.168958 -247.724168) (xy 362.840016 -247.724168) (xy 362.839521 -247.748775) (xy 362.831626 -247.797352)
			(xy 362.816042 -247.844033) (xy 362.793171 -247.88761) (xy 362.763606 -247.926954) (xy 362.728113 -247.961046)
			(xy 362.68761 -247.989002) (xy 362.643148 -248.0101) (xy 362.595877 -248.023792) (xy 362.547022 -248.029724)
			(xy 362.497847 -248.027743) (xy 362.449628 -248.017899) (xy 362.403612 -248.000447) (xy 362.360991 -247.97584)
			(xy 362.32287 -247.944715) (xy 362.290235 -247.907878) (xy 362.263932 -247.866282) (xy 362.244641 -247.821006)
			(xy 362.232864 -247.773222) (xy 362.228904 -247.724168) (xy 361.900216 -247.724168) (xy 361.899721 -247.748775)
			(xy 361.891826 -247.797352) (xy 361.876242 -247.844033) (xy 361.853371 -247.88761) (xy 361.823806 -247.926954)
			(xy 361.788313 -247.961046) (xy 361.74781 -247.989002) (xy 361.703348 -248.0101) (xy 361.656077 -248.023792)
			(xy 361.607222 -248.029724) (xy 361.558047 -248.027743) (xy 361.509828 -248.017899) (xy 361.463812 -248.000447)
			(xy 361.421191 -247.97584) (xy 361.38307 -247.944715) (xy 361.350435 -247.907878) (xy 361.324132 -247.866282)
			(xy 361.304841 -247.821006) (xy 361.293064 -247.773222) (xy 361.289104 -247.724168) (xy 359.955548 -247.724168)
			(xy 359.927394 -247.745629) (xy 359.881138 -247.770782) (xy 359.831585 -247.78858) (xy 359.779895 -247.798604)
			(xy 359.727281 -247.800621) (xy 359.674976 -247.794583) (xy 359.624205 -247.780631) (xy 359.57616 -247.759092)
			(xy 359.531965 -247.730472) (xy 359.492657 -247.695441) (xy 359.459157 -247.65482) (xy 359.432251 -247.609561)
			(xy 359.412568 -247.560726) (xy 359.400571 -247.509458) (xy 359.396541 -247.45696) (xy 357.988941 -247.45696)
			(xy 357.993944 -247.459334) (xy 358.034447 -247.48729) (xy 358.06994 -247.521382) (xy 358.099505 -247.560726)
			(xy 358.122376 -247.604303) (xy 358.13796 -247.650984) (xy 358.145855 -247.699561) (xy 358.14635 -247.724168)
			(xy 358.145855 -247.748775) (xy 358.13796 -247.797352) (xy 358.122376 -247.844033) (xy 358.099505 -247.88761)
			(xy 358.06994 -247.926954) (xy 358.034447 -247.961046) (xy 357.993944 -247.989002) (xy 357.949482 -248.0101)
			(xy 357.902211 -248.023792) (xy 357.853356 -248.029724) (xy 357.804181 -248.027743) (xy 357.755962 -248.017899)
			(xy 357.709946 -248.000447) (xy 357.667325 -247.97584) (xy 357.629204 -247.944715) (xy 357.596569 -247.907878)
			(xy 357.570266 -247.866282) (xy 357.550975 -247.821006) (xy 357.539198 -247.773222) (xy 357.535238 -247.724168)
			(xy 357.20655 -247.724168) (xy 357.206055 -247.748775) (xy 357.19816 -247.797352) (xy 357.182576 -247.844033)
			(xy 357.159705 -247.88761) (xy 357.13014 -247.926954) (xy 357.094647 -247.961046) (xy 357.054144 -247.989002)
			(xy 357.009682 -248.0101) (xy 356.962411 -248.023792) (xy 356.913556 -248.029724) (xy 356.864381 -248.027743)
			(xy 356.816162 -248.017899) (xy 356.770146 -248.000447) (xy 356.727525 -247.97584) (xy 356.689404 -247.944715)
			(xy 356.656769 -247.907878) (xy 356.630466 -247.866282) (xy 356.611175 -247.821006) (xy 356.599398 -247.773222)
			(xy 356.595438 -247.724168) (xy 356.266496 -247.724168) (xy 356.266001 -247.748775) (xy 356.258106 -247.797352)
			(xy 356.242522 -247.844033) (xy 356.219651 -247.88761) (xy 356.190086 -247.926954) (xy 356.154593 -247.961046)
			(xy 356.11409 -247.989002) (xy 356.069628 -248.0101) (xy 356.022357 -248.023792) (xy 355.973502 -248.029724)
			(xy 355.924327 -248.027743) (xy 355.876108 -248.017899) (xy 355.830092 -248.000447) (xy 355.787471 -247.97584)
			(xy 355.74935 -247.944715) (xy 355.716715 -247.907878) (xy 355.690412 -247.866282) (xy 355.671121 -247.821006)
			(xy 355.659344 -247.773222) (xy 355.655384 -247.724168) (xy 355.326442 -247.724168) (xy 355.325947 -247.748775)
			(xy 355.318052 -247.797352) (xy 355.302468 -247.844033) (xy 355.279597 -247.88761) (xy 355.250032 -247.926954)
			(xy 355.214539 -247.961046) (xy 355.174036 -247.989002) (xy 355.129574 -248.0101) (xy 355.082303 -248.023792)
			(xy 355.033448 -248.029724) (xy 354.984273 -248.027743) (xy 354.936054 -248.017899) (xy 354.890038 -248.000447)
			(xy 354.847417 -247.97584) (xy 354.809296 -247.944715) (xy 354.776661 -247.907878) (xy 354.750358 -247.866282)
			(xy 354.731067 -247.821006) (xy 354.71929 -247.773222) (xy 354.71533 -247.724168) (xy 354.386388 -247.724168)
			(xy 354.385893 -247.748775) (xy 354.377998 -247.797352) (xy 354.362414 -247.844033) (xy 354.339543 -247.88761)
			(xy 354.309978 -247.926954) (xy 354.274485 -247.961046) (xy 354.233982 -247.989002) (xy 354.18952 -248.0101)
			(xy 354.142249 -248.023792) (xy 354.093394 -248.029724) (xy 354.044219 -248.027743) (xy 353.996 -248.017899)
			(xy 353.949984 -248.000447) (xy 353.907363 -247.97584) (xy 353.869242 -247.944715) (xy 353.836607 -247.907878)
			(xy 353.810304 -247.866282) (xy 353.791013 -247.821006) (xy 353.779236 -247.773222) (xy 353.775276 -247.724168)
			(xy 353.446334 -247.724168) (xy 353.445839 -247.748775) (xy 353.437944 -247.797352) (xy 353.42236 -247.844033)
			(xy 353.399489 -247.88761) (xy 353.369924 -247.926954) (xy 353.334431 -247.961046) (xy 353.293928 -247.989002)
			(xy 353.249466 -248.0101) (xy 353.202195 -248.023792) (xy 353.15334 -248.029724) (xy 353.104165 -248.027743)
			(xy 353.055946 -248.017899) (xy 353.00993 -248.000447) (xy 352.967309 -247.97584) (xy 352.929188 -247.944715)
			(xy 352.896553 -247.907878) (xy 352.87025 -247.866282) (xy 352.850959 -247.821006) (xy 352.839182 -247.773222)
			(xy 352.835222 -247.724168) (xy 352.506534 -247.724168) (xy 352.506039 -247.748775) (xy 352.498144 -247.797352)
			(xy 352.48256 -247.844033) (xy 352.459689 -247.88761) (xy 352.430124 -247.926954) (xy 352.394631 -247.961046)
			(xy 352.354128 -247.989002) (xy 352.309666 -248.0101) (xy 352.262395 -248.023792) (xy 352.21354 -248.029724)
			(xy 352.164365 -248.027743) (xy 352.116146 -248.017899) (xy 352.07013 -248.000447) (xy 352.027509 -247.97584)
			(xy 351.989388 -247.944715) (xy 351.956753 -247.907878) (xy 351.93045 -247.866282) (xy 351.911159 -247.821006)
			(xy 351.899382 -247.773222) (xy 351.895422 -247.724168) (xy 351.56648 -247.724168) (xy 351.565985 -247.748775)
			(xy 351.55809 -247.797352) (xy 351.542506 -247.844033) (xy 351.519635 -247.88761) (xy 351.49007 -247.926954)
			(xy 351.454577 -247.961046) (xy 351.414074 -247.989002) (xy 351.369612 -248.0101) (xy 351.322341 -248.023792)
			(xy 351.273486 -248.029724) (xy 351.224311 -248.027743) (xy 351.176092 -248.017899) (xy 351.130076 -248.000447)
			(xy 351.087455 -247.97584) (xy 351.049334 -247.944715) (xy 351.016699 -247.907878) (xy 350.990396 -247.866282)
			(xy 350.971105 -247.821006) (xy 350.959328 -247.773222) (xy 350.955368 -247.724168) (xy 350.626426 -247.724168)
			(xy 350.625931 -247.748775) (xy 350.618036 -247.797352) (xy 350.602452 -247.844033) (xy 350.579581 -247.88761)
			(xy 350.550016 -247.926954) (xy 350.514523 -247.961046) (xy 350.47402 -247.989002) (xy 350.429558 -248.0101)
			(xy 350.382287 -248.023792) (xy 350.333432 -248.029724) (xy 350.284257 -248.027743) (xy 350.236038 -248.017899)
			(xy 350.190022 -248.000447) (xy 350.147401 -247.97584) (xy 350.10928 -247.944715) (xy 350.076645 -247.907878)
			(xy 350.050342 -247.866282) (xy 350.031051 -247.821006) (xy 350.019274 -247.773222) (xy 350.015314 -247.724168)
			(xy 349.686372 -247.724168) (xy 349.685877 -247.748775) (xy 349.677982 -247.797352) (xy 349.662398 -247.844033)
			(xy 349.639527 -247.88761) (xy 349.609962 -247.926954) (xy 349.574469 -247.961046) (xy 349.533966 -247.989002)
			(xy 349.489504 -248.0101) (xy 349.442233 -248.023792) (xy 349.393378 -248.029724) (xy 349.344203 -248.027743)
			(xy 349.295984 -248.017899) (xy 349.249968 -248.000447) (xy 349.207347 -247.97584) (xy 349.169226 -247.944715)
			(xy 349.136591 -247.907878) (xy 349.110288 -247.866282) (xy 349.090997 -247.821006) (xy 349.07922 -247.773222)
			(xy 349.07526 -247.724168) (xy 348.746318 -247.724168) (xy 348.745823 -247.748775) (xy 348.737928 -247.797352)
			(xy 348.722344 -247.844033) (xy 348.699473 -247.88761) (xy 348.669908 -247.926954) (xy 348.634415 -247.961046)
			(xy 348.593912 -247.989002) (xy 348.54945 -248.0101) (xy 348.502179 -248.023792) (xy 348.453324 -248.029724)
			(xy 348.404149 -248.027743) (xy 348.35593 -248.017899) (xy 348.309914 -248.000447) (xy 348.267293 -247.97584)
			(xy 348.229172 -247.944715) (xy 348.196537 -247.907878) (xy 348.170234 -247.866282) (xy 348.150943 -247.821006)
			(xy 348.139166 -247.773222) (xy 348.135206 -247.724168) (xy 347.806518 -247.724168) (xy 347.806023 -247.748775)
			(xy 347.798128 -247.797352) (xy 347.782544 -247.844033) (xy 347.759673 -247.88761) (xy 347.730108 -247.926954)
			(xy 347.694615 -247.961046) (xy 347.654112 -247.989002) (xy 347.60965 -248.0101) (xy 347.562379 -248.023792)
			(xy 347.513524 -248.029724) (xy 347.464349 -248.027743) (xy 347.41613 -248.017899) (xy 347.370114 -248.000447)
			(xy 347.327493 -247.97584) (xy 347.289372 -247.944715) (xy 347.256737 -247.907878) (xy 347.230434 -247.866282)
			(xy 347.211143 -247.821006) (xy 347.199366 -247.773222) (xy 347.195406 -247.724168) (xy 346.866464 -247.724168)
			(xy 346.865969 -247.748775) (xy 346.858074 -247.797352) (xy 346.84249 -247.844033) (xy 346.819619 -247.88761)
			(xy 346.790054 -247.926954) (xy 346.754561 -247.961046) (xy 346.714058 -247.989002) (xy 346.669596 -248.0101)
			(xy 346.622325 -248.023792) (xy 346.57347 -248.029724) (xy 346.524295 -248.027743) (xy 346.476076 -248.017899)
			(xy 346.43006 -248.000447) (xy 346.387439 -247.97584) (xy 346.349318 -247.944715) (xy 346.316683 -247.907878)
			(xy 346.29038 -247.866282) (xy 346.271089 -247.821006) (xy 346.259312 -247.773222) (xy 346.255352 -247.724168)
			(xy 345.92641 -247.724168) (xy 345.925915 -247.748775) (xy 345.91802 -247.797352) (xy 345.902436 -247.844033)
			(xy 345.879565 -247.88761) (xy 345.85 -247.926954) (xy 345.814507 -247.961046) (xy 345.774004 -247.989002)
			(xy 345.729542 -248.0101) (xy 345.682271 -248.023792) (xy 345.633416 -248.029724) (xy 345.584241 -248.027743)
			(xy 345.536022 -248.017899) (xy 345.490006 -248.000447) (xy 345.447385 -247.97584) (xy 345.409264 -247.944715)
			(xy 345.376629 -247.907878) (xy 345.350326 -247.866282) (xy 345.331035 -247.821006) (xy 345.319258 -247.773222)
			(xy 345.315298 -247.724168) (xy 344.986356 -247.724168) (xy 344.985861 -247.748775) (xy 344.977966 -247.797352)
			(xy 344.962382 -247.844033) (xy 344.939511 -247.88761) (xy 344.909946 -247.926954) (xy 344.874453 -247.961046)
			(xy 344.83395 -247.989002) (xy 344.789488 -248.0101) (xy 344.742217 -248.023792) (xy 344.693362 -248.029724)
			(xy 344.644187 -248.027743) (xy 344.595968 -248.017899) (xy 344.549952 -248.000447) (xy 344.507331 -247.97584)
			(xy 344.46921 -247.944715) (xy 344.436575 -247.907878) (xy 344.410272 -247.866282) (xy 344.390981 -247.821006)
			(xy 344.379204 -247.773222) (xy 344.375244 -247.724168) (xy 344.056716 -247.724168) (xy 344.056204 -247.749614)
			(xy 344.04804 -247.799848) (xy 344.031924 -247.848122) (xy 344.008273 -247.893185) (xy 343.9777 -247.933871)
			(xy 343.940996 -247.969126) (xy 343.899112 -247.998036) (xy 343.853133 -248.019853) (xy 343.804249 -248.034013)
			(xy 343.753728 -248.040147) (xy 343.702876 -248.038098) (xy 343.653012 -248.027918) (xy 343.605426 -248.009871)
			(xy 343.561352 -247.984425) (xy 343.52193 -247.952238) (xy 343.488182 -247.914144) (xy 343.460981 -247.87113)
			(xy 343.441033 -247.82431) (xy 343.428854 -247.774896) (xy 343.424759 -247.724168) (xy 343.106502 -247.724168)
			(xy 343.106007 -247.748775) (xy 343.098112 -247.797352) (xy 343.082528 -247.844033) (xy 343.059657 -247.88761)
			(xy 343.030092 -247.926954) (xy 342.994599 -247.961046) (xy 342.954096 -247.989002) (xy 342.909634 -248.0101)
			(xy 342.862363 -248.023792) (xy 342.813508 -248.029724) (xy 342.764333 -248.027743) (xy 342.716114 -248.017899)
			(xy 342.670098 -248.000447) (xy 342.627477 -247.97584) (xy 342.589356 -247.944715) (xy 342.556721 -247.907878)
			(xy 342.530418 -247.866282) (xy 342.511127 -247.821006) (xy 342.49935 -247.773222) (xy 342.49539 -247.724168)
			(xy 342.176862 -247.724168) (xy 342.17635 -247.749614) (xy 342.168186 -247.799848) (xy 342.15207 -247.848122)
			(xy 342.128419 -247.893185) (xy 342.097846 -247.933871) (xy 342.061142 -247.969126) (xy 342.019258 -247.998036)
			(xy 341.973279 -248.019853) (xy 341.924395 -248.034013) (xy 341.873874 -248.040147) (xy 341.823022 -248.038098)
			(xy 341.773158 -248.027918) (xy 341.725572 -248.009871) (xy 341.681498 -247.984425) (xy 341.642076 -247.952238)
			(xy 341.608328 -247.914144) (xy 341.581127 -247.87113) (xy 341.561179 -247.82431) (xy 341.549 -247.774896)
			(xy 341.544905 -247.724168) (xy 341.226394 -247.724168) (xy 341.226077 -247.743364) (xy 341.22124 -247.78145)
			(xy 341.216742 -247.800114) (xy 341.215218 -247.80621) (xy 341.215218 -248.135394) (xy 341.215805 -248.146591)
			(xy 341.22529 -248.16688) (xy 341.233506 -248.17451) (xy 341.270844 -248.205498) (xy 341.29218 -248.223278)
			(xy 341.299356 -248.228788) (xy 341.316409 -248.234793) (xy 341.325454 -248.234962) (xy 341.330026 -248.234962)
			(xy 341.34504 -248.232108) (xy 341.37545 -248.229058) (xy 341.390732 -248.228866) (xy 341.393018 -248.228866)
			(xy 341.416524 -248.229462) (xy 341.462936 -248.236989) (xy 341.507646 -248.25154) (xy 341.549598 -248.27277)
			(xy 341.587802 -248.300179) (xy 341.621354 -248.333118) (xy 341.649462 -248.37081) (xy 341.671461 -248.412364)
			(xy 341.686833 -248.456799) (xy 341.695215 -248.503065) (xy 341.696294 -248.526554) (xy 341.696294 -248.534174)
			(xy 341.695776 -248.560115) (xy 341.687003 -248.61125) (xy 341.669706 -248.660164) (xy 341.644384 -248.705447)
			(xy 341.628476 -248.725944) (xy 341.62238 -248.733564) (xy 341.616792 -248.75109) (xy 341.620856 -248.826782)
			(xy 341.621761 -248.836021) (xy 341.629311 -248.852964) (xy 341.635588 -248.859802) (xy 341.703152 -248.927366)
			(xy 341.70366 -248.927874) (xy 341.711043 -248.934453) (xy 341.729341 -248.941898) (xy 341.73922 -248.942352)
			(xy 342.057482 -248.942352) (xy 342.067758 -248.941886) (xy 342.086672 -248.933844) (xy 342.100925 -248.919038)
			(xy 342.10498 -248.909586) (xy 342.138762 -248.820686) (xy 342.141167 -248.813436) (xy 342.142071 -248.798197)
			(xy 342.14054 -248.790714) (xy 342.13927 -248.784872) (xy 342.12038 -248.769825) (xy 342.086963 -248.734962)
			(xy 342.059246 -248.695415) (xy 342.037878 -248.652108) (xy 342.023355 -248.606052) (xy 342.016018 -248.55832)
			(xy 342.015572 -248.534174) (xy 342.016058 -248.509384) (xy 342.023814 -248.460416) (xy 342.039135 -248.413263)
			(xy 342.061644 -248.369088) (xy 342.090786 -248.328977) (xy 342.125843 -248.29392) (xy 342.165954 -248.264778)
			(xy 342.210129 -248.242269) (xy 342.257282 -248.226948) (xy 342.30625 -248.219192) (xy 342.35583 -248.219192)
			(xy 342.404798 -248.226948) (xy 342.451951 -248.242269) (xy 342.496126 -248.264778) (xy 342.536237 -248.29392)
			(xy 342.571294 -248.328977) (xy 342.600436 -248.369088) (xy 342.622945 -248.413263) (xy 342.638266 -248.460416)
			(xy 342.646022 -248.509384) (xy 342.646508 -248.534174) (xy 342.645927 -248.561542) (xy 342.636492 -248.615458)
			(xy 342.617901 -248.66694) (xy 342.59071 -248.714444) (xy 342.555735 -248.756548) (xy 342.535256 -248.774712)
			(xy 342.52936 -248.780188) (xy 342.52096 -248.7939) (xy 342.518746 -248.801636) (xy 342.51773 -248.805954)
			(xy 342.5571 -248.909586) (xy 342.56118 -248.91903) (xy 342.575413 -248.933859) (xy 342.594321 -248.94192)
			(xy 342.604598 -248.942352) (xy 342.997536 -248.942352) (xy 343.007806 -248.941877) (xy 343.026702 -248.933823)
			(xy 343.040938 -248.919016) (xy 343.045034 -248.909586) (xy 343.078816 -248.820686) (xy 343.081219 -248.813436)
			(xy 343.082123 -248.798197) (xy 343.080594 -248.790714) (xy 343.079324 -248.784872) (xy 343.060406 -248.769841)
			(xy 343.026932 -248.735001) (xy 342.999163 -248.695463) (xy 342.977748 -248.652152) (xy 342.963188 -248.606083)
			(xy 342.955824 -248.558332) (xy 342.955372 -248.534174) (xy 342.955859 -248.509364) (xy 342.963621 -248.460356)
			(xy 342.978954 -248.413166) (xy 343.001481 -248.368955) (xy 343.030646 -248.328812) (xy 343.065732 -248.293726)
			(xy 343.105875 -248.264561) (xy 343.150086 -248.242034) (xy 343.197276 -248.226701) (xy 343.246284 -248.218939)
			(xy 343.295904 -248.218939) (xy 343.344912 -248.226701) (xy 343.392102 -248.242034) (xy 343.436313 -248.264561)
			(xy 343.476456 -248.293726) (xy 343.511542 -248.328812) (xy 343.540707 -248.368955) (xy 343.563234 -248.413166)
			(xy 343.578567 -248.460356) (xy 343.586329 -248.509364) (xy 343.586816 -248.534174) (xy 343.905344 -248.534174)
			(xy 343.909304 -248.48512) (xy 343.921081 -248.437336) (xy 343.940372 -248.39206) (xy 343.966675 -248.350464)
			(xy 343.99931 -248.313627) (xy 344.037431 -248.282502) (xy 344.080052 -248.257895) (xy 344.126068 -248.240443)
			(xy 344.174287 -248.230599) (xy 344.223462 -248.228618) (xy 344.272317 -248.23455) (xy 344.319588 -248.248242)
			(xy 344.36405 -248.26934) (xy 344.404553 -248.297296) (xy 344.440046 -248.331388) (xy 344.469611 -248.370732)
			(xy 344.492482 -248.414309) (xy 344.508066 -248.46099) (xy 344.515961 -248.509567) (xy 344.516456 -248.534174)
			(xy 346.725252 -248.534174) (xy 346.729212 -248.48512) (xy 346.740989 -248.437336) (xy 346.76028 -248.39206)
			(xy 346.786583 -248.350464) (xy 346.819218 -248.313627) (xy 346.857339 -248.282502) (xy 346.89996 -248.257895)
			(xy 346.945976 -248.240443) (xy 346.994195 -248.230599) (xy 347.04337 -248.228618) (xy 347.092225 -248.23455)
			(xy 347.139496 -248.248242) (xy 347.183958 -248.26934) (xy 347.224461 -248.297296) (xy 347.259954 -248.331388)
			(xy 347.289519 -248.370732) (xy 347.31239 -248.414309) (xy 347.327974 -248.46099) (xy 347.335869 -248.509567)
			(xy 347.336364 -248.534174) (xy 349.545414 -248.534174) (xy 349.549374 -248.48512) (xy 349.561151 -248.437336)
			(xy 349.580442 -248.39206) (xy 349.606745 -248.350464) (xy 349.63938 -248.313627) (xy 349.677501 -248.282502)
			(xy 349.720122 -248.257895) (xy 349.766138 -248.240443) (xy 349.814357 -248.230599) (xy 349.863532 -248.228618)
			(xy 349.912387 -248.23455) (xy 349.959658 -248.248242) (xy 350.00412 -248.26934) (xy 350.044623 -248.297296)
			(xy 350.080116 -248.331388) (xy 350.109681 -248.370732) (xy 350.132552 -248.414309) (xy 350.148136 -248.46099)
			(xy 350.156031 -248.509567) (xy 350.156526 -248.534174) (xy 352.365322 -248.534174) (xy 352.369282 -248.48512)
			(xy 352.381059 -248.437336) (xy 352.40035 -248.39206) (xy 352.426653 -248.350464) (xy 352.459288 -248.313627)
			(xy 352.497409 -248.282502) (xy 352.54003 -248.257895) (xy 352.586046 -248.240443) (xy 352.634265 -248.230599)
			(xy 352.68344 -248.228618) (xy 352.732295 -248.23455) (xy 352.779566 -248.248242) (xy 352.824028 -248.26934)
			(xy 352.864531 -248.297296) (xy 352.900024 -248.331388) (xy 352.929589 -248.370732) (xy 352.95246 -248.414309)
			(xy 352.968044 -248.46099) (xy 352.975939 -248.509567) (xy 352.976434 -248.534174) (xy 355.18523 -248.534174)
			(xy 355.18919 -248.48512) (xy 355.200967 -248.437336) (xy 355.220258 -248.39206) (xy 355.246561 -248.350464)
			(xy 355.279196 -248.313627) (xy 355.317317 -248.282502) (xy 355.359938 -248.257895) (xy 355.405954 -248.240443)
			(xy 355.454173 -248.230599) (xy 355.503348 -248.228618) (xy 355.552203 -248.23455) (xy 355.599474 -248.248242)
			(xy 355.643936 -248.26934) (xy 355.684439 -248.297296) (xy 355.719932 -248.331388) (xy 355.749497 -248.370732)
			(xy 355.772368 -248.414309) (xy 355.787952 -248.46099) (xy 355.795847 -248.509567) (xy 355.796342 -248.534174)
			(xy 356.125284 -248.534174) (xy 356.129244 -248.48512) (xy 356.141021 -248.437336) (xy 356.160312 -248.39206)
			(xy 356.186615 -248.350464) (xy 356.21925 -248.313627) (xy 356.257371 -248.282502) (xy 356.299992 -248.257895)
			(xy 356.346008 -248.240443) (xy 356.394227 -248.230599) (xy 356.443402 -248.228618) (xy 356.492257 -248.23455)
			(xy 356.539528 -248.248242) (xy 356.58399 -248.26934) (xy 356.624493 -248.297296) (xy 356.659986 -248.331388)
			(xy 356.689551 -248.370732) (xy 356.712422 -248.414309) (xy 356.728006 -248.46099) (xy 356.735901 -248.509567)
			(xy 356.736396 -248.534174) (xy 357.065338 -248.534174) (xy 357.069298 -248.48512) (xy 357.081075 -248.437336)
			(xy 357.100366 -248.39206) (xy 357.126669 -248.350464) (xy 357.159304 -248.313627) (xy 357.197425 -248.282502)
			(xy 357.240046 -248.257895) (xy 357.286062 -248.240443) (xy 357.334281 -248.230599) (xy 357.383456 -248.228618)
			(xy 357.432311 -248.23455) (xy 357.479582 -248.248242) (xy 357.524044 -248.26934) (xy 357.564547 -248.297296)
			(xy 357.60004 -248.331388) (xy 357.629605 -248.370732) (xy 357.652476 -248.414309) (xy 357.66806 -248.46099)
			(xy 357.675955 -248.509567) (xy 357.67645 -248.534174) (xy 358.005392 -248.534174) (xy 358.009352 -248.48512)
			(xy 358.021129 -248.437336) (xy 358.04042 -248.39206) (xy 358.066723 -248.350464) (xy 358.099358 -248.313627)
			(xy 358.137479 -248.282502) (xy 358.1801 -248.257895) (xy 358.226116 -248.240443) (xy 358.274335 -248.230599)
			(xy 358.32351 -248.228618) (xy 358.372365 -248.23455) (xy 358.419636 -248.248242) (xy 358.464098 -248.26934)
			(xy 358.504601 -248.297296) (xy 358.540094 -248.331388) (xy 358.569659 -248.370732) (xy 358.59253 -248.414309)
			(xy 358.608114 -248.46099) (xy 358.616009 -248.509567) (xy 358.616504 -248.534174) (xy 360.81895 -248.534174)
			(xy 360.82291 -248.48512) (xy 360.834687 -248.437336) (xy 360.853978 -248.39206) (xy 360.880281 -248.350464)
			(xy 360.912916 -248.313627) (xy 360.951037 -248.282502) (xy 360.993658 -248.257895) (xy 361.039674 -248.240443)
			(xy 361.087893 -248.230599) (xy 361.137068 -248.228618) (xy 361.185923 -248.23455) (xy 361.233194 -248.248242)
			(xy 361.277656 -248.26934) (xy 361.318159 -248.297296) (xy 361.353652 -248.331388) (xy 361.383217 -248.370732)
			(xy 361.406088 -248.414309) (xy 361.421672 -248.46099) (xy 361.429567 -248.509567) (xy 361.430062 -248.534174)
			(xy 361.430061 -248.5342) (xy 361.758659 -248.5342) (xy 361.762835 -248.48381) (xy 361.775248 -248.434795)
			(xy 361.795559 -248.388491) (xy 361.823214 -248.346162) (xy 361.85746 -248.308962) (xy 361.897361 -248.277907)
			(xy 361.94183 -248.253842) (xy 361.989653 -248.237426) (xy 362.039527 -248.229104) (xy 362.064808 -248.228612)
			(xy 363.004862 -248.228612) (xy 363.030141 -248.229154) (xy 363.080009 -248.23747) (xy 363.127829 -248.253881)
			(xy 363.172294 -248.27794) (xy 363.212193 -248.30899) (xy 363.246437 -248.346184) (xy 363.274091 -248.388507)
			(xy 363.294401 -248.434806) (xy 363.306813 -248.483816) (xy 363.310987 -248.534174) (xy 363.639112 -248.534174)
			(xy 363.643072 -248.48512) (xy 363.654849 -248.437336) (xy 363.67414 -248.39206) (xy 363.700443 -248.350464)
			(xy 363.733078 -248.313627) (xy 363.771199 -248.282502) (xy 363.81382 -248.257895) (xy 363.859836 -248.240443)
			(xy 363.908055 -248.230599) (xy 363.95723 -248.228618) (xy 364.006085 -248.23455) (xy 364.053356 -248.248242)
			(xy 364.097818 -248.26934) (xy 364.138321 -248.297296) (xy 364.173814 -248.331388) (xy 364.203379 -248.370732)
			(xy 364.22625 -248.414309) (xy 364.241834 -248.46099) (xy 364.249729 -248.509567) (xy 364.250224 -248.534174)
			(xy 366.45902 -248.534174) (xy 366.46298 -248.48512) (xy 366.474757 -248.437336) (xy 366.494048 -248.39206)
			(xy 366.520351 -248.350464) (xy 366.552986 -248.313627) (xy 366.591107 -248.282502) (xy 366.633728 -248.257895)
			(xy 366.679744 -248.240443) (xy 366.727963 -248.230599) (xy 366.777138 -248.228618) (xy 366.825993 -248.23455)
			(xy 366.873264 -248.248242) (xy 366.917726 -248.26934) (xy 366.958229 -248.297296) (xy 366.993722 -248.331388)
			(xy 367.023287 -248.370732) (xy 367.046158 -248.414309) (xy 367.061742 -248.46099) (xy 367.069637 -248.509567)
			(xy 367.070132 -248.534174) (xy 369.278928 -248.534174) (xy 369.282888 -248.48512) (xy 369.294665 -248.437336)
			(xy 369.313956 -248.39206) (xy 369.340259 -248.350464) (xy 369.372894 -248.313627) (xy 369.411015 -248.282502)
			(xy 369.453636 -248.257895) (xy 369.499652 -248.240443) (xy 369.547871 -248.230599) (xy 369.597046 -248.228618)
			(xy 369.645901 -248.23455) (xy 369.693172 -248.248242) (xy 369.737634 -248.26934) (xy 369.778137 -248.297296)
			(xy 369.81363 -248.331388) (xy 369.843195 -248.370732) (xy 369.866066 -248.414309) (xy 369.88165 -248.46099)
			(xy 369.889545 -248.509567) (xy 369.89004 -248.534174) (xy 372.09909 -248.534174) (xy 372.10305 -248.48512)
			(xy 372.114827 -248.437336) (xy 372.134118 -248.39206) (xy 372.160421 -248.350464) (xy 372.193056 -248.313627)
			(xy 372.231177 -248.282502) (xy 372.273798 -248.257895) (xy 372.319814 -248.240443) (xy 372.368033 -248.230599)
			(xy 372.417208 -248.228618) (xy 372.466063 -248.23455) (xy 372.513334 -248.248242) (xy 372.557796 -248.26934)
			(xy 372.598299 -248.297296) (xy 372.633792 -248.331388) (xy 372.663357 -248.370732) (xy 372.686228 -248.414309)
			(xy 372.701812 -248.46099) (xy 372.709707 -248.509567) (xy 372.710202 -248.534174) (xy 374.918998 -248.534174)
			(xy 374.922958 -248.48512) (xy 374.934735 -248.437336) (xy 374.954026 -248.39206) (xy 374.980329 -248.350464)
			(xy 375.012964 -248.313627) (xy 375.051085 -248.282502) (xy 375.093706 -248.257895) (xy 375.139722 -248.240443)
			(xy 375.187941 -248.230599) (xy 375.237116 -248.228618) (xy 375.285971 -248.23455) (xy 375.333242 -248.248242)
			(xy 375.377704 -248.26934) (xy 375.418207 -248.297296) (xy 375.4537 -248.331388) (xy 375.483265 -248.370732)
			(xy 375.506136 -248.414309) (xy 375.52172 -248.46099) (xy 375.529615 -248.509567) (xy 375.53011 -248.534174)
			(xy 375.848621 -248.534174) (xy 375.852716 -248.483446) (xy 375.864895 -248.434032) (xy 375.884843 -248.387212)
			(xy 375.912044 -248.344198) (xy 375.945792 -248.306104) (xy 375.985214 -248.273917) (xy 376.029288 -248.248471)
			(xy 376.076874 -248.230424) (xy 376.126738 -248.220244) (xy 376.17759 -248.218195) (xy 376.228111 -248.224329)
			(xy 376.276995 -248.238489) (xy 376.322974 -248.260306) (xy 376.364858 -248.289216) (xy 376.401562 -248.324471)
			(xy 376.432135 -248.365157) (xy 376.455786 -248.41022) (xy 376.471902 -248.458494) (xy 376.480066 -248.508728)
			(xy 376.480578 -248.534174) (xy 376.788675 -248.534174) (xy 376.79277 -248.483446) (xy 376.804949 -248.434032)
			(xy 376.824897 -248.387212) (xy 376.852098 -248.344198) (xy 376.885846 -248.306104) (xy 376.925268 -248.273917)
			(xy 376.969342 -248.248471) (xy 377.016928 -248.230424) (xy 377.066792 -248.220244) (xy 377.117644 -248.218195)
			(xy 377.168165 -248.224329) (xy 377.217049 -248.238489) (xy 377.263028 -248.260306) (xy 377.304912 -248.289216)
			(xy 377.341616 -248.324471) (xy 377.372189 -248.365157) (xy 377.39584 -248.41022) (xy 377.411956 -248.458494)
			(xy 377.42012 -248.508728) (xy 377.420632 -248.534174) (xy 377.42012 -248.55962) (xy 377.411956 -248.609854)
			(xy 377.39584 -248.658128) (xy 377.372189 -248.703191) (xy 377.341616 -248.743877) (xy 377.304912 -248.779132)
			(xy 377.263028 -248.808042) (xy 377.217049 -248.829859) (xy 377.168165 -248.844019) (xy 377.117644 -248.850153)
			(xy 377.066792 -248.848104) (xy 377.016928 -248.837924) (xy 376.969342 -248.819877) (xy 376.925268 -248.794431)
			(xy 376.885846 -248.762244) (xy 376.852098 -248.72415) (xy 376.824897 -248.681136) (xy 376.804949 -248.634316)
			(xy 376.79277 -248.584902) (xy 376.788675 -248.534174) (xy 376.480578 -248.534174) (xy 376.480066 -248.55962)
			(xy 376.471902 -248.609854) (xy 376.455786 -248.658128) (xy 376.432135 -248.703191) (xy 376.401562 -248.743877)
			(xy 376.364858 -248.779132) (xy 376.322974 -248.808042) (xy 376.276995 -248.829859) (xy 376.228111 -248.844019)
			(xy 376.17759 -248.850153) (xy 376.126738 -248.848104) (xy 376.076874 -248.837924) (xy 376.029288 -248.819877)
			(xy 375.985214 -248.794431) (xy 375.945792 -248.762244) (xy 375.912044 -248.72415) (xy 375.884843 -248.681136)
			(xy 375.864895 -248.634316) (xy 375.852716 -248.584902) (xy 375.848621 -248.534174) (xy 375.53011 -248.534174)
			(xy 375.529615 -248.558781) (xy 375.52172 -248.607358) (xy 375.506136 -248.654039) (xy 375.483265 -248.697616)
			(xy 375.4537 -248.73696) (xy 375.418207 -248.771052) (xy 375.377704 -248.799008) (xy 375.333242 -248.820106)
			(xy 375.285971 -248.833798) (xy 375.237116 -248.83973) (xy 375.187941 -248.837749) (xy 375.139722 -248.827905)
			(xy 375.093706 -248.810453) (xy 375.051085 -248.785846) (xy 375.012964 -248.754721) (xy 374.980329 -248.717884)
			(xy 374.954026 -248.676288) (xy 374.934735 -248.631012) (xy 374.922958 -248.583228) (xy 374.918998 -248.534174)
			(xy 372.710202 -248.534174) (xy 372.709707 -248.558781) (xy 372.701812 -248.607358) (xy 372.686228 -248.654039)
			(xy 372.663357 -248.697616) (xy 372.633792 -248.73696) (xy 372.598299 -248.771052) (xy 372.557796 -248.799008)
			(xy 372.513334 -248.820106) (xy 372.466063 -248.833798) (xy 372.417208 -248.83973) (xy 372.368033 -248.837749)
			(xy 372.319814 -248.827905) (xy 372.273798 -248.810453) (xy 372.231177 -248.785846) (xy 372.193056 -248.754721)
			(xy 372.160421 -248.717884) (xy 372.134118 -248.676288) (xy 372.114827 -248.631012) (xy 372.10305 -248.583228)
			(xy 372.09909 -248.534174) (xy 369.89004 -248.534174) (xy 369.889545 -248.558781) (xy 369.88165 -248.607358)
			(xy 369.866066 -248.654039) (xy 369.843195 -248.697616) (xy 369.81363 -248.73696) (xy 369.778137 -248.771052)
			(xy 369.737634 -248.799008) (xy 369.693172 -248.820106) (xy 369.645901 -248.833798) (xy 369.597046 -248.83973)
			(xy 369.547871 -248.837749) (xy 369.499652 -248.827905) (xy 369.453636 -248.810453) (xy 369.411015 -248.785846)
			(xy 369.372894 -248.754721) (xy 369.340259 -248.717884) (xy 369.313956 -248.676288) (xy 369.294665 -248.631012)
			(xy 369.282888 -248.583228) (xy 369.278928 -248.534174) (xy 367.070132 -248.534174) (xy 367.069637 -248.558781)
			(xy 367.061742 -248.607358) (xy 367.046158 -248.654039) (xy 367.023287 -248.697616) (xy 366.993722 -248.73696)
			(xy 366.958229 -248.771052) (xy 366.917726 -248.799008) (xy 366.873264 -248.820106) (xy 366.825993 -248.833798)
			(xy 366.777138 -248.83973) (xy 366.727963 -248.837749) (xy 366.679744 -248.827905) (xy 366.633728 -248.810453)
			(xy 366.591107 -248.785846) (xy 366.552986 -248.754721) (xy 366.520351 -248.717884) (xy 366.494048 -248.676288)
			(xy 366.474757 -248.631012) (xy 366.46298 -248.583228) (xy 366.45902 -248.534174) (xy 364.250224 -248.534174)
			(xy 364.249729 -248.558781) (xy 364.241834 -248.607358) (xy 364.22625 -248.654039) (xy 364.203379 -248.697616)
			(xy 364.173814 -248.73696) (xy 364.138321 -248.771052) (xy 364.097818 -248.799008) (xy 364.053356 -248.820106)
			(xy 364.006085 -248.833798) (xy 363.95723 -248.83973) (xy 363.908055 -248.837749) (xy 363.859836 -248.827905)
			(xy 363.81382 -248.810453) (xy 363.771199 -248.785846) (xy 363.733078 -248.754721) (xy 363.700443 -248.717884)
			(xy 363.67414 -248.676288) (xy 363.654849 -248.631012) (xy 363.643072 -248.583228) (xy 363.639112 -248.534174)
			(xy 363.310987 -248.534174) (xy 363.310989 -248.5342) (xy 363.306813 -248.584584) (xy 363.294401 -248.633594)
			(xy 363.274091 -248.679893) (xy 363.246437 -248.722216) (xy 363.212193 -248.75941) (xy 363.172294 -248.79046)
			(xy 363.127829 -248.814519) (xy 363.080009 -248.83093) (xy 363.030141 -248.839246) (xy 363.004862 -248.839736)
			(xy 362.064808 -248.839736) (xy 362.039527 -248.839296) (xy 361.989653 -248.830974) (xy 361.94183 -248.814558)
			(xy 361.897361 -248.790493) (xy 361.85746 -248.759438) (xy 361.823214 -248.722238) (xy 361.795559 -248.679909)
			(xy 361.775248 -248.633605) (xy 361.762835 -248.58459) (xy 361.758659 -248.5342) (xy 361.430061 -248.5342)
			(xy 361.429567 -248.558781) (xy 361.421672 -248.607358) (xy 361.406088 -248.654039) (xy 361.383217 -248.697616)
			(xy 361.353652 -248.73696) (xy 361.318159 -248.771052) (xy 361.277656 -248.799008) (xy 361.233194 -248.820106)
			(xy 361.185923 -248.833798) (xy 361.137068 -248.83973) (xy 361.087893 -248.837749) (xy 361.039674 -248.827905)
			(xy 360.993658 -248.810453) (xy 360.951037 -248.785846) (xy 360.912916 -248.754721) (xy 360.880281 -248.717884)
			(xy 360.853978 -248.676288) (xy 360.834687 -248.631012) (xy 360.82291 -248.583228) (xy 360.81895 -248.534174)
			(xy 358.616504 -248.534174) (xy 358.616009 -248.558781) (xy 358.608114 -248.607358) (xy 358.59253 -248.654039)
			(xy 358.569659 -248.697616) (xy 358.540094 -248.73696) (xy 358.504601 -248.771052) (xy 358.464098 -248.799008)
			(xy 358.419636 -248.820106) (xy 358.372365 -248.833798) (xy 358.32351 -248.83973) (xy 358.274335 -248.837749)
			(xy 358.226116 -248.827905) (xy 358.1801 -248.810453) (xy 358.137479 -248.785846) (xy 358.099358 -248.754721)
			(xy 358.066723 -248.717884) (xy 358.04042 -248.676288) (xy 358.021129 -248.631012) (xy 358.009352 -248.583228)
			(xy 358.005392 -248.534174) (xy 357.67645 -248.534174) (xy 357.675955 -248.558781) (xy 357.66806 -248.607358)
			(xy 357.652476 -248.654039) (xy 357.629605 -248.697616) (xy 357.60004 -248.73696) (xy 357.564547 -248.771052)
			(xy 357.524044 -248.799008) (xy 357.479582 -248.820106) (xy 357.432311 -248.833798) (xy 357.383456 -248.83973)
			(xy 357.334281 -248.837749) (xy 357.286062 -248.827905) (xy 357.240046 -248.810453) (xy 357.197425 -248.785846)
			(xy 357.159304 -248.754721) (xy 357.126669 -248.717884) (xy 357.100366 -248.676288) (xy 357.081075 -248.631012)
			(xy 357.069298 -248.583228) (xy 357.065338 -248.534174) (xy 356.736396 -248.534174) (xy 356.735901 -248.558781)
			(xy 356.728006 -248.607358) (xy 356.712422 -248.654039) (xy 356.689551 -248.697616) (xy 356.659986 -248.73696)
			(xy 356.624493 -248.771052) (xy 356.58399 -248.799008) (xy 356.539528 -248.820106) (xy 356.492257 -248.833798)
			(xy 356.443402 -248.83973) (xy 356.394227 -248.837749) (xy 356.346008 -248.827905) (xy 356.299992 -248.810453)
			(xy 356.257371 -248.785846) (xy 356.21925 -248.754721) (xy 356.186615 -248.717884) (xy 356.160312 -248.676288)
			(xy 356.141021 -248.631012) (xy 356.129244 -248.583228) (xy 356.125284 -248.534174) (xy 355.796342 -248.534174)
			(xy 355.795847 -248.558781) (xy 355.787952 -248.607358) (xy 355.772368 -248.654039) (xy 355.749497 -248.697616)
			(xy 355.719932 -248.73696) (xy 355.684439 -248.771052) (xy 355.643936 -248.799008) (xy 355.599474 -248.820106)
			(xy 355.552203 -248.833798) (xy 355.503348 -248.83973) (xy 355.454173 -248.837749) (xy 355.405954 -248.827905)
			(xy 355.359938 -248.810453) (xy 355.317317 -248.785846) (xy 355.279196 -248.754721) (xy 355.246561 -248.717884)
			(xy 355.220258 -248.676288) (xy 355.200967 -248.631012) (xy 355.18919 -248.583228) (xy 355.18523 -248.534174)
			(xy 352.976434 -248.534174) (xy 352.975939 -248.558781) (xy 352.968044 -248.607358) (xy 352.95246 -248.654039)
			(xy 352.929589 -248.697616) (xy 352.900024 -248.73696) (xy 352.864531 -248.771052) (xy 352.824028 -248.799008)
			(xy 352.779566 -248.820106) (xy 352.732295 -248.833798) (xy 352.68344 -248.83973) (xy 352.634265 -248.837749)
			(xy 352.586046 -248.827905) (xy 352.54003 -248.810453) (xy 352.497409 -248.785846) (xy 352.459288 -248.754721)
			(xy 352.426653 -248.717884) (xy 352.40035 -248.676288) (xy 352.381059 -248.631012) (xy 352.369282 -248.583228)
			(xy 352.365322 -248.534174) (xy 350.156526 -248.534174) (xy 350.156031 -248.558781) (xy 350.148136 -248.607358)
			(xy 350.132552 -248.654039) (xy 350.109681 -248.697616) (xy 350.080116 -248.73696) (xy 350.044623 -248.771052)
			(xy 350.00412 -248.799008) (xy 349.959658 -248.820106) (xy 349.912387 -248.833798) (xy 349.863532 -248.83973)
			(xy 349.814357 -248.837749) (xy 349.766138 -248.827905) (xy 349.720122 -248.810453) (xy 349.677501 -248.785846)
			(xy 349.63938 -248.754721) (xy 349.606745 -248.717884) (xy 349.580442 -248.676288) (xy 349.561151 -248.631012)
			(xy 349.549374 -248.583228) (xy 349.545414 -248.534174) (xy 347.336364 -248.534174) (xy 347.335869 -248.558781)
			(xy 347.327974 -248.607358) (xy 347.31239 -248.654039) (xy 347.289519 -248.697616) (xy 347.259954 -248.73696)
			(xy 347.224461 -248.771052) (xy 347.183958 -248.799008) (xy 347.139496 -248.820106) (xy 347.092225 -248.833798)
			(xy 347.04337 -248.83973) (xy 346.994195 -248.837749) (xy 346.945976 -248.827905) (xy 346.89996 -248.810453)
			(xy 346.857339 -248.785846) (xy 346.819218 -248.754721) (xy 346.786583 -248.717884) (xy 346.76028 -248.676288)
			(xy 346.740989 -248.631012) (xy 346.729212 -248.583228) (xy 346.725252 -248.534174) (xy 344.516456 -248.534174)
			(xy 344.515961 -248.558781) (xy 344.508066 -248.607358) (xy 344.492482 -248.654039) (xy 344.469611 -248.697616)
			(xy 344.440046 -248.73696) (xy 344.404553 -248.771052) (xy 344.36405 -248.799008) (xy 344.319588 -248.820106)
			(xy 344.272317 -248.833798) (xy 344.223462 -248.83973) (xy 344.174287 -248.837749) (xy 344.126068 -248.827905)
			(xy 344.080052 -248.810453) (xy 344.037431 -248.785846) (xy 343.99931 -248.754721) (xy 343.966675 -248.717884)
			(xy 343.940372 -248.676288) (xy 343.921081 -248.631012) (xy 343.909304 -248.583228) (xy 343.905344 -248.534174)
			(xy 343.586816 -248.534174) (xy 343.586208 -248.561551) (xy 343.576719 -248.615478) (xy 343.558072 -248.66696)
			(xy 343.530826 -248.714456) (xy 343.495797 -248.756541) (xy 343.47531 -248.774712) (xy 343.46941 -248.780185)
			(xy 343.461001 -248.793895) (xy 343.4588 -248.801636) (xy 343.457784 -248.805954) (xy 343.497154 -248.909586)
			(xy 343.501237 -248.919024) (xy 343.515472 -248.933838) (xy 343.534379 -248.941879) (xy 343.544652 -248.942352)
			(xy 346.922344 -248.942352) (xy 346.932185 -248.942882) (xy 346.950357 -248.950457) (xy 346.95765 -248.957084)
			(xy 347.136212 -249.135646) (xy 347.138244 -249.137424) (xy 347.145608 -249.143526) (xy 347.163483 -249.150291)
			(xy 347.173042 -249.150632) (xy 347.254322 -249.149362) (xy 347.27261 -249.141488) (xy 347.279976 -249.133868)
			(xy 347.297377 -249.116241) (xy 347.336837 -249.086305) (xy 347.380616 -249.06314) (xy 347.427564 -249.047357)
			(xy 347.476445 -249.039369) (xy 347.50121 -249.038872) (xy 347.525201 -249.039343) (xy 347.572593 -249.046851)
			(xy 347.618227 -249.061679) (xy 347.66098 -249.083462) (xy 347.699799 -249.111666) (xy 347.733728 -249.145594)
			(xy 347.761932 -249.184412) (xy 347.783718 -249.227164) (xy 347.798547 -249.272797) (xy 347.806056 -249.320189)
			(xy 347.806518 -249.34418) (xy 349.07526 -249.34418) (xy 349.07922 -249.295126) (xy 349.090997 -249.247342)
			(xy 349.110288 -249.202066) (xy 349.136591 -249.16047) (xy 349.169226 -249.123633) (xy 349.207347 -249.092508)
			(xy 349.249968 -249.067901) (xy 349.295984 -249.050449) (xy 349.344203 -249.040605) (xy 349.393378 -249.038624)
			(xy 349.442233 -249.044556) (xy 349.489504 -249.058248) (xy 349.533966 -249.079346) (xy 349.574469 -249.107302)
			(xy 349.609962 -249.141394) (xy 349.639527 -249.180738) (xy 349.662398 -249.224315) (xy 349.677982 -249.270996)
			(xy 349.685877 -249.319573) (xy 349.686372 -249.34418) (xy 350.955368 -249.34418) (xy 350.959328 -249.295126)
			(xy 350.971105 -249.247342) (xy 350.990396 -249.202066) (xy 351.016699 -249.16047) (xy 351.049334 -249.123633)
			(xy 351.087455 -249.092508) (xy 351.130076 -249.067901) (xy 351.176092 -249.050449) (xy 351.224311 -249.040605)
			(xy 351.273486 -249.038624) (xy 351.322341 -249.044556) (xy 351.369612 -249.058248) (xy 351.414074 -249.079346)
			(xy 351.454577 -249.107302) (xy 351.49007 -249.141394) (xy 351.519635 -249.180738) (xy 351.542506 -249.224315)
			(xy 351.55809 -249.270996) (xy 351.565985 -249.319573) (xy 351.56648 -249.34418) (xy 352.835222 -249.34418)
			(xy 352.839182 -249.295126) (xy 352.850959 -249.247342) (xy 352.87025 -249.202066) (xy 352.896553 -249.16047)
			(xy 352.929188 -249.123633) (xy 352.967309 -249.092508) (xy 353.00993 -249.067901) (xy 353.055946 -249.050449)
			(xy 353.104165 -249.040605) (xy 353.15334 -249.038624) (xy 353.202195 -249.044556) (xy 353.249466 -249.058248)
			(xy 353.293928 -249.079346) (xy 353.334431 -249.107302) (xy 353.369924 -249.141394) (xy 353.399489 -249.180738)
			(xy 353.42236 -249.224315) (xy 353.437944 -249.270996) (xy 353.445839 -249.319573) (xy 353.446334 -249.34418)
			(xy 354.71533 -249.34418) (xy 354.71929 -249.295126) (xy 354.731067 -249.247342) (xy 354.750358 -249.202066)
			(xy 354.776661 -249.16047) (xy 354.809296 -249.123633) (xy 354.847417 -249.092508) (xy 354.890038 -249.067901)
			(xy 354.936054 -249.050449) (xy 354.984273 -249.040605) (xy 355.033448 -249.038624) (xy 355.082303 -249.044556)
			(xy 355.129574 -249.058248) (xy 355.174036 -249.079346) (xy 355.214539 -249.107302) (xy 355.250032 -249.141394)
			(xy 355.279597 -249.180738) (xy 355.302468 -249.224315) (xy 355.318052 -249.270996) (xy 355.325947 -249.319573)
			(xy 355.326442 -249.34418) (xy 356.595438 -249.34418) (xy 356.599398 -249.295126) (xy 356.611175 -249.247342)
			(xy 356.630466 -249.202066) (xy 356.656769 -249.16047) (xy 356.689404 -249.123633) (xy 356.727525 -249.092508)
			(xy 356.770146 -249.067901) (xy 356.816162 -249.050449) (xy 356.864381 -249.040605) (xy 356.913556 -249.038624)
			(xy 356.962411 -249.044556) (xy 357.009682 -249.058248) (xy 357.054144 -249.079346) (xy 357.094647 -249.107302)
			(xy 357.13014 -249.141394) (xy 357.159705 -249.180738) (xy 357.182576 -249.224315) (xy 357.19816 -249.270996)
			(xy 357.206055 -249.319573) (xy 357.20655 -249.34418) (xy 357.206192 -249.36196) (xy 359.396541 -249.36196)
			(xy 359.400571 -249.309462) (xy 359.412568 -249.258194) (xy 359.432251 -249.209359) (xy 359.459157 -249.1641)
			(xy 359.492657 -249.123479) (xy 359.531965 -249.088448) (xy 359.57616 -249.059828) (xy 359.624205 -249.038289)
			(xy 359.674976 -249.024337) (xy 359.727281 -249.018299) (xy 359.779895 -249.020316) (xy 359.831585 -249.03034)
			(xy 359.881138 -249.048138) (xy 359.927394 -249.073291) (xy 359.969268 -249.10521) (xy 360.00578 -249.143148)
			(xy 360.036072 -249.186214) (xy 360.059435 -249.233399) (xy 360.075321 -249.283598) (xy 360.083358 -249.335634)
			(xy 360.083522 -249.34418) (xy 361.289104 -249.34418) (xy 361.293064 -249.295126) (xy 361.304841 -249.247342)
			(xy 361.324132 -249.202066) (xy 361.350435 -249.16047) (xy 361.38307 -249.123633) (xy 361.421191 -249.092508)
			(xy 361.463812 -249.067901) (xy 361.509828 -249.050449) (xy 361.558047 -249.040605) (xy 361.607222 -249.038624)
			(xy 361.656077 -249.044556) (xy 361.703348 -249.058248) (xy 361.74781 -249.079346) (xy 361.788313 -249.107302)
			(xy 361.823806 -249.141394) (xy 361.853371 -249.180738) (xy 361.876242 -249.224315) (xy 361.891826 -249.270996)
			(xy 361.899721 -249.319573) (xy 361.900216 -249.34418) (xy 363.168958 -249.34418) (xy 363.172918 -249.295126)
			(xy 363.184695 -249.247342) (xy 363.203986 -249.202066) (xy 363.230289 -249.16047) (xy 363.262924 -249.123633)
			(xy 363.301045 -249.092508) (xy 363.343666 -249.067901) (xy 363.389682 -249.050449) (xy 363.437901 -249.040605)
			(xy 363.487076 -249.038624) (xy 363.535931 -249.044556) (xy 363.583202 -249.058248) (xy 363.627664 -249.079346)
			(xy 363.668167 -249.107302) (xy 363.70366 -249.141394) (xy 363.733225 -249.180738) (xy 363.756096 -249.224315)
			(xy 363.77168 -249.270996) (xy 363.779575 -249.319573) (xy 363.78007 -249.34418) (xy 365.049066 -249.34418)
			(xy 365.053026 -249.295126) (xy 365.064803 -249.247342) (xy 365.084094 -249.202066) (xy 365.110397 -249.16047)
			(xy 365.143032 -249.123633) (xy 365.181153 -249.092508) (xy 365.223774 -249.067901) (xy 365.26979 -249.050449)
			(xy 365.318009 -249.040605) (xy 365.367184 -249.038624) (xy 365.416039 -249.044556) (xy 365.46331 -249.058248)
			(xy 365.507772 -249.079346) (xy 365.548275 -249.107302) (xy 365.583768 -249.141394) (xy 365.613333 -249.180738)
			(xy 365.636204 -249.224315) (xy 365.651788 -249.270996) (xy 365.659683 -249.319573) (xy 365.660178 -249.34418)
			(xy 366.92892 -249.34418) (xy 366.93288 -249.295126) (xy 366.944657 -249.247342) (xy 366.963948 -249.202066)
			(xy 366.990251 -249.16047) (xy 367.022886 -249.123633) (xy 367.061007 -249.092508) (xy 367.103628 -249.067901)
			(xy 367.149644 -249.050449) (xy 367.197863 -249.040605) (xy 367.247038 -249.038624) (xy 367.295893 -249.044556)
			(xy 367.343164 -249.058248) (xy 367.387626 -249.079346) (xy 367.428129 -249.107302) (xy 367.463622 -249.141394)
			(xy 367.493187 -249.180738) (xy 367.516058 -249.224315) (xy 367.531642 -249.270996) (xy 367.539537 -249.319573)
			(xy 367.540032 -249.34418) (xy 368.809028 -249.34418) (xy 368.812988 -249.295126) (xy 368.824765 -249.247342)
			(xy 368.844056 -249.202066) (xy 368.870359 -249.16047) (xy 368.902994 -249.123633) (xy 368.941115 -249.092508)
			(xy 368.983736 -249.067901) (xy 369.029752 -249.050449) (xy 369.077971 -249.040605) (xy 369.127146 -249.038624)
			(xy 369.176001 -249.044556) (xy 369.223272 -249.058248) (xy 369.267734 -249.079346) (xy 369.308237 -249.107302)
			(xy 369.34373 -249.141394) (xy 369.373295 -249.180738) (xy 369.396166 -249.224315) (xy 369.41175 -249.270996)
			(xy 369.419645 -249.319573) (xy 369.42014 -249.34418) (xy 370.688882 -249.34418) (xy 370.692842 -249.295126)
			(xy 370.704619 -249.247342) (xy 370.72391 -249.202066) (xy 370.750213 -249.16047) (xy 370.782848 -249.123633)
			(xy 370.820969 -249.092508) (xy 370.86359 -249.067901) (xy 370.909606 -249.050449) (xy 370.957825 -249.040605)
			(xy 371.007 -249.038624) (xy 371.055855 -249.044556) (xy 371.103126 -249.058248) (xy 371.147588 -249.079346)
			(xy 371.188091 -249.107302) (xy 371.223584 -249.141394) (xy 371.253149 -249.180738) (xy 371.27602 -249.224315)
			(xy 371.291604 -249.270996) (xy 371.299499 -249.319573) (xy 371.299994 -249.34418) (xy 372.56899 -249.34418)
			(xy 372.57295 -249.295126) (xy 372.584727 -249.247342) (xy 372.604018 -249.202066) (xy 372.630321 -249.16047)
			(xy 372.662956 -249.123633) (xy 372.701077 -249.092508) (xy 372.743698 -249.067901) (xy 372.789714 -249.050449)
			(xy 372.837933 -249.040605) (xy 372.887108 -249.038624) (xy 372.935963 -249.044556) (xy 372.983234 -249.058248)
			(xy 373.027696 -249.079346) (xy 373.068199 -249.107302) (xy 373.103692 -249.141394) (xy 373.133257 -249.180738)
			(xy 373.156128 -249.224315) (xy 373.171712 -249.270996) (xy 373.179607 -249.319573) (xy 373.180102 -249.34418)
			(xy 374.449098 -249.34418) (xy 374.453058 -249.295126) (xy 374.464835 -249.247342) (xy 374.484126 -249.202066)
			(xy 374.510429 -249.16047) (xy 374.543064 -249.123633) (xy 374.581185 -249.092508) (xy 374.623806 -249.067901)
			(xy 374.669822 -249.050449) (xy 374.718041 -249.040605) (xy 374.767216 -249.038624) (xy 374.816071 -249.044556)
			(xy 374.863342 -249.058248) (xy 374.907804 -249.079346) (xy 374.948307 -249.107302) (xy 374.9838 -249.141394)
			(xy 375.013365 -249.180738) (xy 375.036236 -249.224315) (xy 375.05182 -249.270996) (xy 375.059715 -249.319573)
			(xy 375.06021 -249.34418) (xy 375.378467 -249.34418) (xy 375.382562 -249.293452) (xy 375.394741 -249.244038)
			(xy 375.414689 -249.197218) (xy 375.44189 -249.154204) (xy 375.475638 -249.11611) (xy 375.51506 -249.083923)
			(xy 375.559134 -249.058477) (xy 375.60672 -249.04043) (xy 375.656584 -249.03025) (xy 375.707436 -249.028201)
			(xy 375.757957 -249.034335) (xy 375.806841 -249.048495) (xy 375.85282 -249.070312) (xy 375.894704 -249.099222)
			(xy 375.931408 -249.134477) (xy 375.961981 -249.175163) (xy 375.985632 -249.220226) (xy 376.001748 -249.2685)
			(xy 376.009912 -249.318734) (xy 376.010424 -249.34418) (xy 376.328952 -249.34418) (xy 376.332912 -249.295126)
			(xy 376.344689 -249.247342) (xy 376.36398 -249.202066) (xy 376.390283 -249.16047) (xy 376.422918 -249.123633)
			(xy 376.461039 -249.092508) (xy 376.50366 -249.067901) (xy 376.549676 -249.050449) (xy 376.597895 -249.040605)
			(xy 376.64707 -249.038624) (xy 376.695925 -249.044556) (xy 376.743196 -249.058248) (xy 376.787658 -249.079346)
			(xy 376.828161 -249.107302) (xy 376.863654 -249.141394) (xy 376.893219 -249.180738) (xy 376.91609 -249.224315)
			(xy 376.931674 -249.270996) (xy 376.939569 -249.319573) (xy 376.940064 -249.34418) (xy 376.939569 -249.368787)
			(xy 376.931674 -249.417364) (xy 376.91609 -249.464045) (xy 376.893219 -249.507622) (xy 376.863654 -249.546966)
			(xy 376.828161 -249.581058) (xy 376.787658 -249.609014) (xy 376.743196 -249.630112) (xy 376.695925 -249.643804)
			(xy 376.64707 -249.649736) (xy 376.597895 -249.647755) (xy 376.549676 -249.637911) (xy 376.50366 -249.620459)
			(xy 376.461039 -249.595852) (xy 376.422918 -249.564727) (xy 376.390283 -249.52789) (xy 376.36398 -249.486294)
			(xy 376.344689 -249.441018) (xy 376.332912 -249.393234) (xy 376.328952 -249.34418) (xy 376.010424 -249.34418)
			(xy 376.009912 -249.369626) (xy 376.001748 -249.41986) (xy 375.985632 -249.468134) (xy 375.961981 -249.513197)
			(xy 375.931408 -249.553883) (xy 375.894704 -249.589138) (xy 375.85282 -249.618048) (xy 375.806841 -249.639865)
			(xy 375.757957 -249.654025) (xy 375.707436 -249.660159) (xy 375.656584 -249.65811) (xy 375.60672 -249.64793)
			(xy 375.559134 -249.629883) (xy 375.51506 -249.604437) (xy 375.475638 -249.57225) (xy 375.44189 -249.534156)
			(xy 375.414689 -249.491142) (xy 375.394741 -249.444322) (xy 375.382562 -249.394908) (xy 375.378467 -249.34418)
			(xy 375.06021 -249.34418) (xy 375.059715 -249.368787) (xy 375.05182 -249.417364) (xy 375.036236 -249.464045)
			(xy 375.013365 -249.507622) (xy 374.9838 -249.546966) (xy 374.948307 -249.581058) (xy 374.907804 -249.609014)
			(xy 374.863342 -249.630112) (xy 374.816071 -249.643804) (xy 374.767216 -249.649736) (xy 374.718041 -249.647755)
			(xy 374.669822 -249.637911) (xy 374.623806 -249.620459) (xy 374.581185 -249.595852) (xy 374.543064 -249.564727)
			(xy 374.510429 -249.52789) (xy 374.484126 -249.486294) (xy 374.464835 -249.441018) (xy 374.453058 -249.393234)
			(xy 374.449098 -249.34418) (xy 373.180102 -249.34418) (xy 373.179607 -249.368787) (xy 373.171712 -249.417364)
			(xy 373.156128 -249.464045) (xy 373.133257 -249.507622) (xy 373.103692 -249.546966) (xy 373.068199 -249.581058)
			(xy 373.027696 -249.609014) (xy 372.983234 -249.630112) (xy 372.935963 -249.643804) (xy 372.887108 -249.649736)
			(xy 372.837933 -249.647755) (xy 372.789714 -249.637911) (xy 372.743698 -249.620459) (xy 372.701077 -249.595852)
			(xy 372.662956 -249.564727) (xy 372.630321 -249.52789) (xy 372.604018 -249.486294) (xy 372.584727 -249.441018)
			(xy 372.57295 -249.393234) (xy 372.56899 -249.34418) (xy 371.299994 -249.34418) (xy 371.299499 -249.368787)
			(xy 371.291604 -249.417364) (xy 371.27602 -249.464045) (xy 371.253149 -249.507622) (xy 371.223584 -249.546966)
			(xy 371.188091 -249.581058) (xy 371.147588 -249.609014) (xy 371.103126 -249.630112) (xy 371.055855 -249.643804)
			(xy 371.007 -249.649736) (xy 370.957825 -249.647755) (xy 370.909606 -249.637911) (xy 370.86359 -249.620459)
			(xy 370.820969 -249.595852) (xy 370.782848 -249.564727) (xy 370.750213 -249.52789) (xy 370.72391 -249.486294)
			(xy 370.704619 -249.441018) (xy 370.692842 -249.393234) (xy 370.688882 -249.34418) (xy 369.42014 -249.34418)
			(xy 369.419645 -249.368787) (xy 369.41175 -249.417364) (xy 369.396166 -249.464045) (xy 369.373295 -249.507622)
			(xy 369.34373 -249.546966) (xy 369.308237 -249.581058) (xy 369.267734 -249.609014) (xy 369.223272 -249.630112)
			(xy 369.176001 -249.643804) (xy 369.127146 -249.649736) (xy 369.077971 -249.647755) (xy 369.029752 -249.637911)
			(xy 368.983736 -249.620459) (xy 368.941115 -249.595852) (xy 368.902994 -249.564727) (xy 368.870359 -249.52789)
			(xy 368.844056 -249.486294) (xy 368.824765 -249.441018) (xy 368.812988 -249.393234) (xy 368.809028 -249.34418)
			(xy 367.540032 -249.34418) (xy 367.539537 -249.368787) (xy 367.531642 -249.417364) (xy 367.516058 -249.464045)
			(xy 367.493187 -249.507622) (xy 367.463622 -249.546966) (xy 367.428129 -249.581058) (xy 367.387626 -249.609014)
			(xy 367.343164 -249.630112) (xy 367.295893 -249.643804) (xy 367.247038 -249.649736) (xy 367.197863 -249.647755)
			(xy 367.149644 -249.637911) (xy 367.103628 -249.620459) (xy 367.061007 -249.595852) (xy 367.022886 -249.564727)
			(xy 366.990251 -249.52789) (xy 366.963948 -249.486294) (xy 366.944657 -249.441018) (xy 366.93288 -249.393234)
			(xy 366.92892 -249.34418) (xy 365.660178 -249.34418) (xy 365.659683 -249.368787) (xy 365.651788 -249.417364)
			(xy 365.636204 -249.464045) (xy 365.613333 -249.507622) (xy 365.583768 -249.546966) (xy 365.548275 -249.581058)
			(xy 365.507772 -249.609014) (xy 365.46331 -249.630112) (xy 365.416039 -249.643804) (xy 365.367184 -249.649736)
			(xy 365.318009 -249.647755) (xy 365.26979 -249.637911) (xy 365.223774 -249.620459) (xy 365.181153 -249.595852)
			(xy 365.143032 -249.564727) (xy 365.110397 -249.52789) (xy 365.084094 -249.486294) (xy 365.064803 -249.441018)
			(xy 365.053026 -249.393234) (xy 365.049066 -249.34418) (xy 363.78007 -249.34418) (xy 363.779575 -249.368787)
			(xy 363.77168 -249.417364) (xy 363.756096 -249.464045) (xy 363.733225 -249.507622) (xy 363.70366 -249.546966)
			(xy 363.668167 -249.581058) (xy 363.627664 -249.609014) (xy 363.583202 -249.630112) (xy 363.535931 -249.643804)
			(xy 363.487076 -249.649736) (xy 363.437901 -249.647755) (xy 363.389682 -249.637911) (xy 363.343666 -249.620459)
			(xy 363.301045 -249.595852) (xy 363.262924 -249.564727) (xy 363.230289 -249.52789) (xy 363.203986 -249.486294)
			(xy 363.184695 -249.441018) (xy 363.172918 -249.393234) (xy 363.168958 -249.34418) (xy 361.900216 -249.34418)
			(xy 361.899721 -249.368787) (xy 361.891826 -249.417364) (xy 361.876242 -249.464045) (xy 361.853371 -249.507622)
			(xy 361.823806 -249.546966) (xy 361.788313 -249.581058) (xy 361.74781 -249.609014) (xy 361.703348 -249.630112)
			(xy 361.656077 -249.643804) (xy 361.607222 -249.649736) (xy 361.558047 -249.647755) (xy 361.509828 -249.637911)
			(xy 361.463812 -249.620459) (xy 361.421191 -249.595852) (xy 361.38307 -249.564727) (xy 361.350435 -249.52789)
			(xy 361.324132 -249.486294) (xy 361.304841 -249.441018) (xy 361.293064 -249.393234) (xy 361.289104 -249.34418)
			(xy 360.083522 -249.34418) (xy 360.083862 -249.36196) (xy 360.083358 -249.388286) (xy 360.075321 -249.440322)
			(xy 360.059435 -249.490521) (xy 360.036072 -249.537706) (xy 360.00578 -249.580772) (xy 359.969268 -249.61871)
			(xy 359.927394 -249.650629) (xy 359.881138 -249.675782) (xy 359.831585 -249.69358) (xy 359.779895 -249.703604)
			(xy 359.727281 -249.705621) (xy 359.674976 -249.699583) (xy 359.624205 -249.685631) (xy 359.57616 -249.664092)
			(xy 359.531965 -249.635472) (xy 359.492657 -249.600441) (xy 359.459157 -249.55982) (xy 359.432251 -249.514561)
			(xy 359.412568 -249.465726) (xy 359.400571 -249.414458) (xy 359.396541 -249.36196) (xy 357.206192 -249.36196)
			(xy 357.206055 -249.368787) (xy 357.19816 -249.417364) (xy 357.182576 -249.464045) (xy 357.159705 -249.507622)
			(xy 357.13014 -249.546966) (xy 357.094647 -249.581058) (xy 357.054144 -249.609014) (xy 357.009682 -249.630112)
			(xy 356.962411 -249.643804) (xy 356.913556 -249.649736) (xy 356.864381 -249.647755) (xy 356.816162 -249.637911)
			(xy 356.770146 -249.620459) (xy 356.727525 -249.595852) (xy 356.689404 -249.564727) (xy 356.656769 -249.52789)
			(xy 356.630466 -249.486294) (xy 356.611175 -249.441018) (xy 356.599398 -249.393234) (xy 356.595438 -249.34418)
			(xy 355.326442 -249.34418) (xy 355.325947 -249.368787) (xy 355.318052 -249.417364) (xy 355.302468 -249.464045)
			(xy 355.279597 -249.507622) (xy 355.250032 -249.546966) (xy 355.214539 -249.581058) (xy 355.174036 -249.609014)
			(xy 355.129574 -249.630112) (xy 355.082303 -249.643804) (xy 355.033448 -249.649736) (xy 354.984273 -249.647755)
			(xy 354.936054 -249.637911) (xy 354.890038 -249.620459) (xy 354.847417 -249.595852) (xy 354.809296 -249.564727)
			(xy 354.776661 -249.52789) (xy 354.750358 -249.486294) (xy 354.731067 -249.441018) (xy 354.71929 -249.393234)
			(xy 354.71533 -249.34418) (xy 353.446334 -249.34418) (xy 353.445839 -249.368787) (xy 353.437944 -249.417364)
			(xy 353.42236 -249.464045) (xy 353.399489 -249.507622) (xy 353.369924 -249.546966) (xy 353.334431 -249.581058)
			(xy 353.293928 -249.609014) (xy 353.249466 -249.630112) (xy 353.202195 -249.643804) (xy 353.15334 -249.649736)
			(xy 353.104165 -249.647755) (xy 353.055946 -249.637911) (xy 353.00993 -249.620459) (xy 352.967309 -249.595852)
			(xy 352.929188 -249.564727) (xy 352.896553 -249.52789) (xy 352.87025 -249.486294) (xy 352.850959 -249.441018)
			(xy 352.839182 -249.393234) (xy 352.835222 -249.34418) (xy 351.56648 -249.34418) (xy 351.565985 -249.368787)
			(xy 351.55809 -249.417364) (xy 351.542506 -249.464045) (xy 351.519635 -249.507622) (xy 351.49007 -249.546966)
			(xy 351.454577 -249.581058) (xy 351.414074 -249.609014) (xy 351.369612 -249.630112) (xy 351.322341 -249.643804)
			(xy 351.273486 -249.649736) (xy 351.224311 -249.647755) (xy 351.176092 -249.637911) (xy 351.130076 -249.620459)
			(xy 351.087455 -249.595852) (xy 351.049334 -249.564727) (xy 351.016699 -249.52789) (xy 350.990396 -249.486294)
			(xy 350.971105 -249.441018) (xy 350.959328 -249.393234) (xy 350.955368 -249.34418) (xy 349.686372 -249.34418)
			(xy 349.685877 -249.368787) (xy 349.677982 -249.417364) (xy 349.662398 -249.464045) (xy 349.639527 -249.507622)
			(xy 349.609962 -249.546966) (xy 349.574469 -249.581058) (xy 349.533966 -249.609014) (xy 349.489504 -249.630112)
			(xy 349.442233 -249.643804) (xy 349.393378 -249.649736) (xy 349.344203 -249.647755) (xy 349.295984 -249.637911)
			(xy 349.249968 -249.620459) (xy 349.207347 -249.595852) (xy 349.169226 -249.564727) (xy 349.136591 -249.52789)
			(xy 349.110288 -249.486294) (xy 349.090997 -249.441018) (xy 349.07922 -249.393234) (xy 349.07526 -249.34418)
			(xy 347.806518 -249.34418) (xy 347.806038 -249.368946) (xy 347.79804 -249.417827) (xy 347.782253 -249.464775)
			(xy 347.759089 -249.508556) (xy 347.729158 -249.548021) (xy 347.711522 -249.565414) (xy 347.703902 -249.57278)
			(xy 347.696028 -249.591068) (xy 347.694758 -249.672348) (xy 347.695016 -249.681921) (xy 347.701813 -249.699807)
			(xy 347.707966 -249.707146) (xy 347.708728 -249.708162) (xy 347.845888 -249.845322) (xy 347.852409 -249.851294)
			(xy 347.868414 -249.858779) (xy 347.88601 -249.860384) (xy 347.894656 -249.85853) (xy 347.89491 -249.85853)
			(xy 347.897704 -249.857768) (xy 347.915519 -249.85365) (xy 347.951812 -249.849198) (xy 347.970094 -249.848878)
			(xy 347.97492 -249.848878) (xy 347.998712 -249.849632) (xy 348.045639 -249.857608) (xy 348.090759 -249.872772)
			(xy 348.132978 -249.894757) (xy 348.171273 -249.923028) (xy 348.204715 -249.956901) (xy 348.232494 -249.995554)
			(xy 348.253936 -250.038051) (xy 348.268521 -250.083361) (xy 348.275897 -250.130386) (xy 348.276418 -250.154186)
			(xy 349.545414 -250.154186) (xy 349.549374 -250.105132) (xy 349.561151 -250.057348) (xy 349.580442 -250.012072)
			(xy 349.606745 -249.970476) (xy 349.63938 -249.933639) (xy 349.677501 -249.902514) (xy 349.720122 -249.877907)
			(xy 349.766138 -249.860455) (xy 349.814357 -249.850611) (xy 349.863532 -249.84863) (xy 349.912387 -249.854562)
			(xy 349.959658 -249.868254) (xy 350.00412 -249.889352) (xy 350.044623 -249.917308) (xy 350.080116 -249.9514)
			(xy 350.109681 -249.990744) (xy 350.132552 -250.034321) (xy 350.148136 -250.081002) (xy 350.156031 -250.129579)
			(xy 350.156526 -250.154186) (xy 351.425268 -250.154186) (xy 351.429228 -250.105132) (xy 351.441005 -250.057348)
			(xy 351.460296 -250.012072) (xy 351.486599 -249.970476) (xy 351.519234 -249.933639) (xy 351.557355 -249.902514)
			(xy 351.599976 -249.877907) (xy 351.645992 -249.860455) (xy 351.694211 -249.850611) (xy 351.743386 -249.84863)
			(xy 351.792241 -249.854562) (xy 351.839512 -249.868254) (xy 351.883974 -249.889352) (xy 351.924477 -249.917308)
			(xy 351.95997 -249.9514) (xy 351.989535 -249.990744) (xy 352.012406 -250.034321) (xy 352.02799 -250.081002)
			(xy 352.035885 -250.129579) (xy 352.03638 -250.154186) (xy 353.305376 -250.154186) (xy 353.309336 -250.105132)
			(xy 353.321113 -250.057348) (xy 353.340404 -250.012072) (xy 353.366707 -249.970476) (xy 353.399342 -249.933639)
			(xy 353.437463 -249.902514) (xy 353.480084 -249.877907) (xy 353.5261 -249.860455) (xy 353.574319 -249.850611)
			(xy 353.623494 -249.84863) (xy 353.672349 -249.854562) (xy 353.71962 -249.868254) (xy 353.764082 -249.889352)
			(xy 353.804585 -249.917308) (xy 353.840078 -249.9514) (xy 353.869643 -249.990744) (xy 353.892514 -250.034321)
			(xy 353.908098 -250.081002) (xy 353.915993 -250.129579) (xy 353.916488 -250.154186) (xy 355.18523 -250.154186)
			(xy 355.18919 -250.105132) (xy 355.200967 -250.057348) (xy 355.220258 -250.012072) (xy 355.246561 -249.970476)
			(xy 355.279196 -249.933639) (xy 355.317317 -249.902514) (xy 355.359938 -249.877907) (xy 355.405954 -249.860455)
			(xy 355.454173 -249.850611) (xy 355.503348 -249.84863) (xy 355.552203 -249.854562) (xy 355.599474 -249.868254)
			(xy 355.643936 -249.889352) (xy 355.684439 -249.917308) (xy 355.719932 -249.9514) (xy 355.749497 -249.990744)
			(xy 355.772368 -250.034321) (xy 355.787952 -250.081002) (xy 355.795847 -250.129579) (xy 355.796342 -250.154186)
			(xy 355.795847 -250.178793) (xy 355.787952 -250.22737) (xy 355.772368 -250.274051) (xy 355.749497 -250.317628)
			(xy 355.719932 -250.356972) (xy 355.684439 -250.391064) (xy 355.643936 -250.41902) (xy 355.599474 -250.440118)
			(xy 355.552203 -250.45381) (xy 355.503348 -250.459742) (xy 355.454173 -250.457761) (xy 355.405954 -250.447917)
			(xy 355.359938 -250.430465) (xy 355.317317 -250.405858) (xy 355.279196 -250.374733) (xy 355.246561 -250.337896)
			(xy 355.220258 -250.2963) (xy 355.200967 -250.251024) (xy 355.18919 -250.20324) (xy 355.18523 -250.154186)
			(xy 353.916488 -250.154186) (xy 353.915993 -250.178793) (xy 353.908098 -250.22737) (xy 353.892514 -250.274051)
			(xy 353.869643 -250.317628) (xy 353.840078 -250.356972) (xy 353.804585 -250.391064) (xy 353.764082 -250.41902)
			(xy 353.71962 -250.440118) (xy 353.672349 -250.45381) (xy 353.623494 -250.459742) (xy 353.574319 -250.457761)
			(xy 353.5261 -250.447917) (xy 353.480084 -250.430465) (xy 353.437463 -250.405858) (xy 353.399342 -250.374733)
			(xy 353.366707 -250.337896) (xy 353.340404 -250.2963) (xy 353.321113 -250.251024) (xy 353.309336 -250.20324)
			(xy 353.305376 -250.154186) (xy 352.03638 -250.154186) (xy 352.035885 -250.178793) (xy 352.02799 -250.22737)
			(xy 352.012406 -250.274051) (xy 351.989535 -250.317628) (xy 351.95997 -250.356972) (xy 351.924477 -250.391064)
			(xy 351.883974 -250.41902) (xy 351.839512 -250.440118) (xy 351.792241 -250.45381) (xy 351.743386 -250.459742)
			(xy 351.694211 -250.457761) (xy 351.645992 -250.447917) (xy 351.599976 -250.430465) (xy 351.557355 -250.405858)
			(xy 351.519234 -250.374733) (xy 351.486599 -250.337896) (xy 351.460296 -250.2963) (xy 351.441005 -250.251024)
			(xy 351.429228 -250.20324) (xy 351.425268 -250.154186) (xy 350.156526 -250.154186) (xy 350.156031 -250.178793)
			(xy 350.148136 -250.22737) (xy 350.132552 -250.274051) (xy 350.109681 -250.317628) (xy 350.080116 -250.356972)
			(xy 350.044623 -250.391064) (xy 350.00412 -250.41902) (xy 349.959658 -250.440118) (xy 349.912387 -250.45381)
			(xy 349.863532 -250.459742) (xy 349.814357 -250.457761) (xy 349.766138 -250.447917) (xy 349.720122 -250.430465)
			(xy 349.677501 -250.405858) (xy 349.63938 -250.374733) (xy 349.606745 -250.337896) (xy 349.580442 -250.2963)
			(xy 349.561151 -250.251024) (xy 349.549374 -250.20324) (xy 349.545414 -250.154186) (xy 348.276418 -250.154186)
			(xy 348.276418 -250.154694) (xy 348.276127 -250.173954) (xy 348.271292 -250.212171) (xy 348.266766 -250.230894)
			(xy 348.264921 -250.239499) (xy 348.266549 -250.257008) (xy 348.274021 -250.272926) (xy 348.279974 -250.279408)
			(xy 348.92107 -250.920504) (xy 348.927568 -250.926427) (xy 348.943486 -250.933866) (xy 348.960979 -250.935518)
			(xy 348.969584 -250.933712) (xy 349.03791 -250.916186) (xy 349.038418 -250.916186) (xy 349.051372 -250.912884)
			(xy 349.059831 -250.910447) (xy 349.074504 -250.900745) (xy 349.085019 -250.886643) (xy 349.087948 -250.87834)
			(xy 349.089218 -250.874276) (xy 349.096816 -250.851201) (xy 349.118286 -250.807627) (xy 349.146388 -250.768003)
			(xy 349.180411 -250.733331) (xy 349.219498 -250.704486) (xy 349.262659 -250.682197) (xy 349.308807 -250.667027)
			(xy 349.356775 -250.659357) (xy 349.381064 -250.658884) (xy 349.405388 -250.65936) (xy 349.45342 -250.66708)
			(xy 349.499621 -250.682313) (xy 349.542825 -250.704676) (xy 349.581939 -250.733602) (xy 349.615975 -250.768362)
			(xy 349.644072 -250.808076) (xy 349.66552 -250.85174) (xy 349.679778 -250.898252) (xy 349.683578 -250.922282)
			(xy 349.685864 -250.939554) (xy 349.686372 -250.946412) (xy 349.686372 -250.964192) (xy 349.68561 -250.985782)
			(xy 349.685329 -250.996198) (xy 349.692165 -251.01586) (xy 349.698818 -251.023882) (xy 349.748348 -251.077476)
			(xy 349.755866 -251.084862) (xy 349.775159 -251.093286) (xy 349.785686 -251.093732) (xy 350.857058 -251.093732)
			(xy 350.867377 -251.093244) (xy 350.886292 -251.084994) (xy 350.893634 -251.07773) (xy 350.95053 -251.016008)
			(xy 350.957388 -250.99645) (xy 350.956626 -250.985782) (xy 350.955864 -250.964446) (xy 350.955864 -250.964192)
			(xy 350.956335 -250.9402) (xy 350.963842 -250.892808) (xy 350.97867 -250.847173) (xy 351.000453 -250.80442)
			(xy 351.028656 -250.7656) (xy 351.062585 -250.731669) (xy 351.101403 -250.703464) (xy 351.144155 -250.681678)
			(xy 351.189789 -250.666847) (xy 351.23718 -250.659337) (xy 351.261172 -250.658884) (xy 351.285496 -250.659361)
			(xy 351.333526 -250.667081) (xy 351.379727 -250.682316) (xy 351.42293 -250.704679) (xy 351.462042 -250.733605)
			(xy 351.496077 -250.768365) (xy 351.524173 -250.808078) (xy 351.545621 -250.851743) (xy 351.559879 -250.898254)
			(xy 351.563686 -250.922282) (xy 351.565972 -250.939554) (xy 351.56648 -250.946412) (xy 351.56648 -250.964192)
			(xy 351.565718 -250.985782) (xy 351.565437 -250.996198) (xy 351.572274 -251.015859) (xy 351.578926 -251.023882)
			(xy 351.628456 -251.077476) (xy 351.635975 -251.08486) (xy 351.655267 -251.093282) (xy 351.665794 -251.093732)
			(xy 352.736912 -251.093732) (xy 352.747226 -251.093234) (xy 352.766126 -251.08497) (xy 352.773488 -251.07773)
			(xy 352.830384 -251.016008) (xy 352.837242 -250.99645) (xy 352.83648 -250.985782) (xy 352.835718 -250.964446)
			(xy 352.835718 -250.964192) (xy 352.836165 -250.9402) (xy 352.843673 -250.892807) (xy 352.858502 -250.847172)
			(xy 352.880288 -250.804419) (xy 352.908495 -250.7656) (xy 352.942426 -250.731673) (xy 352.981248 -250.703471)
			(xy 353.024004 -250.681689) (xy 353.06964 -250.666865) (xy 353.117034 -250.659362) (xy 353.141026 -250.658884)
			(xy 353.165352 -250.659357) (xy 353.213388 -250.667072) (xy 353.259595 -250.682302) (xy 353.302804 -250.704662)
			(xy 353.341923 -250.733588) (xy 353.375963 -250.768348) (xy 353.404064 -250.808063) (xy 353.425516 -250.85173)
			(xy 353.439777 -250.898245) (xy 353.44354 -250.922282) (xy 353.445826 -250.939554) (xy 353.446334 -250.946412)
			(xy 353.446334 -250.964192) (xy 353.445572 -250.985782) (xy 353.44529 -250.996199) (xy 353.452122 -251.015863)
			(xy 353.45878 -251.023882) (xy 353.50831 -251.077476) (xy 353.515832 -251.084852) (xy 353.535124 -251.093252)
			(xy 353.545648 -251.093732) (xy 354.61702 -251.093732) (xy 354.627334 -251.093232) (xy 354.646231 -251.084967)
			(xy 354.653596 -251.07773) (xy 354.710492 -251.016008) (xy 354.71735 -250.99645) (xy 354.716588 -250.985782)
			(xy 354.715826 -250.964446) (xy 354.715826 -250.964192) (xy 354.716273 -250.9402) (xy 354.723781 -250.892808)
			(xy 354.73861 -250.847173) (xy 354.760397 -250.804421) (xy 354.788603 -250.765603) (xy 354.822535 -250.731676)
			(xy 354.861357 -250.703475) (xy 354.904112 -250.681694) (xy 354.949749 -250.666871) (xy 354.997142 -250.65937)
			(xy 355.021134 -250.658884) (xy 355.045459 -250.659358) (xy 355.093495 -250.667074) (xy 355.1397 -250.682304)
			(xy 355.182908 -250.704665) (xy 355.222026 -250.733591) (xy 355.256065 -250.768351) (xy 355.284166 -250.808066)
			(xy 355.305617 -250.851733) (xy 355.319877 -250.898247) (xy 355.323648 -250.922282) (xy 355.325934 -250.939554)
			(xy 355.326442 -250.946412) (xy 355.326442 -250.964192) (xy 355.32568 -250.985782) (xy 355.325398 -250.996199)
			(xy 355.332231 -251.015863) (xy 355.338888 -251.023882) (xy 355.388418 -251.077476) (xy 355.39594 -251.08485)
			(xy 355.415233 -251.093248) (xy 355.425756 -251.093732) (xy 356.497128 -251.093732) (xy 356.507441 -251.093231)
			(xy 356.526336 -251.084963) (xy 356.533704 -251.07773) (xy 356.5906 -251.016008) (xy 356.597458 -250.99645)
			(xy 356.596696 -250.985782) (xy 356.595934 -250.964446) (xy 356.595934 -250.964192) (xy 356.5964 -250.940266)
			(xy 356.603868 -250.893) (xy 356.61862 -250.847478) (xy 356.640294 -250.804815) (xy 356.668359 -250.766057)
			(xy 356.702128 -250.732152) (xy 356.740774 -250.703933) (xy 356.783349 -250.682088) (xy 356.828812 -250.667155)
			(xy 356.876048 -250.659498) (xy 356.899972 -250.658884) (xy 356.90175 -250.658884) (xy 356.924586 -250.659326)
			(xy 356.969737 -250.666214) (xy 356.991666 -250.6726) (xy 356.992936 -250.672854) (xy 356.999468 -250.674619)
			(xy 357.012987 -250.675013) (xy 357.019606 -250.673616) (xy 357.026381 -250.671794) (xy 357.038628 -250.664963)
			(xy 357.043736 -250.660154) (xy 357.174038 -250.529852) (xy 357.181658 -250.519946) (xy 357.185267 -250.513548)
			(xy 357.18901 -250.499351) (xy 357.189024 -250.492006) (xy 357.18623 -250.409202) (xy 357.17734 -250.390406)
			(xy 357.169466 -250.383294) (xy 357.150332 -250.365778) (xy 357.11773 -250.325432) (xy 357.09242 -250.280153)
			(xy 357.075131 -250.231247) (xy 357.066362 -250.180122) (xy 357.065834 -250.154186) (xy 357.066281 -250.130195)
			(xy 357.07379 -250.082803) (xy 357.08862 -250.03717) (xy 357.110407 -249.994419) (xy 357.138614 -249.955603)
			(xy 357.172546 -249.921677) (xy 357.211367 -249.893478) (xy 357.254122 -249.871699) (xy 357.299758 -249.856877)
			(xy 357.347151 -249.849377) (xy 357.371142 -249.848878) (xy 357.394941 -249.849337) (xy 357.441962 -249.85673)
			(xy 357.487266 -249.87133) (xy 357.529756 -249.892784) (xy 357.568402 -249.920572) (xy 357.602267 -249.95402)
			(xy 357.630531 -249.992319) (xy 357.652509 -250.034539) (xy 357.66767 -250.079659) (xy 357.675645 -250.126585)
			(xy 357.67645 -250.150376) (xy 357.67645 -250.15444) (xy 357.675913 -250.179347) (xy 357.66774 -250.228487)
			(xy 357.660194 -250.25223) (xy 357.660194 -250.252738) (xy 357.658494 -250.25835) (xy 357.657478 -250.270028)
			(xy 357.658162 -250.275852) (xy 357.65994 -250.288298) (xy 357.713788 -250.363736) (xy 357.72141 -250.373232)
			(xy 357.743032 -250.384351) (xy 357.75519 -250.385072) (xy 360.740706 -250.385072) (xy 360.752867 -250.384379)
			(xy 360.77449 -250.373241) (xy 360.782108 -250.363736) (xy 360.828844 -250.298204) (xy 360.832201 -250.293204)
			(xy 360.836705 -250.282039) (xy 360.837734 -250.276106) (xy 360.839512 -250.263914) (xy 360.835702 -250.25223)
			(xy 360.82836 -250.229223) (xy 360.820187 -250.181627) (xy 360.819446 -250.157488) (xy 360.819446 -250.150376)
			(xy 360.820264 -250.125327) (xy 360.829064 -250.075992) (xy 360.845802 -250.028755) (xy 360.870029 -249.984887)
			(xy 360.901095 -249.945563) (xy 360.938165 -249.91184) (xy 360.980244 -249.884623) (xy 361.026203 -249.864643)
			(xy 361.074808 -249.852437) (xy 361.124754 -249.848331) (xy 361.1747 -249.852437) (xy 361.223305 -249.864643)
			(xy 361.269264 -249.884623) (xy 361.311343 -249.91184) (xy 361.348413 -249.945563) (xy 361.379479 -249.984887)
			(xy 361.403706 -250.028755) (xy 361.420444 -250.075992) (xy 361.429244 -250.125327) (xy 361.430062 -250.150376)
			(xy 361.430062 -250.15444) (xy 361.429526 -250.179347) (xy 361.421353 -250.228488) (xy 361.413806 -250.25223)
			(xy 361.413806 -250.252738) (xy 361.412106 -250.25835) (xy 361.411089 -250.270028) (xy 361.411774 -250.275852)
			(xy 361.413552 -250.288298) (xy 361.4674 -250.363736) (xy 361.475016 -250.373247) (xy 361.496637 -250.384403)
			(xy 361.508802 -250.385072) (xy 362.620814 -250.385072) (xy 362.632974 -250.384377) (xy 362.654595 -250.373237)
			(xy 362.662216 -250.363736) (xy 362.708952 -250.298204) (xy 362.712308 -250.293204) (xy 362.716812 -250.282039)
			(xy 362.717842 -250.276106) (xy 362.71962 -250.263914) (xy 362.71581 -250.25223) (xy 362.708467 -250.229223)
			(xy 362.700294 -250.181627) (xy 362.699554 -250.157488) (xy 362.699554 -250.150376) (xy 362.700308 -250.126583)
			(xy 362.708285 -250.079655) (xy 362.723449 -250.034535) (xy 362.745433 -249.992314) (xy 362.773704 -249.954018)
			(xy 362.807576 -249.920574) (xy 362.846229 -249.892793) (xy 362.888726 -249.871349) (xy 362.934036 -249.85676)
			(xy 362.981061 -249.849381) (xy 363.004862 -249.848878) (xy 363.028562 -249.84933) (xy 363.07539 -249.856662)
			(xy 363.120524 -249.871141) (xy 363.16288 -249.892418) (xy 363.20144 -249.919984) (xy 363.235278 -249.953175)
			(xy 363.263582 -249.991196) (xy 363.285673 -250.033133) (xy 363.30102 -250.077979) (xy 363.309254 -250.124658)
			(xy 363.31017 -250.148344) (xy 363.31017 -250.154186) (xy 364.578912 -250.154186) (xy 364.582872 -250.105132)
			(xy 364.594649 -250.057348) (xy 364.61394 -250.012072) (xy 364.640243 -249.970476) (xy 364.672878 -249.933639)
			(xy 364.710999 -249.902514) (xy 364.75362 -249.877907) (xy 364.799636 -249.860455) (xy 364.847855 -249.850611)
			(xy 364.89703 -249.84863) (xy 364.945885 -249.854562) (xy 364.993156 -249.868254) (xy 365.037618 -249.889352)
			(xy 365.078121 -249.917308) (xy 365.113614 -249.9514) (xy 365.143179 -249.990744) (xy 365.16605 -250.034321)
			(xy 365.181634 -250.081002) (xy 365.189529 -250.129579) (xy 365.190024 -250.154186) (xy 365.189529 -250.178793)
			(xy 365.181634 -250.22737) (xy 365.16605 -250.274051) (xy 365.143179 -250.317628) (xy 365.113614 -250.356972)
			(xy 365.078121 -250.391064) (xy 365.037618 -250.41902) (xy 364.993156 -250.440118) (xy 364.945885 -250.45381)
			(xy 364.89703 -250.459742) (xy 364.847855 -250.457761) (xy 364.799636 -250.447917) (xy 364.75362 -250.430465)
			(xy 364.710999 -250.405858) (xy 364.672878 -250.374733) (xy 364.640243 -250.337896) (xy 364.61394 -250.2963)
			(xy 364.594649 -250.251024) (xy 364.582872 -250.20324) (xy 364.578912 -250.154186) (xy 363.31017 -250.154186)
			(xy 363.31017 -250.15444) (xy 363.309607 -250.180278) (xy 363.300863 -250.23121) (xy 363.283666 -250.279941)
			(xy 363.271562 -250.302776) (xy 363.271054 -250.303792) (xy 363.269276 -250.307348) (xy 363.265079 -250.316931)
			(xy 363.263987 -250.337801) (xy 363.271278 -250.357387) (xy 363.278166 -250.36526) (xy 363.278674 -250.365768)
			(xy 363.59719 -250.684284) (xy 363.605318 -250.688094) (xy 363.628827 -250.69981) (xy 363.671772 -250.730046)
			(xy 363.708915 -250.767181) (xy 363.739159 -250.81012) (xy 363.75086 -250.833636) (xy 363.75467 -250.841764)
			(xy 364.151672 -251.238766) (xy 364.15218 -251.239274) (xy 364.159564 -251.24585) (xy 364.177862 -251.253287)
			(xy 364.18774 -251.253752)
		)
		(stroke
			(width 0)
			(type solid)
		)
		(fill yes)
		(layer "In4.Cu")
		(net "PVDDCR_CPU0_P0")
	)
	(gr_poly
		(pts
			(xy 64.968374 -335.09712) (xy 64.975618 -335.095491) (xy 64.988787 -335.088651) (xy 64.994282 -335.083658)
			(xy 68.36664 -331.7113) (xy 68.36664 -331.70114) (xy 68.633594 -331.434186) (xy 68.640988 -331.427329)
			(xy 68.659587 -331.419579) (xy 68.669662 -331.4192) (xy 71.637398 -331.4192) (xy 71.64705 -331.418184)
			(xy 71.654295 -331.416557) (xy 71.667465 -331.409718) (xy 71.672958 -331.404722) (xy 72.575674 -330.502006)
			(xy 72.583076 -330.495171) (xy 72.601675 -330.487462) (xy 72.611742 -330.48702) (xy 106.393234 -330.48702)
			(xy 106.403302 -330.486591) (xy 106.421899 -330.47887) (xy 106.429302 -330.472034) (xy 106.79938 -330.101956)
			(xy 106.806222 -330.094556) (xy 106.813943 -330.075958) (xy 106.814366 -330.065888) (xy 106.814366 -319.639188)
			(xy 106.814059 -319.630429) (xy 106.808223 -319.613918) (xy 106.802936 -319.60693) (xy 103.934768 -316.112144)
			(xy 103.925839 -316.101145) (xy 103.90894 -316.078402) (xy 103.900986 -316.066678) (xy 103.650288 -315.691266)
			(xy 103.643938 -315.683646) (xy 103.58882 -315.628528) (xy 103.581708 -315.619638) (xy 103.24211 -315.08065)
			(xy 103.241602 -315.079634) (xy 100.461826 -310.919622) (xy 100.446297 -310.895736) (xy 100.419454 -310.845479)
			(xy 100.408232 -310.819292) (xy 99.997768 -309.828438) (xy 99.99314 -309.818687) (xy 99.977385 -309.803963)
			(xy 99.956988 -309.796961) (xy 99.946206 -309.79745) (xy 99.849686 -309.80634) (xy 99.838993 -309.807798)
			(xy 99.820213 -309.818392) (xy 99.807458 -309.835776) (xy 99.804728 -309.846218) (xy 99.797945 -309.875783)
			(xy 99.778272 -309.933164) (xy 99.751912 -309.987797) (xy 99.719241 -310.038906) (xy 99.700334 -310.062626)
			(xy 99.695102 -310.069645) (xy 99.68926 -310.086136) (xy 99.688904 -310.094884) (xy 99.688904 -310.248808)
			(xy 99.68921 -310.257567) (xy 99.695042 -310.274081) (xy 99.700334 -310.281066) (xy 99.722082 -310.30845)
			(xy 99.758652 -310.368056) (xy 99.786703 -310.432114) (xy 99.805705 -310.499413) (xy 99.815301 -310.568681)
			(xy 99.815904 -310.603646) (xy 99.815437 -310.634375) (xy 99.808024 -310.695385) (xy 99.793312 -310.755056)
			(xy 99.771514 -310.812519) (xy 99.742949 -310.866936) (xy 99.708034 -310.917513) (xy 99.667277 -310.963513)
			(xy 99.621273 -311.004265) (xy 99.570693 -311.039175) (xy 99.516273 -311.067735) (xy 99.458808 -311.089526)
			(xy 99.399135 -311.104233) (xy 99.338125 -311.11164) (xy 99.307396 -311.112154) (xy 99.273904 -311.111638)
			(xy 99.207497 -311.102875) (xy 99.142817 -311.085461) (xy 99.080986 -311.059698) (xy 99.023077 -311.026034)
			(xy 98.996246 -311.005982) (xy 98.986682 -310.999252) (xy 98.963814 -310.994483) (xy 98.94119 -311.000299)
			(xy 98.931984 -311.007506) (xy 98.913914 -311.022556) (xy 98.874317 -311.047926) (xy 98.831524 -311.067425)
			(xy 98.786398 -311.080659) (xy 98.739851 -311.08736) (xy 98.716338 -311.08777) (xy 98.69035 -311.08729)
			(xy 98.639012 -311.079164) (xy 98.589579 -311.063107) (xy 98.543265 -311.039514) (xy 98.501214 -311.008966)
			(xy 98.464459 -310.972215) (xy 98.433906 -310.930167) (xy 98.410307 -310.883857) (xy 98.394245 -310.834425)
			(xy 98.386113 -310.783088) (xy 98.386113 -310.731112) (xy 98.394245 -310.679775) (xy 98.410307 -310.630343)
			(xy 98.433906 -310.584033) (xy 98.464459 -310.541985) (xy 98.501214 -310.505234) (xy 98.543265 -310.474686)
			(xy 98.589579 -310.451093) (xy 98.639012 -310.435036) (xy 98.69035 -310.42691) (xy 98.716338 -310.426354)
			(xy 98.733159 -310.426577) (xy 98.766624 -310.430015) (xy 98.78314 -310.433212) (xy 98.794669 -310.434979)
			(xy 98.817222 -310.42913) (xy 98.834916 -310.413972) (xy 98.840036 -310.403494) (xy 98.854762 -310.370688)
			(xy 98.892117 -310.309243) (xy 98.914458 -310.281066) (xy 98.919658 -310.274103) (xy 98.925497 -310.257744)
			(xy 98.925888 -310.249062) (xy 98.925888 -310.094884) (xy 98.925581 -310.086125) (xy 98.919746 -310.069614)
			(xy 98.914458 -310.062626) (xy 98.895802 -310.039213) (xy 98.863511 -309.988801) (xy 98.837351 -309.934951)
			(xy 98.817685 -309.878406) (xy 98.810826 -309.849266) (xy 98.807749 -309.838018) (xy 98.79323 -309.8198)
			(xy 98.772187 -309.809805) (xy 98.760534 -309.809388) (xy 98.75647 -309.809388) (xy 98.730486 -309.808876)
			(xy 98.679158 -309.800742) (xy 98.629735 -309.78468) (xy 98.583432 -309.761084) (xy 98.541391 -309.730535)
			(xy 98.504645 -309.693787) (xy 98.474101 -309.651742) (xy 98.450509 -309.605438) (xy 98.434451 -309.556013)
			(xy 98.426321 -309.504684) (xy 98.426321 -309.452716) (xy 98.434451 -309.401387) (xy 98.450509 -309.351962)
			(xy 98.474101 -309.305658) (xy 98.504645 -309.263613) (xy 98.541391 -309.226865) (xy 98.583432 -309.196316)
			(xy 98.629735 -309.17272) (xy 98.679158 -309.156658) (xy 98.730486 -309.148524) (xy 98.75647 -309.147972)
			(xy 98.78125 -309.14841) (xy 98.830257 -309.155797) (xy 98.877614 -309.170408) (xy 98.922263 -309.191919)
			(xy 98.963206 -309.219846) (xy 98.999525 -309.253568) (xy 99.015296 -309.272686) (xy 99.022992 -309.281384)
			(xy 99.043961 -309.291316) (xy 99.067162 -309.291104) (xy 99.07778 -309.286402) (xy 99.10455 -309.273326)
			(xy 99.160487 -309.252809) (xy 99.218436 -309.238965) (xy 99.277606 -309.231983) (xy 99.307396 -309.231538)
			(xy 99.336651 -309.231948) (xy 99.394774 -309.238659) (xy 99.451744 -309.251994) (xy 99.506808 -309.271777)
			(xy 99.559239 -309.297745) (xy 99.584002 -309.313326) (xy 99.597972 -309.32247) (xy 99.630992 -309.320438)
			(xy 99.718622 -309.24754) (xy 99.726624 -309.240269) (xy 99.736123 -309.220868) (xy 99.7368 -309.199278)
			(xy 99.7331 -309.18912) (xy 96.46031 -301.287688) (xy 96.454881 -301.276579) (xy 96.435896 -301.2608)
			(xy 96.423988 -301.257462) (xy 96.329754 -301.23765) (xy 96.305624 -301.244508) (xy 96.29648 -301.253144)
			(xy 96.275051 -301.272813) (xy 96.227346 -301.306091) (xy 96.175145 -301.331747) (xy 96.119657 -301.349187)
			(xy 96.062164 -301.358008) (xy 96.033082 -301.358554) (xy 96.00583 -301.358067) (xy 95.951882 -301.350309)
			(xy 95.899587 -301.334952) (xy 95.850009 -301.312311) (xy 95.804158 -301.282845) (xy 95.762966 -301.247154)
			(xy 95.727272 -301.205965) (xy 95.697803 -301.160116) (xy 95.675157 -301.110539) (xy 95.659797 -301.058245)
			(xy 95.652035 -301.004298) (xy 95.651574 -300.977046) (xy 95.652034 -300.950207) (xy 95.659561 -300.897059)
			(xy 95.67446 -300.845489) (xy 95.696437 -300.796516) (xy 95.725058 -300.751104) (xy 95.759759 -300.71015)
			(xy 95.799854 -300.674461) (xy 95.844555 -300.644741) (xy 95.892978 -300.621577) (xy 95.944168 -300.605424)
			(xy 95.997117 -300.596603) (xy 96.023938 -300.595538) (xy 96.036413 -300.594661) (xy 96.058264 -300.582554)
			(xy 96.065594 -300.572424) (xy 96.11106 -300.50232) (xy 96.117367 -300.491651) (xy 96.119768 -300.467012)
			(xy 96.115632 -300.45533) (xy 95.894652 -299.922184) (xy 95.880694 -299.886899) (xy 95.86103 -299.81361)
			(xy 95.851097 -299.738382) (xy 95.850456 -299.700442) (xy 95.850456 -296.559224) (xy 95.850013 -296.549195)
			(xy 95.842428 -296.530629) (xy 95.835724 -296.523156) (xy 95.678498 -296.366184) (xy 95.671723 -296.358759)
			(xy 95.664135 -296.340162) (xy 95.663766 -296.330116) (xy 95.663766 -295.863518) (xy 95.664206 -295.853456)
			(xy 95.671949 -295.834879) (xy 95.678752 -295.82745) (xy 96.181164 -295.325038) (xy 96.188005 -295.317638)
			(xy 96.195722 -295.299039) (xy 96.19615 -295.28897) (xy 96.19615 -294.976296) (xy 96.196575 -294.966227)
			(xy 96.204296 -294.947629) (xy 96.211136 -294.940228) (xy 96.433386 -294.717978) (xy 96.44023 -294.710579)
			(xy 96.447959 -294.691981) (xy 96.448372 -294.68191) (xy 96.448372 -294.660574) (xy 96.447988 -294.651151)
			(xy 96.441156 -294.633585) (xy 96.428428 -294.619685) (xy 96.420178 -294.615108) (xy 96.32569 -294.568118)
			(xy 96.296988 -294.570912) (xy 96.285558 -294.579548) (xy 96.265529 -294.594118) (xy 96.221743 -294.617261)
			(xy 96.174795 -294.633032) (xy 96.125917 -294.641019) (xy 96.101154 -294.641524) (xy 96.0759 -294.640999)
			(xy 96.026081 -294.632679) (xy 95.978312 -294.616273) (xy 95.933893 -294.592229) (xy 95.894038 -294.561203)
			(xy 95.859832 -294.52404) (xy 95.832209 -294.481754) (xy 95.811921 -294.435499) (xy 95.799524 -294.386536)
			(xy 95.795353 -294.3362) (xy 95.799524 -294.285864) (xy 95.811921 -294.236901) (xy 95.832209 -294.190646)
			(xy 95.859832 -294.14836) (xy 95.894038 -294.111197) (xy 95.933893 -294.080171) (xy 95.978312 -294.056127)
			(xy 96.026081 -294.039721) (xy 96.0759 -294.031401) (xy 96.101154 -294.030908) (xy 96.127902 -294.031467)
			(xy 96.180579 -294.040796) (xy 96.230825 -294.059159) (xy 96.277104 -294.085994) (xy 96.318 -294.120481)
			(xy 96.335596 -294.140636) (xy 96.342359 -294.14794) (xy 96.359977 -294.157165) (xy 96.379777 -294.159024)
			(xy 96.389444 -294.156638) (xy 96.412304 -294.14978) (xy 96.422532 -294.146137) (xy 96.438846 -294.131842)
			(xy 96.447853 -294.112109) (xy 96.448372 -294.101266) (xy 96.448372 -294.022272) (xy 96.447943 -294.012205)
			(xy 96.440218 -293.99361) (xy 96.433386 -293.986204) (xy 96.140016 -293.692834) (xy 96.133178 -293.685433)
			(xy 96.125465 -293.666834) (xy 96.12503 -293.656766) (xy 96.12503 -293.367968) (xy 96.12546 -293.357901)
			(xy 96.133186 -293.339308) (xy 96.140016 -293.3319) (xy 96.488758 -292.983158) (xy 96.495602 -292.975759)
			(xy 96.503328 -292.957161) (xy 96.503744 -292.94709) (xy 96.503744 -292.818566) (xy 96.503239 -292.80815)
			(xy 96.494959 -292.789033) (xy 96.479774 -292.774771) (xy 96.460176 -292.767705) (xy 96.439384 -292.768997)
			(xy 96.42081 -292.778432) (xy 96.407506 -292.794463) (xy 96.404176 -292.804342) (xy 96.396567 -292.828584)
			(xy 96.374702 -292.874444) (xy 96.345777 -292.916212) (xy 96.310538 -292.952811) (xy 96.269896 -292.983297)
			(xy 96.224897 -293.006884) (xy 96.176703 -293.022963) (xy 96.126557 -293.031121) (xy 96.101154 -293.031672)
			(xy 96.076366 -293.031183) (xy 96.027403 -293.023421) (xy 95.980255 -293.008096) (xy 95.936086 -292.985585)
			(xy 95.895981 -292.956441) (xy 95.860929 -292.921384) (xy 95.831791 -292.881275) (xy 95.809287 -292.837102)
			(xy 95.793968 -292.789953) (xy 95.786214 -292.740988) (xy 95.786214 -292.691412) (xy 95.793968 -292.642447)
			(xy 95.809287 -292.595298) (xy 95.831791 -292.551125) (xy 95.860929 -292.511016) (xy 95.895981 -292.475959)
			(xy 95.936086 -292.446815) (xy 95.980255 -292.424304) (xy 96.027403 -292.408979) (xy 96.076366 -292.401217)
			(xy 96.101154 -292.400736) (xy 96.126562 -292.401242) (xy 96.176723 -292.409378) (xy 96.224931 -292.425447)
			(xy 96.269941 -292.449034) (xy 96.31059 -292.479529) (xy 96.345827 -292.516143) (xy 96.374741 -292.557932)
			(xy 96.396584 -292.603813) (xy 96.404176 -292.628066) (xy 96.409002 -292.644322) (xy 96.435926 -292.664642)
			(xy 96.452944 -292.664642) (xy 96.462949 -292.664147) (xy 96.481433 -292.656481) (xy 96.495582 -292.642331)
			(xy 96.503247 -292.623847) (xy 96.503744 -292.613842) (xy 96.503744 -292.43274) (xy 96.50362 -292.426807)
			(xy 96.500931 -292.415252) (xy 96.49841 -292.40988) (xy 96.495616 -292.404292) (xy 96.18726 -292.095936)
			(xy 96.180417 -292.088537) (xy 96.172696 -292.069938) (xy 96.172274 -292.059868) (xy 96.172274 -291.83838)
			(xy 96.171946 -291.829774) (xy 96.166243 -291.813535) (xy 96.161098 -291.80663) (xy 96.135157 -291.77391)
			(xy 96.087612 -291.705259) (xy 96.066102 -291.66947) (xy 96.0628 -291.663882) (xy 95.702374 -291.303456)
			(xy 95.695526 -291.296059) (xy 95.687796 -291.27746) (xy 95.687388 -291.267388) (xy 95.687388 -290.812728)
			(xy 95.687824 -290.802663) (xy 95.695555 -290.784077) (xy 95.702374 -290.77666) (xy 95.703898 -290.775136)
			(xy 95.710571 -290.767734) (xy 95.71815 -290.749325) (xy 95.718139 -290.729417) (xy 95.71482 -290.720018)
			(xy 95.678752 -290.632896) (xy 95.674519 -290.623805) (xy 95.660321 -290.609665) (xy 95.641783 -290.602059)
			(xy 95.631762 -290.601654) (xy 95.606932 -290.60125) (xy 95.557868 -290.593588) (xy 95.51061 -290.578334)
			(xy 95.466326 -290.555863) (xy 95.42611 -290.526732) (xy 95.390954 -290.49166) (xy 95.361728 -290.451513)
			(xy 95.339153 -290.407282) (xy 95.323786 -290.360061) (xy 95.316008 -290.311015) (xy 95.315532 -290.286186)
			(xy 95.316018 -290.261396) (xy 95.323774 -290.212428) (xy 95.339095 -290.165275) (xy 95.361604 -290.1211)
			(xy 95.390746 -290.080989) (xy 95.425803 -290.045932) (xy 95.465914 -290.01679) (xy 95.510089 -289.994281)
			(xy 95.557242 -289.97896) (xy 95.60621 -289.971204) (xy 95.65579 -289.971204) (xy 95.704758 -289.97896)
			(xy 95.751911 -289.994281) (xy 95.796086 -290.01679) (xy 95.836197 -290.045932) (xy 95.871254 -290.080989)
			(xy 95.900396 -290.1211) (xy 95.922905 -290.165275) (xy 95.938226 -290.212428) (xy 95.945982 -290.261396)
			(xy 95.946468 -290.286186) (xy 95.946027 -290.310083) (xy 95.938815 -290.357331) (xy 95.924554 -290.402948)
			(xy 95.914464 -290.424616) (xy 95.907352 -290.439348) (xy 95.912686 -290.471098) (xy 95.92437 -290.482782)
			(xy 95.931736 -290.489622) (xy 95.950269 -290.497364) (xy 95.970353 -290.497364) (xy 95.988886 -290.489622)
			(xy 95.996252 -290.482782) (xy 96.110044 -290.36899) (xy 96.116895 -290.361594) (xy 96.124635 -290.342995)
			(xy 96.12503 -290.332922) (xy 96.12503 -290.09721) (xy 96.125452 -290.08714) (xy 96.133167 -290.068535)
			(xy 96.140016 -290.061142) (xy 96.464882 -289.736276) (xy 96.471727 -289.728877) (xy 96.479455 -289.710279)
			(xy 96.479868 -289.700208) (xy 96.479868 -289.639502) (xy 96.479448 -289.629483) (xy 96.471777 -289.610971)
			(xy 96.457604 -289.596806) (xy 96.439087 -289.589146) (xy 96.429068 -289.588702) (xy 96.41459 -289.588702)
			(xy 96.389952 -289.603942) (xy 96.383602 -289.616896) (xy 96.372011 -289.639047) (xy 96.342914 -289.679699)
			(xy 96.307776 -289.715259) (xy 96.267475 -289.744841) (xy 96.223018 -289.767705) (xy 96.175514 -289.783281)
			(xy 96.12615 -289.79118) (xy 96.101154 -289.791648) (xy 96.076368 -289.791158) (xy 96.027408 -289.783397)
			(xy 95.980265 -289.768073) (xy 95.936099 -289.745564) (xy 95.895997 -289.716423) (xy 95.860947 -289.681368)
			(xy 95.831812 -289.641262) (xy 95.809309 -289.597093) (xy 95.793992 -289.549947) (xy 95.786238 -289.500986)
			(xy 95.786238 -289.451414) (xy 95.793992 -289.402453) (xy 95.809309 -289.355307) (xy 95.831812 -289.311138)
			(xy 95.860947 -289.271032) (xy 95.895997 -289.235977) (xy 95.936099 -289.206836) (xy 95.980265 -289.184327)
			(xy 96.027408 -289.169003) (xy 96.076368 -289.161242) (xy 96.101154 -289.160712) (xy 96.126153 -289.161185)
			(xy 96.175525 -289.169061) (xy 96.223039 -289.184623) (xy 96.267504 -289.207482) (xy 96.307809 -289.237066)
			(xy 96.342945 -289.272635) (xy 96.372033 -289.313299) (xy 96.383602 -289.335464) (xy 96.389952 -289.348418)
			(xy 96.41459 -289.363658) (xy 96.429068 -289.363658) (xy 96.43909 -289.363243) (xy 96.457611 -289.355578)
			(xy 96.471783 -289.341403) (xy 96.479445 -289.322881) (xy 96.479868 -289.312858) (xy 96.479868 -289.221672)
			(xy 96.479439 -289.211605) (xy 96.471714 -289.193011) (xy 96.464882 -289.185604) (xy 96.20504 -288.925762)
			(xy 96.198195 -288.918363) (xy 96.190468 -288.899765) (xy 96.190054 -288.889694) (xy 96.190054 -288.502852)
			(xy 96.190308 -288.502598) (xy 96.190308 -288.319718) (xy 96.190746 -288.309655) (xy 96.198483 -288.291073)
			(xy 96.205294 -288.28365) (xy 96.247204 -288.24174) (xy 96.253889 -288.234326) (xy 96.26149 -288.215889)
			(xy 96.261498 -288.195947) (xy 96.25391 -288.177505) (xy 96.247204 -288.170112) (xy 96.24695 -288.169858)
			(xy 96.240157 -288.163656) (xy 96.223384 -288.15614) (xy 96.205036 -288.15504) (xy 96.19615 -288.157412)
			(xy 96.195896 -288.157412) (xy 96.172806 -288.164244) (xy 96.125228 -288.171648) (xy 96.101154 -288.172144)
			(xy 96.076343 -288.171654) (xy 96.027333 -288.163884) (xy 95.980143 -288.148543) (xy 95.935932 -288.126009)
			(xy 95.895791 -288.096837) (xy 95.860708 -288.061745) (xy 95.831547 -288.021596) (xy 95.809024 -287.97738)
			(xy 95.793696 -287.930185) (xy 95.78594 -287.881173) (xy 95.785946 -287.831551) (xy 95.793714 -287.782541)
			(xy 95.809054 -287.73535) (xy 95.831586 -287.691139) (xy 95.860758 -287.650998) (xy 95.895849 -287.615913)
			(xy 95.935997 -287.586751) (xy 95.980213 -287.564227) (xy 96.027407 -287.548898) (xy 96.076419 -287.54114)
			(xy 96.126041 -287.541145) (xy 96.175051 -287.548912) (xy 96.222243 -287.56425) (xy 96.266454 -287.586782)
			(xy 96.306596 -287.615952) (xy 96.341681 -287.651043) (xy 96.370845 -287.69119) (xy 96.393369 -287.735405)
			(xy 96.4087 -287.7826) (xy 96.416459 -287.831611) (xy 96.416876 -287.856422) (xy 96.416386 -287.880497)
			(xy 96.408989 -287.928077) (xy 96.402144 -287.951164) (xy 96.402144 -287.951418) (xy 96.399811 -287.960307)
			(xy 96.400928 -287.978638) (xy 96.408423 -287.995403) (xy 96.41459 -288.002218) (xy 96.414844 -288.002472)
			(xy 96.422256 -288.009156) (xy 96.440689 -288.016753) (xy 96.460627 -288.016753) (xy 96.47906 -288.009156)
			(xy 96.486472 -288.002472) (xy 96.548194 -287.94075) (xy 96.555033 -287.933349) (xy 96.56275 -287.914751)
			(xy 96.56318 -287.904682) (xy 96.56318 -287.689544) (xy 96.563613 -287.679478) (xy 96.571339 -287.660886)
			(xy 96.578166 -287.653476) (xy 97.06229 -287.169352) (xy 97.06913 -287.161951) (xy 97.076849 -287.143353)
			(xy 97.077276 -287.133284) (xy 97.077276 -286.87395) (xy 97.077708 -286.863883) (xy 97.085432 -286.84529)
			(xy 97.092262 -286.837882) (xy 97.461832 -286.468312) (xy 97.461832 -286.460692) (xy 97.450276 -286.432949)
			(xy 97.432457 -286.375548) (xy 97.426272 -286.346138) (xy 97.424021 -286.336921) (xy 97.413784 -286.32096)
			(xy 97.398456 -286.3098) (xy 97.380123 -286.30496) (xy 97.361283 -286.307099) (xy 97.344502 -286.315926)
			(xy 97.332066 -286.33024) (xy 97.328482 -286.339026) (xy 97.320199 -286.360964) (xy 97.297872 -286.402198)
			(xy 97.269505 -286.439535) (xy 97.235762 -286.472096) (xy 97.197439 -286.499116) (xy 97.155435 -286.519959)
			(xy 97.110738 -286.534136) (xy 97.064399 -286.541313) (xy 97.040954 -286.541718) (xy 97.0157 -286.541193)
			(xy 96.965883 -286.532873) (xy 96.918114 -286.516467) (xy 96.873696 -286.492424) (xy 96.833842 -286.461398)
			(xy 96.799637 -286.424236) (xy 96.772014 -286.381951) (xy 96.751727 -286.335697) (xy 96.739329 -286.286735)
			(xy 96.735159 -286.2364) (xy 96.739329 -286.186065) (xy 96.751727 -286.137103) (xy 96.772014 -286.090849)
			(xy 96.799637 -286.048564) (xy 96.833842 -286.011402) (xy 96.873696 -285.980376) (xy 96.918114 -285.956333)
			(xy 96.965883 -285.939927) (xy 97.0157 -285.931607) (xy 97.040954 -285.931102) (xy 97.064129 -285.93153)
			(xy 97.109946 -285.938536) (xy 97.154176 -285.952394) (xy 97.1958 -285.972785) (xy 97.233859 -285.999239)
			(xy 97.267478 -286.031147) (xy 97.282 -286.049212) (xy 97.290382 -286.060134) (xy 97.315274 -286.070294)
			(xy 97.430082 -286.054292) (xy 97.451418 -286.037274) (xy 97.456498 -286.024828) (xy 97.47158 -285.989234)
			(xy 97.510075 -285.922197) (xy 97.533206 -285.891224) (xy 97.541588 -285.880302) (xy 97.545144 -285.853632)
			(xy 97.501964 -285.747206) (xy 97.480882 -285.730696) (xy 97.467166 -285.728664) (xy 97.443281 -285.724697)
			(xy 97.397082 -285.710212) (xy 97.353745 -285.688626) (xy 97.314351 -285.660479) (xy 97.279887 -285.626474)
			(xy 97.251214 -285.587462) (xy 97.229049 -285.544417) (xy 97.213945 -285.498417) (xy 97.206282 -285.450612)
			(xy 97.2058 -285.426404) (xy 97.206322 -285.401149) (xy 97.214635 -285.351327) (xy 97.231036 -285.303553)
			(xy 97.255077 -285.25913) (xy 97.286101 -285.21927) (xy 97.323263 -285.18506) (xy 97.365549 -285.157434)
			(xy 97.411805 -285.137144) (xy 97.46077 -285.124744) (xy 97.511108 -285.120573) (xy 97.561446 -285.124744)
			(xy 97.610411 -285.137144) (xy 97.656667 -285.157434) (xy 97.698953 -285.18506) (xy 97.736115 -285.21927)
			(xy 97.767139 -285.25913) (xy 97.79118 -285.303553) (xy 97.807581 -285.351327) (xy 97.815894 -285.401149)
			(xy 97.816416 -285.426404) (xy 97.815762 -285.455103) (xy 97.80502 -285.511487) (xy 97.79508 -285.538418)
			(xy 97.79 -285.550864) (xy 97.794064 -285.577534) (xy 97.865184 -285.667958) (xy 97.890076 -285.677864)
			(xy 97.903538 -285.676086) (xy 97.922808 -285.673588) (xy 97.961577 -285.670918) (xy 97.981008 -285.670752)
			(xy 98.070162 -285.670752) (xy 98.082554 -285.670208) (xy 98.104523 -285.658752) (xy 98.112072 -285.648908)
			(xy 98.15957 -285.580074) (xy 98.165859 -285.569646) (xy 98.168892 -285.545518) (xy 98.165412 -285.533846)
			(xy 98.165412 -285.533592) (xy 98.156341 -285.507725) (xy 98.1465 -285.453807) (xy 98.145854 -285.426404)
			(xy 98.146376 -285.401149) (xy 98.154689 -285.351327) (xy 98.17109 -285.303553) (xy 98.195131 -285.25913)
			(xy 98.226155 -285.21927) (xy 98.263317 -285.18506) (xy 98.305603 -285.157434) (xy 98.351859 -285.137144)
			(xy 98.400824 -285.124744) (xy 98.451162 -285.120573) (xy 98.5015 -285.124744) (xy 98.550465 -285.137144)
			(xy 98.596721 -285.157434) (xy 98.639007 -285.18506) (xy 98.676169 -285.21927) (xy 98.707193 -285.25913)
			(xy 98.731234 -285.303553) (xy 98.747635 -285.351327) (xy 98.755948 -285.401149) (xy 98.75647 -285.426404)
			(xy 98.755822 -285.453746) (xy 98.745988 -285.507539) (xy 98.736912 -285.533338) (xy 98.736912 -285.533846)
			(xy 98.732594 -285.545276) (xy 98.735642 -285.569914) (xy 98.790252 -285.648908) (xy 98.797916 -285.658614)
			(xy 98.819816 -285.670019) (xy 98.832162 -285.670752) (xy 98.921062 -285.670752) (xy 98.940493 -285.670916)
			(xy 98.979262 -285.673586) (xy 98.998532 -285.676086) (xy 99.011994 -285.677864) (xy 99.036886 -285.667958)
			(xy 99.108006 -285.577534) (xy 99.11207 -285.550864) (xy 99.10699 -285.538418) (xy 99.097073 -285.511481)
			(xy 99.086339 -285.4551) (xy 99.085654 -285.426404) (xy 99.08614 -285.401579) (xy 99.094172 -285.352584)
			(xy 99.110025 -285.305534) (xy 99.133281 -285.261668) (xy 99.163328 -285.222143) (xy 99.199373 -285.187999)
			(xy 99.240468 -285.160137) (xy 99.285529 -285.139291) (xy 99.333369 -285.126009) (xy 99.382727 -285.120643)
			(xy 99.432303 -285.123333) (xy 99.480792 -285.134008) (xy 99.526914 -285.152387) (xy 99.569455 -285.177986)
			(xy 99.607294 -285.21013) (xy 99.639434 -285.247973) (xy 99.665028 -285.290517) (xy 99.683402 -285.336641)
			(xy 99.694072 -285.38513) (xy 99.696306 -285.426404) (xy 100.025212 -285.426404) (xy 100.029172 -285.37735)
			(xy 100.040949 -285.329566) (xy 100.06024 -285.28429) (xy 100.086543 -285.242694) (xy 100.119178 -285.205857)
			(xy 100.157299 -285.174732) (xy 100.19992 -285.150125) (xy 100.245936 -285.132673) (xy 100.294155 -285.122829)
			(xy 100.34333 -285.120848) (xy 100.392185 -285.12678) (xy 100.439456 -285.140472) (xy 100.483918 -285.16157)
			(xy 100.524421 -285.189526) (xy 100.559914 -285.223618) (xy 100.589479 -285.262962) (xy 100.61235 -285.306539)
			(xy 100.627934 -285.35322) (xy 100.635829 -285.401797) (xy 100.636324 -285.426404) (xy 100.965266 -285.426404)
			(xy 100.969226 -285.37735) (xy 100.981003 -285.329566) (xy 101.000294 -285.28429) (xy 101.026597 -285.242694)
			(xy 101.059232 -285.205857) (xy 101.097353 -285.174732) (xy 101.139974 -285.150125) (xy 101.18599 -285.132673)
			(xy 101.234209 -285.122829) (xy 101.283384 -285.120848) (xy 101.332239 -285.12678) (xy 101.37951 -285.140472)
			(xy 101.423972 -285.16157) (xy 101.464475 -285.189526) (xy 101.499968 -285.223618) (xy 101.529533 -285.262962)
			(xy 101.552404 -285.306539) (xy 101.567988 -285.35322) (xy 101.575883 -285.401797) (xy 101.576378 -285.426404)
			(xy 101.90532 -285.426404) (xy 101.90928 -285.37735) (xy 101.921057 -285.329566) (xy 101.940348 -285.28429)
			(xy 101.966651 -285.242694) (xy 101.999286 -285.205857) (xy 102.037407 -285.174732) (xy 102.080028 -285.150125)
			(xy 102.126044 -285.132673) (xy 102.174263 -285.122829) (xy 102.223438 -285.120848) (xy 102.272293 -285.12678)
			(xy 102.319564 -285.140472) (xy 102.364026 -285.16157) (xy 102.404529 -285.189526) (xy 102.440022 -285.223618)
			(xy 102.469587 -285.262962) (xy 102.492458 -285.306539) (xy 102.508042 -285.35322) (xy 102.515937 -285.401797)
			(xy 102.516432 -285.426404) (xy 102.845374 -285.426404) (xy 102.849334 -285.37735) (xy 102.861111 -285.329566)
			(xy 102.880402 -285.28429) (xy 102.906705 -285.242694) (xy 102.93934 -285.205857) (xy 102.977461 -285.174732)
			(xy 103.020082 -285.150125) (xy 103.066098 -285.132673) (xy 103.114317 -285.122829) (xy 103.163492 -285.120848)
			(xy 103.212347 -285.12678) (xy 103.259618 -285.140472) (xy 103.30408 -285.16157) (xy 103.344583 -285.189526)
			(xy 103.380076 -285.223618) (xy 103.409641 -285.262962) (xy 103.432512 -285.306539) (xy 103.448096 -285.35322)
			(xy 103.455991 -285.401797) (xy 103.456486 -285.426404) (xy 103.785174 -285.426404) (xy 103.789134 -285.37735)
			(xy 103.800911 -285.329566) (xy 103.820202 -285.28429) (xy 103.846505 -285.242694) (xy 103.87914 -285.205857)
			(xy 103.917261 -285.174732) (xy 103.959882 -285.150125) (xy 104.005898 -285.132673) (xy 104.054117 -285.122829)
			(xy 104.103292 -285.120848) (xy 104.152147 -285.12678) (xy 104.199418 -285.140472) (xy 104.24388 -285.16157)
			(xy 104.284383 -285.189526) (xy 104.319876 -285.223618) (xy 104.349441 -285.262962) (xy 104.372312 -285.306539)
			(xy 104.387896 -285.35322) (xy 104.395791 -285.401797) (xy 104.396286 -285.426404) (xy 104.725228 -285.426404)
			(xy 104.729188 -285.37735) (xy 104.740965 -285.329566) (xy 104.760256 -285.28429) (xy 104.786559 -285.242694)
			(xy 104.819194 -285.205857) (xy 104.857315 -285.174732) (xy 104.899936 -285.150125) (xy 104.945952 -285.132673)
			(xy 104.994171 -285.122829) (xy 105.043346 -285.120848) (xy 105.092201 -285.12678) (xy 105.139472 -285.140472)
			(xy 105.183934 -285.16157) (xy 105.224437 -285.189526) (xy 105.25993 -285.223618) (xy 105.289495 -285.262962)
			(xy 105.312366 -285.306539) (xy 105.32795 -285.35322) (xy 105.335845 -285.401797) (xy 105.33634 -285.426404)
			(xy 105.665282 -285.426404) (xy 105.669242 -285.37735) (xy 105.681019 -285.329566) (xy 105.70031 -285.28429)
			(xy 105.726613 -285.242694) (xy 105.759248 -285.205857) (xy 105.797369 -285.174732) (xy 105.83999 -285.150125)
			(xy 105.886006 -285.132673) (xy 105.934225 -285.122829) (xy 105.9834 -285.120848) (xy 106.032255 -285.12678)
			(xy 106.079526 -285.140472) (xy 106.123988 -285.16157) (xy 106.164491 -285.189526) (xy 106.199984 -285.223618)
			(xy 106.229549 -285.262962) (xy 106.25242 -285.306539) (xy 106.268004 -285.35322) (xy 106.275899 -285.401797)
			(xy 106.276394 -285.426404) (xy 106.605336 -285.426404) (xy 106.609296 -285.37735) (xy 106.621073 -285.329566)
			(xy 106.640364 -285.28429) (xy 106.666667 -285.242694) (xy 106.699302 -285.205857) (xy 106.737423 -285.174732)
			(xy 106.780044 -285.150125) (xy 106.82606 -285.132673) (xy 106.874279 -285.122829) (xy 106.923454 -285.120848)
			(xy 106.972309 -285.12678) (xy 107.01958 -285.140472) (xy 107.064042 -285.16157) (xy 107.104545 -285.189526)
			(xy 107.140038 -285.223618) (xy 107.169603 -285.262962) (xy 107.192474 -285.306539) (xy 107.208058 -285.35322)
			(xy 107.215953 -285.401797) (xy 107.216448 -285.426404) (xy 107.545136 -285.426404) (xy 107.549096 -285.37735)
			(xy 107.560873 -285.329566) (xy 107.580164 -285.28429) (xy 107.606467 -285.242694) (xy 107.639102 -285.205857)
			(xy 107.677223 -285.174732) (xy 107.719844 -285.150125) (xy 107.76586 -285.132673) (xy 107.814079 -285.122829)
			(xy 107.863254 -285.120848) (xy 107.912109 -285.12678) (xy 107.95938 -285.140472) (xy 108.003842 -285.16157)
			(xy 108.044345 -285.189526) (xy 108.079838 -285.223618) (xy 108.109403 -285.262962) (xy 108.132274 -285.306539)
			(xy 108.147858 -285.35322) (xy 108.155753 -285.401797) (xy 108.156248 -285.4264) (xy 108.485173 -285.4264)
			(xy 108.489344 -285.376063) (xy 108.501743 -285.327099) (xy 108.522032 -285.280844) (xy 108.549658 -285.238559)
			(xy 108.583867 -285.201398) (xy 108.623725 -285.170374) (xy 108.668147 -285.146334) (xy 108.715919 -285.129932)
			(xy 108.765739 -285.121618) (xy 108.790994 -285.121096) (xy 109.731048 -285.121096) (xy 109.756301 -285.121613)
			(xy 109.806117 -285.129933) (xy 109.853885 -285.146339) (xy 109.898301 -285.170382) (xy 109.938155 -285.201407)
			(xy 109.972359 -285.238568) (xy 109.999981 -285.280852) (xy 110.020267 -285.327105) (xy 110.032665 -285.376066)
			(xy 110.036835 -285.4264) (xy 110.036835 -285.426404) (xy 110.365298 -285.426404) (xy 110.369258 -285.37735)
			(xy 110.381035 -285.329566) (xy 110.400326 -285.28429) (xy 110.426629 -285.242694) (xy 110.459264 -285.205857)
			(xy 110.497385 -285.174732) (xy 110.540006 -285.150125) (xy 110.586022 -285.132673) (xy 110.634241 -285.122829)
			(xy 110.683416 -285.120848) (xy 110.732271 -285.12678) (xy 110.779542 -285.140472) (xy 110.824004 -285.16157)
			(xy 110.864507 -285.189526) (xy 110.9 -285.223618) (xy 110.929565 -285.262962) (xy 110.952436 -285.306539)
			(xy 110.96802 -285.35322) (xy 110.975915 -285.401797) (xy 110.97641 -285.426404) (xy 113.178856 -285.426404)
			(xy 113.182816 -285.37735) (xy 113.194593 -285.329566) (xy 113.213884 -285.28429) (xy 113.240187 -285.242694)
			(xy 113.272822 -285.205857) (xy 113.310943 -285.174732) (xy 113.353564 -285.150125) (xy 113.39958 -285.132673)
			(xy 113.447799 -285.122829) (xy 113.496974 -285.120848) (xy 113.545829 -285.12678) (xy 113.5931 -285.140472)
			(xy 113.637562 -285.16157) (xy 113.678065 -285.189526) (xy 113.713558 -285.223618) (xy 113.743123 -285.262962)
			(xy 113.765994 -285.306539) (xy 113.781578 -285.35322) (xy 113.789473 -285.401797) (xy 113.789968 -285.4264)
			(xy 114.118844 -285.4264) (xy 114.123016 -285.376056) (xy 114.135417 -285.327086) (xy 114.15571 -285.280825)
			(xy 114.18334 -285.238535) (xy 114.217555 -285.201369) (xy 114.25742 -285.170343) (xy 114.301849 -285.146301)
			(xy 114.349628 -285.1299) (xy 114.399456 -285.121588) (xy 114.424714 -285.121096) (xy 115.364768 -285.121096)
			(xy 115.390028 -285.121578) (xy 115.439859 -285.129889) (xy 115.487643 -285.146288) (xy 115.532075 -285.17033)
			(xy 115.571944 -285.201357) (xy 115.606161 -285.238524) (xy 115.633795 -285.280816) (xy 115.654089 -285.32708)
			(xy 115.666492 -285.376053) (xy 115.670664 -285.4264) (xy 115.670664 -285.426404) (xy 115.999018 -285.426404)
			(xy 116.002978 -285.37735) (xy 116.014755 -285.329566) (xy 116.034046 -285.28429) (xy 116.060349 -285.242694)
			(xy 116.092984 -285.205857) (xy 116.131105 -285.174732) (xy 116.173726 -285.150125) (xy 116.219742 -285.132673)
			(xy 116.267961 -285.122829) (xy 116.317136 -285.120848) (xy 116.365991 -285.12678) (xy 116.413262 -285.140472)
			(xy 116.457724 -285.16157) (xy 116.498227 -285.189526) (xy 116.53372 -285.223618) (xy 116.563285 -285.262962)
			(xy 116.586156 -285.306539) (xy 116.60174 -285.35322) (xy 116.609635 -285.401797) (xy 116.61013 -285.426404)
			(xy 116.938818 -285.426404) (xy 116.942778 -285.37735) (xy 116.954555 -285.329566) (xy 116.973846 -285.28429)
			(xy 117.000149 -285.242694) (xy 117.032784 -285.205857) (xy 117.070905 -285.174732) (xy 117.113526 -285.150125)
			(xy 117.159542 -285.132673) (xy 117.207761 -285.122829) (xy 117.256936 -285.120848) (xy 117.305791 -285.12678)
			(xy 117.353062 -285.140472) (xy 117.397524 -285.16157) (xy 117.438027 -285.189526) (xy 117.47352 -285.223618)
			(xy 117.503085 -285.262962) (xy 117.525956 -285.306539) (xy 117.54154 -285.35322) (xy 117.549435 -285.401797)
			(xy 117.54993 -285.426404) (xy 117.878872 -285.426404) (xy 117.882832 -285.37735) (xy 117.894609 -285.329566)
			(xy 117.9139 -285.28429) (xy 117.940203 -285.242694) (xy 117.972838 -285.205857) (xy 118.010959 -285.174732)
			(xy 118.05358 -285.150125) (xy 118.099596 -285.132673) (xy 118.147815 -285.122829) (xy 118.19699 -285.120848)
			(xy 118.245845 -285.12678) (xy 118.293116 -285.140472) (xy 118.337578 -285.16157) (xy 118.378081 -285.189526)
			(xy 118.413574 -285.223618) (xy 118.443139 -285.262962) (xy 118.46601 -285.306539) (xy 118.481594 -285.35322)
			(xy 118.489489 -285.401797) (xy 118.489984 -285.426404) (xy 118.818926 -285.426404) (xy 118.822886 -285.37735)
			(xy 118.834663 -285.329566) (xy 118.853954 -285.28429) (xy 118.880257 -285.242694) (xy 118.912892 -285.205857)
			(xy 118.951013 -285.174732) (xy 118.993634 -285.150125) (xy 119.03965 -285.132673) (xy 119.087869 -285.122829)
			(xy 119.137044 -285.120848) (xy 119.185899 -285.12678) (xy 119.23317 -285.140472) (xy 119.277632 -285.16157)
			(xy 119.318135 -285.189526) (xy 119.353628 -285.223618) (xy 119.383193 -285.262962) (xy 119.406064 -285.306539)
			(xy 119.421648 -285.35322) (xy 119.429543 -285.401797) (xy 119.430038 -285.426404) (xy 119.75898 -285.426404)
			(xy 119.76294 -285.37735) (xy 119.774717 -285.329566) (xy 119.794008 -285.28429) (xy 119.820311 -285.242694)
			(xy 119.852946 -285.205857) (xy 119.891067 -285.174732) (xy 119.933688 -285.150125) (xy 119.979704 -285.132673)
			(xy 120.027923 -285.122829) (xy 120.077098 -285.120848) (xy 120.125953 -285.12678) (xy 120.173224 -285.140472)
			(xy 120.217686 -285.16157) (xy 120.258189 -285.189526) (xy 120.293682 -285.223618) (xy 120.323247 -285.262962)
			(xy 120.346118 -285.306539) (xy 120.361702 -285.35322) (xy 120.369597 -285.401797) (xy 120.370092 -285.426404)
			(xy 120.699034 -285.426404) (xy 120.702994 -285.37735) (xy 120.714771 -285.329566) (xy 120.734062 -285.28429)
			(xy 120.760365 -285.242694) (xy 120.793 -285.205857) (xy 120.831121 -285.174732) (xy 120.873742 -285.150125)
			(xy 120.919758 -285.132673) (xy 120.967977 -285.122829) (xy 121.017152 -285.120848) (xy 121.066007 -285.12678)
			(xy 121.113278 -285.140472) (xy 121.15774 -285.16157) (xy 121.198243 -285.189526) (xy 121.233736 -285.223618)
			(xy 121.263301 -285.262962) (xy 121.286172 -285.306539) (xy 121.301756 -285.35322) (xy 121.309651 -285.401797)
			(xy 121.310146 -285.426404) (xy 121.638834 -285.426404) (xy 121.642794 -285.37735) (xy 121.654571 -285.329566)
			(xy 121.673862 -285.28429) (xy 121.700165 -285.242694) (xy 121.7328 -285.205857) (xy 121.770921 -285.174732)
			(xy 121.813542 -285.150125) (xy 121.859558 -285.132673) (xy 121.907777 -285.122829) (xy 121.956952 -285.120848)
			(xy 122.005807 -285.12678) (xy 122.053078 -285.140472) (xy 122.09754 -285.16157) (xy 122.138043 -285.189526)
			(xy 122.173536 -285.223618) (xy 122.203101 -285.262962) (xy 122.225972 -285.306539) (xy 122.241556 -285.35322)
			(xy 122.249451 -285.401797) (xy 122.249946 -285.426404) (xy 122.578888 -285.426404) (xy 122.582848 -285.37735)
			(xy 122.594625 -285.329566) (xy 122.613916 -285.28429) (xy 122.640219 -285.242694) (xy 122.672854 -285.205857)
			(xy 122.710975 -285.174732) (xy 122.753596 -285.150125) (xy 122.799612 -285.132673) (xy 122.847831 -285.122829)
			(xy 122.897006 -285.120848) (xy 122.945861 -285.12678) (xy 122.993132 -285.140472) (xy 123.037594 -285.16157)
			(xy 123.078097 -285.189526) (xy 123.11359 -285.223618) (xy 123.143155 -285.262962) (xy 123.166026 -285.306539)
			(xy 123.18161 -285.35322) (xy 123.189505 -285.401797) (xy 123.19 -285.426404) (xy 123.518942 -285.426404)
			(xy 123.522902 -285.37735) (xy 123.534679 -285.329566) (xy 123.55397 -285.28429) (xy 123.580273 -285.242694)
			(xy 123.612908 -285.205857) (xy 123.651029 -285.174732) (xy 123.69365 -285.150125) (xy 123.739666 -285.132673)
			(xy 123.787885 -285.122829) (xy 123.83706 -285.120848) (xy 123.885915 -285.12678) (xy 123.933186 -285.140472)
			(xy 123.977648 -285.16157) (xy 124.018151 -285.189526) (xy 124.053644 -285.223618) (xy 124.083209 -285.262962)
			(xy 124.10608 -285.306539) (xy 124.121664 -285.35322) (xy 124.129559 -285.401797) (xy 124.130054 -285.426404)
			(xy 124.129559 -285.451011) (xy 124.121664 -285.499588) (xy 124.10608 -285.546269) (xy 124.083209 -285.589846)
			(xy 124.053644 -285.62919) (xy 124.018151 -285.663282) (xy 123.977648 -285.691238) (xy 123.933186 -285.712336)
			(xy 123.885915 -285.726028) (xy 123.83706 -285.73196) (xy 123.787885 -285.729979) (xy 123.739666 -285.720135)
			(xy 123.69365 -285.702683) (xy 123.651029 -285.678076) (xy 123.612908 -285.646951) (xy 123.580273 -285.610114)
			(xy 123.55397 -285.568518) (xy 123.534679 -285.523242) (xy 123.522902 -285.475458) (xy 123.518942 -285.426404)
			(xy 123.19 -285.426404) (xy 123.189505 -285.451011) (xy 123.18161 -285.499588) (xy 123.166026 -285.546269)
			(xy 123.143155 -285.589846) (xy 123.11359 -285.62919) (xy 123.078097 -285.663282) (xy 123.037594 -285.691238)
			(xy 122.993132 -285.712336) (xy 122.945861 -285.726028) (xy 122.897006 -285.73196) (xy 122.847831 -285.729979)
			(xy 122.799612 -285.720135) (xy 122.753596 -285.702683) (xy 122.710975 -285.678076) (xy 122.672854 -285.646951)
			(xy 122.640219 -285.610114) (xy 122.613916 -285.568518) (xy 122.594625 -285.523242) (xy 122.582848 -285.475458)
			(xy 122.578888 -285.426404) (xy 122.249946 -285.426404) (xy 122.249451 -285.451011) (xy 122.241556 -285.499588)
			(xy 122.225972 -285.546269) (xy 122.203101 -285.589846) (xy 122.173536 -285.62919) (xy 122.138043 -285.663282)
			(xy 122.09754 -285.691238) (xy 122.053078 -285.712336) (xy 122.005807 -285.726028) (xy 121.956952 -285.73196)
			(xy 121.907777 -285.729979) (xy 121.859558 -285.720135) (xy 121.813542 -285.702683) (xy 121.770921 -285.678076)
			(xy 121.7328 -285.646951) (xy 121.700165 -285.610114) (xy 121.673862 -285.568518) (xy 121.654571 -285.523242)
			(xy 121.642794 -285.475458) (xy 121.638834 -285.426404) (xy 121.310146 -285.426404) (xy 121.309651 -285.451011)
			(xy 121.301756 -285.499588) (xy 121.286172 -285.546269) (xy 121.263301 -285.589846) (xy 121.233736 -285.62919)
			(xy 121.198243 -285.663282) (xy 121.15774 -285.691238) (xy 121.113278 -285.712336) (xy 121.066007 -285.726028)
			(xy 121.017152 -285.73196) (xy 120.967977 -285.729979) (xy 120.919758 -285.720135) (xy 120.873742 -285.702683)
			(xy 120.831121 -285.678076) (xy 120.793 -285.646951) (xy 120.760365 -285.610114) (xy 120.734062 -285.568518)
			(xy 120.714771 -285.523242) (xy 120.702994 -285.475458) (xy 120.699034 -285.426404) (xy 120.370092 -285.426404)
			(xy 120.369597 -285.451011) (xy 120.361702 -285.499588) (xy 120.346118 -285.546269) (xy 120.323247 -285.589846)
			(xy 120.293682 -285.62919) (xy 120.258189 -285.663282) (xy 120.217686 -285.691238) (xy 120.173224 -285.712336)
			(xy 120.125953 -285.726028) (xy 120.077098 -285.73196) (xy 120.027923 -285.729979) (xy 119.979704 -285.720135)
			(xy 119.933688 -285.702683) (xy 119.891067 -285.678076) (xy 119.852946 -285.646951) (xy 119.820311 -285.610114)
			(xy 119.794008 -285.568518) (xy 119.774717 -285.523242) (xy 119.76294 -285.475458) (xy 119.75898 -285.426404)
			(xy 119.430038 -285.426404) (xy 119.429543 -285.451011) (xy 119.421648 -285.499588) (xy 119.406064 -285.546269)
			(xy 119.383193 -285.589846) (xy 119.353628 -285.62919) (xy 119.318135 -285.663282) (xy 119.277632 -285.691238)
			(xy 119.23317 -285.712336) (xy 119.185899 -285.726028) (xy 119.137044 -285.73196) (xy 119.087869 -285.729979)
			(xy 119.03965 -285.720135) (xy 118.993634 -285.702683) (xy 118.951013 -285.678076) (xy 118.912892 -285.646951)
			(xy 118.880257 -285.610114) (xy 118.853954 -285.568518) (xy 118.834663 -285.523242) (xy 118.822886 -285.475458)
			(xy 118.818926 -285.426404) (xy 118.489984 -285.426404) (xy 118.489489 -285.451011) (xy 118.481594 -285.499588)
			(xy 118.46601 -285.546269) (xy 118.443139 -285.589846) (xy 118.413574 -285.62919) (xy 118.378081 -285.663282)
			(xy 118.337578 -285.691238) (xy 118.293116 -285.712336) (xy 118.245845 -285.726028) (xy 118.19699 -285.73196)
			(xy 118.147815 -285.729979) (xy 118.099596 -285.720135) (xy 118.05358 -285.702683) (xy 118.010959 -285.678076)
			(xy 117.972838 -285.646951) (xy 117.940203 -285.610114) (xy 117.9139 -285.568518) (xy 117.894609 -285.523242)
			(xy 117.882832 -285.475458) (xy 117.878872 -285.426404) (xy 117.54993 -285.426404) (xy 117.549435 -285.451011)
			(xy 117.54154 -285.499588) (xy 117.525956 -285.546269) (xy 117.503085 -285.589846) (xy 117.47352 -285.62919)
			(xy 117.438027 -285.663282) (xy 117.397524 -285.691238) (xy 117.353062 -285.712336) (xy 117.305791 -285.726028)
			(xy 117.256936 -285.73196) (xy 117.207761 -285.729979) (xy 117.159542 -285.720135) (xy 117.113526 -285.702683)
			(xy 117.070905 -285.678076) (xy 117.032784 -285.646951) (xy 117.000149 -285.610114) (xy 116.973846 -285.568518)
			(xy 116.954555 -285.523242) (xy 116.942778 -285.475458) (xy 116.938818 -285.426404) (xy 116.61013 -285.426404)
			(xy 116.609635 -285.451011) (xy 116.60174 -285.499588) (xy 116.586156 -285.546269) (xy 116.563285 -285.589846)
			(xy 116.53372 -285.62919) (xy 116.498227 -285.663282) (xy 116.457724 -285.691238) (xy 116.413262 -285.712336)
			(xy 116.365991 -285.726028) (xy 116.317136 -285.73196) (xy 116.267961 -285.729979) (xy 116.219742 -285.720135)
			(xy 116.173726 -285.702683) (xy 116.131105 -285.678076) (xy 116.092984 -285.646951) (xy 116.060349 -285.610114)
			(xy 116.034046 -285.568518) (xy 116.014755 -285.523242) (xy 116.002978 -285.475458) (xy 115.999018 -285.426404)
			(xy 115.670664 -285.426404) (xy 115.666492 -285.476747) (xy 115.654089 -285.52572) (xy 115.633795 -285.571984)
			(xy 115.606161 -285.614276) (xy 115.571944 -285.651443) (xy 115.532075 -285.68247) (xy 115.487643 -285.706512)
			(xy 115.439859 -285.722911) (xy 115.390028 -285.731222) (xy 115.364768 -285.731712) (xy 114.424714 -285.731712)
			(xy 114.399456 -285.731212) (xy 114.349628 -285.7229) (xy 114.301849 -285.706499) (xy 114.25742 -285.682457)
			(xy 114.217555 -285.651431) (xy 114.18334 -285.614265) (xy 114.15571 -285.571975) (xy 114.135417 -285.525714)
			(xy 114.123016 -285.476744) (xy 114.118844 -285.4264) (xy 113.789968 -285.4264) (xy 113.789968 -285.426404)
			(xy 113.789473 -285.451011) (xy 113.781578 -285.499588) (xy 113.765994 -285.546269) (xy 113.743123 -285.589846)
			(xy 113.713558 -285.62919) (xy 113.678065 -285.663282) (xy 113.637562 -285.691238) (xy 113.5931 -285.712336)
			(xy 113.545829 -285.726028) (xy 113.496974 -285.73196) (xy 113.447799 -285.729979) (xy 113.39958 -285.720135)
			(xy 113.353564 -285.702683) (xy 113.310943 -285.678076) (xy 113.272822 -285.646951) (xy 113.240187 -285.610114)
			(xy 113.213884 -285.568518) (xy 113.194593 -285.523242) (xy 113.182816 -285.475458) (xy 113.178856 -285.426404)
			(xy 110.97641 -285.426404) (xy 110.975915 -285.451011) (xy 110.96802 -285.499588) (xy 110.952436 -285.546269)
			(xy 110.929565 -285.589846) (xy 110.9 -285.62919) (xy 110.864507 -285.663282) (xy 110.824004 -285.691238)
			(xy 110.779542 -285.712336) (xy 110.732271 -285.726028) (xy 110.683416 -285.73196) (xy 110.634241 -285.729979)
			(xy 110.586022 -285.720135) (xy 110.540006 -285.702683) (xy 110.497385 -285.678076) (xy 110.459264 -285.646951)
			(xy 110.426629 -285.610114) (xy 110.400326 -285.568518) (xy 110.381035 -285.523242) (xy 110.369258 -285.475458)
			(xy 110.365298 -285.426404) (xy 110.036835 -285.426404) (xy 110.032665 -285.476734) (xy 110.020267 -285.525695)
			(xy 109.999981 -285.571948) (xy 109.972359 -285.614232) (xy 109.938155 -285.651393) (xy 109.898301 -285.682418)
			(xy 109.853885 -285.706461) (xy 109.806117 -285.722867) (xy 109.756301 -285.731187) (xy 109.731048 -285.731712)
			(xy 108.790994 -285.731712) (xy 108.765739 -285.731182) (xy 108.715919 -285.722868) (xy 108.668147 -285.706466)
			(xy 108.623725 -285.682426) (xy 108.583867 -285.651402) (xy 108.549658 -285.614241) (xy 108.522032 -285.571956)
			(xy 108.501743 -285.525701) (xy 108.489344 -285.476737) (xy 108.485173 -285.4264) (xy 108.156248 -285.4264)
			(xy 108.156248 -285.426404) (xy 108.155753 -285.451011) (xy 108.147858 -285.499588) (xy 108.132274 -285.546269)
			(xy 108.109403 -285.589846) (xy 108.079838 -285.62919) (xy 108.044345 -285.663282) (xy 108.003842 -285.691238)
			(xy 107.95938 -285.712336) (xy 107.912109 -285.726028) (xy 107.863254 -285.73196) (xy 107.814079 -285.729979)
			(xy 107.76586 -285.720135) (xy 107.719844 -285.702683) (xy 107.677223 -285.678076) (xy 107.639102 -285.646951)
			(xy 107.606467 -285.610114) (xy 107.580164 -285.568518) (xy 107.560873 -285.523242) (xy 107.549096 -285.475458)
			(xy 107.545136 -285.426404) (xy 107.216448 -285.426404) (xy 107.215953 -285.451011) (xy 107.208058 -285.499588)
			(xy 107.192474 -285.546269) (xy 107.169603 -285.589846) (xy 107.140038 -285.62919) (xy 107.104545 -285.663282)
			(xy 107.064042 -285.691238) (xy 107.01958 -285.712336) (xy 106.972309 -285.726028) (xy 106.923454 -285.73196)
			(xy 106.874279 -285.729979) (xy 106.82606 -285.720135) (xy 106.780044 -285.702683) (xy 106.737423 -285.678076)
			(xy 106.699302 -285.646951) (xy 106.666667 -285.610114) (xy 106.640364 -285.568518) (xy 106.621073 -285.523242)
			(xy 106.609296 -285.475458) (xy 106.605336 -285.426404) (xy 106.276394 -285.426404) (xy 106.275899 -285.451011)
			(xy 106.268004 -285.499588) (xy 106.25242 -285.546269) (xy 106.229549 -285.589846) (xy 106.199984 -285.62919)
			(xy 106.164491 -285.663282) (xy 106.123988 -285.691238) (xy 106.079526 -285.712336) (xy 106.032255 -285.726028)
			(xy 105.9834 -285.73196) (xy 105.934225 -285.729979) (xy 105.886006 -285.720135) (xy 105.83999 -285.702683)
			(xy 105.797369 -285.678076) (xy 105.759248 -285.646951) (xy 105.726613 -285.610114) (xy 105.70031 -285.568518)
			(xy 105.681019 -285.523242) (xy 105.669242 -285.475458) (xy 105.665282 -285.426404) (xy 105.33634 -285.426404)
			(xy 105.335845 -285.451011) (xy 105.32795 -285.499588) (xy 105.312366 -285.546269) (xy 105.289495 -285.589846)
			(xy 105.25993 -285.62919) (xy 105.224437 -285.663282) (xy 105.183934 -285.691238) (xy 105.139472 -285.712336)
			(xy 105.092201 -285.726028) (xy 105.043346 -285.73196) (xy 104.994171 -285.729979) (xy 104.945952 -285.720135)
			(xy 104.899936 -285.702683) (xy 104.857315 -285.678076) (xy 104.819194 -285.646951) (xy 104.786559 -285.610114)
			(xy 104.760256 -285.568518) (xy 104.740965 -285.523242) (xy 104.729188 -285.475458) (xy 104.725228 -285.426404)
			(xy 104.396286 -285.426404) (xy 104.395791 -285.451011) (xy 104.387896 -285.499588) (xy 104.372312 -285.546269)
			(xy 104.349441 -285.589846) (xy 104.319876 -285.62919) (xy 104.284383 -285.663282) (xy 104.24388 -285.691238)
			(xy 104.199418 -285.712336) (xy 104.152147 -285.726028) (xy 104.103292 -285.73196) (xy 104.054117 -285.729979)
			(xy 104.005898 -285.720135) (xy 103.959882 -285.702683) (xy 103.917261 -285.678076) (xy 103.87914 -285.646951)
			(xy 103.846505 -285.610114) (xy 103.820202 -285.568518) (xy 103.800911 -285.523242) (xy 103.789134 -285.475458)
			(xy 103.785174 -285.426404) (xy 103.456486 -285.426404) (xy 103.455991 -285.451011) (xy 103.448096 -285.499588)
			(xy 103.432512 -285.546269) (xy 103.409641 -285.589846) (xy 103.380076 -285.62919) (xy 103.344583 -285.663282)
			(xy 103.30408 -285.691238) (xy 103.259618 -285.712336) (xy 103.212347 -285.726028) (xy 103.163492 -285.73196)
			(xy 103.114317 -285.729979) (xy 103.066098 -285.720135) (xy 103.020082 -285.702683) (xy 102.977461 -285.678076)
			(xy 102.93934 -285.646951) (xy 102.906705 -285.610114) (xy 102.880402 -285.568518) (xy 102.861111 -285.523242)
			(xy 102.849334 -285.475458) (xy 102.845374 -285.426404) (xy 102.516432 -285.426404) (xy 102.515937 -285.451011)
			(xy 102.508042 -285.499588) (xy 102.492458 -285.546269) (xy 102.469587 -285.589846) (xy 102.440022 -285.62919)
			(xy 102.404529 -285.663282) (xy 102.364026 -285.691238) (xy 102.319564 -285.712336) (xy 102.272293 -285.726028)
			(xy 102.223438 -285.73196) (xy 102.174263 -285.729979) (xy 102.126044 -285.720135) (xy 102.080028 -285.702683)
			(xy 102.037407 -285.678076) (xy 101.999286 -285.646951) (xy 101.966651 -285.610114) (xy 101.940348 -285.568518)
			(xy 101.921057 -285.523242) (xy 101.90928 -285.475458) (xy 101.90532 -285.426404) (xy 101.576378 -285.426404)
			(xy 101.575883 -285.451011) (xy 101.567988 -285.499588) (xy 101.552404 -285.546269) (xy 101.529533 -285.589846)
			(xy 101.499968 -285.62919) (xy 101.464475 -285.663282) (xy 101.423972 -285.691238) (xy 101.37951 -285.712336)
			(xy 101.332239 -285.726028) (xy 101.283384 -285.73196) (xy 101.234209 -285.729979) (xy 101.18599 -285.720135)
			(xy 101.139974 -285.702683) (xy 101.097353 -285.678076) (xy 101.059232 -285.646951) (xy 101.026597 -285.610114)
			(xy 101.000294 -285.568518) (xy 100.981003 -285.523242) (xy 100.969226 -285.475458) (xy 100.965266 -285.426404)
			(xy 100.636324 -285.426404) (xy 100.635829 -285.451011) (xy 100.627934 -285.499588) (xy 100.61235 -285.546269)
			(xy 100.589479 -285.589846) (xy 100.559914 -285.62919) (xy 100.524421 -285.663282) (xy 100.483918 -285.691238)
			(xy 100.439456 -285.712336) (xy 100.392185 -285.726028) (xy 100.34333 -285.73196) (xy 100.294155 -285.729979)
			(xy 100.245936 -285.720135) (xy 100.19992 -285.702683) (xy 100.157299 -285.678076) (xy 100.119178 -285.646951)
			(xy 100.086543 -285.610114) (xy 100.06024 -285.568518) (xy 100.040949 -285.523242) (xy 100.029172 -285.475458)
			(xy 100.025212 -285.426404) (xy 99.696306 -285.426404) (xy 99.696756 -285.434707) (xy 99.691384 -285.484065)
			(xy 99.678097 -285.531903) (xy 99.657246 -285.576962) (xy 99.62938 -285.618053) (xy 99.595232 -285.654095)
			(xy 99.555703 -285.684138) (xy 99.511835 -285.707389) (xy 99.464783 -285.723237) (xy 99.415787 -285.731263)
			(xy 99.390962 -285.731712) (xy 99.3902 -285.731712) (xy 99.377823 -285.731584) (xy 99.353154 -285.729551)
			(xy 99.340924 -285.727648) (xy 99.332796 -285.726886) (xy 99.322788 -285.727374) (xy 99.304295 -285.735034)
			(xy 99.29014 -285.749186) (xy 99.282476 -285.767678) (xy 99.281996 -285.777686) (xy 99.294442 -285.80588)
			(xy 99.296657 -285.810514) (xy 99.302667 -285.818841) (xy 99.30638 -285.82239) (xy 99.322382 -285.838138)
			(xy 99.329782 -285.844978) (xy 99.348381 -285.852692) (xy 99.35845 -285.853124) (xy 113.012728 -285.853124)
			(xy 113.022795 -285.853553) (xy 113.04139 -285.861277) (xy 113.048796 -285.86811) (xy 113.647474 -286.466534)
			(xy 113.654873 -286.473376) (xy 113.673472 -286.481094) (xy 113.683542 -286.48152) (xy 114.39271 -286.48152)
			(xy 114.395758 -286.48152) (xy 114.424714 -286.480504) (xy 114.722656 -286.480504) (xy 114.751612 -286.48152)
			(xy 115.034822 -286.48152) (xy 115.03787 -286.48152) (xy 115.066826 -286.480504) (xy 115.364768 -286.480504)
			(xy 115.393724 -286.48152) (xy 115.453922 -286.48152) (xy 115.46548 -286.480908) (xy 115.486244 -286.47073)
			(xy 115.4938 -286.461962) (xy 115.54333 -286.390588) (xy 115.546684 -286.385468) (xy 115.551042 -286.374033)
			(xy 115.551966 -286.367982) (xy 115.55349 -286.356044) (xy 115.552728 -286.354266) (xy 115.548918 -286.344106)
			(xy 115.539829 -286.318178) (xy 115.529984 -286.264131) (xy 115.52936 -286.236664) (xy 115.52936 -286.232346)
			(xy 115.530197 -286.207311) (xy 115.539029 -286.158008) (xy 115.55579 -286.110807) (xy 115.580029 -286.066975)
			(xy 115.611098 -286.027687) (xy 115.648162 -285.993996) (xy 115.690228 -285.966806) (xy 115.736167 -285.946847)
			(xy 115.784748 -285.934653) (xy 115.834668 -285.930552) (xy 115.884588 -285.934653) (xy 115.933169 -285.946847)
			(xy 115.979108 -285.966806) (xy 116.021174 -285.993996) (xy 116.058238 -286.027687) (xy 116.089307 -286.066975)
			(xy 116.113546 -286.110807) (xy 116.130307 -286.158008) (xy 116.139139 -286.207311) (xy 116.139976 -286.232346)
			(xy 116.139976 -286.2364) (xy 116.468595 -286.2364) (xy 116.472771 -286.186015) (xy 116.485183 -286.137004)
			(xy 116.505492 -286.090704) (xy 116.533146 -286.048379) (xy 116.56739 -286.011184) (xy 116.607288 -285.980132)
			(xy 116.651754 -285.956071) (xy 116.699574 -285.939658) (xy 116.749443 -285.931339) (xy 116.774722 -285.930848)
			(xy 117.714776 -285.930848) (xy 117.740057 -285.931319) (xy 117.789929 -285.939638) (xy 117.837753 -285.956052)
			(xy 117.882222 -285.980115) (xy 117.922123 -286.011168) (xy 117.956369 -286.048366) (xy 117.984025 -286.090694)
			(xy 118.004336 -286.136997) (xy 118.016749 -286.186011) (xy 118.020925 -286.2364) (xy 118.020924 -286.23641)
			(xy 118.349026 -286.23641) (xy 118.352986 -286.187356) (xy 118.364763 -286.139572) (xy 118.384054 -286.094296)
			(xy 118.410357 -286.0527) (xy 118.442992 -286.015863) (xy 118.481113 -285.984738) (xy 118.523734 -285.960131)
			(xy 118.56975 -285.942679) (xy 118.617969 -285.932835) (xy 118.667144 -285.930854) (xy 118.715999 -285.936786)
			(xy 118.76327 -285.950478) (xy 118.807732 -285.971576) (xy 118.848235 -285.999532) (xy 118.883728 -286.033624)
			(xy 118.913293 -286.072968) (xy 118.936164 -286.116545) (xy 118.951748 -286.163226) (xy 118.959643 -286.211803)
			(xy 118.960138 -286.2364) (xy 119.288495 -286.2364) (xy 119.292671 -286.186014) (xy 119.305083 -286.137002)
			(xy 119.325394 -286.090702) (xy 119.353048 -286.048377) (xy 119.387293 -286.011181) (xy 119.427193 -285.980129)
			(xy 119.47166 -285.956069) (xy 119.51948 -285.939656) (xy 119.56935 -285.931339) (xy 119.59463 -285.930848)
			(xy 120.534684 -285.930848) (xy 120.559964 -285.93132) (xy 120.609836 -285.93964) (xy 120.657658 -285.956055)
			(xy 120.702126 -285.980117) (xy 120.742026 -286.011171) (xy 120.776271 -286.048369) (xy 120.803926 -286.090696)
			(xy 120.824237 -286.136998) (xy 120.836649 -286.186012) (xy 120.840825 -286.2364) (xy 120.840824 -286.23641)
			(xy 121.168934 -286.23641) (xy 121.172894 -286.187356) (xy 121.184671 -286.139572) (xy 121.203962 -286.094296)
			(xy 121.230265 -286.0527) (xy 121.2629 -286.015863) (xy 121.301021 -285.984738) (xy 121.343642 -285.960131)
			(xy 121.389658 -285.942679) (xy 121.437877 -285.932835) (xy 121.487052 -285.930854) (xy 121.535907 -285.936786)
			(xy 121.583178 -285.950478) (xy 121.62764 -285.971576) (xy 121.668143 -285.999532) (xy 121.703636 -286.033624)
			(xy 121.733201 -286.072968) (xy 121.756072 -286.116545) (xy 121.771656 -286.163226) (xy 121.779551 -286.211803)
			(xy 121.780046 -286.2364) (xy 122.108724 -286.2364) (xy 122.112899 -286.186022) (xy 122.125308 -286.137019)
			(xy 122.145613 -286.090726) (xy 122.173261 -286.048407) (xy 122.207498 -286.011216) (xy 122.247388 -285.980167)
			(xy 122.291845 -285.956107) (xy 122.339656 -285.939692) (xy 122.389517 -285.931371) (xy 122.414792 -285.930848)
			(xy 123.354846 -285.930848) (xy 123.380121 -285.931354) (xy 123.42998 -285.93968) (xy 123.477788 -285.9561)
			(xy 123.522243 -285.980163) (xy 123.562131 -286.011215) (xy 123.596364 -286.048408) (xy 123.62401 -286.090727)
			(xy 123.644314 -286.13702) (xy 123.656722 -286.186023) (xy 123.660896 -286.2364) (xy 123.656722 -286.286777)
			(xy 123.644314 -286.33578) (xy 123.62401 -286.382073) (xy 123.596364 -286.424392) (xy 123.562131 -286.461585)
			(xy 123.522243 -286.492637) (xy 123.477788 -286.5167) (xy 123.42998 -286.53312) (xy 123.380121 -286.541446)
			(xy 123.354846 -286.541972) (xy 122.414792 -286.541972) (xy 122.389517 -286.541429) (xy 122.339656 -286.533108)
			(xy 122.291845 -286.516693) (xy 122.247388 -286.492633) (xy 122.207498 -286.461584) (xy 122.173261 -286.424393)
			(xy 122.145613 -286.382074) (xy 122.125308 -286.335781) (xy 122.112899 -286.286778) (xy 122.108724 -286.2364)
			(xy 121.780046 -286.2364) (xy 121.780046 -286.23641) (xy 121.779551 -286.261017) (xy 121.771656 -286.309594)
			(xy 121.756072 -286.356275) (xy 121.733201 -286.399852) (xy 121.703636 -286.439196) (xy 121.668143 -286.473288)
			(xy 121.62764 -286.501244) (xy 121.583178 -286.522342) (xy 121.535907 -286.536034) (xy 121.487052 -286.541966)
			(xy 121.437877 -286.539985) (xy 121.389658 -286.530141) (xy 121.343642 -286.512689) (xy 121.301021 -286.488082)
			(xy 121.2629 -286.456957) (xy 121.230265 -286.42012) (xy 121.203962 -286.378524) (xy 121.184671 -286.333248)
			(xy 121.172894 -286.285464) (xy 121.168934 -286.23641) (xy 120.840824 -286.23641) (xy 120.836649 -286.286788)
			(xy 120.824237 -286.335802) (xy 120.803926 -286.382104) (xy 120.776271 -286.424431) (xy 120.742026 -286.461629)
			(xy 120.702126 -286.492683) (xy 120.657658 -286.516745) (xy 120.609836 -286.53316) (xy 120.559964 -286.54148)
			(xy 120.534684 -286.541972) (xy 119.59463 -286.541972) (xy 119.56935 -286.541461) (xy 119.51948 -286.533144)
			(xy 119.47166 -286.516731) (xy 119.427193 -286.492671) (xy 119.387293 -286.461619) (xy 119.353048 -286.424423)
			(xy 119.325394 -286.382098) (xy 119.305083 -286.335798) (xy 119.292671 -286.286786) (xy 119.288495 -286.2364)
			(xy 118.960138 -286.2364) (xy 118.960138 -286.23641) (xy 118.959643 -286.261017) (xy 118.951748 -286.309594)
			(xy 118.936164 -286.356275) (xy 118.913293 -286.399852) (xy 118.883728 -286.439196) (xy 118.848235 -286.473288)
			(xy 118.807732 -286.501244) (xy 118.76327 -286.522342) (xy 118.715999 -286.536034) (xy 118.667144 -286.541966)
			(xy 118.617969 -286.539985) (xy 118.56975 -286.530141) (xy 118.523734 -286.512689) (xy 118.481113 -286.488082)
			(xy 118.442992 -286.456957) (xy 118.410357 -286.42012) (xy 118.384054 -286.378524) (xy 118.364763 -286.333248)
			(xy 118.352986 -286.285464) (xy 118.349026 -286.23641) (xy 118.020924 -286.23641) (xy 118.016749 -286.286789)
			(xy 118.004336 -286.335803) (xy 117.984025 -286.382106) (xy 117.956369 -286.424434) (xy 117.922123 -286.461632)
			(xy 117.882222 -286.492685) (xy 117.837753 -286.516748) (xy 117.789929 -286.533162) (xy 117.740057 -286.541481)
			(xy 117.714776 -286.541972) (xy 116.774722 -286.541972) (xy 116.749443 -286.541461) (xy 116.699574 -286.533142)
			(xy 116.651754 -286.516729) (xy 116.607288 -286.492668) (xy 116.56739 -286.461616) (xy 116.533146 -286.424421)
			(xy 116.505492 -286.382096) (xy 116.485183 -286.335796) (xy 116.472771 -286.286785) (xy 116.468595 -286.2364)
			(xy 116.139976 -286.2364) (xy 116.139976 -286.236664) (xy 116.139392 -286.264135) (xy 116.129545 -286.318188)
			(xy 116.120418 -286.344106) (xy 116.116608 -286.354266) (xy 116.115846 -286.356044) (xy 116.11737 -286.367982)
			(xy 116.118314 -286.374028) (xy 116.122668 -286.38546) (xy 116.126006 -286.390588) (xy 116.175536 -286.461962)
			(xy 116.183078 -286.47075) (xy 116.203848 -286.480935) (xy 116.215414 -286.48152) (xy 116.22532 -286.48152)
			(xy 116.965222 -287.221422) (xy 116.970721 -287.226409) (xy 116.983888 -287.233251) (xy 116.99113 -287.234884)
			(xy 117.000782 -287.2359) (xy 118.727474 -287.2359) (xy 118.738894 -287.235272) (xy 118.759479 -287.225379)
			(xy 118.767098 -287.21685) (xy 118.816628 -287.155128) (xy 118.82011 -287.150532) (xy 118.825108 -287.140142)
			(xy 118.826534 -287.134554) (xy 118.829074 -287.123378) (xy 118.826788 -287.112202) (xy 118.823384 -287.095903)
			(xy 118.819692 -287.06281) (xy 118.819422 -287.046162) (xy 118.819944 -287.020907) (xy 118.828257 -286.971085)
			(xy 118.844658 -286.923311) (xy 118.868699 -286.878888) (xy 118.899723 -286.839028) (xy 118.936885 -286.804818)
			(xy 118.979171 -286.777192) (xy 119.025427 -286.756902) (xy 119.074392 -286.744502) (xy 119.12473 -286.740331)
			(xy 119.175068 -286.744502) (xy 119.224033 -286.756902) (xy 119.270289 -286.777192) (xy 119.312575 -286.804818)
			(xy 119.349737 -286.839028) (xy 119.380761 -286.878888) (xy 119.404802 -286.923311) (xy 119.421203 -286.971085)
			(xy 119.429516 -287.020907) (xy 119.430038 -287.046162) (xy 119.429792 -287.062812) (xy 119.426105 -287.095908)
			(xy 119.422672 -287.112202) (xy 119.420386 -287.123378) (xy 119.422926 -287.134554) (xy 119.424345 -287.140144)
			(xy 119.429348 -287.150532) (xy 119.432832 -287.155128) (xy 119.482362 -287.21685) (xy 119.489991 -287.225369)
			(xy 119.510568 -287.235276) (xy 119.521986 -287.2359) (xy 121.547382 -287.2359) (xy 121.558801 -287.23527)
			(xy 121.579384 -287.225376) (xy 121.587006 -287.21685) (xy 121.636536 -287.155128) (xy 121.640018 -287.150531)
			(xy 121.645014 -287.140141) (xy 121.646442 -287.134554) (xy 121.648982 -287.123378) (xy 121.646696 -287.112202)
			(xy 121.643292 -287.095903) (xy 121.6396 -287.06281) (xy 121.63933 -287.046162) (xy 121.639852 -287.020907)
			(xy 121.648165 -286.971085) (xy 121.664566 -286.923311) (xy 121.688607 -286.878888) (xy 121.719631 -286.839028)
			(xy 121.756793 -286.804818) (xy 121.799079 -286.777192) (xy 121.845335 -286.756902) (xy 121.8943 -286.744502)
			(xy 121.944638 -286.740331) (xy 121.994976 -286.744502) (xy 122.043941 -286.756902) (xy 122.090197 -286.777192)
			(xy 122.132483 -286.804818) (xy 122.169645 -286.839028) (xy 122.200669 -286.878888) (xy 122.22471 -286.923311)
			(xy 122.241111 -286.971085) (xy 122.249424 -287.020907) (xy 122.249946 -287.046162) (xy 122.2497 -287.062812)
			(xy 122.246011 -287.095908) (xy 122.24258 -287.112202) (xy 122.240294 -287.123378) (xy 122.242834 -287.134554)
			(xy 122.24425 -287.140145) (xy 122.249246 -287.150539) (xy 122.25274 -287.155128) (xy 122.30227 -287.21685)
			(xy 122.3099 -287.225368) (xy 122.330477 -287.235272) (xy 122.341894 -287.2359) (xy 124.134118 -287.2359)
			(xy 124.14377 -287.234884) (xy 124.151013 -287.233255) (xy 124.16418 -287.226411) (xy 124.169678 -287.221422)
			(xy 124.504196 -286.886904) (xy 124.50699 -286.882332) (xy 124.522484 -286.860234) (xy 124.533325 -286.846594)
			(xy 124.557643 -286.82164) (xy 124.570998 -286.81045) (xy 124.571506 -286.809942) (xy 124.582682 -286.801052)
			(xy 124.591479 -286.793515) (xy 124.601675 -286.772743) (xy 124.60224 -286.761174) (xy 124.60224 -286.587184)
			(xy 124.601864 -286.578619) (xy 124.596147 -286.562467) (xy 124.58545 -286.549082) (xy 124.578364 -286.544258)
			(xy 124.516642 -286.508952) (xy 124.499878 -286.4993) (xy 124.494062 -286.496201) (xy 124.48132 -286.492851)
			(xy 124.474732 -286.492696) (xy 124.461016 -286.492696) (xy 124.45746 -286.494982) (xy 124.449332 -286.499808)
			(xy 124.425861 -286.512918) (xy 124.375444 -286.531572) (xy 124.322539 -286.541105) (xy 124.295662 -286.541718)
			(xy 124.28855 -286.541718) (xy 124.263621 -286.540729) (xy 124.214569 -286.531647) (xy 124.167644 -286.514713)
			(xy 124.124096 -286.490377) (xy 124.085083 -286.459286) (xy 124.051642 -286.422268) (xy 124.024662 -286.380307)
			(xy 124.004861 -286.334519) (xy 123.992766 -286.286121) (xy 123.988699 -286.2364) (xy 123.992766 -286.18668)
			(xy 124.004861 -286.138282) (xy 124.024662 -286.092493) (xy 124.051642 -286.050532) (xy 124.085083 -286.013514)
			(xy 124.124096 -285.982423) (xy 124.167644 -285.958087) (xy 124.214568 -285.941153) (xy 124.263621 -285.932071)
			(xy 124.28855 -285.931102) (xy 124.295154 -285.931102) (xy 124.322115 -285.931696) (xy 124.375195 -285.941199)
			(xy 124.425785 -285.959866) (xy 124.449332 -285.973012) (xy 124.45746 -285.977838) (xy 124.461016 -285.980124)
			(xy 124.474732 -285.980124) (xy 124.481311 -285.97991) (xy 124.494037 -285.976557) (xy 124.499878 -285.97352)
			(xy 124.516642 -285.963868) (xy 124.578364 -285.928562) (xy 124.585473 -285.923754) (xy 124.596219 -285.910387)
			(xy 124.601921 -285.894211) (xy 124.60224 -285.885636) (xy 124.60224 -285.836868) (xy 124.602361 -285.831914)
			(xy 124.604284 -285.822194) (xy 124.60605 -285.817564) (xy 124.60986 -285.80842) (xy 124.610114 -285.807912)
			(xy 124.602748 -285.70809) (xy 124.602206 -285.702704) (xy 124.599138 -285.692325) (xy 124.596652 -285.687516)
			(xy 124.591572 -285.678118) (xy 124.582428 -285.67126) (xy 124.563695 -285.656751) (xy 124.530525 -285.622918)
			(xy 124.502978 -285.584368) (xy 124.481718 -285.542025) (xy 124.467255 -285.496906) (xy 124.459934 -285.450094)
			(xy 124.459492 -285.426404) (xy 124.459938 -285.402411) (xy 124.467444 -285.355015) (xy 124.482272 -285.309376)
			(xy 124.504057 -285.26662) (xy 124.532263 -285.227798) (xy 124.566194 -285.193866) (xy 124.605016 -285.16566)
			(xy 124.647773 -285.143874) (xy 124.693411 -285.129045) (xy 124.740807 -285.121538) (xy 124.7648 -285.121096)
			(xy 124.790524 -285.121629) (xy 124.841244 -285.130255) (xy 124.8898 -285.147263) (xy 124.934816 -285.172172)
			(xy 124.975019 -285.204277) (xy 125.00927 -285.242667) (xy 125.036599 -285.286257) (xy 125.056232 -285.333812)
			(xy 125.067613 -285.383986) (xy 125.0696 -285.40964) (xy 125.0696 -285.410402) (xy 125.070611 -285.419876)
			(xy 125.078691 -285.437115) (xy 125.085348 -285.44393) (xy 125.092206 -285.450788) (xy 125.11024 -285.4579)
			(xy 125.349508 -285.4579) (xy 125.35921 -285.457479) (xy 125.37724 -285.45031) (xy 125.38456 -285.44393)
			(xy 125.391418 -285.437326) (xy 125.399292 -285.420054) (xy 125.400054 -285.409894) (xy 125.401848 -285.385578)
			(xy 125.412188 -285.337932) (xy 125.429969 -285.292536) (xy 125.454738 -285.250542) (xy 125.485867 -285.213018)
			(xy 125.522565 -285.180919) (xy 125.563897 -285.155061) (xy 125.608813 -285.1361) (xy 125.656173 -285.124518)
			(xy 125.70477 -285.120611) (xy 125.753372 -285.124477) (xy 125.800741 -285.136018) (xy 125.845673 -285.154941)
			(xy 125.887027 -285.180765) (xy 125.923752 -285.212833) (xy 125.954913 -285.25033) (xy 125.979718 -285.292303)
			(xy 125.997537 -285.337684) (xy 126.007917 -285.385321) (xy 126.009654 -285.40964) (xy 126.009654 -285.410402)
			(xy 126.010667 -285.419874) (xy 126.018753 -285.437108) (xy 126.025402 -285.44393) (xy 126.03226 -285.450788)
			(xy 126.050294 -285.4579) (xy 126.289308 -285.4579) (xy 126.29901 -285.457479) (xy 126.31704 -285.45031)
			(xy 126.32436 -285.44393) (xy 126.331218 -285.437326) (xy 126.339092 -285.420054) (xy 126.339854 -285.409894)
			(xy 126.341785 -285.384225) (xy 126.35316 -285.334026) (xy 126.37279 -285.286444) (xy 126.400118 -285.242826)
			(xy 126.434372 -285.204407) (xy 126.474581 -285.172274) (xy 126.519608 -285.147336) (xy 126.568179 -285.1303)
			(xy 126.618918 -285.121647) (xy 126.644654 -285.121096) (xy 126.644908 -285.121096) (xy 126.668161 -285.121527)
			(xy 126.714129 -285.128578) (xy 126.758492 -285.14253) (xy 126.800222 -285.163059) (xy 126.838348 -285.189689)
			(xy 126.855474 -285.205424) (xy 126.863094 -285.212536) (xy 126.871476 -285.215838) (xy 126.876103 -285.217614)
			(xy 126.885825 -285.219539) (xy 126.89078 -285.219648) (xy 126.964694 -285.218886) (xy 126.972698 -285.218033)
			(xy 126.987588 -285.211939) (xy 126.993904 -285.206948) (xy 126.995428 -285.205678) (xy 126.997206 -285.204154)
			(xy 126.998222 -285.203138) (xy 127.003204 -285.197636) (xy 127.010036 -285.184468) (xy 127.011684 -285.17723)
			(xy 127.0127 -285.167578) (xy 127.0127 -284.937962) (xy 127.01245 -284.930782) (xy 127.008448 -284.916989)
			(xy 127.004826 -284.910784) (xy 127.001016 -284.904942) (xy 126.990602 -284.895544) (xy 126.983744 -284.892242)
			(xy 126.961751 -284.881223) (xy 126.921303 -284.853233) (xy 126.885862 -284.819124) (xy 126.856343 -284.779777)
			(xy 126.83351 -284.736209) (xy 126.817952 -284.689546) (xy 126.810072 -284.640993) (xy 126.810072 -284.591805)
			(xy 126.817953 -284.543252) (xy 126.833511 -284.496589) (xy 126.856344 -284.453021) (xy 126.885863 -284.413675)
			(xy 126.921304 -284.379566) (xy 126.961752 -284.351576) (xy 126.983744 -284.340554) (xy 126.990166 -284.337254)
			(xy 127.000991 -284.32771) (xy 127.00508 -284.321758) (xy 127.00889 -284.315916) (xy 127.0127 -284.3022)
			(xy 127.0127 -283.31795) (xy 127.012448 -283.31077) (xy 127.008444 -283.29698) (xy 127.004826 -283.290772)
			(xy 127.001016 -283.28493) (xy 126.990602 -283.275532) (xy 126.983744 -283.27223) (xy 126.961752 -283.261211)
			(xy 126.921306 -283.233221) (xy 126.885866 -283.199113) (xy 126.85635 -283.159767) (xy 126.833518 -283.1162)
			(xy 126.817962 -283.069539) (xy 126.810082 -283.020987) (xy 126.810083 -282.971801) (xy 126.817964 -282.92325)
			(xy 126.833523 -282.876588) (xy 126.856356 -282.833023) (xy 126.885874 -282.793678) (xy 126.921315 -282.759571)
			(xy 126.961762 -282.731583) (xy 126.983744 -282.720542) (xy 126.990166 -282.717242) (xy 127.000989 -282.707696)
			(xy 127.00508 -282.701746) (xy 127.00889 -282.695904) (xy 127.0127 -282.682188) (xy 127.0127 -282.493974)
			(xy 127.012265 -282.484264) (xy 127.005037 -282.466239) (xy 126.991626 -282.452193) (xy 126.982982 -282.447746)
			(xy 126.898654 -282.409138) (xy 126.89197 -282.406364) (xy 126.877654 -282.404294) (xy 126.87046 -282.405074)
			(xy 126.863602 -282.40609) (xy 126.85014 -282.412186) (xy 126.844552 -282.417012) (xy 126.823565 -282.434432)
			(xy 126.776681 -282.462291) (xy 126.725591 -282.481369) (xy 126.671922 -282.491059) (xy 126.644654 -282.491688)
			(xy 126.619403 -282.491163) (xy 126.56959 -282.482844) (xy 126.521826 -282.46644) (xy 126.477413 -282.442399)
			(xy 126.437562 -282.411376) (xy 126.40336 -282.374218) (xy 126.37574 -282.331937) (xy 126.355456 -282.285687)
			(xy 126.343059 -282.23673) (xy 126.338889 -282.1864) (xy 126.343059 -282.13607) (xy 126.355456 -282.087113)
			(xy 126.37574 -282.040863) (xy 126.40336 -281.998582) (xy 126.437562 -281.961424) (xy 126.477413 -281.930401)
			(xy 126.521826 -281.90636) (xy 126.56959 -281.889956) (xy 126.619403 -281.881637) (xy 126.644654 -281.881072)
			(xy 126.657417 -281.881211) (xy 126.682851 -281.883375) (xy 126.695454 -281.88539) (xy 126.695454 -281.885136)
			(xy 126.718775 -281.889524) (xy 126.763784 -281.904557) (xy 126.805925 -281.926372) (xy 126.844183 -281.954445)
			(xy 126.877637 -281.988099) (xy 126.905482 -282.026523) (xy 126.916688 -282.047442) (xy 126.916688 -282.047696)
			(xy 126.916942 -282.04795) (xy 126.920276 -282.053919) (xy 126.929548 -282.06396) (xy 126.93523 -282.067762)
			(xy 126.947422 -282.075382) (xy 126.9619 -282.075382) (xy 126.97192 -282.074962) (xy 126.990434 -282.067292)
			(xy 127.004602 -282.053119) (xy 127.012266 -282.034602) (xy 127.0127 -282.024582) (xy 127.0127 -281.973782)
			(xy 127.012536 -281.967771) (xy 127.009719 -281.956086) (xy 127.007112 -281.950668) (xy 127.005272 -281.947194)
			(xy 127.000678 -281.940816) (xy 126.997968 -281.937968) (xy 126.58725 -281.52725) (xy 126.57879 -281.519694)
			(xy 126.557427 -281.512159) (xy 126.546102 -281.512772) (xy 126.467616 -281.520646) (xy 126.461984 -281.521366)
			(xy 126.451212 -281.524946) (xy 126.44628 -281.527758) (xy 126.441962 -281.530552) (xy 126.433834 -281.538426)
			(xy 126.430532 -281.543506) (xy 126.416282 -281.564359) (xy 126.382078 -281.601517) (xy 126.34223 -281.632545)
			(xy 126.297824 -281.656601) (xy 126.250067 -281.673029) (xy 126.200259 -281.681382) (xy 126.175008 -281.681936)
			(xy 125.2347 -281.681936) (xy 125.209426 -281.681414) (xy 125.159567 -281.673094) (xy 125.111757 -281.656681)
			(xy 125.067301 -281.632623) (xy 125.027412 -281.601575) (xy 124.993176 -281.564386) (xy 124.965529 -281.522068)
			(xy 124.945224 -281.475777) (xy 124.932815 -281.426776) (xy 124.928641 -281.3764) (xy 124.932815 -281.326024)
			(xy 124.945224 -281.277023) (xy 124.965529 -281.230732) (xy 124.993176 -281.188414) (xy 125.027412 -281.151225)
			(xy 125.067301 -281.120177) (xy 125.111757 -281.096119) (xy 125.159567 -281.079706) (xy 125.209426 -281.071386)
			(xy 125.2347 -281.070812) (xy 126.008638 -281.070812) (xy 126.017735 -281.070395) (xy 126.034754 -281.063958)
			(xy 126.048452 -281.051979) (xy 126.053088 -281.044142) (xy 126.05512 -281.039062) (xy 126.057842 -281.03203)
			(xy 126.059393 -281.017038) (xy 126.058168 -281.009598) (xy 126.056898 -281.002994) (xy 126.049786 -280.989786)
			(xy 125.979428 -280.919428) (xy 125.979428 -280.906728) (xy 125.883416 -280.845768) (xy 125.877824 -280.842487)
			(xy 125.865487 -280.838512) (xy 125.859032 -280.837894) (xy 125.846586 -280.837132) (xy 125.834648 -280.84272)
			(xy 125.814248 -280.851871) (xy 125.771441 -280.864771) (xy 125.727209 -280.871288) (xy 125.704854 -280.871676)
			(xy 125.679604 -280.871151) (xy 125.629793 -280.862832) (xy 125.582031 -280.846429) (xy 125.537619 -280.822389)
			(xy 125.49777 -280.791367) (xy 125.46357 -280.75421) (xy 125.435951 -280.711931) (xy 125.415667 -280.665684)
			(xy 125.403271 -280.616728) (xy 125.399101 -280.5664) (xy 125.403271 -280.516072) (xy 125.415667 -280.467116)
			(xy 125.435951 -280.420869) (xy 125.46357 -280.37859) (xy 125.49777 -280.341433) (xy 125.537619 -280.310411)
			(xy 125.582031 -280.286371) (xy 125.629793 -280.269968) (xy 125.679604 -280.261649) (xy 125.704854 -280.26106)
			(xy 125.717617 -280.261199) (xy 125.743051 -280.263363) (xy 125.755654 -280.265378) (xy 125.755654 -280.265124)
			(xy 125.776909 -280.269148) (xy 125.818084 -280.282412) (xy 125.837696 -280.29154) (xy 125.846586 -280.295604)
			(xy 125.859032 -280.294842) (xy 125.865499 -280.294292) (xy 125.877844 -280.290298) (xy 125.883416 -280.286968)
			(xy 125.921516 -280.262838) (xy 125.95733 -280.239978) (xy 125.960886 -280.237438) (xy 125.968461 -280.230596)
			(xy 125.977895 -280.212513) (xy 125.979174 -280.202386) (xy 125.979428 -280.198068) (xy 125.979428 -280.013918)
			(xy 125.979174 -280.008584) (xy 125.977871 -279.999685) (xy 125.969924 -279.983563) (xy 125.96368 -279.977088)
			(xy 125.946177 -279.959681) (xy 125.916468 -279.92026) (xy 125.893484 -279.876575) (xy 125.877823 -279.829764)
			(xy 125.869892 -279.781043) (xy 125.869446 -279.756362) (xy 125.869446 -279.756108) (xy 125.869819 -279.734473)
			(xy 125.875934 -279.691637) (xy 125.881638 -279.670764) (xy 125.889701 -279.645148) (xy 125.913522 -279.597021)
			(xy 125.945383 -279.553795) (xy 125.964442 -279.534874) (xy 125.979428 -279.521666) (xy 125.986794 -279.51557)
			(xy 125.991366 -279.507188) (xy 125.993536 -279.503075) (xy 125.996476 -279.494254) (xy 125.997208 -279.489662)
			(xy 126.006606 -279.423368) (xy 126.007146 -279.418731) (xy 126.006762 -279.409404) (xy 126.005844 -279.404826)
			(xy 126.003558 -279.395428) (xy 125.998224 -279.387808) (xy 125.977106 -279.356042) (xy 125.940446 -279.289141)
			(xy 125.910465 -279.218994) (xy 125.887449 -279.146263) (xy 125.871614 -279.071638) (xy 125.863111 -278.995828)
			(xy 125.86202 -278.919549) (xy 125.868352 -278.843527) (xy 125.882047 -278.76848) (xy 125.902975 -278.695121)
			(xy 125.930938 -278.624145) (xy 125.947932 -278.589994) (xy 125.947932 -278.589486) (xy 125.948186 -278.589232)
			(xy 125.950839 -278.583433) (xy 125.95353 -278.570972) (xy 125.95352 -278.564594) (xy 125.953012 -278.55164)
			(xy 125.899926 -278.464518) (xy 125.892456 -278.454501) (xy 125.87049 -278.442647) (xy 125.858016 -278.441912)
			(xy 125.2347 -278.441912) (xy 125.20942 -278.44139) (xy 125.159548 -278.433068) (xy 125.111727 -278.416651)
			(xy 125.06726 -278.392586) (xy 125.02736 -278.361531) (xy 124.993116 -278.324332) (xy 124.965462 -278.282004)
			(xy 124.945152 -278.235702) (xy 124.93274 -278.186688) (xy 124.928565 -278.1363) (xy 124.93274 -278.085912)
			(xy 124.945152 -278.036898) (xy 124.965462 -277.990596) (xy 124.993116 -277.948268) (xy 125.02736 -277.911069)
			(xy 125.06726 -277.880014) (xy 125.111727 -277.855949) (xy 125.159548 -277.839532) (xy 125.20942 -277.83121)
			(xy 125.2347 -277.830788) (xy 126.174754 -277.830788) (xy 126.20121 -277.831397) (xy 126.253318 -277.840598)
			(xy 126.278386 -277.849076) (xy 126.282704 -277.8506) (xy 126.299722 -277.853648) (xy 126.309882 -277.853648)
			(xy 126.329948 -277.84552) (xy 126.381256 -277.824692) (xy 126.385732 -277.822795) (xy 126.393919 -277.817553)
			(xy 126.397512 -277.814278) (xy 126.403608 -277.808436) (xy 126.407926 -277.799546) (xy 126.43231 -277.752556)
			(xy 126.440711 -277.737805) (xy 126.458623 -277.708965) (xy 126.468124 -277.694898) (xy 126.47214 -277.688544)
			(xy 126.476644 -277.674212) (xy 126.477014 -277.666704) (xy 126.476506 -277.659084) (xy 126.467108 -277.59279)
			(xy 126.466352 -277.588204) (xy 126.463412 -277.579387) (xy 126.461266 -277.575264) (xy 126.456948 -277.56739)
			(xy 126.449328 -277.56104) (xy 126.429095 -277.543476) (xy 126.394528 -277.502545) (xy 126.367636 -277.456208)
			(xy 126.349246 -277.405889) (xy 126.339921 -277.353132) (xy 126.339346 -277.326344) (xy 126.339813 -277.302349)
			(xy 126.347314 -277.254949) (xy 126.362137 -277.209307) (xy 126.383917 -277.166545) (xy 126.412119 -277.127716)
			(xy 126.446048 -277.093777) (xy 126.484868 -277.065564) (xy 126.527623 -277.043771) (xy 126.573262 -277.028935)
			(xy 126.620659 -277.02142) (xy 126.644654 -277.021036) (xy 126.645162 -277.021036) (xy 126.666075 -277.021377)
			(xy 126.707509 -277.027082) (xy 126.747776 -277.038391) (xy 126.767082 -277.046436) (xy 126.771654 -277.048468)
			(xy 126.790196 -277.052786) (xy 126.80442 -277.052024) (xy 126.83109 -277.042118) (xy 126.834795 -277.04051)
			(xy 126.841684 -277.036298) (xy 126.844806 -277.033736) (xy 126.867412 -277.0124) (xy 126.871476 -277.003002)
			(xy 126.872492 -277.00097) (xy 126.877064 -276.99081) (xy 126.877064 -276.732746) (xy 126.876975 -276.728802)
			(xy 126.875696 -276.721019) (xy 126.874524 -276.717252) (xy 126.867666 -276.695916) (xy 126.863348 -276.689566)
			(xy 126.848874 -276.667564) (xy 126.826892 -276.61971) (xy 126.813436 -276.568797) (xy 126.808902 -276.516331)
			(xy 126.813425 -276.463865) (xy 126.826871 -276.412949) (xy 126.848843 -276.365091) (xy 126.863348 -276.34311)
			(xy 126.867666 -276.33676) (xy 126.874524 -276.315424) (xy 126.87567 -276.311651) (xy 126.876945 -276.303871)
			(xy 126.877064 -276.29993) (xy 126.877064 -275.112734) (xy 126.876974 -275.10879) (xy 126.875693 -275.101007)
			(xy 126.874524 -275.09724) (xy 126.867666 -275.075904) (xy 126.863348 -275.069554) (xy 126.848875 -275.047552)
			(xy 126.826895 -274.999698) (xy 126.813441 -274.948786) (xy 126.808909 -274.896321) (xy 126.813434 -274.843856)
			(xy 126.826881 -274.792942) (xy 126.848854 -274.745085) (xy 126.863348 -274.723098) (xy 126.867666 -274.716748)
			(xy 126.874524 -274.695412) (xy 126.875669 -274.691639) (xy 126.876943 -274.683859) (xy 126.877064 -274.679918)
			(xy 126.877064 -274.46986) (xy 126.876363 -274.457703) (xy 126.865216 -274.436093) (xy 126.855728 -274.428458)
			(xy 126.790196 -274.381722) (xy 126.785088 -274.378269) (xy 126.773661 -274.373651) (xy 126.76759 -274.372578)
			(xy 126.755652 -274.371054) (xy 126.75489 -274.371308) (xy 126.743968 -274.375118) (xy 126.720907 -274.382536)
			(xy 126.673183 -274.39083) (xy 126.648972 -274.391628) (xy 126.640844 -274.391628) (xy 126.615796 -274.390807)
			(xy 126.566463 -274.382001) (xy 126.51923 -274.365258) (xy 126.475365 -274.341027) (xy 126.436045 -274.309958)
			(xy 126.402326 -274.272887) (xy 126.375112 -274.230807) (xy 126.355134 -274.184848) (xy 126.342929 -274.136245)
			(xy 126.338824 -274.0863) (xy 126.342929 -274.036356) (xy 126.355134 -273.987752) (xy 126.375112 -273.941793)
			(xy 126.402325 -273.899714) (xy 126.436044 -273.862642) (xy 126.475364 -273.831574) (xy 126.51923 -273.807343)
			(xy 126.566462 -273.790599) (xy 126.615795 -273.781793) (xy 126.640844 -273.781012) (xy 126.645162 -273.781012)
			(xy 126.670334 -273.781547) (xy 126.719991 -273.789841) (xy 126.743968 -273.797522) (xy 126.75489 -273.801332)
			(xy 126.755652 -273.801586) (xy 126.76759 -273.800062) (xy 126.77367 -273.799025) (xy 126.785097 -273.79439)
			(xy 126.790196 -273.790918) (xy 126.855728 -273.744182) (xy 126.865237 -273.736566) (xy 126.876388 -273.714944)
			(xy 126.877064 -273.70278) (xy 126.877064 -273.492722) (xy 126.876973 -273.488779) (xy 126.875691 -273.480996)
			(xy 126.874524 -273.477228) (xy 126.867666 -273.455892) (xy 126.863348 -273.449542) (xy 126.848876 -273.42754)
			(xy 126.826899 -273.379686) (xy 126.813446 -273.328775) (xy 126.808916 -273.276312) (xy 126.813442 -273.223848)
			(xy 126.826891 -273.172935) (xy 126.848864 -273.12508) (xy 126.863348 -273.103086) (xy 126.867666 -273.096736)
			(xy 126.874524 -273.0754) (xy 126.875668 -273.071627) (xy 126.87694 -273.063847) (xy 126.877064 -273.059906)
			(xy 126.877064 -271.87271) (xy 126.87698 -271.868765) (xy 126.875711 -271.860979) (xy 126.874524 -271.857216)
			(xy 126.867666 -271.83588) (xy 126.863348 -271.82953) (xy 126.848877 -271.807528) (xy 126.826902 -271.759675)
			(xy 126.813451 -271.708764) (xy 126.808922 -271.656302) (xy 126.81345 -271.603839) (xy 126.8269 -271.552928)
			(xy 126.848875 -271.505075) (xy 126.863348 -271.483074) (xy 126.867666 -271.476724) (xy 126.874524 -271.455388)
			(xy 126.875667 -271.451615) (xy 126.876938 -271.443835) (xy 126.877064 -271.439894) (xy 126.877064 -271.229836)
			(xy 126.876358 -271.217682) (xy 126.865205 -271.196081) (xy 126.855728 -271.188434) (xy 126.790196 -271.141698)
			(xy 126.785088 -271.138247) (xy 126.773661 -271.13363) (xy 126.76759 -271.132554) (xy 126.755652 -271.13103)
			(xy 126.75489 -271.131284) (xy 126.743968 -271.135094) (xy 126.720908 -271.142512) (xy 126.673183 -271.150808)
			(xy 126.648972 -271.151604) (xy 126.640844 -271.151604) (xy 126.615798 -271.150783) (xy 126.566469 -271.141977)
			(xy 126.51924 -271.125235) (xy 126.475378 -271.101006) (xy 126.436061 -271.06994) (xy 126.402345 -271.032872)
			(xy 126.375133 -270.990795) (xy 126.355157 -270.94484) (xy 126.342953 -270.89624) (xy 126.338849 -270.8463)
			(xy 126.342953 -270.79636) (xy 126.355158 -270.74776) (xy 126.375133 -270.701805) (xy 126.402345 -270.659728)
			(xy 126.436061 -270.62266) (xy 126.475378 -270.591594) (xy 126.51924 -270.567365) (xy 126.566469 -270.550623)
			(xy 126.615798 -270.541817) (xy 126.640844 -270.540988) (xy 126.645162 -270.540988) (xy 126.670334 -270.541523)
			(xy 126.71999 -270.54982) (xy 126.743968 -270.557498) (xy 126.75489 -270.561308) (xy 126.755652 -270.561562)
			(xy 126.76759 -270.560038) (xy 126.773671 -270.559003) (xy 126.785102 -270.554373) (xy 126.790196 -270.550894)
			(xy 126.855728 -270.504158) (xy 126.865233 -270.49654) (xy 126.876373 -270.474918) (xy 126.877064 -270.462756)
			(xy 126.877064 -270.252698) (xy 126.876979 -270.248754) (xy 126.875708 -270.240967) (xy 126.874524 -270.237204)
			(xy 126.867666 -270.215868) (xy 126.863348 -270.209518) (xy 126.848878 -270.187516) (xy 126.826905 -270.139663)
			(xy 126.813456 -270.088753) (xy 126.808929 -270.036292) (xy 126.813459 -269.983831) (xy 126.82691 -269.932921)
			(xy 126.848886 -269.88507) (xy 126.863348 -269.863062) (xy 126.867666 -269.856712) (xy 126.874524 -269.835376)
			(xy 126.875666 -269.831603) (xy 126.876935 -269.823822) (xy 126.877064 -269.819882) (xy 126.877064 -269.561818)
			(xy 126.872492 -269.551658) (xy 126.855818 -269.513916) (xy 126.829588 -269.43568) (xy 126.811736 -269.355118)
			(xy 126.802459 -269.273125) (xy 126.801626 -269.231872) (xy 126.801626 -269.226284) (xy 126.801195 -269.209554)
			(xy 126.794118 -269.17685) (xy 126.780288 -269.146382) (xy 126.76033 -269.119525) (xy 126.748032 -269.108174)
			(xy 126.747778 -269.10792) (xy 126.74219 -269.103348) (xy 126.725172 -269.093188) (xy 126.72187 -269.09141)
			(xy 126.721362 -269.091156) (xy 126.720092 -269.090394) (xy 126.719584 -269.09014) (xy 126.684644 -269.069237)
			(xy 126.618879 -269.021228) (xy 126.55848 -268.966622) (xy 126.504104 -268.906015) (xy 126.456345 -268.840069)
			(xy 126.415723 -268.769501) (xy 126.382682 -268.695083) (xy 126.35758 -268.617624) (xy 126.340693 -268.53797)
			(xy 126.332205 -268.45699) (xy 126.331726 -268.416278) (xy 126.331283 -268.399099) (xy 126.323843 -268.365556)
			(xy 126.309321 -268.334418) (xy 126.299214 -268.32052) (xy 126.288038 -268.307312) (xy 126.287022 -268.306296)
			(xy 126.28626 -268.305534) (xy 126.27991 -268.299692) (xy 126.27229 -268.293088) (xy 126.259844 -268.285722)
			(xy 126.252986 -268.281912) (xy 126.229364 -268.268196) (xy 126.217426 -268.261338) (xy 126.194058 -268.246352)
			(xy 126.190502 -268.243812) (xy 126.17577 -268.233398) (xy 126.173738 -268.231874) (xy 126.173484 -268.23162)
			(xy 126.155958 -268.217904) (xy 126.125795 -268.19317) (xy 126.070009 -268.138641) (xy 126.019922 -268.078836)
			(xy 125.976028 -268.014347) (xy 125.938763 -267.945814) (xy 125.908497 -267.873915) (xy 125.88553 -267.799364)
			(xy 125.870088 -267.722899) (xy 125.862325 -267.645277) (xy 125.861826 -267.606272) (xy 125.86208 -267.541502)
			(xy 125.86208 -267.486384) (xy 125.861826 -267.48613) (xy 125.861826 -267.377164) (xy 125.861332 -267.367159)
			(xy 125.853667 -267.348675) (xy 125.839516 -267.334527) (xy 125.821031 -267.326866) (xy 125.811026 -267.326364)
			(xy 125.12802 -267.326364) (xy 125.121162 -267.326872) (xy 125.111284 -267.328699) (xy 125.094004 -267.338915)
			(xy 125.087634 -267.346684) (xy 125.040898 -267.421614) (xy 125.037613 -267.427206) (xy 125.033627 -267.439541)
			(xy 125.033024 -267.445998) (xy 125.032516 -267.458952) (xy 125.034548 -267.462762) (xy 125.038612 -267.47089)
			(xy 125.048273 -267.491396) (xy 125.062105 -267.534561) (xy 125.069402 -267.579298) (xy 125.070108 -267.601954)
			(xy 125.070108 -267.611352) (xy 125.069193 -267.636332) (xy 125.060233 -267.685506) (xy 125.043383 -267.732564)
			(xy 125.019095 -267.77625) (xy 124.988016 -267.815397) (xy 124.950976 -267.848959) (xy 124.908964 -267.876041)
			(xy 124.863103 -267.895918) (xy 124.814617 -267.908061) (xy 124.7648 -267.912145) (xy 124.714983 -267.908061)
			(xy 124.666497 -267.895918) (xy 124.620636 -267.876041) (xy 124.578624 -267.848959) (xy 124.541584 -267.815397)
			(xy 124.510505 -267.77625) (xy 124.486217 -267.732564) (xy 124.469367 -267.685506) (xy 124.460407 -267.636332)
			(xy 124.459492 -267.611352) (xy 124.459492 -267.605764) (xy 124.459955 -267.582467) (xy 124.467071 -267.53642)
			(xy 124.481089 -267.491984) (xy 124.490988 -267.47089) (xy 124.495052 -267.462762) (xy 124.497084 -267.458952)
			(xy 124.496576 -267.445998) (xy 124.49603 -267.439529) (xy 124.492044 -267.427179) (xy 124.488702 -267.421614)
			(xy 124.441966 -267.346684) (xy 124.435604 -267.338909) (xy 124.418317 -267.328703) (xy 124.408438 -267.326872)
			(xy 124.40158 -267.326364) (xy 124.009658 -267.326364) (xy 123.999817 -267.325835) (xy 123.981642 -267.318262)
			(xy 123.974352 -267.311632) (xy 123.693174 -267.030454) (xy 123.686566 -267.024428) (xy 123.670307 -267.017006)
			(xy 123.661424 -267.015976) (xy 123.630436 -267.014706) (xy 123.629928 -267.014706) (xy 123.59132 -267.013436)
			(xy 123.581668 -267.013944) (xy 123.574762 -267.01529) (xy 123.562009 -267.021223) (xy 123.556522 -267.025628)
			(xy 123.55576 -267.026136) (xy 123.555506 -267.02639) (xy 123.534464 -267.043931) (xy 123.487424 -267.071995)
			(xy 123.436132 -267.091216) (xy 123.382234 -267.100978) (xy 123.354846 -267.101574) (xy 123.33605 -267.101066)
			(xy 123.329192 -267.100558) (xy 123.303659 -267.09788) (xy 123.253944 -267.08508) (xy 123.20707 -267.064147)
			(xy 123.164357 -267.035669) (xy 123.127008 -267.00045) (xy 123.096075 -266.95948) (xy 123.07243 -266.913914)
			(xy 123.056737 -266.865035) (xy 123.052586 -266.8397) (xy 123.050808 -266.827) (xy 123.049284 -266.796266)
			(xy 123.049715 -266.772503) (xy 123.05703 -266.725545) (xy 123.071527 -266.680285) (xy 123.081796 -266.658852)
			(xy 123.084564 -266.652949) (xy 123.08739 -266.640226) (xy 123.087384 -266.633706) (xy 123.086876 -266.620752)
			(xy 123.035822 -266.537948) (xy 123.031836 -266.531763) (xy 123.020994 -266.521824) (xy 123.014486 -266.51839)
			(xy 123.014232 -266.51839) (xy 123.009173 -266.516185) (xy 122.998411 -266.513758) (xy 122.992896 -266.513564)
			(xy 122.246898 -266.513564) (xy 122.237062 -266.514105) (xy 122.218906 -266.521696) (xy 122.211592 -266.528296)
			(xy 121.466356 -267.273532) (xy 121.459115 -267.280238) (xy 121.44091 -267.287817) (xy 121.43105 -267.288264)
			(xy 121.346976 -267.288264) (xy 121.338167 -267.288684) (xy 121.321612 -267.294728) (xy 121.308062 -267.305996)
			(xy 121.303288 -267.31341) (xy 121.281698 -267.35278) (xy 121.26087 -267.39088) (xy 121.256842 -267.398989)
			(xy 121.254181 -267.416887) (xy 121.25787 -267.434601) (xy 121.262394 -267.442442) (xy 121.262648 -267.442696)
			(xy 121.277318 -267.466987) (xy 121.298341 -267.51969) (xy 121.30927 -267.575368) (xy 121.310146 -267.603732)
			(xy 121.310146 -267.606272) (xy 122.578888 -267.606272) (xy 122.582848 -267.557218) (xy 122.594625 -267.509434)
			(xy 122.613916 -267.464158) (xy 122.640219 -267.422562) (xy 122.672854 -267.385725) (xy 122.710975 -267.3546)
			(xy 122.753596 -267.329993) (xy 122.799612 -267.312541) (xy 122.847831 -267.302697) (xy 122.897006 -267.300716)
			(xy 122.945861 -267.306648) (xy 122.993132 -267.32034) (xy 123.037594 -267.341438) (xy 123.078097 -267.369394)
			(xy 123.11359 -267.403486) (xy 123.143155 -267.44283) (xy 123.166026 -267.486407) (xy 123.18161 -267.533088)
			(xy 123.189505 -267.581665) (xy 123.19 -267.606272) (xy 123.189505 -267.630879) (xy 123.18161 -267.679456)
			(xy 123.166026 -267.726137) (xy 123.143155 -267.769714) (xy 123.11359 -267.809058) (xy 123.078097 -267.84315)
			(xy 123.037594 -267.871106) (xy 122.993132 -267.892204) (xy 122.945861 -267.905896) (xy 122.897006 -267.911828)
			(xy 122.847831 -267.909847) (xy 122.799612 -267.900003) (xy 122.753596 -267.882551) (xy 122.710975 -267.857944)
			(xy 122.672854 -267.826819) (xy 122.640219 -267.789982) (xy 122.613916 -267.748386) (xy 122.594625 -267.70311)
			(xy 122.582848 -267.655326) (xy 122.578888 -267.606272) (xy 121.310146 -267.606272) (xy 121.310073 -267.61563)
			(xy 121.308927 -267.634312) (xy 121.30786 -267.64361) (xy 121.307098 -267.649706) (xy 121.303191 -267.673634)
			(xy 121.288801 -267.719929) (xy 121.267275 -267.763368) (xy 121.239155 -267.80286) (xy 121.205147 -267.837411)
			(xy 121.166105 -267.866154) (xy 121.123012 -267.888365) (xy 121.076951 -267.903486) (xy 121.029078 -267.911139)
			(xy 121.004838 -267.91158) (xy 120.980844 -267.911137) (xy 120.933445 -267.903634) (xy 120.887804 -267.888809)
			(xy 120.845045 -267.867025) (xy 120.80622 -267.83882) (xy 120.772287 -267.804887) (xy 120.74408 -267.766064)
			(xy 120.722295 -267.723305) (xy 120.707468 -267.677664) (xy 120.699964 -267.630266) (xy 120.69953 -267.606272)
			(xy 120.699668 -267.593509) (xy 120.701829 -267.568075) (xy 120.703848 -267.555472) (xy 120.703594 -267.555472)
			(xy 120.709375 -267.525661) (xy 120.731126 -267.468974) (xy 120.746774 -267.44295) (xy 120.747282 -267.442442)
			(xy 120.748298 -267.440664) (xy 120.752336 -267.432952) (xy 120.755474 -267.41584) (xy 120.752698 -267.398666)
			(xy 120.748806 -267.39088) (xy 120.711468 -267.3223) (xy 120.706642 -267.313918) (xy 120.701942 -267.306333)
			(xy 120.688348 -267.294793) (xy 120.671615 -267.28863) (xy 120.6627 -267.288264) (xy 120.255538 -267.288264)
			(xy 120.245698 -267.287731) (xy 120.227529 -267.280154) (xy 120.220232 -267.273532) (xy 119.955564 -267.008864)
			(xy 119.951946 -267.005431) (xy 119.943628 -266.99993) (xy 119.939054 -266.997942) (xy 119.92991 -266.994132)
			(xy 119.883682 -266.994386) (xy 119.848884 -266.99464) (xy 119.843787 -266.994754) (xy 119.833803 -266.996805)
			(xy 119.829072 -266.998704) (xy 119.820182 -267.002514) (xy 119.812816 -267.00988) (xy 119.795468 -267.026928)
			(xy 119.756365 -267.055849) (xy 119.713168 -267.078198) (xy 119.666972 -267.093411) (xy 119.618948 -267.101101)
			(xy 119.59463 -267.101574) (xy 119.570752 -267.101115) (xy 119.523579 -267.093683) (xy 119.478138 -267.078996)
			(xy 119.435538 -267.057413) (xy 119.396819 -267.02946) (xy 119.362925 -266.995818) (xy 119.334683 -266.957309)
			(xy 119.312782 -266.914872) (xy 119.297756 -266.869542) (xy 119.289972 -266.822425) (xy 119.289322 -266.798552)
			(xy 119.289322 -266.796012) (xy 119.289508 -266.78073) (xy 119.29256 -266.750319) (xy 119.295418 -266.735306)
			(xy 119.295926 -266.733274) (xy 119.297034 -266.722652) (xy 119.291521 -266.702046) (xy 119.285258 -266.693396)
			(xy 119.285004 -266.693142) (xy 119.236236 -266.633706) (xy 119.228632 -266.625428) (xy 119.208342 -266.615816)
			(xy 119.19712 -266.615164) (xy 118.337838 -266.615164) (xy 118.327999 -266.615698) (xy 118.309833 -266.623279)
			(xy 118.302532 -266.629896) (xy 117.975888 -266.95654) (xy 117.970046 -266.963906) (xy 117.968776 -266.965684)
			(xy 117.951478 -266.990361) (xy 117.908871 -267.032969) (xy 117.884194 -267.050266) (xy 117.882416 -267.051536)
			(xy 117.87505 -267.057378) (xy 117.620796 -267.311632) (xy 117.615932 -267.316229) (xy 117.604348 -267.322924)
			(xy 117.597936 -267.32484) (xy 117.595396 -267.325602) (xy 117.587335 -267.328438) (xy 117.573583 -267.338565)
			(xy 117.568472 -267.345414) (xy 117.557296 -267.363194) (xy 117.557296 -267.363702) (xy 117.52072 -267.421614)
			(xy 117.517434 -267.427205) (xy 117.513446 -267.439541) (xy 117.512846 -267.445998) (xy 117.512338 -267.458952)
			(xy 117.518434 -267.47089) (xy 117.528094 -267.491396) (xy 117.541926 -267.534561) (xy 117.549222 -267.579298)
			(xy 117.54993 -267.601954) (xy 117.54993 -267.606272) (xy 118.818926 -267.606272) (xy 118.822886 -267.557218)
			(xy 118.834663 -267.509434) (xy 118.853954 -267.464158) (xy 118.880257 -267.422562) (xy 118.912892 -267.385725)
			(xy 118.951013 -267.3546) (xy 118.993634 -267.329993) (xy 119.03965 -267.312541) (xy 119.087869 -267.302697)
			(xy 119.137044 -267.300716) (xy 119.185899 -267.306648) (xy 119.23317 -267.32034) (xy 119.277632 -267.341438)
			(xy 119.318135 -267.369394) (xy 119.353628 -267.403486) (xy 119.383193 -267.44283) (xy 119.406064 -267.486407)
			(xy 119.421648 -267.533088) (xy 119.429543 -267.581665) (xy 119.430038 -267.606272) (xy 119.429543 -267.630879)
			(xy 119.421648 -267.679456) (xy 119.406064 -267.726137) (xy 119.383193 -267.769714) (xy 119.353628 -267.809058)
			(xy 119.318135 -267.84315) (xy 119.277632 -267.871106) (xy 119.23317 -267.892204) (xy 119.185899 -267.905896)
			(xy 119.137044 -267.911828) (xy 119.087869 -267.909847) (xy 119.03965 -267.900003) (xy 118.993634 -267.882551)
			(xy 118.951013 -267.857944) (xy 118.912892 -267.826819) (xy 118.880257 -267.789982) (xy 118.853954 -267.748386)
			(xy 118.834663 -267.70311) (xy 118.822886 -267.655326) (xy 118.818926 -267.606272) (xy 117.54993 -267.606272)
			(xy 117.54993 -267.611352) (xy 117.549015 -267.636332) (xy 117.540055 -267.685506) (xy 117.523205 -267.732564)
			(xy 117.498917 -267.77625) (xy 117.467838 -267.815397) (xy 117.430798 -267.848959) (xy 117.388786 -267.876041)
			(xy 117.342925 -267.895918) (xy 117.294439 -267.908061) (xy 117.244622 -267.912145) (xy 117.194805 -267.908061)
			(xy 117.146319 -267.895918) (xy 117.100458 -267.876041) (xy 117.058446 -267.848959) (xy 117.021406 -267.815397)
			(xy 116.990327 -267.77625) (xy 116.966039 -267.732564) (xy 116.949189 -267.685506) (xy 116.940229 -267.636332)
			(xy 116.939314 -267.611352) (xy 116.939314 -267.605764) (xy 116.939777 -267.582467) (xy 116.946894 -267.53642)
			(xy 116.960912 -267.491985) (xy 116.97081 -267.47089) (xy 116.974874 -267.462762) (xy 116.976906 -267.458952)
			(xy 116.976398 -267.445998) (xy 116.975851 -267.43953) (xy 116.971859 -267.427183) (xy 116.968524 -267.421614)
			(xy 116.921788 -267.346684) (xy 116.915427 -267.338906) (xy 116.898142 -267.328692) (xy 116.88826 -267.326872)
			(xy 116.881402 -267.326364) (xy 116.463318 -267.326364) (xy 116.45348 -267.325828) (xy 116.435316 -267.318245)
			(xy 116.428012 -267.311632) (xy 116.139722 -267.023342) (xy 116.136105 -267.019907) (xy 116.127788 -267.014406)
			(xy 116.123212 -267.01242) (xy 116.11356 -267.008356) (xy 116.082318 -267.008864) (xy 116.069618 -267.010642)
			(xy 116.064284 -267.01242) (xy 116.040662 -267.021818) (xy 116.034058 -267.027406) (xy 116.013098 -267.044724)
			(xy 115.96631 -267.072409) (xy 115.915356 -267.091364) (xy 115.861851 -267.100992) (xy 115.834668 -267.101574)
			(xy 115.810717 -267.101104) (xy 115.763405 -267.093617) (xy 115.717842 -267.078833) (xy 115.675148 -267.057114)
			(xy 115.63637 -267.028993) (xy 115.60246 -266.99516) (xy 115.574251 -266.956446) (xy 115.552434 -266.913801)
			(xy 115.537546 -266.868273) (xy 115.529951 -266.820977) (xy 115.52936 -266.797028) (xy 115.52936 -266.795758)
			(xy 115.529913 -266.77065) (xy 115.538212 -266.721124) (xy 115.54587 -266.697206) (xy 115.54587 -266.696952)
			(xy 115.549094 -266.685876) (xy 115.546304 -266.663001) (xy 115.540536 -266.65301) (xy 115.490244 -266.58316)
			(xy 115.482626 -266.574765) (xy 115.462192 -266.565017) (xy 115.450874 -266.564364) (xy 114.657378 -266.564364)
			(xy 114.647536 -266.56489) (xy 114.629359 -266.572461) (xy 114.622072 -266.579096) (xy 113.899696 -267.301472)
			(xy 113.89246 -267.30819) (xy 113.874255 -267.315794) (xy 113.86439 -267.316204) (xy 113.843054 -267.316204)
			(xy 113.834328 -267.316561) (xy 113.817901 -267.322451) (xy 113.804437 -267.333555) (xy 113.79962 -267.340842)
			(xy 113.755932 -267.41374) (xy 113.754662 -267.416026) (xy 113.754662 -267.457428) (xy 113.757202 -267.468604)
			(xy 113.759742 -267.473684) (xy 113.769199 -267.494231) (xy 113.782611 -267.537428) (xy 113.789478 -267.582134)
			(xy 113.789968 -267.604748) (xy 113.789968 -267.606272) (xy 115.058964 -267.606272) (xy 115.062924 -267.557218)
			(xy 115.074701 -267.509434) (xy 115.093992 -267.464158) (xy 115.120295 -267.422562) (xy 115.15293 -267.385725)
			(xy 115.191051 -267.3546) (xy 115.233672 -267.329993) (xy 115.279688 -267.312541) (xy 115.327907 -267.302697)
			(xy 115.377082 -267.300716) (xy 115.425937 -267.306648) (xy 115.473208 -267.32034) (xy 115.51767 -267.341438)
			(xy 115.558173 -267.369394) (xy 115.593666 -267.403486) (xy 115.623231 -267.44283) (xy 115.646102 -267.486407)
			(xy 115.661686 -267.533088) (xy 115.669581 -267.581665) (xy 115.670076 -267.606272) (xy 115.669581 -267.630879)
			(xy 115.661686 -267.679456) (xy 115.646102 -267.726137) (xy 115.623231 -267.769714) (xy 115.593666 -267.809058)
			(xy 115.558173 -267.84315) (xy 115.51767 -267.871106) (xy 115.473208 -267.892204) (xy 115.425937 -267.905896)
			(xy 115.377082 -267.911828) (xy 115.327907 -267.909847) (xy 115.279688 -267.900003) (xy 115.233672 -267.882551)
			(xy 115.191051 -267.857944) (xy 115.15293 -267.826819) (xy 115.120295 -267.789982) (xy 115.093992 -267.748386)
			(xy 115.074701 -267.70311) (xy 115.062924 -267.655326) (xy 115.058964 -267.606272) (xy 113.789968 -267.606272)
			(xy 113.789968 -267.610844) (xy 113.789092 -267.635852) (xy 113.780195 -267.68509) (xy 113.763391 -267.73222)
			(xy 113.739127 -267.775979) (xy 113.708053 -267.815196) (xy 113.671001 -267.848822) (xy 113.628962 -267.875958)
			(xy 113.583062 -267.895876) (xy 113.534528 -267.908045) (xy 113.48466 -267.912137) (xy 113.434792 -267.908045)
			(xy 113.386258 -267.895876) (xy 113.340358 -267.875958) (xy 113.298319 -267.848822) (xy 113.261267 -267.815196)
			(xy 113.230193 -267.775979) (xy 113.205929 -267.73222) (xy 113.189125 -267.68509) (xy 113.180228 -267.635852)
			(xy 113.179352 -267.610844) (xy 113.179352 -267.606018) (xy 113.17983 -267.581293) (xy 113.187803 -267.532492)
			(xy 113.203543 -267.485615) (xy 113.214658 -267.463524) (xy 113.218429 -267.455676) (xy 113.220952 -267.438461)
			(xy 113.217526 -267.421403) (xy 113.213388 -267.41374) (xy 113.211102 -267.409676) (xy 113.172748 -267.345668)
			(xy 113.165636 -267.336778) (xy 112.55629 -266.727432) (xy 112.553439 -266.724727) (xy 112.54706 -266.720135)
			(xy 112.54359 -266.718288) (xy 112.538164 -266.715702) (xy 112.526484 -266.712871) (xy 112.520476 -266.7127)
			(xy 111.490506 -266.7127) (xy 111.484498 -266.712872) (xy 111.47282 -266.715705) (xy 111.467392 -266.718288)
			(xy 111.463917 -266.720127) (xy 111.457537 -266.724718) (xy 111.454692 -266.727432) (xy 110.880906 -267.301218)
			(xy 110.873512 -267.308074) (xy 110.854913 -267.315824) (xy 110.844838 -267.316204) (xy 110.089442 -267.316204)
			(xy 110.080708 -267.316547) (xy 110.064259 -267.322418) (xy 110.050772 -267.333515) (xy 110.046008 -267.340842)
			(xy 110.00232 -267.41374) (xy 110.00105 -267.416026) (xy 110.00105 -267.457428) (xy 110.00359 -267.468604)
			(xy 110.00613 -267.473684) (xy 110.015585 -267.494232) (xy 110.028992 -267.537429) (xy 110.035857 -267.582135)
			(xy 110.036356 -267.604748) (xy 110.036356 -267.610844) (xy 110.035549 -267.6346) (xy 110.027485 -267.681442)
			(xy 110.012258 -267.726468) (xy 109.990237 -267.76859) (xy 109.961954 -267.806791) (xy 109.928093 -267.840146)
			(xy 109.889471 -267.867851) (xy 109.847022 -267.889235) (xy 109.801772 -267.903782) (xy 109.754814 -267.911141)
			(xy 109.731048 -267.91158) (xy 109.707053 -267.911137) (xy 109.659654 -267.903636) (xy 109.614011 -267.888812)
			(xy 109.57125 -267.867029) (xy 109.532425 -267.838823) (xy 109.49849 -267.804891) (xy 109.470282 -267.766067)
			(xy 109.448496 -267.723307) (xy 109.433668 -267.677666) (xy 109.426164 -267.630267) (xy 109.42574 -267.606272)
			(xy 109.426176 -267.582735) (xy 109.433403 -267.536219) (xy 109.44768 -267.491362) (xy 109.468669 -267.449226)
			(xy 109.495875 -267.410809) (xy 109.528652 -267.377021) (xy 109.566225 -267.348661) (xy 109.607703 -267.326401)
			(xy 109.652106 -267.310769) (xy 109.675168 -267.306044) (xy 109.682026 -267.304774) (xy 109.694472 -267.298678)
			(xy 109.699552 -267.29436) (xy 109.70458 -267.289631) (xy 109.712051 -267.278031) (xy 109.714284 -267.2715)
			(xy 109.714538 -267.270484) (xy 109.740192 -267.187426) (xy 109.742532 -267.178534) (xy 109.741429 -267.160194)
			(xy 109.733946 -267.143414) (xy 109.727746 -267.136626) (xy 109.61116 -267.02004) (xy 109.607588 -267.01664)
			(xy 109.5994 -267.011145) (xy 109.594904 -267.009118) (xy 109.586014 -267.005308) (xy 109.54258 -267.0048)
			(xy 109.542072 -267.0048) (xy 109.506512 -267.004292) (xy 109.501579 -267.004282) (xy 109.491855 -267.005939)
			(xy 109.487208 -267.007594) (xy 109.478318 -267.01115) (xy 109.470952 -267.018008) (xy 109.453854 -267.033613)
			(xy 109.415821 -267.060002) (xy 109.374237 -267.080337) (xy 109.330055 -267.094152) (xy 109.284293 -267.101128)
			(xy 109.261148 -267.101574) (xy 109.237153 -267.101131) (xy 109.189754 -267.09363) (xy 109.144112 -267.078806)
			(xy 109.101352 -267.057022) (xy 109.062526 -267.028817) (xy 109.028592 -266.994884) (xy 109.000385 -266.95606)
			(xy 108.9786 -266.913301) (xy 108.963773 -266.86766) (xy 108.95627 -266.820261) (xy 108.95584 -266.796266)
			(xy 108.95584 -266.795504) (xy 108.956592 -266.765357) (xy 108.968487 -266.706244) (xy 108.979462 -266.678156)
			(xy 108.979462 -266.677902) (xy 108.981736 -266.672085) (xy 108.983672 -266.65975) (xy 108.983272 -266.653518)
			(xy 108.982256 -266.641326) (xy 108.928154 -266.560046) (xy 108.924344 -266.55522) (xy 108.917782 -266.548711)
			(xy 108.901238 -266.540508) (xy 108.892086 -266.539218) (xy 108.88726 -266.538964) (xy 108.246418 -266.538964)
			(xy 108.236581 -266.539501) (xy 108.218419 -266.547087) (xy 108.211112 -266.553696) (xy 107.503976 -267.260832)
			(xy 107.496736 -267.267541) (xy 107.478531 -267.275128) (xy 107.46867 -267.275564) (xy 106.305096 -267.275564)
			(xy 106.299254 -267.275818) (xy 106.28823 -267.277651) (xy 106.269237 -267.289377) (xy 106.262678 -267.298424)
			(xy 106.260138 -267.302488) (xy 106.21899 -267.379958) (xy 106.215998 -267.38626) (xy 106.213156 -267.399911)
			(xy 106.213402 -267.406882) (xy 106.214164 -267.420852) (xy 106.222292 -267.432536) (xy 106.235039 -267.451738)
			(xy 106.25523 -267.493169) (xy 106.268968 -267.537162) (xy 106.275942 -267.58272) (xy 106.276394 -267.605764)
			(xy 106.276394 -267.606272) (xy 107.545136 -267.606272) (xy 107.549096 -267.557218) (xy 107.560873 -267.509434)
			(xy 107.580164 -267.464158) (xy 107.606467 -267.422562) (xy 107.639102 -267.385725) (xy 107.677223 -267.3546)
			(xy 107.719844 -267.329993) (xy 107.76586 -267.312541) (xy 107.814079 -267.302697) (xy 107.863254 -267.300716)
			(xy 107.912109 -267.306648) (xy 107.95938 -267.32034) (xy 108.003842 -267.341438) (xy 108.044345 -267.369394)
			(xy 108.079838 -267.403486) (xy 108.109403 -267.44283) (xy 108.132274 -267.486407) (xy 108.147858 -267.533088)
			(xy 108.155753 -267.581665) (xy 108.156248 -267.606272) (xy 108.155753 -267.630879) (xy 108.147858 -267.679456)
			(xy 108.132274 -267.726137) (xy 108.109403 -267.769714) (xy 108.079838 -267.809058) (xy 108.044345 -267.84315)
			(xy 108.003842 -267.871106) (xy 107.95938 -267.892204) (xy 107.912109 -267.905896) (xy 107.863254 -267.911828)
			(xy 107.814079 -267.909847) (xy 107.76586 -267.900003) (xy 107.719844 -267.882551) (xy 107.677223 -267.857944)
			(xy 107.639102 -267.826819) (xy 107.606467 -267.789982) (xy 107.580164 -267.748386) (xy 107.560873 -267.70311)
			(xy 107.549096 -267.655326) (xy 107.545136 -267.606272) (xy 106.276394 -267.606272) (xy 106.275872 -267.631527)
			(xy 106.267559 -267.681349) (xy 106.251158 -267.729123) (xy 106.227117 -267.773546) (xy 106.196093 -267.813406)
			(xy 106.158931 -267.847616) (xy 106.116645 -267.875242) (xy 106.070389 -267.895532) (xy 106.021424 -267.907932)
			(xy 105.971086 -267.912103) (xy 105.920748 -267.907932) (xy 105.871783 -267.895532) (xy 105.825527 -267.875242)
			(xy 105.783241 -267.847616) (xy 105.746079 -267.813406) (xy 105.715055 -267.773546) (xy 105.691014 -267.729123)
			(xy 105.674613 -267.681349) (xy 105.6663 -267.631527) (xy 105.665778 -267.606272) (xy 105.665778 -267.605764)
			(xy 105.665895 -267.59416) (xy 105.667671 -267.571021) (xy 105.669334 -267.559536) (xy 105.669842 -267.556488)
			(xy 105.669842 -267.555472) (xy 105.674561 -267.530503) (xy 105.691183 -267.482487) (xy 105.715525 -267.437885)
			(xy 105.746915 -267.397928) (xy 105.784487 -267.36372) (xy 105.827204 -267.336204) (xy 105.873886 -267.31614)
			(xy 105.898442 -267.3096) (xy 105.898696 -267.3096) (xy 105.899712 -267.309346) (xy 105.90276 -267.308584)
			(xy 105.914153 -267.304335) (xy 105.931517 -267.287362) (xy 105.936034 -267.276072) (xy 105.96118 -267.187934)
			(xy 105.962267 -267.182398) (xy 105.962258 -267.17112) (xy 105.96118 -267.165582) (xy 105.95991 -267.16101)
			(xy 105.957877 -267.155398) (xy 105.951587 -267.145259) (xy 105.947464 -267.140944) (xy 105.83799 -267.03147)
			(xy 105.834509 -267.028185) (xy 105.826581 -267.022823) (xy 105.822242 -267.020802) (xy 105.814114 -267.017246)
			(xy 105.736136 -267.014198) (xy 105.731215 -267.014149) (xy 105.721496 -267.015679) (xy 105.716832 -267.017246)
			(xy 105.708704 -267.020294) (xy 105.701338 -267.026644) (xy 105.680303 -267.044124) (xy 105.633306 -267.072086)
			(xy 105.582086 -267.091246) (xy 105.528275 -267.100993) (xy 105.500932 -267.101574) (xy 105.476695 -267.101104)
			(xy 105.428831 -267.093438) (xy 105.382778 -267.078309) (xy 105.339692 -267.056096) (xy 105.300655 -267.027358)
			(xy 105.266647 -266.992815) (xy 105.238521 -266.953335) (xy 105.216983 -266.909908) (xy 105.202573 -266.863625)
			(xy 105.198672 -266.8397) (xy 105.196894 -266.827) (xy 105.19537 -266.796266) (xy 105.195801 -266.772503)
			(xy 105.203116 -266.725545) (xy 105.217612 -266.680285) (xy 105.227882 -266.658852) (xy 105.230651 -266.652949)
			(xy 105.233477 -266.640226) (xy 105.23347 -266.633706) (xy 105.232962 -266.620752) (xy 105.181908 -266.537948)
			(xy 105.177921 -266.531764) (xy 105.167077 -266.521828) (xy 105.160572 -266.51839) (xy 105.160318 -266.51839)
			(xy 105.155259 -266.516186) (xy 105.144497 -266.513762) (xy 105.138982 -266.513564) (xy 104.426258 -266.513564)
			(xy 104.416418 -266.514094) (xy 104.398246 -266.52167) (xy 104.390952 -266.528296) (xy 103.633016 -267.286232)
			(xy 103.625779 -267.292947) (xy 103.607574 -267.300549) (xy 103.59771 -267.300964) (xy 102.561136 -267.300964)
			(xy 102.548944 -267.302488) (xy 102.540054 -267.305536) (xy 102.536244 -267.307314) (xy 102.530768 -267.310566)
			(xy 102.521504 -267.319298) (xy 102.517956 -267.324586) (xy 102.51694 -267.326364) (xy 102.474268 -267.400786)
			(xy 102.471118 -267.40672) (xy 102.467763 -267.419723) (xy 102.467664 -267.42644) (xy 102.467664 -267.439902)
			(xy 102.474776 -267.45184) (xy 102.487846 -267.475366) (xy 102.506407 -267.525877) (xy 102.515836 -267.578857)
			(xy 102.516432 -267.605764) (xy 102.516432 -267.606272) (xy 103.785174 -267.606272) (xy 103.789134 -267.557218)
			(xy 103.800911 -267.509434) (xy 103.820202 -267.464158) (xy 103.846505 -267.422562) (xy 103.87914 -267.385725)
			(xy 103.917261 -267.3546) (xy 103.959882 -267.329993) (xy 104.005898 -267.312541) (xy 104.054117 -267.302697)
			(xy 104.103292 -267.300716) (xy 104.152147 -267.306648) (xy 104.199418 -267.32034) (xy 104.24388 -267.341438)
			(xy 104.284383 -267.369394) (xy 104.319876 -267.403486) (xy 104.349441 -267.44283) (xy 104.372312 -267.486407)
			(xy 104.387896 -267.533088) (xy 104.395791 -267.581665) (xy 104.396286 -267.606272) (xy 104.395791 -267.630879)
			(xy 104.387896 -267.679456) (xy 104.372312 -267.726137) (xy 104.349441 -267.769714) (xy 104.319876 -267.809058)
			(xy 104.284383 -267.84315) (xy 104.24388 -267.871106) (xy 104.199418 -267.892204) (xy 104.152147 -267.905896)
			(xy 104.103292 -267.911828) (xy 104.054117 -267.909847) (xy 104.005898 -267.900003) (xy 103.959882 -267.882551)
			(xy 103.917261 -267.857944) (xy 103.87914 -267.826819) (xy 103.846505 -267.789982) (xy 103.820202 -267.748386)
			(xy 103.800911 -267.70311) (xy 103.789134 -267.655326) (xy 103.785174 -267.606272) (xy 102.516432 -267.606272)
			(xy 102.51591 -267.631527) (xy 102.507597 -267.681349) (xy 102.491196 -267.729123) (xy 102.467155 -267.773546)
			(xy 102.436131 -267.813406) (xy 102.398969 -267.847616) (xy 102.356683 -267.875242) (xy 102.310427 -267.895532)
			(xy 102.261462 -267.907932) (xy 102.211124 -267.912103) (xy 102.160786 -267.907932) (xy 102.111821 -267.895532)
			(xy 102.065565 -267.875242) (xy 102.023279 -267.847616) (xy 101.986117 -267.813406) (xy 101.955093 -267.773546)
			(xy 101.931052 -267.729123) (xy 101.914651 -267.681349) (xy 101.906338 -267.631527) (xy 101.905816 -267.606272)
			(xy 101.905816 -267.605764) (xy 101.90638 -267.578855) (xy 101.915807 -267.525868) (xy 101.93438 -267.475356)
			(xy 101.947472 -267.45184) (xy 101.947472 -267.451586) (xy 101.950786 -267.445756) (xy 101.954526 -267.432884)
			(xy 101.954838 -267.426186) (xy 101.954838 -267.412724) (xy 101.905308 -267.326364) (xy 101.904292 -267.324586)
			(xy 101.900721 -267.319316) (xy 101.891469 -267.310579) (xy 101.886004 -267.307314) (xy 101.882194 -267.305536)
			(xy 101.873304 -267.302488) (xy 101.861112 -267.300964) (xy 101.683058 -267.300964) (xy 101.673217 -267.300435)
			(xy 101.655042 -267.292862) (xy 101.647752 -267.286232) (xy 100.760784 -266.399264) (xy 100.757053 -266.395744)
			(xy 100.748478 -266.390117) (xy 100.743766 -266.388088) (xy 100.73513 -266.384532) (xy 96.3803 -266.384532)
			(xy 96.370066 -266.385006) (xy 96.351221 -266.392996) (xy 96.33696 -266.40768) (xy 96.332802 -266.417044)
			(xy 96.298766 -266.50569) (xy 96.295582 -266.515407) (xy 96.296356 -266.535824) (xy 96.304995 -266.554338)
			(xy 96.312228 -266.56157) (xy 96.331569 -266.579669) (xy 96.364509 -266.621147) (xy 96.390057 -266.667545)
			(xy 96.407495 -266.717559) (xy 96.416332 -266.769783) (xy 96.416876 -266.796266) (xy 96.73515 -266.796266)
			(xy 96.73911 -266.747212) (xy 96.750887 -266.699428) (xy 96.770178 -266.654152) (xy 96.796481 -266.612556)
			(xy 96.829116 -266.575719) (xy 96.867237 -266.544594) (xy 96.909858 -266.519987) (xy 96.955874 -266.502535)
			(xy 97.004093 -266.492691) (xy 97.053268 -266.49071) (xy 97.102123 -266.496642) (xy 97.149394 -266.510334)
			(xy 97.193856 -266.531432) (xy 97.234359 -266.559388) (xy 97.269852 -266.59348) (xy 97.299417 -266.632824)
			(xy 97.322288 -266.676401) (xy 97.337872 -266.723082) (xy 97.345767 -266.771659) (xy 97.346262 -266.796266)
			(xy 97.675204 -266.796266) (xy 97.679164 -266.747212) (xy 97.690941 -266.699428) (xy 97.710232 -266.654152)
			(xy 97.736535 -266.612556) (xy 97.76917 -266.575719) (xy 97.807291 -266.544594) (xy 97.849912 -266.519987)
			(xy 97.895928 -266.502535) (xy 97.944147 -266.492691) (xy 97.993322 -266.49071) (xy 98.042177 -266.496642)
			(xy 98.089448 -266.510334) (xy 98.13391 -266.531432) (xy 98.174413 -266.559388) (xy 98.209906 -266.59348)
			(xy 98.239471 -266.632824) (xy 98.262342 -266.676401) (xy 98.277926 -266.723082) (xy 98.285821 -266.771659)
			(xy 98.286316 -266.796266) (xy 98.615258 -266.796266) (xy 98.619218 -266.747212) (xy 98.630995 -266.699428)
			(xy 98.650286 -266.654152) (xy 98.676589 -266.612556) (xy 98.709224 -266.575719) (xy 98.747345 -266.544594)
			(xy 98.789966 -266.519987) (xy 98.835982 -266.502535) (xy 98.884201 -266.492691) (xy 98.933376 -266.49071)
			(xy 98.982231 -266.496642) (xy 99.029502 -266.510334) (xy 99.073964 -266.531432) (xy 99.114467 -266.559388)
			(xy 99.14996 -266.59348) (xy 99.179525 -266.632824) (xy 99.202396 -266.676401) (xy 99.21798 -266.723082)
			(xy 99.225875 -266.771659) (xy 99.22637 -266.796266) (xy 99.555312 -266.796266) (xy 99.559272 -266.747212)
			(xy 99.571049 -266.699428) (xy 99.59034 -266.654152) (xy 99.616643 -266.612556) (xy 99.649278 -266.575719)
			(xy 99.687399 -266.544594) (xy 99.73002 -266.519987) (xy 99.776036 -266.502535) (xy 99.824255 -266.492691)
			(xy 99.87343 -266.49071) (xy 99.922285 -266.496642) (xy 99.969556 -266.510334) (xy 100.014018 -266.531432)
			(xy 100.054521 -266.559388) (xy 100.090014 -266.59348) (xy 100.119579 -266.632824) (xy 100.14245 -266.676401)
			(xy 100.158034 -266.723082) (xy 100.165929 -266.771659) (xy 100.166424 -266.796266) (xy 100.165929 -266.820873)
			(xy 100.158034 -266.86945) (xy 100.14245 -266.916131) (xy 100.119579 -266.959708) (xy 100.090014 -266.999052)
			(xy 100.054521 -267.033144) (xy 100.014018 -267.0611) (xy 99.969556 -267.082198) (xy 99.922285 -267.09589)
			(xy 99.87343 -267.101822) (xy 99.824255 -267.099841) (xy 99.776036 -267.089997) (xy 99.73002 -267.072545)
			(xy 99.687399 -267.047938) (xy 99.649278 -267.016813) (xy 99.616643 -266.979976) (xy 99.59034 -266.93838)
			(xy 99.571049 -266.893104) (xy 99.559272 -266.84532) (xy 99.555312 -266.796266) (xy 99.22637 -266.796266)
			(xy 99.225875 -266.820873) (xy 99.21798 -266.86945) (xy 99.202396 -266.916131) (xy 99.179525 -266.959708)
			(xy 99.14996 -266.999052) (xy 99.114467 -267.033144) (xy 99.073964 -267.0611) (xy 99.029502 -267.082198)
			(xy 98.982231 -267.09589) (xy 98.933376 -267.101822) (xy 98.884201 -267.099841) (xy 98.835982 -267.089997)
			(xy 98.789966 -267.072545) (xy 98.747345 -267.047938) (xy 98.709224 -267.016813) (xy 98.676589 -266.979976)
			(xy 98.650286 -266.93838) (xy 98.630995 -266.893104) (xy 98.619218 -266.84532) (xy 98.615258 -266.796266)
			(xy 98.286316 -266.796266) (xy 98.285821 -266.820873) (xy 98.277926 -266.86945) (xy 98.262342 -266.916131)
			(xy 98.239471 -266.959708) (xy 98.209906 -266.999052) (xy 98.174413 -267.033144) (xy 98.13391 -267.0611)
			(xy 98.089448 -267.082198) (xy 98.042177 -267.09589) (xy 97.993322 -267.101822) (xy 97.944147 -267.099841)
			(xy 97.895928 -267.089997) (xy 97.849912 -267.072545) (xy 97.807291 -267.047938) (xy 97.76917 -267.016813)
			(xy 97.736535 -266.979976) (xy 97.710232 -266.93838) (xy 97.690941 -266.893104) (xy 97.679164 -266.84532)
			(xy 97.675204 -266.796266) (xy 97.346262 -266.796266) (xy 97.345767 -266.820873) (xy 97.337872 -266.86945)
			(xy 97.322288 -266.916131) (xy 97.299417 -266.959708) (xy 97.269852 -266.999052) (xy 97.234359 -267.033144)
			(xy 97.193856 -267.0611) (xy 97.149394 -267.082198) (xy 97.102123 -267.09589) (xy 97.053268 -267.101822)
			(xy 97.004093 -267.099841) (xy 96.955874 -267.089997) (xy 96.909858 -267.072545) (xy 96.867237 -267.047938)
			(xy 96.829116 -267.016813) (xy 96.796481 -266.979976) (xy 96.770178 -266.93838) (xy 96.750887 -266.893104)
			(xy 96.73911 -266.84532) (xy 96.73515 -266.796266) (xy 96.416876 -266.796266) (xy 96.416389 -266.821076)
			(xy 96.408627 -266.870084) (xy 96.393294 -266.917274) (xy 96.370767 -266.961485) (xy 96.341602 -267.001628)
			(xy 96.306516 -267.036714) (xy 96.266373 -267.065879) (xy 96.222162 -267.088406) (xy 96.174972 -267.103739)
			(xy 96.125964 -267.111501) (xy 96.076344 -267.111501) (xy 96.027336 -267.103739) (xy 95.980146 -267.088406)
			(xy 95.935935 -267.065879) (xy 95.895792 -267.036714) (xy 95.860706 -267.001628) (xy 95.831541 -266.961485)
			(xy 95.809014 -266.917274) (xy 95.793681 -266.870084) (xy 95.785919 -266.821076) (xy 95.785432 -266.796266)
			(xy 95.785976 -266.769784) (xy 95.794824 -266.717563) (xy 95.812265 -266.667552) (xy 95.837812 -266.621156)
			(xy 95.870745 -266.579675) (xy 95.89008 -266.56157) (xy 95.901764 -266.550902) (xy 95.90913 -266.520422)
			(xy 95.869506 -266.417044) (xy 95.865396 -266.407645) (xy 95.851142 -266.392921) (xy 95.832257 -266.38496)
			(xy 95.822008 -266.384532) (xy 94.500192 -266.384532) (xy 94.489959 -266.385007) (xy 94.471116 -266.392999)
			(xy 94.456858 -266.407683) (xy 94.452694 -266.417044) (xy 94.418658 -266.50569) (xy 94.415475 -266.515407)
			(xy 94.416249 -266.535824) (xy 94.424886 -266.554339) (xy 94.43212 -266.56157) (xy 94.451462 -266.579669)
			(xy 94.484402 -266.621146) (xy 94.509951 -266.667544) (xy 94.527389 -266.717558) (xy 94.536227 -266.769782)
			(xy 94.536768 -266.796266) (xy 94.855296 -266.796266) (xy 94.859256 -266.747212) (xy 94.871033 -266.699428)
			(xy 94.890324 -266.654152) (xy 94.916627 -266.612556) (xy 94.949262 -266.575719) (xy 94.987383 -266.544594)
			(xy 95.030004 -266.519987) (xy 95.07602 -266.502535) (xy 95.124239 -266.492691) (xy 95.173414 -266.49071)
			(xy 95.222269 -266.496642) (xy 95.26954 -266.510334) (xy 95.314002 -266.531432) (xy 95.354505 -266.559388)
			(xy 95.389998 -266.59348) (xy 95.419563 -266.632824) (xy 95.442434 -266.676401) (xy 95.458018 -266.723082)
			(xy 95.465913 -266.771659) (xy 95.466408 -266.796266) (xy 95.465913 -266.820873) (xy 95.458018 -266.86945)
			(xy 95.442434 -266.916131) (xy 95.419563 -266.959708) (xy 95.389998 -266.999052) (xy 95.354505 -267.033144)
			(xy 95.314002 -267.0611) (xy 95.26954 -267.082198) (xy 95.222269 -267.09589) (xy 95.173414 -267.101822)
			(xy 95.124239 -267.099841) (xy 95.07602 -267.089997) (xy 95.030004 -267.072545) (xy 94.987383 -267.047938)
			(xy 94.949262 -267.016813) (xy 94.916627 -266.979976) (xy 94.890324 -266.93838) (xy 94.871033 -266.893104)
			(xy 94.859256 -266.84532) (xy 94.855296 -266.796266) (xy 94.536768 -266.796266) (xy 94.536284 -266.821079)
			(xy 94.528526 -266.870094) (xy 94.513197 -266.917292) (xy 94.490673 -266.961511) (xy 94.461509 -267.001662)
			(xy 94.426423 -267.036757) (xy 94.386279 -267.065931) (xy 94.342066 -267.088466) (xy 94.294872 -267.103807)
			(xy 94.245859 -267.111578) (xy 94.221046 -267.111988) (xy 94.194809 -267.111471) (xy 94.143057 -267.102797)
			(xy 94.093454 -267.08568) (xy 94.047367 -267.060592) (xy 94.006065 -267.028224) (xy 93.970688 -266.989469)
			(xy 93.942211 -266.945395) (xy 93.921418 -266.897216) (xy 93.908883 -266.846262) (xy 93.90634 -266.820142)
			(xy 93.90634 -266.819634) (xy 93.905832 -266.81303) (xy 93.904997 -266.805741) (xy 93.899697 -266.792067)
			(xy 93.895418 -266.786106) (xy 93.89364 -266.78382) (xy 93.799406 -266.749276) (xy 93.790209 -266.746342)
			(xy 93.770927 -266.746852) (xy 93.7532 -266.754456) (xy 93.746066 -266.76096) (xy 93.518228 -266.988798)
			(xy 93.515688 -266.991592) (xy 93.514926 -266.992608) (xy 93.50626 -267.002711) (xy 93.487438 -267.021535)
			(xy 93.477334 -267.0302) (xy 93.476318 -267.030962) (xy 93.473524 -267.033502) (xy 93.161866 -267.34516)
			(xy 93.155147 -267.352396) (xy 93.147538 -267.370601) (xy 93.147134 -267.380466) (xy 93.147134 -267.606272)
			(xy 93.445342 -267.606272) (xy 93.449302 -267.557218) (xy 93.461079 -267.509434) (xy 93.48037 -267.464158)
			(xy 93.506673 -267.422562) (xy 93.539308 -267.385725) (xy 93.577429 -267.3546) (xy 93.62005 -267.329993)
			(xy 93.666066 -267.312541) (xy 93.714285 -267.302697) (xy 93.76346 -267.300716) (xy 93.812315 -267.306648)
			(xy 93.859586 -267.32034) (xy 93.904048 -267.341438) (xy 93.944551 -267.369394) (xy 93.980044 -267.403486)
			(xy 94.009609 -267.44283) (xy 94.03248 -267.486407) (xy 94.048064 -267.533088) (xy 94.055959 -267.581665)
			(xy 94.056454 -267.606272) (xy 94.374711 -267.606272) (xy 94.378806 -267.555544) (xy 94.390985 -267.50613)
			(xy 94.410933 -267.45931) (xy 94.438134 -267.416296) (xy 94.471882 -267.378202) (xy 94.511304 -267.346015)
			(xy 94.555378 -267.320569) (xy 94.602964 -267.302522) (xy 94.652828 -267.292342) (xy 94.70368 -267.290293)
			(xy 94.754201 -267.296427) (xy 94.803085 -267.310587) (xy 94.849064 -267.332404) (xy 94.890948 -267.361314)
			(xy 94.927652 -267.396569) (xy 94.958225 -267.437255) (xy 94.981876 -267.482318) (xy 94.997992 -267.530592)
			(xy 95.006156 -267.580826) (xy 95.006668 -267.606272) (xy 95.325196 -267.606272) (xy 95.329156 -267.557218)
			(xy 95.340933 -267.509434) (xy 95.360224 -267.464158) (xy 95.386527 -267.422562) (xy 95.419162 -267.385725)
			(xy 95.457283 -267.3546) (xy 95.499904 -267.329993) (xy 95.54592 -267.312541) (xy 95.594139 -267.302697)
			(xy 95.643314 -267.300716) (xy 95.692169 -267.306648) (xy 95.73944 -267.32034) (xy 95.783902 -267.341438)
			(xy 95.824405 -267.369394) (xy 95.859898 -267.403486) (xy 95.889463 -267.44283) (xy 95.912334 -267.486407)
			(xy 95.927918 -267.533088) (xy 95.935813 -267.581665) (xy 95.936308 -267.606272) (xy 96.26525 -267.606272)
			(xy 96.26921 -267.557218) (xy 96.280987 -267.509434) (xy 96.300278 -267.464158) (xy 96.326581 -267.422562)
			(xy 96.359216 -267.385725) (xy 96.397337 -267.3546) (xy 96.439958 -267.329993) (xy 96.485974 -267.312541)
			(xy 96.534193 -267.302697) (xy 96.583368 -267.300716) (xy 96.632223 -267.306648) (xy 96.679494 -267.32034)
			(xy 96.723956 -267.341438) (xy 96.764459 -267.369394) (xy 96.799952 -267.403486) (xy 96.829517 -267.44283)
			(xy 96.852388 -267.486407) (xy 96.867972 -267.533088) (xy 96.875867 -267.581665) (xy 96.876362 -267.606272)
			(xy 97.205304 -267.606272) (xy 97.209264 -267.557218) (xy 97.221041 -267.509434) (xy 97.240332 -267.464158)
			(xy 97.266635 -267.422562) (xy 97.29927 -267.385725) (xy 97.337391 -267.3546) (xy 97.380012 -267.329993)
			(xy 97.426028 -267.312541) (xy 97.474247 -267.302697) (xy 97.523422 -267.300716) (xy 97.572277 -267.306648)
			(xy 97.619548 -267.32034) (xy 97.66401 -267.341438) (xy 97.704513 -267.369394) (xy 97.740006 -267.403486)
			(xy 97.769571 -267.44283) (xy 97.792442 -267.486407) (xy 97.808026 -267.533088) (xy 97.815921 -267.581665)
			(xy 97.816416 -267.606272) (xy 98.145358 -267.606272) (xy 98.149318 -267.557218) (xy 98.161095 -267.509434)
			(xy 98.180386 -267.464158) (xy 98.206689 -267.422562) (xy 98.239324 -267.385725) (xy 98.277445 -267.3546)
			(xy 98.320066 -267.329993) (xy 98.366082 -267.312541) (xy 98.414301 -267.302697) (xy 98.463476 -267.300716)
			(xy 98.512331 -267.306648) (xy 98.559602 -267.32034) (xy 98.604064 -267.341438) (xy 98.644567 -267.369394)
			(xy 98.68006 -267.403486) (xy 98.709625 -267.44283) (xy 98.732496 -267.486407) (xy 98.74808 -267.533088)
			(xy 98.755975 -267.581665) (xy 98.75647 -267.606272) (xy 99.085158 -267.606272) (xy 99.089118 -267.557218)
			(xy 99.100895 -267.509434) (xy 99.120186 -267.464158) (xy 99.146489 -267.422562) (xy 99.179124 -267.385725)
			(xy 99.217245 -267.3546) (xy 99.259866 -267.329993) (xy 99.305882 -267.312541) (xy 99.354101 -267.302697)
			(xy 99.403276 -267.300716) (xy 99.452131 -267.306648) (xy 99.499402 -267.32034) (xy 99.543864 -267.341438)
			(xy 99.584367 -267.369394) (xy 99.61986 -267.403486) (xy 99.649425 -267.44283) (xy 99.672296 -267.486407)
			(xy 99.68788 -267.533088) (xy 99.695775 -267.581665) (xy 99.69627 -267.606272) (xy 100.025212 -267.606272)
			(xy 100.029172 -267.557218) (xy 100.040949 -267.509434) (xy 100.06024 -267.464158) (xy 100.086543 -267.422562)
			(xy 100.119178 -267.385725) (xy 100.157299 -267.3546) (xy 100.19992 -267.329993) (xy 100.245936 -267.312541)
			(xy 100.294155 -267.302697) (xy 100.34333 -267.300716) (xy 100.392185 -267.306648) (xy 100.439456 -267.32034)
			(xy 100.483918 -267.341438) (xy 100.524421 -267.369394) (xy 100.559914 -267.403486) (xy 100.589479 -267.44283)
			(xy 100.61235 -267.486407) (xy 100.627934 -267.533088) (xy 100.635829 -267.581665) (xy 100.636324 -267.606272)
			(xy 100.635829 -267.630879) (xy 100.627934 -267.679456) (xy 100.61235 -267.726137) (xy 100.589479 -267.769714)
			(xy 100.559914 -267.809058) (xy 100.524421 -267.84315) (xy 100.483918 -267.871106) (xy 100.439456 -267.892204)
			(xy 100.392185 -267.905896) (xy 100.34333 -267.911828) (xy 100.294155 -267.909847) (xy 100.245936 -267.900003)
			(xy 100.19992 -267.882551) (xy 100.157299 -267.857944) (xy 100.119178 -267.826819) (xy 100.086543 -267.789982)
			(xy 100.06024 -267.748386) (xy 100.040949 -267.70311) (xy 100.029172 -267.655326) (xy 100.025212 -267.606272)
			(xy 99.69627 -267.606272) (xy 99.695775 -267.630879) (xy 99.68788 -267.679456) (xy 99.672296 -267.726137)
			(xy 99.649425 -267.769714) (xy 99.61986 -267.809058) (xy 99.584367 -267.84315) (xy 99.543864 -267.871106)
			(xy 99.499402 -267.892204) (xy 99.452131 -267.905896) (xy 99.403276 -267.911828) (xy 99.354101 -267.909847)
			(xy 99.305882 -267.900003) (xy 99.259866 -267.882551) (xy 99.217245 -267.857944) (xy 99.179124 -267.826819)
			(xy 99.146489 -267.789982) (xy 99.120186 -267.748386) (xy 99.100895 -267.70311) (xy 99.089118 -267.655326)
			(xy 99.085158 -267.606272) (xy 98.75647 -267.606272) (xy 98.755975 -267.630879) (xy 98.74808 -267.679456)
			(xy 98.732496 -267.726137) (xy 98.709625 -267.769714) (xy 98.68006 -267.809058) (xy 98.644567 -267.84315)
			(xy 98.604064 -267.871106) (xy 98.559602 -267.892204) (xy 98.512331 -267.905896) (xy 98.463476 -267.911828)
			(xy 98.414301 -267.909847) (xy 98.366082 -267.900003) (xy 98.320066 -267.882551) (xy 98.277445 -267.857944)
			(xy 98.239324 -267.826819) (xy 98.206689 -267.789982) (xy 98.180386 -267.748386) (xy 98.161095 -267.70311)
			(xy 98.149318 -267.655326) (xy 98.145358 -267.606272) (xy 97.816416 -267.606272) (xy 97.815921 -267.630879)
			(xy 97.808026 -267.679456) (xy 97.792442 -267.726137) (xy 97.769571 -267.769714) (xy 97.740006 -267.809058)
			(xy 97.704513 -267.84315) (xy 97.66401 -267.871106) (xy 97.619548 -267.892204) (xy 97.572277 -267.905896)
			(xy 97.523422 -267.911828) (xy 97.474247 -267.909847) (xy 97.426028 -267.900003) (xy 97.380012 -267.882551)
			(xy 97.337391 -267.857944) (xy 97.29927 -267.826819) (xy 97.266635 -267.789982) (xy 97.240332 -267.748386)
			(xy 97.221041 -267.70311) (xy 97.209264 -267.655326) (xy 97.205304 -267.606272) (xy 96.876362 -267.606272)
			(xy 96.875867 -267.630879) (xy 96.867972 -267.679456) (xy 96.852388 -267.726137) (xy 96.829517 -267.769714)
			(xy 96.799952 -267.809058) (xy 96.764459 -267.84315) (xy 96.723956 -267.871106) (xy 96.679494 -267.892204)
			(xy 96.632223 -267.905896) (xy 96.583368 -267.911828) (xy 96.534193 -267.909847) (xy 96.485974 -267.900003)
			(xy 96.439958 -267.882551) (xy 96.397337 -267.857944) (xy 96.359216 -267.826819) (xy 96.326581 -267.789982)
			(xy 96.300278 -267.748386) (xy 96.280987 -267.70311) (xy 96.26921 -267.655326) (xy 96.26525 -267.606272)
			(xy 95.936308 -267.606272) (xy 95.935813 -267.630879) (xy 95.927918 -267.679456) (xy 95.912334 -267.726137)
			(xy 95.889463 -267.769714) (xy 95.859898 -267.809058) (xy 95.824405 -267.84315) (xy 95.783902 -267.871106)
			(xy 95.73944 -267.892204) (xy 95.692169 -267.905896) (xy 95.643314 -267.911828) (xy 95.594139 -267.909847)
			(xy 95.54592 -267.900003) (xy 95.499904 -267.882551) (xy 95.457283 -267.857944) (xy 95.419162 -267.826819)
			(xy 95.386527 -267.789982) (xy 95.360224 -267.748386) (xy 95.340933 -267.70311) (xy 95.329156 -267.655326)
			(xy 95.325196 -267.606272) (xy 95.006668 -267.606272) (xy 95.006156 -267.631718) (xy 94.997992 -267.681952)
			(xy 94.981876 -267.730226) (xy 94.958225 -267.775289) (xy 94.927652 -267.815975) (xy 94.890948 -267.85123)
			(xy 94.849064 -267.88014) (xy 94.803085 -267.901957) (xy 94.754201 -267.916117) (xy 94.70368 -267.922251)
			(xy 94.652828 -267.920202) (xy 94.602964 -267.910022) (xy 94.555378 -267.891975) (xy 94.511304 -267.866529)
			(xy 94.471882 -267.834342) (xy 94.438134 -267.796248) (xy 94.410933 -267.753234) (xy 94.390985 -267.706414)
			(xy 94.378806 -267.657) (xy 94.374711 -267.606272) (xy 94.056454 -267.606272) (xy 94.055959 -267.630879)
			(xy 94.048064 -267.679456) (xy 94.03248 -267.726137) (xy 94.009609 -267.769714) (xy 93.980044 -267.809058)
			(xy 93.944551 -267.84315) (xy 93.904048 -267.871106) (xy 93.859586 -267.892204) (xy 93.812315 -267.905896)
			(xy 93.76346 -267.911828) (xy 93.714285 -267.909847) (xy 93.666066 -267.900003) (xy 93.62005 -267.882551)
			(xy 93.577429 -267.857944) (xy 93.539308 -267.826819) (xy 93.506673 -267.789982) (xy 93.48037 -267.748386)
			(xy 93.461079 -267.70311) (xy 93.449302 -267.655326) (xy 93.445342 -267.606272) (xy 93.147134 -267.606272)
			(xy 93.147134 -268.005814) (xy 111.710473 -268.005814) (xy 111.714503 -267.953316) (xy 111.7265 -267.902048)
			(xy 111.746183 -267.853213) (xy 111.773089 -267.807954) (xy 111.806589 -267.767333) (xy 111.845897 -267.732302)
			(xy 111.890092 -267.703682) (xy 111.938137 -267.682143) (xy 111.988908 -267.668191) (xy 112.041213 -267.662153)
			(xy 112.093827 -267.66417) (xy 112.145517 -267.674194) (xy 112.19507 -267.691992) (xy 112.241326 -267.717145)
			(xy 112.2832 -267.749064) (xy 112.319712 -267.787002) (xy 112.350004 -267.830068) (xy 112.373367 -267.877253)
			(xy 112.389253 -267.927452) (xy 112.39729 -267.979488) (xy 112.397794 -268.005814) (xy 112.39729 -268.03214)
			(xy 112.389253 -268.084176) (xy 112.373367 -268.134375) (xy 112.350004 -268.18156) (xy 112.319712 -268.224626)
			(xy 112.2832 -268.262564) (xy 112.241326 -268.294483) (xy 112.19507 -268.319636) (xy 112.145517 -268.337434)
			(xy 112.093827 -268.347458) (xy 112.041213 -268.349475) (xy 111.988908 -268.343437) (xy 111.938137 -268.329485)
			(xy 111.890092 -268.307946) (xy 111.845897 -268.279326) (xy 111.806589 -268.244295) (xy 111.773089 -268.203674)
			(xy 111.746183 -268.158415) (xy 111.7265 -268.10958) (xy 111.714503 -268.058312) (xy 111.710473 -268.005814)
			(xy 93.147134 -268.005814) (xy 93.147134 -268.012164) (xy 93.147719 -268.022699) (xy 93.156248 -268.041976)
			(xy 93.163644 -268.049502) (xy 93.219778 -268.101064) (xy 93.227387 -268.106649) (xy 93.245395 -268.112259)
			(xy 93.25483 -268.111986) (xy 93.2561 -268.111986) (xy 93.257878 -268.111732) (xy 93.277436 -268.11097)
			(xy 93.282262 -268.11097) (xy 93.307451 -268.11159) (xy 93.357115 -268.120067) (xy 93.404713 -268.136581)
			(xy 93.448955 -268.160685) (xy 93.488639 -268.191726) (xy 93.52269 -268.22886) (xy 93.550182 -268.27108)
			(xy 93.57037 -268.317241) (xy 93.582706 -268.366089) (xy 93.586854 -268.416278) (xy 93.915242 -268.416278)
			(xy 93.919202 -268.367224) (xy 93.930979 -268.31944) (xy 93.95027 -268.274164) (xy 93.976573 -268.232568)
			(xy 94.009208 -268.195731) (xy 94.047329 -268.164606) (xy 94.08995 -268.139999) (xy 94.135966 -268.122547)
			(xy 94.184185 -268.112703) (xy 94.23336 -268.110722) (xy 94.282215 -268.116654) (xy 94.329486 -268.130346)
			(xy 94.373948 -268.151444) (xy 94.414451 -268.1794) (xy 94.449944 -268.213492) (xy 94.479509 -268.252836)
			(xy 94.50238 -268.296413) (xy 94.517964 -268.343094) (xy 94.525859 -268.391671) (xy 94.526354 -268.416278)
			(xy 94.855296 -268.416278) (xy 94.859256 -268.367224) (xy 94.871033 -268.31944) (xy 94.890324 -268.274164)
			(xy 94.916627 -268.232568) (xy 94.949262 -268.195731) (xy 94.987383 -268.164606) (xy 95.030004 -268.139999)
			(xy 95.07602 -268.122547) (xy 95.124239 -268.112703) (xy 95.173414 -268.110722) (xy 95.222269 -268.116654)
			(xy 95.26954 -268.130346) (xy 95.314002 -268.151444) (xy 95.354505 -268.1794) (xy 95.389998 -268.213492)
			(xy 95.419563 -268.252836) (xy 95.442434 -268.296413) (xy 95.458018 -268.343094) (xy 95.465913 -268.391671)
			(xy 95.466408 -268.416278) (xy 95.79535 -268.416278) (xy 95.79931 -268.367224) (xy 95.811087 -268.31944)
			(xy 95.830378 -268.274164) (xy 95.856681 -268.232568) (xy 95.889316 -268.195731) (xy 95.927437 -268.164606)
			(xy 95.970058 -268.139999) (xy 96.016074 -268.122547) (xy 96.064293 -268.112703) (xy 96.113468 -268.110722)
			(xy 96.162323 -268.116654) (xy 96.209594 -268.130346) (xy 96.254056 -268.151444) (xy 96.294559 -268.1794)
			(xy 96.330052 -268.213492) (xy 96.359617 -268.252836) (xy 96.382488 -268.296413) (xy 96.398072 -268.343094)
			(xy 96.405967 -268.391671) (xy 96.406462 -268.416278) (xy 96.73515 -268.416278) (xy 96.73911 -268.367224)
			(xy 96.750887 -268.31944) (xy 96.770178 -268.274164) (xy 96.796481 -268.232568) (xy 96.829116 -268.195731)
			(xy 96.867237 -268.164606) (xy 96.909858 -268.139999) (xy 96.955874 -268.122547) (xy 97.004093 -268.112703)
			(xy 97.053268 -268.110722) (xy 97.102123 -268.116654) (xy 97.149394 -268.130346) (xy 97.193856 -268.151444)
			(xy 97.234359 -268.1794) (xy 97.269852 -268.213492) (xy 97.299417 -268.252836) (xy 97.322288 -268.296413)
			(xy 97.337872 -268.343094) (xy 97.345767 -268.391671) (xy 97.346262 -268.416278) (xy 97.675204 -268.416278)
			(xy 97.679164 -268.367224) (xy 97.690941 -268.31944) (xy 97.710232 -268.274164) (xy 97.736535 -268.232568)
			(xy 97.76917 -268.195731) (xy 97.807291 -268.164606) (xy 97.849912 -268.139999) (xy 97.895928 -268.122547)
			(xy 97.944147 -268.112703) (xy 97.993322 -268.110722) (xy 98.042177 -268.116654) (xy 98.089448 -268.130346)
			(xy 98.13391 -268.151444) (xy 98.174413 -268.1794) (xy 98.209906 -268.213492) (xy 98.239471 -268.252836)
			(xy 98.262342 -268.296413) (xy 98.277926 -268.343094) (xy 98.285821 -268.391671) (xy 98.286316 -268.416278)
			(xy 99.555312 -268.416278) (xy 99.559272 -268.367224) (xy 99.571049 -268.31944) (xy 99.59034 -268.274164)
			(xy 99.616643 -268.232568) (xy 99.649278 -268.195731) (xy 99.687399 -268.164606) (xy 99.73002 -268.139999)
			(xy 99.776036 -268.122547) (xy 99.824255 -268.112703) (xy 99.87343 -268.110722) (xy 99.922285 -268.116654)
			(xy 99.969556 -268.130346) (xy 100.014018 -268.151444) (xy 100.054521 -268.1794) (xy 100.090014 -268.213492)
			(xy 100.119579 -268.252836) (xy 100.14245 -268.296413) (xy 100.158034 -268.343094) (xy 100.165929 -268.391671)
			(xy 100.166424 -268.416278) (xy 101.435166 -268.416278) (xy 101.439126 -268.367224) (xy 101.450903 -268.31944)
			(xy 101.470194 -268.274164) (xy 101.496497 -268.232568) (xy 101.529132 -268.195731) (xy 101.567253 -268.164606)
			(xy 101.609874 -268.139999) (xy 101.65589 -268.122547) (xy 101.704109 -268.112703) (xy 101.753284 -268.110722)
			(xy 101.802139 -268.116654) (xy 101.84941 -268.130346) (xy 101.893872 -268.151444) (xy 101.934375 -268.1794)
			(xy 101.969868 -268.213492) (xy 101.999433 -268.252836) (xy 102.022304 -268.296413) (xy 102.037888 -268.343094)
			(xy 102.045783 -268.391671) (xy 102.046278 -268.416278) (xy 103.315274 -268.416278) (xy 103.319234 -268.367224)
			(xy 103.331011 -268.31944) (xy 103.350302 -268.274164) (xy 103.376605 -268.232568) (xy 103.40924 -268.195731)
			(xy 103.447361 -268.164606) (xy 103.489982 -268.139999) (xy 103.535998 -268.122547) (xy 103.584217 -268.112703)
			(xy 103.633392 -268.110722) (xy 103.682247 -268.116654) (xy 103.729518 -268.130346) (xy 103.77398 -268.151444)
			(xy 103.814483 -268.1794) (xy 103.849976 -268.213492) (xy 103.879541 -268.252836) (xy 103.902412 -268.296413)
			(xy 103.917996 -268.343094) (xy 103.925891 -268.391671) (xy 103.926386 -268.416278) (xy 105.195128 -268.416278)
			(xy 105.199088 -268.367224) (xy 105.210865 -268.31944) (xy 105.230156 -268.274164) (xy 105.256459 -268.232568)
			(xy 105.289094 -268.195731) (xy 105.327215 -268.164606) (xy 105.369836 -268.139999) (xy 105.415852 -268.122547)
			(xy 105.464071 -268.112703) (xy 105.513246 -268.110722) (xy 105.562101 -268.116654) (xy 105.609372 -268.130346)
			(xy 105.653834 -268.151444) (xy 105.694337 -268.1794) (xy 105.72983 -268.213492) (xy 105.759395 -268.252836)
			(xy 105.782266 -268.296413) (xy 105.79785 -268.343094) (xy 105.805745 -268.391671) (xy 105.80624 -268.416278)
			(xy 107.075236 -268.416278) (xy 107.079196 -268.367224) (xy 107.090973 -268.31944) (xy 107.110264 -268.274164)
			(xy 107.136567 -268.232568) (xy 107.169202 -268.195731) (xy 107.207323 -268.164606) (xy 107.249944 -268.139999)
			(xy 107.29596 -268.122547) (xy 107.344179 -268.112703) (xy 107.393354 -268.110722) (xy 107.442209 -268.116654)
			(xy 107.48948 -268.130346) (xy 107.533942 -268.151444) (xy 107.574445 -268.1794) (xy 107.609938 -268.213492)
			(xy 107.639503 -268.252836) (xy 107.662374 -268.296413) (xy 107.677958 -268.343094) (xy 107.685853 -268.391671)
			(xy 107.686348 -268.416278) (xy 108.955344 -268.416278) (xy 108.959304 -268.367224) (xy 108.971081 -268.31944)
			(xy 108.990372 -268.274164) (xy 109.016675 -268.232568) (xy 109.04931 -268.195731) (xy 109.087431 -268.164606)
			(xy 109.130052 -268.139999) (xy 109.176068 -268.122547) (xy 109.224287 -268.112703) (xy 109.273462 -268.110722)
			(xy 109.322317 -268.116654) (xy 109.369588 -268.130346) (xy 109.41405 -268.151444) (xy 109.454553 -268.1794)
			(xy 109.490046 -268.213492) (xy 109.519611 -268.252836) (xy 109.542482 -268.296413) (xy 109.558066 -268.343094)
			(xy 109.565961 -268.391671) (xy 109.566456 -268.416278) (xy 113.64901 -268.416278) (xy 113.65297 -268.367224)
			(xy 113.664747 -268.31944) (xy 113.684038 -268.274164) (xy 113.710341 -268.232568) (xy 113.742976 -268.195731)
			(xy 113.781097 -268.164606) (xy 113.823718 -268.139999) (xy 113.869734 -268.122547) (xy 113.917953 -268.112703)
			(xy 113.967128 -268.110722) (xy 114.015983 -268.116654) (xy 114.063254 -268.130346) (xy 114.107716 -268.151444)
			(xy 114.148219 -268.1794) (xy 114.183712 -268.213492) (xy 114.213277 -268.252836) (xy 114.236148 -268.296413)
			(xy 114.251732 -268.343094) (xy 114.259627 -268.391671) (xy 114.260122 -268.416278) (xy 115.528864 -268.416278)
			(xy 115.532824 -268.367224) (xy 115.544601 -268.31944) (xy 115.563892 -268.274164) (xy 115.590195 -268.232568)
			(xy 115.62283 -268.195731) (xy 115.660951 -268.164606) (xy 115.703572 -268.139999) (xy 115.749588 -268.122547)
			(xy 115.797807 -268.112703) (xy 115.846982 -268.110722) (xy 115.895837 -268.116654) (xy 115.943108 -268.130346)
			(xy 115.98757 -268.151444) (xy 116.028073 -268.1794) (xy 116.063566 -268.213492) (xy 116.093131 -268.252836)
			(xy 116.116002 -268.296413) (xy 116.131586 -268.343094) (xy 116.139481 -268.391671) (xy 116.139976 -268.416278)
			(xy 117.408972 -268.416278) (xy 117.412932 -268.367224) (xy 117.424709 -268.31944) (xy 117.444 -268.274164)
			(xy 117.470303 -268.232568) (xy 117.502938 -268.195731) (xy 117.541059 -268.164606) (xy 117.58368 -268.139999)
			(xy 117.629696 -268.122547) (xy 117.677915 -268.112703) (xy 117.72709 -268.110722) (xy 117.775945 -268.116654)
			(xy 117.823216 -268.130346) (xy 117.867678 -268.151444) (xy 117.908181 -268.1794) (xy 117.943674 -268.213492)
			(xy 117.973239 -268.252836) (xy 117.99611 -268.296413) (xy 118.011694 -268.343094) (xy 118.019589 -268.391671)
			(xy 118.020084 -268.416278) (xy 119.288826 -268.416278) (xy 119.292786 -268.367224) (xy 119.304563 -268.31944)
			(xy 119.323854 -268.274164) (xy 119.350157 -268.232568) (xy 119.382792 -268.195731) (xy 119.420913 -268.164606)
			(xy 119.463534 -268.139999) (xy 119.50955 -268.122547) (xy 119.557769 -268.112703) (xy 119.606944 -268.110722)
			(xy 119.655799 -268.116654) (xy 119.70307 -268.130346) (xy 119.747532 -268.151444) (xy 119.788035 -268.1794)
			(xy 119.823528 -268.213492) (xy 119.853093 -268.252836) (xy 119.875964 -268.296413) (xy 119.891548 -268.343094)
			(xy 119.899443 -268.391671) (xy 119.899938 -268.416278) (xy 121.168934 -268.416278) (xy 121.172894 -268.367224)
			(xy 121.184671 -268.31944) (xy 121.203962 -268.274164) (xy 121.230265 -268.232568) (xy 121.2629 -268.195731)
			(xy 121.301021 -268.164606) (xy 121.343642 -268.139999) (xy 121.389658 -268.122547) (xy 121.437877 -268.112703)
			(xy 121.487052 -268.110722) (xy 121.535907 -268.116654) (xy 121.583178 -268.130346) (xy 121.62764 -268.151444)
			(xy 121.668143 -268.1794) (xy 121.703636 -268.213492) (xy 121.733201 -268.252836) (xy 121.756072 -268.296413)
			(xy 121.771656 -268.343094) (xy 121.779551 -268.391671) (xy 121.780046 -268.416278) (xy 123.049042 -268.416278)
			(xy 123.053002 -268.367224) (xy 123.064779 -268.31944) (xy 123.08407 -268.274164) (xy 123.110373 -268.232568)
			(xy 123.143008 -268.195731) (xy 123.181129 -268.164606) (xy 123.22375 -268.139999) (xy 123.269766 -268.122547)
			(xy 123.317985 -268.112703) (xy 123.36716 -268.110722) (xy 123.416015 -268.116654) (xy 123.463286 -268.130346)
			(xy 123.507748 -268.151444) (xy 123.548251 -268.1794) (xy 123.583744 -268.213492) (xy 123.613309 -268.252836)
			(xy 123.63618 -268.296413) (xy 123.651764 -268.343094) (xy 123.659659 -268.391671) (xy 123.660154 -268.416278)
			(xy 124.928896 -268.416278) (xy 124.932856 -268.367224) (xy 124.944633 -268.31944) (xy 124.963924 -268.274164)
			(xy 124.990227 -268.232568) (xy 125.022862 -268.195731) (xy 125.060983 -268.164606) (xy 125.103604 -268.139999)
			(xy 125.14962 -268.122547) (xy 125.197839 -268.112703) (xy 125.247014 -268.110722) (xy 125.295869 -268.116654)
			(xy 125.34314 -268.130346) (xy 125.387602 -268.151444) (xy 125.428105 -268.1794) (xy 125.463598 -268.213492)
			(xy 125.493163 -268.252836) (xy 125.516034 -268.296413) (xy 125.531618 -268.343094) (xy 125.539513 -268.391671)
			(xy 125.540008 -268.416278) (xy 125.539513 -268.440885) (xy 125.531618 -268.489462) (xy 125.516034 -268.536143)
			(xy 125.493163 -268.57972) (xy 125.463598 -268.619064) (xy 125.428105 -268.653156) (xy 125.387602 -268.681112)
			(xy 125.34314 -268.70221) (xy 125.295869 -268.715902) (xy 125.247014 -268.721834) (xy 125.197839 -268.719853)
			(xy 125.14962 -268.710009) (xy 125.103604 -268.692557) (xy 125.060983 -268.66795) (xy 125.022862 -268.636825)
			(xy 124.990227 -268.599988) (xy 124.963924 -268.558392) (xy 124.944633 -268.513116) (xy 124.932856 -268.465332)
			(xy 124.928896 -268.416278) (xy 123.660154 -268.416278) (xy 123.659659 -268.440885) (xy 123.651764 -268.489462)
			(xy 123.63618 -268.536143) (xy 123.613309 -268.57972) (xy 123.583744 -268.619064) (xy 123.548251 -268.653156)
			(xy 123.507748 -268.681112) (xy 123.463286 -268.70221) (xy 123.416015 -268.715902) (xy 123.36716 -268.721834)
			(xy 123.317985 -268.719853) (xy 123.269766 -268.710009) (xy 123.22375 -268.692557) (xy 123.181129 -268.66795)
			(xy 123.143008 -268.636825) (xy 123.110373 -268.599988) (xy 123.08407 -268.558392) (xy 123.064779 -268.513116)
			(xy 123.053002 -268.465332) (xy 123.049042 -268.416278) (xy 121.780046 -268.416278) (xy 121.779551 -268.440885)
			(xy 121.771656 -268.489462) (xy 121.756072 -268.536143) (xy 121.733201 -268.57972) (xy 121.703636 -268.619064)
			(xy 121.668143 -268.653156) (xy 121.62764 -268.681112) (xy 121.583178 -268.70221) (xy 121.535907 -268.715902)
			(xy 121.487052 -268.721834) (xy 121.437877 -268.719853) (xy 121.389658 -268.710009) (xy 121.343642 -268.692557)
			(xy 121.301021 -268.66795) (xy 121.2629 -268.636825) (xy 121.230265 -268.599988) (xy 121.203962 -268.558392)
			(xy 121.184671 -268.513116) (xy 121.172894 -268.465332) (xy 121.168934 -268.416278) (xy 119.899938 -268.416278)
			(xy 119.899443 -268.440885) (xy 119.891548 -268.489462) (xy 119.875964 -268.536143) (xy 119.853093 -268.57972)
			(xy 119.823528 -268.619064) (xy 119.788035 -268.653156) (xy 119.747532 -268.681112) (xy 119.70307 -268.70221)
			(xy 119.655799 -268.715902) (xy 119.606944 -268.721834) (xy 119.557769 -268.719853) (xy 119.50955 -268.710009)
			(xy 119.463534 -268.692557) (xy 119.420913 -268.66795) (xy 119.382792 -268.636825) (xy 119.350157 -268.599988)
			(xy 119.323854 -268.558392) (xy 119.304563 -268.513116) (xy 119.292786 -268.465332) (xy 119.288826 -268.416278)
			(xy 118.020084 -268.416278) (xy 118.019589 -268.440885) (xy 118.011694 -268.489462) (xy 117.99611 -268.536143)
			(xy 117.973239 -268.57972) (xy 117.943674 -268.619064) (xy 117.908181 -268.653156) (xy 117.867678 -268.681112)
			(xy 117.823216 -268.70221) (xy 117.775945 -268.715902) (xy 117.72709 -268.721834) (xy 117.677915 -268.719853)
			(xy 117.629696 -268.710009) (xy 117.58368 -268.692557) (xy 117.541059 -268.66795) (xy 117.502938 -268.636825)
			(xy 117.470303 -268.599988) (xy 117.444 -268.558392) (xy 117.424709 -268.513116) (xy 117.412932 -268.465332)
			(xy 117.408972 -268.416278) (xy 116.139976 -268.416278) (xy 116.139481 -268.440885) (xy 116.131586 -268.489462)
			(xy 116.116002 -268.536143) (xy 116.093131 -268.57972) (xy 116.063566 -268.619064) (xy 116.028073 -268.653156)
			(xy 115.98757 -268.681112) (xy 115.943108 -268.70221) (xy 115.895837 -268.715902) (xy 115.846982 -268.721834)
			(xy 115.797807 -268.719853) (xy 115.749588 -268.710009) (xy 115.703572 -268.692557) (xy 115.660951 -268.66795)
			(xy 115.62283 -268.636825) (xy 115.590195 -268.599988) (xy 115.563892 -268.558392) (xy 115.544601 -268.513116)
			(xy 115.532824 -268.465332) (xy 115.528864 -268.416278) (xy 114.260122 -268.416278) (xy 114.259627 -268.440885)
			(xy 114.251732 -268.489462) (xy 114.236148 -268.536143) (xy 114.213277 -268.57972) (xy 114.183712 -268.619064)
			(xy 114.148219 -268.653156) (xy 114.107716 -268.681112) (xy 114.063254 -268.70221) (xy 114.015983 -268.715902)
			(xy 113.967128 -268.721834) (xy 113.917953 -268.719853) (xy 113.869734 -268.710009) (xy 113.823718 -268.692557)
			(xy 113.781097 -268.66795) (xy 113.742976 -268.636825) (xy 113.710341 -268.599988) (xy 113.684038 -268.558392)
			(xy 113.664747 -268.513116) (xy 113.65297 -268.465332) (xy 113.64901 -268.416278) (xy 109.566456 -268.416278)
			(xy 109.565961 -268.440885) (xy 109.558066 -268.489462) (xy 109.542482 -268.536143) (xy 109.519611 -268.57972)
			(xy 109.490046 -268.619064) (xy 109.454553 -268.653156) (xy 109.41405 -268.681112) (xy 109.369588 -268.70221)
			(xy 109.322317 -268.715902) (xy 109.273462 -268.721834) (xy 109.224287 -268.719853) (xy 109.176068 -268.710009)
			(xy 109.130052 -268.692557) (xy 109.087431 -268.66795) (xy 109.04931 -268.636825) (xy 109.016675 -268.599988)
			(xy 108.990372 -268.558392) (xy 108.971081 -268.513116) (xy 108.959304 -268.465332) (xy 108.955344 -268.416278)
			(xy 107.686348 -268.416278) (xy 107.685853 -268.440885) (xy 107.677958 -268.489462) (xy 107.662374 -268.536143)
			(xy 107.639503 -268.57972) (xy 107.609938 -268.619064) (xy 107.574445 -268.653156) (xy 107.533942 -268.681112)
			(xy 107.48948 -268.70221) (xy 107.442209 -268.715902) (xy 107.393354 -268.721834) (xy 107.344179 -268.719853)
			(xy 107.29596 -268.710009) (xy 107.249944 -268.692557) (xy 107.207323 -268.66795) (xy 107.169202 -268.636825)
			(xy 107.136567 -268.599988) (xy 107.110264 -268.558392) (xy 107.090973 -268.513116) (xy 107.079196 -268.465332)
			(xy 107.075236 -268.416278) (xy 105.80624 -268.416278) (xy 105.805745 -268.440885) (xy 105.79785 -268.489462)
			(xy 105.782266 -268.536143) (xy 105.759395 -268.57972) (xy 105.72983 -268.619064) (xy 105.694337 -268.653156)
			(xy 105.653834 -268.681112) (xy 105.609372 -268.70221) (xy 105.562101 -268.715902) (xy 105.513246 -268.721834)
			(xy 105.464071 -268.719853) (xy 105.415852 -268.710009) (xy 105.369836 -268.692557) (xy 105.327215 -268.66795)
			(xy 105.289094 -268.636825) (xy 105.256459 -268.599988) (xy 105.230156 -268.558392) (xy 105.210865 -268.513116)
			(xy 105.199088 -268.465332) (xy 105.195128 -268.416278) (xy 103.926386 -268.416278) (xy 103.925891 -268.440885)
			(xy 103.917996 -268.489462) (xy 103.902412 -268.536143) (xy 103.879541 -268.57972) (xy 103.849976 -268.619064)
			(xy 103.814483 -268.653156) (xy 103.77398 -268.681112) (xy 103.729518 -268.70221) (xy 103.682247 -268.715902)
			(xy 103.633392 -268.721834) (xy 103.584217 -268.719853) (xy 103.535998 -268.710009) (xy 103.489982 -268.692557)
			(xy 103.447361 -268.66795) (xy 103.40924 -268.636825) (xy 103.376605 -268.599988) (xy 103.350302 -268.558392)
			(xy 103.331011 -268.513116) (xy 103.319234 -268.465332) (xy 103.315274 -268.416278) (xy 102.046278 -268.416278)
			(xy 102.045783 -268.440885) (xy 102.037888 -268.489462) (xy 102.022304 -268.536143) (xy 101.999433 -268.57972)
			(xy 101.969868 -268.619064) (xy 101.934375 -268.653156) (xy 101.893872 -268.681112) (xy 101.84941 -268.70221)
			(xy 101.802139 -268.715902) (xy 101.753284 -268.721834) (xy 101.704109 -268.719853) (xy 101.65589 -268.710009)
			(xy 101.609874 -268.692557) (xy 101.567253 -268.66795) (xy 101.529132 -268.636825) (xy 101.496497 -268.599988)
			(xy 101.470194 -268.558392) (xy 101.450903 -268.513116) (xy 101.439126 -268.465332) (xy 101.435166 -268.416278)
			(xy 100.166424 -268.416278) (xy 100.165929 -268.440885) (xy 100.158034 -268.489462) (xy 100.14245 -268.536143)
			(xy 100.119579 -268.57972) (xy 100.090014 -268.619064) (xy 100.054521 -268.653156) (xy 100.014018 -268.681112)
			(xy 99.969556 -268.70221) (xy 99.922285 -268.715902) (xy 99.87343 -268.721834) (xy 99.824255 -268.719853)
			(xy 99.776036 -268.710009) (xy 99.73002 -268.692557) (xy 99.687399 -268.66795) (xy 99.649278 -268.636825)
			(xy 99.616643 -268.599988) (xy 99.59034 -268.558392) (xy 99.571049 -268.513116) (xy 99.559272 -268.465332)
			(xy 99.555312 -268.416278) (xy 98.286316 -268.416278) (xy 98.285821 -268.440885) (xy 98.277926 -268.489462)
			(xy 98.262342 -268.536143) (xy 98.239471 -268.57972) (xy 98.209906 -268.619064) (xy 98.174413 -268.653156)
			(xy 98.13391 -268.681112) (xy 98.089448 -268.70221) (xy 98.042177 -268.715902) (xy 97.993322 -268.721834)
			(xy 97.944147 -268.719853) (xy 97.895928 -268.710009) (xy 97.849912 -268.692557) (xy 97.807291 -268.66795)
			(xy 97.76917 -268.636825) (xy 97.736535 -268.599988) (xy 97.710232 -268.558392) (xy 97.690941 -268.513116)
			(xy 97.679164 -268.465332) (xy 97.675204 -268.416278) (xy 97.346262 -268.416278) (xy 97.345767 -268.440885)
			(xy 97.337872 -268.489462) (xy 97.322288 -268.536143) (xy 97.299417 -268.57972) (xy 97.269852 -268.619064)
			(xy 97.234359 -268.653156) (xy 97.193856 -268.681112) (xy 97.149394 -268.70221) (xy 97.102123 -268.715902)
			(xy 97.053268 -268.721834) (xy 97.004093 -268.719853) (xy 96.955874 -268.710009) (xy 96.909858 -268.692557)
			(xy 96.867237 -268.66795) (xy 96.829116 -268.636825) (xy 96.796481 -268.599988) (xy 96.770178 -268.558392)
			(xy 96.750887 -268.513116) (xy 96.73911 -268.465332) (xy 96.73515 -268.416278) (xy 96.406462 -268.416278)
			(xy 96.405967 -268.440885) (xy 96.398072 -268.489462) (xy 96.382488 -268.536143) (xy 96.359617 -268.57972)
			(xy 96.330052 -268.619064) (xy 96.294559 -268.653156) (xy 96.254056 -268.681112) (xy 96.209594 -268.70221)
			(xy 96.162323 -268.715902) (xy 96.113468 -268.721834) (xy 96.064293 -268.719853) (xy 96.016074 -268.710009)
			(xy 95.970058 -268.692557) (xy 95.927437 -268.66795) (xy 95.889316 -268.636825) (xy 95.856681 -268.599988)
			(xy 95.830378 -268.558392) (xy 95.811087 -268.513116) (xy 95.79931 -268.465332) (xy 95.79535 -268.416278)
			(xy 95.466408 -268.416278) (xy 95.465913 -268.440885) (xy 95.458018 -268.489462) (xy 95.442434 -268.536143)
			(xy 95.419563 -268.57972) (xy 95.389998 -268.619064) (xy 95.354505 -268.653156) (xy 95.314002 -268.681112)
			(xy 95.26954 -268.70221) (xy 95.222269 -268.715902) (xy 95.173414 -268.721834) (xy 95.124239 -268.719853)
			(xy 95.07602 -268.710009) (xy 95.030004 -268.692557) (xy 94.987383 -268.66795) (xy 94.949262 -268.636825)
			(xy 94.916627 -268.599988) (xy 94.890324 -268.558392) (xy 94.871033 -268.513116) (xy 94.859256 -268.465332)
			(xy 94.855296 -268.416278) (xy 94.526354 -268.416278) (xy 94.525859 -268.440885) (xy 94.517964 -268.489462)
			(xy 94.50238 -268.536143) (xy 94.479509 -268.57972) (xy 94.449944 -268.619064) (xy 94.414451 -268.653156)
			(xy 94.373948 -268.681112) (xy 94.329486 -268.70221) (xy 94.282215 -268.715902) (xy 94.23336 -268.721834)
			(xy 94.184185 -268.719853) (xy 94.135966 -268.710009) (xy 94.08995 -268.692557) (xy 94.047329 -268.66795)
			(xy 94.009208 -268.636825) (xy 93.976573 -268.599988) (xy 93.95027 -268.558392) (xy 93.930979 -268.513116)
			(xy 93.919202 -268.465332) (xy 93.915242 -268.416278) (xy 93.586854 -268.416278) (xy 93.586856 -268.4163)
			(xy 93.582706 -268.466511) (xy 93.57037 -268.515359) (xy 93.550182 -268.56152) (xy 93.52269 -268.60374)
			(xy 93.488639 -268.640874) (xy 93.448955 -268.671914) (xy 93.404713 -268.696019) (xy 93.357115 -268.712533)
			(xy 93.307451 -268.72101) (xy 93.282262 -268.721586) (xy 93.280738 -268.721586) (xy 93.257878 -268.720824)
			(xy 93.2561 -268.72057) (xy 93.25483 -268.72057) (xy 93.245454 -268.72031) (xy 93.227566 -268.725907)
			(xy 93.220032 -268.731492) (xy 93.16339 -268.783308) (xy 93.156081 -268.790721) (xy 93.147672 -268.809742)
			(xy 93.147134 -268.820138) (xy 93.147134 -269.226284) (xy 93.445342 -269.226284) (xy 93.449302 -269.17723)
			(xy 93.461079 -269.129446) (xy 93.48037 -269.08417) (xy 93.506673 -269.042574) (xy 93.539308 -269.005737)
			(xy 93.577429 -268.974612) (xy 93.62005 -268.950005) (xy 93.666066 -268.932553) (xy 93.714285 -268.922709)
			(xy 93.76346 -268.920728) (xy 93.812315 -268.92666) (xy 93.859586 -268.940352) (xy 93.904048 -268.96145)
			(xy 93.944551 -268.989406) (xy 93.980044 -269.023498) (xy 94.009609 -269.062842) (xy 94.03248 -269.106419)
			(xy 94.048064 -269.1531) (xy 94.055959 -269.201677) (xy 94.056454 -269.226284) (xy 94.374711 -269.226284)
			(xy 94.378806 -269.175556) (xy 94.390985 -269.126142) (xy 94.410933 -269.079322) (xy 94.438134 -269.036308)
			(xy 94.471882 -268.998214) (xy 94.511304 -268.966027) (xy 94.555378 -268.940581) (xy 94.602964 -268.922534)
			(xy 94.652828 -268.912354) (xy 94.70368 -268.910305) (xy 94.754201 -268.916439) (xy 94.803085 -268.930599)
			(xy 94.849064 -268.952416) (xy 94.890948 -268.981326) (xy 94.927652 -269.016581) (xy 94.958225 -269.057267)
			(xy 94.981876 -269.10233) (xy 94.997992 -269.150604) (xy 95.006156 -269.200838) (xy 95.006668 -269.226284)
			(xy 95.325196 -269.226284) (xy 95.329156 -269.17723) (xy 95.340933 -269.129446) (xy 95.360224 -269.08417)
			(xy 95.386527 -269.042574) (xy 95.419162 -269.005737) (xy 95.457283 -268.974612) (xy 95.499904 -268.950005)
			(xy 95.54592 -268.932553) (xy 95.594139 -268.922709) (xy 95.643314 -268.920728) (xy 95.692169 -268.92666)
			(xy 95.73944 -268.940352) (xy 95.783902 -268.96145) (xy 95.824405 -268.989406) (xy 95.859898 -269.023498)
			(xy 95.889463 -269.062842) (xy 95.912334 -269.106419) (xy 95.927918 -269.1531) (xy 95.935813 -269.201677)
			(xy 95.936308 -269.226284) (xy 96.26525 -269.226284) (xy 96.26921 -269.17723) (xy 96.280987 -269.129446)
			(xy 96.300278 -269.08417) (xy 96.326581 -269.042574) (xy 96.359216 -269.005737) (xy 96.397337 -268.974612)
			(xy 96.439958 -268.950005) (xy 96.485974 -268.932553) (xy 96.534193 -268.922709) (xy 96.583368 -268.920728)
			(xy 96.632223 -268.92666) (xy 96.679494 -268.940352) (xy 96.723956 -268.96145) (xy 96.764459 -268.989406)
			(xy 96.799952 -269.023498) (xy 96.829517 -269.062842) (xy 96.852388 -269.106419) (xy 96.867972 -269.1531)
			(xy 96.875867 -269.201677) (xy 96.876362 -269.226284) (xy 99.085158 -269.226284) (xy 99.089118 -269.17723)
			(xy 99.100895 -269.129446) (xy 99.120186 -269.08417) (xy 99.146489 -269.042574) (xy 99.179124 -269.005737)
			(xy 99.217245 -268.974612) (xy 99.259866 -268.950005) (xy 99.305882 -268.932553) (xy 99.354101 -268.922709)
			(xy 99.403276 -268.920728) (xy 99.452131 -268.92666) (xy 99.499402 -268.940352) (xy 99.543864 -268.96145)
			(xy 99.584367 -268.989406) (xy 99.61986 -269.023498) (xy 99.649425 -269.062842) (xy 99.672296 -269.106419)
			(xy 99.68788 -269.1531) (xy 99.695775 -269.201677) (xy 99.69627 -269.226284) (xy 101.90532 -269.226284)
			(xy 101.90928 -269.17723) (xy 101.921057 -269.129446) (xy 101.940348 -269.08417) (xy 101.966651 -269.042574)
			(xy 101.999286 -269.005737) (xy 102.037407 -268.974612) (xy 102.080028 -268.950005) (xy 102.126044 -268.932553)
			(xy 102.174263 -268.922709) (xy 102.223438 -268.920728) (xy 102.272293 -268.92666) (xy 102.319564 -268.940352)
			(xy 102.364026 -268.96145) (xy 102.404529 -268.989406) (xy 102.440022 -269.023498) (xy 102.469587 -269.062842)
			(xy 102.492458 -269.106419) (xy 102.508042 -269.1531) (xy 102.515937 -269.201677) (xy 102.516432 -269.226284)
			(xy 104.725228 -269.226284) (xy 104.729188 -269.17723) (xy 104.740965 -269.129446) (xy 104.760256 -269.08417)
			(xy 104.786559 -269.042574) (xy 104.819194 -269.005737) (xy 104.857315 -268.974612) (xy 104.899936 -268.950005)
			(xy 104.945952 -268.932553) (xy 104.994171 -268.922709) (xy 105.043346 -268.920728) (xy 105.092201 -268.92666)
			(xy 105.139472 -268.940352) (xy 105.183934 -268.96145) (xy 105.224437 -268.989406) (xy 105.25993 -269.023498)
			(xy 105.289495 -269.062842) (xy 105.312366 -269.106419) (xy 105.32795 -269.1531) (xy 105.335845 -269.201677)
			(xy 105.33634 -269.226284) (xy 107.545136 -269.226284) (xy 107.549096 -269.17723) (xy 107.560873 -269.129446)
			(xy 107.580164 -269.08417) (xy 107.606467 -269.042574) (xy 107.639102 -269.005737) (xy 107.677223 -268.974612)
			(xy 107.719844 -268.950005) (xy 107.76586 -268.932553) (xy 107.814079 -268.922709) (xy 107.863254 -268.920728)
			(xy 107.912109 -268.92666) (xy 107.95938 -268.940352) (xy 108.003842 -268.96145) (xy 108.044345 -268.989406)
			(xy 108.079838 -269.023498) (xy 108.109403 -269.062842) (xy 108.132274 -269.106419) (xy 108.147858 -269.1531)
			(xy 108.155753 -269.201677) (xy 108.156248 -269.226284) (xy 108.48519 -269.226284) (xy 108.48915 -269.17723)
			(xy 108.500927 -269.129446) (xy 108.520218 -269.08417) (xy 108.546521 -269.042574) (xy 108.579156 -269.005737)
			(xy 108.617277 -268.974612) (xy 108.659898 -268.950005) (xy 108.705914 -268.932553) (xy 108.754133 -268.922709)
			(xy 108.803308 -268.920728) (xy 108.852163 -268.92666) (xy 108.899434 -268.940352) (xy 108.943896 -268.96145)
			(xy 108.984399 -268.989406) (xy 109.019892 -269.023498) (xy 109.049457 -269.062842) (xy 109.072328 -269.106419)
			(xy 109.087912 -269.1531) (xy 109.095807 -269.201677) (xy 109.096302 -269.226284) (xy 109.425244 -269.226284)
			(xy 109.429204 -269.17723) (xy 109.440981 -269.129446) (xy 109.460272 -269.08417) (xy 109.486575 -269.042574)
			(xy 109.51921 -269.005737) (xy 109.557331 -268.974612) (xy 109.599952 -268.950005) (xy 109.645968 -268.932553)
			(xy 109.694187 -268.922709) (xy 109.743362 -268.920728) (xy 109.792217 -268.92666) (xy 109.839488 -268.940352)
			(xy 109.88395 -268.96145) (xy 109.924453 -268.989406) (xy 109.959946 -269.023498) (xy 109.989511 -269.062842)
			(xy 110.012382 -269.106419) (xy 110.027966 -269.1531) (xy 110.035861 -269.201677) (xy 110.036356 -269.226284)
			(xy 110.365298 -269.226284) (xy 110.369258 -269.17723) (xy 110.381035 -269.129446) (xy 110.400326 -269.08417)
			(xy 110.426629 -269.042574) (xy 110.459264 -269.005737) (xy 110.497385 -268.974612) (xy 110.540006 -268.950005)
			(xy 110.586022 -268.932553) (xy 110.634241 -268.922709) (xy 110.683416 -268.920728) (xy 110.732271 -268.92666)
			(xy 110.779542 -268.940352) (xy 110.824004 -268.96145) (xy 110.864507 -268.989406) (xy 110.9 -269.023498)
			(xy 110.929565 -269.062842) (xy 110.952436 -269.106419) (xy 110.96802 -269.1531) (xy 110.975915 -269.201677)
			(xy 110.97641 -269.226284) (xy 113.178856 -269.226284) (xy 113.182816 -269.17723) (xy 113.194593 -269.129446)
			(xy 113.213884 -269.08417) (xy 113.240187 -269.042574) (xy 113.272822 -269.005737) (xy 113.310943 -268.974612)
			(xy 113.353564 -268.950005) (xy 113.39958 -268.932553) (xy 113.447799 -268.922709) (xy 113.496974 -268.920728)
			(xy 113.545829 -268.92666) (xy 113.5931 -268.940352) (xy 113.637562 -268.96145) (xy 113.678065 -268.989406)
			(xy 113.713558 -269.023498) (xy 113.743123 -269.062842) (xy 113.765994 -269.106419) (xy 113.781578 -269.1531)
			(xy 113.789473 -269.201677) (xy 113.789968 -269.226284) (xy 114.11891 -269.226284) (xy 114.12287 -269.17723)
			(xy 114.134647 -269.129446) (xy 114.153938 -269.08417) (xy 114.180241 -269.042574) (xy 114.212876 -269.005737)
			(xy 114.250997 -268.974612) (xy 114.293618 -268.950005) (xy 114.339634 -268.932553) (xy 114.387853 -268.922709)
			(xy 114.437028 -268.920728) (xy 114.485883 -268.92666) (xy 114.533154 -268.940352) (xy 114.577616 -268.96145)
			(xy 114.618119 -268.989406) (xy 114.653612 -269.023498) (xy 114.683177 -269.062842) (xy 114.706048 -269.106419)
			(xy 114.721632 -269.1531) (xy 114.729527 -269.201677) (xy 114.730022 -269.226284) (xy 115.058964 -269.226284)
			(xy 115.062924 -269.17723) (xy 115.074701 -269.129446) (xy 115.093992 -269.08417) (xy 115.120295 -269.042574)
			(xy 115.15293 -269.005737) (xy 115.191051 -268.974612) (xy 115.233672 -268.950005) (xy 115.279688 -268.932553)
			(xy 115.327907 -268.922709) (xy 115.377082 -268.920728) (xy 115.425937 -268.92666) (xy 115.473208 -268.940352)
			(xy 115.51767 -268.96145) (xy 115.558173 -268.989406) (xy 115.593666 -269.023498) (xy 115.623231 -269.062842)
			(xy 115.646102 -269.106419) (xy 115.661686 -269.1531) (xy 115.669581 -269.201677) (xy 115.670076 -269.226284)
			(xy 115.999018 -269.226284) (xy 116.002978 -269.17723) (xy 116.014755 -269.129446) (xy 116.034046 -269.08417)
			(xy 116.060349 -269.042574) (xy 116.092984 -269.005737) (xy 116.131105 -268.974612) (xy 116.173726 -268.950005)
			(xy 116.219742 -268.932553) (xy 116.267961 -268.922709) (xy 116.317136 -268.920728) (xy 116.365991 -268.92666)
			(xy 116.413262 -268.940352) (xy 116.457724 -268.96145) (xy 116.498227 -268.989406) (xy 116.53372 -269.023498)
			(xy 116.563285 -269.062842) (xy 116.586156 -269.106419) (xy 116.60174 -269.1531) (xy 116.609635 -269.201677)
			(xy 116.61013 -269.226284) (xy 118.818926 -269.226284) (xy 118.822886 -269.17723) (xy 118.834663 -269.129446)
			(xy 118.853954 -269.08417) (xy 118.880257 -269.042574) (xy 118.912892 -269.005737) (xy 118.951013 -268.974612)
			(xy 118.993634 -268.950005) (xy 119.03965 -268.932553) (xy 119.087869 -268.922709) (xy 119.137044 -268.920728)
			(xy 119.185899 -268.92666) (xy 119.23317 -268.940352) (xy 119.277632 -268.96145) (xy 119.318135 -268.989406)
			(xy 119.353628 -269.023498) (xy 119.383193 -269.062842) (xy 119.406064 -269.106419) (xy 119.421648 -269.1531)
			(xy 119.429543 -269.201677) (xy 119.430038 -269.226284) (xy 121.638834 -269.226284) (xy 121.642794 -269.17723)
			(xy 121.654571 -269.129446) (xy 121.673862 -269.08417) (xy 121.700165 -269.042574) (xy 121.7328 -269.005737)
			(xy 121.770921 -268.974612) (xy 121.813542 -268.950005) (xy 121.859558 -268.932553) (xy 121.907777 -268.922709)
			(xy 121.956952 -268.920728) (xy 122.005807 -268.92666) (xy 122.053078 -268.940352) (xy 122.09754 -268.96145)
			(xy 122.138043 -268.989406) (xy 122.173536 -269.023498) (xy 122.203101 -269.062842) (xy 122.225972 -269.106419)
			(xy 122.241556 -269.1531) (xy 122.249451 -269.201677) (xy 122.249946 -269.226284) (xy 124.458996 -269.226284)
			(xy 124.462956 -269.17723) (xy 124.474733 -269.129446) (xy 124.494024 -269.08417) (xy 124.520327 -269.042574)
			(xy 124.552962 -269.005737) (xy 124.591083 -268.974612) (xy 124.633704 -268.950005) (xy 124.67972 -268.932553)
			(xy 124.727939 -268.922709) (xy 124.777114 -268.920728) (xy 124.825969 -268.92666) (xy 124.87324 -268.940352)
			(xy 124.917702 -268.96145) (xy 124.958205 -268.989406) (xy 124.993698 -269.023498) (xy 125.023263 -269.062842)
			(xy 125.046134 -269.106419) (xy 125.061718 -269.1531) (xy 125.069613 -269.201677) (xy 125.070108 -269.226284)
			(xy 125.069613 -269.250891) (xy 125.061718 -269.299468) (xy 125.046134 -269.346149) (xy 125.023263 -269.389726)
			(xy 124.993698 -269.42907) (xy 124.958205 -269.463162) (xy 124.917702 -269.491118) (xy 124.87324 -269.512216)
			(xy 124.825969 -269.525908) (xy 124.777114 -269.53184) (xy 124.727939 -269.529859) (xy 124.67972 -269.520015)
			(xy 124.633704 -269.502563) (xy 124.591083 -269.477956) (xy 124.552962 -269.446831) (xy 124.520327 -269.409994)
			(xy 124.494024 -269.368398) (xy 124.474733 -269.323122) (xy 124.462956 -269.275338) (xy 124.458996 -269.226284)
			(xy 122.249946 -269.226284) (xy 122.249451 -269.250891) (xy 122.241556 -269.299468) (xy 122.225972 -269.346149)
			(xy 122.203101 -269.389726) (xy 122.173536 -269.42907) (xy 122.138043 -269.463162) (xy 122.09754 -269.491118)
			(xy 122.053078 -269.512216) (xy 122.005807 -269.525908) (xy 121.956952 -269.53184) (xy 121.907777 -269.529859)
			(xy 121.859558 -269.520015) (xy 121.813542 -269.502563) (xy 121.770921 -269.477956) (xy 121.7328 -269.446831)
			(xy 121.700165 -269.409994) (xy 121.673862 -269.368398) (xy 121.654571 -269.323122) (xy 121.642794 -269.275338)
			(xy 121.638834 -269.226284) (xy 119.430038 -269.226284) (xy 119.429543 -269.250891) (xy 119.421648 -269.299468)
			(xy 119.406064 -269.346149) (xy 119.383193 -269.389726) (xy 119.353628 -269.42907) (xy 119.318135 -269.463162)
			(xy 119.277632 -269.491118) (xy 119.23317 -269.512216) (xy 119.185899 -269.525908) (xy 119.137044 -269.53184)
			(xy 119.087869 -269.529859) (xy 119.03965 -269.520015) (xy 118.993634 -269.502563) (xy 118.951013 -269.477956)
			(xy 118.912892 -269.446831) (xy 118.880257 -269.409994) (xy 118.853954 -269.368398) (xy 118.834663 -269.323122)
			(xy 118.822886 -269.275338) (xy 118.818926 -269.226284) (xy 116.61013 -269.226284) (xy 116.609635 -269.250891)
			(xy 116.60174 -269.299468) (xy 116.586156 -269.346149) (xy 116.563285 -269.389726) (xy 116.53372 -269.42907)
			(xy 116.498227 -269.463162) (xy 116.457724 -269.491118) (xy 116.413262 -269.512216) (xy 116.365991 -269.525908)
			(xy 116.317136 -269.53184) (xy 116.267961 -269.529859) (xy 116.219742 -269.520015) (xy 116.173726 -269.502563)
			(xy 116.131105 -269.477956) (xy 116.092984 -269.446831) (xy 116.060349 -269.409994) (xy 116.034046 -269.368398)
			(xy 116.014755 -269.323122) (xy 116.002978 -269.275338) (xy 115.999018 -269.226284) (xy 115.670076 -269.226284)
			(xy 115.669581 -269.250891) (xy 115.661686 -269.299468) (xy 115.646102 -269.346149) (xy 115.623231 -269.389726)
			(xy 115.593666 -269.42907) (xy 115.558173 -269.463162) (xy 115.51767 -269.491118) (xy 115.473208 -269.512216)
			(xy 115.425937 -269.525908) (xy 115.377082 -269.53184) (xy 115.327907 -269.529859) (xy 115.279688 -269.520015)
			(xy 115.233672 -269.502563) (xy 115.191051 -269.477956) (xy 115.15293 -269.446831) (xy 115.120295 -269.409994)
			(xy 115.093992 -269.368398) (xy 115.074701 -269.323122) (xy 115.062924 -269.275338) (xy 115.058964 -269.226284)
			(xy 114.730022 -269.226284) (xy 114.729527 -269.250891) (xy 114.721632 -269.299468) (xy 114.706048 -269.346149)
			(xy 114.683177 -269.389726) (xy 114.653612 -269.42907) (xy 114.618119 -269.463162) (xy 114.577616 -269.491118)
			(xy 114.533154 -269.512216) (xy 114.485883 -269.525908) (xy 114.437028 -269.53184) (xy 114.387853 -269.529859)
			(xy 114.339634 -269.520015) (xy 114.293618 -269.502563) (xy 114.250997 -269.477956) (xy 114.212876 -269.446831)
			(xy 114.180241 -269.409994) (xy 114.153938 -269.368398) (xy 114.134647 -269.323122) (xy 114.12287 -269.275338)
			(xy 114.11891 -269.226284) (xy 113.789968 -269.226284) (xy 113.789473 -269.250891) (xy 113.781578 -269.299468)
			(xy 113.765994 -269.346149) (xy 113.743123 -269.389726) (xy 113.713558 -269.42907) (xy 113.678065 -269.463162)
			(xy 113.637562 -269.491118) (xy 113.5931 -269.512216) (xy 113.545829 -269.525908) (xy 113.496974 -269.53184)
			(xy 113.447799 -269.529859) (xy 113.39958 -269.520015) (xy 113.353564 -269.502563) (xy 113.310943 -269.477956)
			(xy 113.272822 -269.446831) (xy 113.240187 -269.409994) (xy 113.213884 -269.368398) (xy 113.194593 -269.323122)
			(xy 113.182816 -269.275338) (xy 113.178856 -269.226284) (xy 110.97641 -269.226284) (xy 110.975915 -269.250891)
			(xy 110.96802 -269.299468) (xy 110.952436 -269.346149) (xy 110.929565 -269.389726) (xy 110.9 -269.42907)
			(xy 110.864507 -269.463162) (xy 110.824004 -269.491118) (xy 110.779542 -269.512216) (xy 110.732271 -269.525908)
			(xy 110.683416 -269.53184) (xy 110.634241 -269.529859) (xy 110.586022 -269.520015) (xy 110.540006 -269.502563)
			(xy 110.497385 -269.477956) (xy 110.459264 -269.446831) (xy 110.426629 -269.409994) (xy 110.400326 -269.368398)
			(xy 110.381035 -269.323122) (xy 110.369258 -269.275338) (xy 110.365298 -269.226284) (xy 110.036356 -269.226284)
			(xy 110.035861 -269.250891) (xy 110.027966 -269.299468) (xy 110.012382 -269.346149) (xy 109.989511 -269.389726)
			(xy 109.959946 -269.42907) (xy 109.924453 -269.463162) (xy 109.88395 -269.491118) (xy 109.839488 -269.512216)
			(xy 109.792217 -269.525908) (xy 109.743362 -269.53184) (xy 109.694187 -269.529859) (xy 109.645968 -269.520015)
			(xy 109.599952 -269.502563) (xy 109.557331 -269.477956) (xy 109.51921 -269.446831) (xy 109.486575 -269.409994)
			(xy 109.460272 -269.368398) (xy 109.440981 -269.323122) (xy 109.429204 -269.275338) (xy 109.425244 -269.226284)
			(xy 109.096302 -269.226284) (xy 109.095807 -269.250891) (xy 109.087912 -269.299468) (xy 109.072328 -269.346149)
			(xy 109.049457 -269.389726) (xy 109.019892 -269.42907) (xy 108.984399 -269.463162) (xy 108.943896 -269.491118)
			(xy 108.899434 -269.512216) (xy 108.852163 -269.525908) (xy 108.803308 -269.53184) (xy 108.754133 -269.529859)
			(xy 108.705914 -269.520015) (xy 108.659898 -269.502563) (xy 108.617277 -269.477956) (xy 108.579156 -269.446831)
			(xy 108.546521 -269.409994) (xy 108.520218 -269.368398) (xy 108.500927 -269.323122) (xy 108.48915 -269.275338)
			(xy 108.48519 -269.226284) (xy 108.156248 -269.226284) (xy 108.155753 -269.250891) (xy 108.147858 -269.299468)
			(xy 108.132274 -269.346149) (xy 108.109403 -269.389726) (xy 108.079838 -269.42907) (xy 108.044345 -269.463162)
			(xy 108.003842 -269.491118) (xy 107.95938 -269.512216) (xy 107.912109 -269.525908) (xy 107.863254 -269.53184)
			(xy 107.814079 -269.529859) (xy 107.76586 -269.520015) (xy 107.719844 -269.502563) (xy 107.677223 -269.477956)
			(xy 107.639102 -269.446831) (xy 107.606467 -269.409994) (xy 107.580164 -269.368398) (xy 107.560873 -269.323122)
			(xy 107.549096 -269.275338) (xy 107.545136 -269.226284) (xy 105.33634 -269.226284) (xy 105.335845 -269.250891)
			(xy 105.32795 -269.299468) (xy 105.312366 -269.346149) (xy 105.289495 -269.389726) (xy 105.25993 -269.42907)
			(xy 105.224437 -269.463162) (xy 105.183934 -269.491118) (xy 105.139472 -269.512216) (xy 105.092201 -269.525908)
			(xy 105.043346 -269.53184) (xy 104.994171 -269.529859) (xy 104.945952 -269.520015) (xy 104.899936 -269.502563)
			(xy 104.857315 -269.477956) (xy 104.819194 -269.446831) (xy 104.786559 -269.409994) (xy 104.760256 -269.368398)
			(xy 104.740965 -269.323122) (xy 104.729188 -269.275338) (xy 104.725228 -269.226284) (xy 102.516432 -269.226284)
			(xy 102.515937 -269.250891) (xy 102.508042 -269.299468) (xy 102.492458 -269.346149) (xy 102.469587 -269.389726)
			(xy 102.440022 -269.42907) (xy 102.404529 -269.463162) (xy 102.364026 -269.491118) (xy 102.319564 -269.512216)
			(xy 102.272293 -269.525908) (xy 102.223438 -269.53184) (xy 102.174263 -269.529859) (xy 102.126044 -269.520015)
			(xy 102.080028 -269.502563) (xy 102.037407 -269.477956) (xy 101.999286 -269.446831) (xy 101.966651 -269.409994)
			(xy 101.940348 -269.368398) (xy 101.921057 -269.323122) (xy 101.90928 -269.275338) (xy 101.90532 -269.226284)
			(xy 99.69627 -269.226284) (xy 99.695775 -269.250891) (xy 99.68788 -269.299468) (xy 99.672296 -269.346149)
			(xy 99.649425 -269.389726) (xy 99.61986 -269.42907) (xy 99.584367 -269.463162) (xy 99.543864 -269.491118)
			(xy 99.499402 -269.512216) (xy 99.452131 -269.525908) (xy 99.403276 -269.53184) (xy 99.354101 -269.529859)
			(xy 99.305882 -269.520015) (xy 99.259866 -269.502563) (xy 99.217245 -269.477956) (xy 99.179124 -269.446831)
			(xy 99.146489 -269.409994) (xy 99.120186 -269.368398) (xy 99.100895 -269.323122) (xy 99.089118 -269.275338)
			(xy 99.085158 -269.226284) (xy 96.876362 -269.226284) (xy 96.875867 -269.250891) (xy 96.867972 -269.299468)
			(xy 96.852388 -269.346149) (xy 96.829517 -269.389726) (xy 96.799952 -269.42907) (xy 96.764459 -269.463162)
			(xy 96.723956 -269.491118) (xy 96.679494 -269.512216) (xy 96.632223 -269.525908) (xy 96.583368 -269.53184)
			(xy 96.534193 -269.529859) (xy 96.485974 -269.520015) (xy 96.439958 -269.502563) (xy 96.397337 -269.477956)
			(xy 96.359216 -269.446831) (xy 96.326581 -269.409994) (xy 96.300278 -269.368398) (xy 96.280987 -269.323122)
			(xy 96.26921 -269.275338) (xy 96.26525 -269.226284) (xy 95.936308 -269.226284) (xy 95.935813 -269.250891)
			(xy 95.927918 -269.299468) (xy 95.912334 -269.346149) (xy 95.889463 -269.389726) (xy 95.859898 -269.42907)
			(xy 95.824405 -269.463162) (xy 95.783902 -269.491118) (xy 95.73944 -269.512216) (xy 95.692169 -269.525908)
			(xy 95.643314 -269.53184) (xy 95.594139 -269.529859) (xy 95.54592 -269.520015) (xy 95.499904 -269.502563)
			(xy 95.457283 -269.477956) (xy 95.419162 -269.446831) (xy 95.386527 -269.409994) (xy 95.360224 -269.368398)
			(xy 95.340933 -269.323122) (xy 95.329156 -269.275338) (xy 95.325196 -269.226284) (xy 95.006668 -269.226284)
			(xy 95.006156 -269.25173) (xy 94.997992 -269.301964) (xy 94.981876 -269.350238) (xy 94.958225 -269.395301)
			(xy 94.927652 -269.435987) (xy 94.890948 -269.471242) (xy 94.849064 -269.500152) (xy 94.803085 -269.521969)
			(xy 94.754201 -269.536129) (xy 94.70368 -269.542263) (xy 94.652828 -269.540214) (xy 94.602964 -269.530034)
			(xy 94.555378 -269.511987) (xy 94.511304 -269.486541) (xy 94.471882 -269.454354) (xy 94.438134 -269.41626)
			(xy 94.410933 -269.373246) (xy 94.390985 -269.326426) (xy 94.378806 -269.277012) (xy 94.374711 -269.226284)
			(xy 94.056454 -269.226284) (xy 94.055959 -269.250891) (xy 94.048064 -269.299468) (xy 94.03248 -269.346149)
			(xy 94.009609 -269.389726) (xy 93.980044 -269.42907) (xy 93.944551 -269.463162) (xy 93.904048 -269.491118)
			(xy 93.859586 -269.512216) (xy 93.812315 -269.525908) (xy 93.76346 -269.53184) (xy 93.714285 -269.529859)
			(xy 93.666066 -269.520015) (xy 93.62005 -269.502563) (xy 93.577429 -269.477956) (xy 93.539308 -269.446831)
			(xy 93.506673 -269.409994) (xy 93.48037 -269.368398) (xy 93.461079 -269.323122) (xy 93.449302 -269.275338)
			(xy 93.445342 -269.226284) (xy 93.147134 -269.226284) (xy 93.147134 -269.632176) (xy 93.147721 -269.64271)
			(xy 93.156253 -269.661983) (xy 93.163644 -269.669514) (xy 93.219778 -269.721076) (xy 93.227387 -269.72666)
			(xy 93.245395 -269.732269) (xy 93.25483 -269.731998) (xy 93.2561 -269.731998) (xy 93.257878 -269.731744)
			(xy 93.277436 -269.730982) (xy 93.282262 -269.730982) (xy 93.306189 -269.731547) (xy 93.353429 -269.739209)
			(xy 93.398895 -269.754148) (xy 93.441473 -269.775997) (xy 93.480121 -269.804223) (xy 93.513892 -269.838132)
			(xy 93.541959 -269.876896) (xy 93.563633 -269.919563) (xy 93.578386 -269.96509) (xy 93.585854 -270.012361)
			(xy 93.5863 -270.03629) (xy 93.904811 -270.03629) (xy 93.908906 -269.985562) (xy 93.921085 -269.936148)
			(xy 93.941033 -269.889328) (xy 93.968234 -269.846314) (xy 94.001982 -269.80822) (xy 94.041404 -269.776033)
			(xy 94.085478 -269.750587) (xy 94.133064 -269.73254) (xy 94.182928 -269.72236) (xy 94.23378 -269.720311)
			(xy 94.284301 -269.726445) (xy 94.333185 -269.740605) (xy 94.379164 -269.762422) (xy 94.421048 -269.791332)
			(xy 94.457752 -269.826587) (xy 94.488325 -269.867273) (xy 94.511976 -269.912336) (xy 94.528092 -269.96061)
			(xy 94.536256 -270.010844) (xy 94.536768 -270.03629) (xy 94.855296 -270.03629) (xy 94.859256 -269.987236)
			(xy 94.871033 -269.939452) (xy 94.890324 -269.894176) (xy 94.916627 -269.85258) (xy 94.949262 -269.815743)
			(xy 94.987383 -269.784618) (xy 95.030004 -269.760011) (xy 95.07602 -269.742559) (xy 95.124239 -269.732715)
			(xy 95.173414 -269.730734) (xy 95.222269 -269.736666) (xy 95.26954 -269.750358) (xy 95.314002 -269.771456)
			(xy 95.354505 -269.799412) (xy 95.389998 -269.833504) (xy 95.419563 -269.872848) (xy 95.442434 -269.916425)
			(xy 95.458018 -269.963106) (xy 95.465913 -270.011683) (xy 95.466408 -270.03629) (xy 95.784919 -270.03629)
			(xy 95.789014 -269.985562) (xy 95.801193 -269.936148) (xy 95.821141 -269.889328) (xy 95.848342 -269.846314)
			(xy 95.88209 -269.80822) (xy 95.921512 -269.776033) (xy 95.965586 -269.750587) (xy 96.013172 -269.73254)
			(xy 96.063036 -269.72236) (xy 96.113888 -269.720311) (xy 96.164409 -269.726445) (xy 96.213293 -269.740605)
			(xy 96.259272 -269.762422) (xy 96.301156 -269.791332) (xy 96.33786 -269.826587) (xy 96.368433 -269.867273)
			(xy 96.392084 -269.912336) (xy 96.4082 -269.96061) (xy 96.416364 -270.010844) (xy 96.416876 -270.03629)
			(xy 96.73515 -270.03629) (xy 96.73911 -269.987236) (xy 96.750887 -269.939452) (xy 96.770178 -269.894176)
			(xy 96.796481 -269.85258) (xy 96.829116 -269.815743) (xy 96.867237 -269.784618) (xy 96.909858 -269.760011)
			(xy 96.955874 -269.742559) (xy 97.004093 -269.732715) (xy 97.053268 -269.730734) (xy 97.102123 -269.736666)
			(xy 97.149394 -269.750358) (xy 97.193856 -269.771456) (xy 97.234359 -269.799412) (xy 97.269852 -269.833504)
			(xy 97.299417 -269.872848) (xy 97.322288 -269.916425) (xy 97.337872 -269.963106) (xy 97.345767 -270.011683)
			(xy 97.346262 -270.03629) (xy 97.675204 -270.03629) (xy 97.679164 -269.987236) (xy 97.690941 -269.939452)
			(xy 97.710232 -269.894176) (xy 97.736535 -269.85258) (xy 97.76917 -269.815743) (xy 97.807291 -269.784618)
			(xy 97.849912 -269.760011) (xy 97.895928 -269.742559) (xy 97.944147 -269.732715) (xy 97.993322 -269.730734)
			(xy 98.042177 -269.736666) (xy 98.089448 -269.750358) (xy 98.13391 -269.771456) (xy 98.174413 -269.799412)
			(xy 98.209906 -269.833504) (xy 98.239471 -269.872848) (xy 98.262342 -269.916425) (xy 98.277926 -269.963106)
			(xy 98.285821 -270.011683) (xy 98.286316 -270.03629) (xy 98.615258 -270.03629) (xy 98.619218 -269.987236)
			(xy 98.630995 -269.939452) (xy 98.650286 -269.894176) (xy 98.676589 -269.85258) (xy 98.709224 -269.815743)
			(xy 98.747345 -269.784618) (xy 98.789966 -269.760011) (xy 98.835982 -269.742559) (xy 98.884201 -269.732715)
			(xy 98.933376 -269.730734) (xy 98.982231 -269.736666) (xy 99.029502 -269.750358) (xy 99.073964 -269.771456)
			(xy 99.114467 -269.799412) (xy 99.14996 -269.833504) (xy 99.179525 -269.872848) (xy 99.202396 -269.916425)
			(xy 99.21798 -269.963106) (xy 99.225875 -270.011683) (xy 99.22637 -270.03629) (xy 99.555312 -270.03629)
			(xy 99.559272 -269.987236) (xy 99.571049 -269.939452) (xy 99.59034 -269.894176) (xy 99.616643 -269.85258)
			(xy 99.649278 -269.815743) (xy 99.687399 -269.784618) (xy 99.73002 -269.760011) (xy 99.776036 -269.742559)
			(xy 99.824255 -269.732715) (xy 99.87343 -269.730734) (xy 99.922285 -269.736666) (xy 99.969556 -269.750358)
			(xy 100.014018 -269.771456) (xy 100.054521 -269.799412) (xy 100.090014 -269.833504) (xy 100.119579 -269.872848)
			(xy 100.14245 -269.916425) (xy 100.158034 -269.963106) (xy 100.165929 -270.011683) (xy 100.166424 -270.03629)
			(xy 100.495366 -270.03629) (xy 100.499326 -269.987236) (xy 100.511103 -269.939452) (xy 100.530394 -269.894176)
			(xy 100.556697 -269.85258) (xy 100.589332 -269.815743) (xy 100.627453 -269.784618) (xy 100.670074 -269.760011)
			(xy 100.71609 -269.742559) (xy 100.764309 -269.732715) (xy 100.813484 -269.730734) (xy 100.862339 -269.736666)
			(xy 100.90961 -269.750358) (xy 100.954072 -269.771456) (xy 100.994575 -269.799412) (xy 101.030068 -269.833504)
			(xy 101.059633 -269.872848) (xy 101.082504 -269.916425) (xy 101.098088 -269.963106) (xy 101.105983 -270.011683)
			(xy 101.106478 -270.03629) (xy 101.435166 -270.03629) (xy 101.439126 -269.987236) (xy 101.450903 -269.939452)
			(xy 101.470194 -269.894176) (xy 101.496497 -269.85258) (xy 101.529132 -269.815743) (xy 101.567253 -269.784618)
			(xy 101.609874 -269.760011) (xy 101.65589 -269.742559) (xy 101.704109 -269.732715) (xy 101.753284 -269.730734)
			(xy 101.802139 -269.736666) (xy 101.84941 -269.750358) (xy 101.893872 -269.771456) (xy 101.934375 -269.799412)
			(xy 101.969868 -269.833504) (xy 101.999433 -269.872848) (xy 102.022304 -269.916425) (xy 102.037888 -269.963106)
			(xy 102.045783 -270.011683) (xy 102.046278 -270.03629) (xy 102.37522 -270.03629) (xy 102.37918 -269.987236)
			(xy 102.390957 -269.939452) (xy 102.410248 -269.894176) (xy 102.436551 -269.85258) (xy 102.469186 -269.815743)
			(xy 102.507307 -269.784618) (xy 102.549928 -269.760011) (xy 102.595944 -269.742559) (xy 102.644163 -269.732715)
			(xy 102.693338 -269.730734) (xy 102.742193 -269.736666) (xy 102.789464 -269.750358) (xy 102.833926 -269.771456)
			(xy 102.874429 -269.799412) (xy 102.909922 -269.833504) (xy 102.939487 -269.872848) (xy 102.962358 -269.916425)
			(xy 102.977942 -269.963106) (xy 102.985837 -270.011683) (xy 102.986332 -270.03629) (xy 103.315274 -270.03629)
			(xy 103.319234 -269.987236) (xy 103.331011 -269.939452) (xy 103.350302 -269.894176) (xy 103.376605 -269.85258)
			(xy 103.40924 -269.815743) (xy 103.447361 -269.784618) (xy 103.489982 -269.760011) (xy 103.535998 -269.742559)
			(xy 103.584217 -269.732715) (xy 103.633392 -269.730734) (xy 103.682247 -269.736666) (xy 103.729518 -269.750358)
			(xy 103.77398 -269.771456) (xy 103.814483 -269.799412) (xy 103.849976 -269.833504) (xy 103.879541 -269.872848)
			(xy 103.902412 -269.916425) (xy 103.917996 -269.963106) (xy 103.925891 -270.011683) (xy 103.926386 -270.03629)
			(xy 104.255328 -270.03629) (xy 104.259288 -269.987236) (xy 104.271065 -269.939452) (xy 104.290356 -269.894176)
			(xy 104.316659 -269.85258) (xy 104.349294 -269.815743) (xy 104.387415 -269.784618) (xy 104.430036 -269.760011)
			(xy 104.476052 -269.742559) (xy 104.524271 -269.732715) (xy 104.573446 -269.730734) (xy 104.622301 -269.736666)
			(xy 104.669572 -269.750358) (xy 104.714034 -269.771456) (xy 104.754537 -269.799412) (xy 104.79003 -269.833504)
			(xy 104.819595 -269.872848) (xy 104.842466 -269.916425) (xy 104.85805 -269.963106) (xy 104.865945 -270.011683)
			(xy 104.86644 -270.03629) (xy 105.195128 -270.03629) (xy 105.199088 -269.987236) (xy 105.210865 -269.939452)
			(xy 105.230156 -269.894176) (xy 105.256459 -269.85258) (xy 105.289094 -269.815743) (xy 105.327215 -269.784618)
			(xy 105.369836 -269.760011) (xy 105.415852 -269.742559) (xy 105.464071 -269.732715) (xy 105.513246 -269.730734)
			(xy 105.562101 -269.736666) (xy 105.609372 -269.750358) (xy 105.653834 -269.771456) (xy 105.694337 -269.799412)
			(xy 105.72983 -269.833504) (xy 105.759395 -269.872848) (xy 105.782266 -269.916425) (xy 105.79785 -269.963106)
			(xy 105.805745 -270.011683) (xy 105.80624 -270.03629) (xy 106.135182 -270.03629) (xy 106.139142 -269.987236)
			(xy 106.150919 -269.939452) (xy 106.17021 -269.894176) (xy 106.196513 -269.85258) (xy 106.229148 -269.815743)
			(xy 106.267269 -269.784618) (xy 106.30989 -269.760011) (xy 106.355906 -269.742559) (xy 106.404125 -269.732715)
			(xy 106.4533 -269.730734) (xy 106.502155 -269.736666) (xy 106.549426 -269.750358) (xy 106.593888 -269.771456)
			(xy 106.634391 -269.799412) (xy 106.669884 -269.833504) (xy 106.699449 -269.872848) (xy 106.72232 -269.916425)
			(xy 106.737904 -269.963106) (xy 106.745799 -270.011683) (xy 106.746294 -270.03629) (xy 107.075236 -270.03629)
			(xy 107.079196 -269.987236) (xy 107.090973 -269.939452) (xy 107.110264 -269.894176) (xy 107.136567 -269.85258)
			(xy 107.169202 -269.815743) (xy 107.207323 -269.784618) (xy 107.249944 -269.760011) (xy 107.29596 -269.742559)
			(xy 107.344179 -269.732715) (xy 107.393354 -269.730734) (xy 107.442209 -269.736666) (xy 107.48948 -269.750358)
			(xy 107.533942 -269.771456) (xy 107.574445 -269.799412) (xy 107.609938 -269.833504) (xy 107.639503 -269.872848)
			(xy 107.662374 -269.916425) (xy 107.677958 -269.963106) (xy 107.685853 -270.011683) (xy 107.686348 -270.03629)
			(xy 108.01529 -270.03629) (xy 108.01925 -269.987236) (xy 108.031027 -269.939452) (xy 108.050318 -269.894176)
			(xy 108.076621 -269.85258) (xy 108.109256 -269.815743) (xy 108.147377 -269.784618) (xy 108.189998 -269.760011)
			(xy 108.236014 -269.742559) (xy 108.284233 -269.732715) (xy 108.333408 -269.730734) (xy 108.382263 -269.736666)
			(xy 108.429534 -269.750358) (xy 108.473996 -269.771456) (xy 108.514499 -269.799412) (xy 108.549992 -269.833504)
			(xy 108.579557 -269.872848) (xy 108.602428 -269.916425) (xy 108.618012 -269.963106) (xy 108.625907 -270.011683)
			(xy 108.626402 -270.03629) (xy 108.955344 -270.03629) (xy 108.959304 -269.987236) (xy 108.971081 -269.939452)
			(xy 108.990372 -269.894176) (xy 109.016675 -269.85258) (xy 109.04931 -269.815743) (xy 109.087431 -269.784618)
			(xy 109.130052 -269.760011) (xy 109.176068 -269.742559) (xy 109.224287 -269.732715) (xy 109.273462 -269.730734)
			(xy 109.322317 -269.736666) (xy 109.369588 -269.750358) (xy 109.41405 -269.771456) (xy 109.454553 -269.799412)
			(xy 109.490046 -269.833504) (xy 109.519611 -269.872848) (xy 109.542482 -269.916425) (xy 109.558066 -269.963106)
			(xy 109.565961 -270.011683) (xy 109.566456 -270.03629) (xy 109.895144 -270.03629) (xy 109.899104 -269.987236)
			(xy 109.910881 -269.939452) (xy 109.930172 -269.894176) (xy 109.956475 -269.85258) (xy 109.98911 -269.815743)
			(xy 110.027231 -269.784618) (xy 110.069852 -269.760011) (xy 110.115868 -269.742559) (xy 110.164087 -269.732715)
			(xy 110.213262 -269.730734) (xy 110.262117 -269.736666) (xy 110.309388 -269.750358) (xy 110.35385 -269.771456)
			(xy 110.394353 -269.799412) (xy 110.429846 -269.833504) (xy 110.459411 -269.872848) (xy 110.482282 -269.916425)
			(xy 110.497866 -269.963106) (xy 110.505761 -270.011683) (xy 110.506256 -270.03629) (xy 113.64901 -270.03629)
			(xy 113.65297 -269.987236) (xy 113.664747 -269.939452) (xy 113.684038 -269.894176) (xy 113.710341 -269.85258)
			(xy 113.742976 -269.815743) (xy 113.781097 -269.784618) (xy 113.823718 -269.760011) (xy 113.869734 -269.742559)
			(xy 113.917953 -269.732715) (xy 113.967128 -269.730734) (xy 114.015983 -269.736666) (xy 114.063254 -269.750358)
			(xy 114.107716 -269.771456) (xy 114.148219 -269.799412) (xy 114.183712 -269.833504) (xy 114.213277 -269.872848)
			(xy 114.236148 -269.916425) (xy 114.251732 -269.963106) (xy 114.259627 -270.011683) (xy 114.260122 -270.03629)
			(xy 114.58881 -270.03629) (xy 114.59277 -269.987236) (xy 114.604547 -269.939452) (xy 114.623838 -269.894176)
			(xy 114.650141 -269.85258) (xy 114.682776 -269.815743) (xy 114.720897 -269.784618) (xy 114.763518 -269.760011)
			(xy 114.809534 -269.742559) (xy 114.857753 -269.732715) (xy 114.906928 -269.730734) (xy 114.955783 -269.736666)
			(xy 115.003054 -269.750358) (xy 115.047516 -269.771456) (xy 115.088019 -269.799412) (xy 115.123512 -269.833504)
			(xy 115.153077 -269.872848) (xy 115.175948 -269.916425) (xy 115.191532 -269.963106) (xy 115.199427 -270.011683)
			(xy 115.199922 -270.03629) (xy 115.528864 -270.03629) (xy 115.532824 -269.987236) (xy 115.544601 -269.939452)
			(xy 115.563892 -269.894176) (xy 115.590195 -269.85258) (xy 115.62283 -269.815743) (xy 115.660951 -269.784618)
			(xy 115.703572 -269.760011) (xy 115.749588 -269.742559) (xy 115.797807 -269.732715) (xy 115.846982 -269.730734)
			(xy 115.895837 -269.736666) (xy 115.943108 -269.750358) (xy 115.98757 -269.771456) (xy 116.028073 -269.799412)
			(xy 116.063566 -269.833504) (xy 116.093131 -269.872848) (xy 116.116002 -269.916425) (xy 116.131586 -269.963106)
			(xy 116.139481 -270.011683) (xy 116.139976 -270.03629) (xy 116.468918 -270.03629) (xy 116.472878 -269.987236)
			(xy 116.484655 -269.939452) (xy 116.503946 -269.894176) (xy 116.530249 -269.85258) (xy 116.562884 -269.815743)
			(xy 116.601005 -269.784618) (xy 116.643626 -269.760011) (xy 116.689642 -269.742559) (xy 116.737861 -269.732715)
			(xy 116.787036 -269.730734) (xy 116.835891 -269.736666) (xy 116.883162 -269.750358) (xy 116.927624 -269.771456)
			(xy 116.968127 -269.799412) (xy 117.00362 -269.833504) (xy 117.033185 -269.872848) (xy 117.056056 -269.916425)
			(xy 117.07164 -269.963106) (xy 117.079535 -270.011683) (xy 117.08003 -270.03629) (xy 117.408972 -270.03629)
			(xy 117.412932 -269.987236) (xy 117.424709 -269.939452) (xy 117.444 -269.894176) (xy 117.470303 -269.85258)
			(xy 117.502938 -269.815743) (xy 117.541059 -269.784618) (xy 117.58368 -269.760011) (xy 117.629696 -269.742559)
			(xy 117.677915 -269.732715) (xy 117.72709 -269.730734) (xy 117.775945 -269.736666) (xy 117.823216 -269.750358)
			(xy 117.867678 -269.771456) (xy 117.908181 -269.799412) (xy 117.943674 -269.833504) (xy 117.973239 -269.872848)
			(xy 117.99611 -269.916425) (xy 118.011694 -269.963106) (xy 118.019589 -270.011683) (xy 118.020084 -270.03629)
			(xy 118.349026 -270.03629) (xy 118.352986 -269.987236) (xy 118.364763 -269.939452) (xy 118.384054 -269.894176)
			(xy 118.410357 -269.85258) (xy 118.442992 -269.815743) (xy 118.481113 -269.784618) (xy 118.523734 -269.760011)
			(xy 118.56975 -269.742559) (xy 118.617969 -269.732715) (xy 118.667144 -269.730734) (xy 118.715999 -269.736666)
			(xy 118.76327 -269.750358) (xy 118.807732 -269.771456) (xy 118.848235 -269.799412) (xy 118.883728 -269.833504)
			(xy 118.913293 -269.872848) (xy 118.936164 -269.916425) (xy 118.951748 -269.963106) (xy 118.959643 -270.011683)
			(xy 118.960138 -270.03629) (xy 119.288826 -270.03629) (xy 119.292786 -269.987236) (xy 119.304563 -269.939452)
			(xy 119.323854 -269.894176) (xy 119.350157 -269.85258) (xy 119.382792 -269.815743) (xy 119.420913 -269.784618)
			(xy 119.463534 -269.760011) (xy 119.50955 -269.742559) (xy 119.557769 -269.732715) (xy 119.606944 -269.730734)
			(xy 119.655799 -269.736666) (xy 119.70307 -269.750358) (xy 119.747532 -269.771456) (xy 119.788035 -269.799412)
			(xy 119.823528 -269.833504) (xy 119.853093 -269.872848) (xy 119.875964 -269.916425) (xy 119.891548 -269.963106)
			(xy 119.899443 -270.011683) (xy 119.899938 -270.03629) (xy 120.22888 -270.03629) (xy 120.23284 -269.987236)
			(xy 120.244617 -269.939452) (xy 120.263908 -269.894176) (xy 120.290211 -269.85258) (xy 120.322846 -269.815743)
			(xy 120.360967 -269.784618) (xy 120.403588 -269.760011) (xy 120.449604 -269.742559) (xy 120.497823 -269.732715)
			(xy 120.546998 -269.730734) (xy 120.595853 -269.736666) (xy 120.643124 -269.750358) (xy 120.687586 -269.771456)
			(xy 120.728089 -269.799412) (xy 120.763582 -269.833504) (xy 120.793147 -269.872848) (xy 120.816018 -269.916425)
			(xy 120.831602 -269.963106) (xy 120.839497 -270.011683) (xy 120.839992 -270.03629) (xy 121.168934 -270.03629)
			(xy 121.172894 -269.987236) (xy 121.184671 -269.939452) (xy 121.203962 -269.894176) (xy 121.230265 -269.85258)
			(xy 121.2629 -269.815743) (xy 121.301021 -269.784618) (xy 121.343642 -269.760011) (xy 121.389658 -269.742559)
			(xy 121.437877 -269.732715) (xy 121.487052 -269.730734) (xy 121.535907 -269.736666) (xy 121.583178 -269.750358)
			(xy 121.62764 -269.771456) (xy 121.668143 -269.799412) (xy 121.703636 -269.833504) (xy 121.733201 -269.872848)
			(xy 121.756072 -269.916425) (xy 121.771656 -269.963106) (xy 121.779551 -270.011683) (xy 121.780046 -270.03629)
			(xy 122.108988 -270.03629) (xy 122.112948 -269.987236) (xy 122.124725 -269.939452) (xy 122.144016 -269.894176)
			(xy 122.170319 -269.85258) (xy 122.202954 -269.815743) (xy 122.241075 -269.784618) (xy 122.283696 -269.760011)
			(xy 122.329712 -269.742559) (xy 122.377931 -269.732715) (xy 122.427106 -269.730734) (xy 122.475961 -269.736666)
			(xy 122.523232 -269.750358) (xy 122.567694 -269.771456) (xy 122.608197 -269.799412) (xy 122.64369 -269.833504)
			(xy 122.673255 -269.872848) (xy 122.696126 -269.916425) (xy 122.71171 -269.963106) (xy 122.719605 -270.011683)
			(xy 122.7201 -270.03629) (xy 123.049042 -270.03629) (xy 123.053002 -269.987236) (xy 123.064779 -269.939452)
			(xy 123.08407 -269.894176) (xy 123.110373 -269.85258) (xy 123.143008 -269.815743) (xy 123.181129 -269.784618)
			(xy 123.22375 -269.760011) (xy 123.269766 -269.742559) (xy 123.317985 -269.732715) (xy 123.36716 -269.730734)
			(xy 123.416015 -269.736666) (xy 123.463286 -269.750358) (xy 123.507748 -269.771456) (xy 123.548251 -269.799412)
			(xy 123.583744 -269.833504) (xy 123.613309 -269.872848) (xy 123.63618 -269.916425) (xy 123.651764 -269.963106)
			(xy 123.659659 -270.011683) (xy 123.660154 -270.03629) (xy 123.988842 -270.03629) (xy 123.992802 -269.987236)
			(xy 124.004579 -269.939452) (xy 124.02387 -269.894176) (xy 124.050173 -269.85258) (xy 124.082808 -269.815743)
			(xy 124.120929 -269.784618) (xy 124.16355 -269.760011) (xy 124.209566 -269.742559) (xy 124.257785 -269.732715)
			(xy 124.30696 -269.730734) (xy 124.355815 -269.736666) (xy 124.403086 -269.750358) (xy 124.447548 -269.771456)
			(xy 124.488051 -269.799412) (xy 124.523544 -269.833504) (xy 124.553109 -269.872848) (xy 124.57598 -269.916425)
			(xy 124.591564 -269.963106) (xy 124.599459 -270.011683) (xy 124.599954 -270.03629) (xy 124.928896 -270.03629)
			(xy 124.932856 -269.987236) (xy 124.944633 -269.939452) (xy 124.963924 -269.894176) (xy 124.990227 -269.85258)
			(xy 125.022862 -269.815743) (xy 125.060983 -269.784618) (xy 125.103604 -269.760011) (xy 125.14962 -269.742559)
			(xy 125.197839 -269.732715) (xy 125.247014 -269.730734) (xy 125.295869 -269.736666) (xy 125.34314 -269.750358)
			(xy 125.387602 -269.771456) (xy 125.428105 -269.799412) (xy 125.463598 -269.833504) (xy 125.493163 -269.872848)
			(xy 125.516034 -269.916425) (xy 125.531618 -269.963106) (xy 125.539513 -270.011683) (xy 125.540008 -270.03629)
			(xy 125.86895 -270.03629) (xy 125.87291 -269.987236) (xy 125.884687 -269.939452) (xy 125.903978 -269.894176)
			(xy 125.930281 -269.85258) (xy 125.962916 -269.815743) (xy 126.001037 -269.784618) (xy 126.043658 -269.760011)
			(xy 126.089674 -269.742559) (xy 126.137893 -269.732715) (xy 126.187068 -269.730734) (xy 126.235923 -269.736666)
			(xy 126.283194 -269.750358) (xy 126.327656 -269.771456) (xy 126.368159 -269.799412) (xy 126.403652 -269.833504)
			(xy 126.433217 -269.872848) (xy 126.456088 -269.916425) (xy 126.471672 -269.963106) (xy 126.479567 -270.011683)
			(xy 126.480062 -270.03629) (xy 126.479567 -270.060897) (xy 126.471672 -270.109474) (xy 126.456088 -270.156155)
			(xy 126.433217 -270.199732) (xy 126.403652 -270.239076) (xy 126.368159 -270.273168) (xy 126.327656 -270.301124)
			(xy 126.283194 -270.322222) (xy 126.235923 -270.335914) (xy 126.187068 -270.341846) (xy 126.137893 -270.339865)
			(xy 126.089674 -270.330021) (xy 126.043658 -270.312569) (xy 126.001037 -270.287962) (xy 125.962916 -270.256837)
			(xy 125.930281 -270.22) (xy 125.903978 -270.178404) (xy 125.884687 -270.133128) (xy 125.87291 -270.085344)
			(xy 125.86895 -270.03629) (xy 125.540008 -270.03629) (xy 125.539513 -270.060897) (xy 125.531618 -270.109474)
			(xy 125.516034 -270.156155) (xy 125.493163 -270.199732) (xy 125.463598 -270.239076) (xy 125.428105 -270.273168)
			(xy 125.387602 -270.301124) (xy 125.34314 -270.322222) (xy 125.295869 -270.335914) (xy 125.247014 -270.341846)
			(xy 125.197839 -270.339865) (xy 125.14962 -270.330021) (xy 125.103604 -270.312569) (xy 125.060983 -270.287962)
			(xy 125.022862 -270.256837) (xy 124.990227 -270.22) (xy 124.963924 -270.178404) (xy 124.944633 -270.133128)
			(xy 124.932856 -270.085344) (xy 124.928896 -270.03629) (xy 124.599954 -270.03629) (xy 124.599459 -270.060897)
			(xy 124.591564 -270.109474) (xy 124.57598 -270.156155) (xy 124.553109 -270.199732) (xy 124.523544 -270.239076)
			(xy 124.488051 -270.273168) (xy 124.447548 -270.301124) (xy 124.403086 -270.322222) (xy 124.355815 -270.335914)
			(xy 124.30696 -270.341846) (xy 124.257785 -270.339865) (xy 124.209566 -270.330021) (xy 124.16355 -270.312569)
			(xy 124.120929 -270.287962) (xy 124.082808 -270.256837) (xy 124.050173 -270.22) (xy 124.02387 -270.178404)
			(xy 124.004579 -270.133128) (xy 123.992802 -270.085344) (xy 123.988842 -270.03629) (xy 123.660154 -270.03629)
			(xy 123.659659 -270.060897) (xy 123.651764 -270.109474) (xy 123.63618 -270.156155) (xy 123.613309 -270.199732)
			(xy 123.583744 -270.239076) (xy 123.548251 -270.273168) (xy 123.507748 -270.301124) (xy 123.463286 -270.322222)
			(xy 123.416015 -270.335914) (xy 123.36716 -270.341846) (xy 123.317985 -270.339865) (xy 123.269766 -270.330021)
			(xy 123.22375 -270.312569) (xy 123.181129 -270.287962) (xy 123.143008 -270.256837) (xy 123.110373 -270.22)
			(xy 123.08407 -270.178404) (xy 123.064779 -270.133128) (xy 123.053002 -270.085344) (xy 123.049042 -270.03629)
			(xy 122.7201 -270.03629) (xy 122.719605 -270.060897) (xy 122.71171 -270.109474) (xy 122.696126 -270.156155)
			(xy 122.673255 -270.199732) (xy 122.64369 -270.239076) (xy 122.608197 -270.273168) (xy 122.567694 -270.301124)
			(xy 122.523232 -270.322222) (xy 122.475961 -270.335914) (xy 122.427106 -270.341846) (xy 122.377931 -270.339865)
			(xy 122.329712 -270.330021) (xy 122.283696 -270.312569) (xy 122.241075 -270.287962) (xy 122.202954 -270.256837)
			(xy 122.170319 -270.22) (xy 122.144016 -270.178404) (xy 122.124725 -270.133128) (xy 122.112948 -270.085344)
			(xy 122.108988 -270.03629) (xy 121.780046 -270.03629) (xy 121.779551 -270.060897) (xy 121.771656 -270.109474)
			(xy 121.756072 -270.156155) (xy 121.733201 -270.199732) (xy 121.703636 -270.239076) (xy 121.668143 -270.273168)
			(xy 121.62764 -270.301124) (xy 121.583178 -270.322222) (xy 121.535907 -270.335914) (xy 121.487052 -270.341846)
			(xy 121.437877 -270.339865) (xy 121.389658 -270.330021) (xy 121.343642 -270.312569) (xy 121.301021 -270.287962)
			(xy 121.2629 -270.256837) (xy 121.230265 -270.22) (xy 121.203962 -270.178404) (xy 121.184671 -270.133128)
			(xy 121.172894 -270.085344) (xy 121.168934 -270.03629) (xy 120.839992 -270.03629) (xy 120.839497 -270.060897)
			(xy 120.831602 -270.109474) (xy 120.816018 -270.156155) (xy 120.793147 -270.199732) (xy 120.763582 -270.239076)
			(xy 120.728089 -270.273168) (xy 120.687586 -270.301124) (xy 120.643124 -270.322222) (xy 120.595853 -270.335914)
			(xy 120.546998 -270.341846) (xy 120.497823 -270.339865) (xy 120.449604 -270.330021) (xy 120.403588 -270.312569)
			(xy 120.360967 -270.287962) (xy 120.322846 -270.256837) (xy 120.290211 -270.22) (xy 120.263908 -270.178404)
			(xy 120.244617 -270.133128) (xy 120.23284 -270.085344) (xy 120.22888 -270.03629) (xy 119.899938 -270.03629)
			(xy 119.899443 -270.060897) (xy 119.891548 -270.109474) (xy 119.875964 -270.156155) (xy 119.853093 -270.199732)
			(xy 119.823528 -270.239076) (xy 119.788035 -270.273168) (xy 119.747532 -270.301124) (xy 119.70307 -270.322222)
			(xy 119.655799 -270.335914) (xy 119.606944 -270.341846) (xy 119.557769 -270.339865) (xy 119.50955 -270.330021)
			(xy 119.463534 -270.312569) (xy 119.420913 -270.287962) (xy 119.382792 -270.256837) (xy 119.350157 -270.22)
			(xy 119.323854 -270.178404) (xy 119.304563 -270.133128) (xy 119.292786 -270.085344) (xy 119.288826 -270.03629)
			(xy 118.960138 -270.03629) (xy 118.959643 -270.060897) (xy 118.951748 -270.109474) (xy 118.936164 -270.156155)
			(xy 118.913293 -270.199732) (xy 118.883728 -270.239076) (xy 118.848235 -270.273168) (xy 118.807732 -270.301124)
			(xy 118.76327 -270.322222) (xy 118.715999 -270.335914) (xy 118.667144 -270.341846) (xy 118.617969 -270.339865)
			(xy 118.56975 -270.330021) (xy 118.523734 -270.312569) (xy 118.481113 -270.287962) (xy 118.442992 -270.256837)
			(xy 118.410357 -270.22) (xy 118.384054 -270.178404) (xy 118.364763 -270.133128) (xy 118.352986 -270.085344)
			(xy 118.349026 -270.03629) (xy 118.020084 -270.03629) (xy 118.019589 -270.060897) (xy 118.011694 -270.109474)
			(xy 117.99611 -270.156155) (xy 117.973239 -270.199732) (xy 117.943674 -270.239076) (xy 117.908181 -270.273168)
			(xy 117.867678 -270.301124) (xy 117.823216 -270.322222) (xy 117.775945 -270.335914) (xy 117.72709 -270.341846)
			(xy 117.677915 -270.339865) (xy 117.629696 -270.330021) (xy 117.58368 -270.312569) (xy 117.541059 -270.287962)
			(xy 117.502938 -270.256837) (xy 117.470303 -270.22) (xy 117.444 -270.178404) (xy 117.424709 -270.133128)
			(xy 117.412932 -270.085344) (xy 117.408972 -270.03629) (xy 117.08003 -270.03629) (xy 117.079535 -270.060897)
			(xy 117.07164 -270.109474) (xy 117.056056 -270.156155) (xy 117.033185 -270.199732) (xy 117.00362 -270.239076)
			(xy 116.968127 -270.273168) (xy 116.927624 -270.301124) (xy 116.883162 -270.322222) (xy 116.835891 -270.335914)
			(xy 116.787036 -270.341846) (xy 116.737861 -270.339865) (xy 116.689642 -270.330021) (xy 116.643626 -270.312569)
			(xy 116.601005 -270.287962) (xy 116.562884 -270.256837) (xy 116.530249 -270.22) (xy 116.503946 -270.178404)
			(xy 116.484655 -270.133128) (xy 116.472878 -270.085344) (xy 116.468918 -270.03629) (xy 116.139976 -270.03629)
			(xy 116.139481 -270.060897) (xy 116.131586 -270.109474) (xy 116.116002 -270.156155) (xy 116.093131 -270.199732)
			(xy 116.063566 -270.239076) (xy 116.028073 -270.273168) (xy 115.98757 -270.301124) (xy 115.943108 -270.322222)
			(xy 115.895837 -270.335914) (xy 115.846982 -270.341846) (xy 115.797807 -270.339865) (xy 115.749588 -270.330021)
			(xy 115.703572 -270.312569) (xy 115.660951 -270.287962) (xy 115.62283 -270.256837) (xy 115.590195 -270.22)
			(xy 115.563892 -270.178404) (xy 115.544601 -270.133128) (xy 115.532824 -270.085344) (xy 115.528864 -270.03629)
			(xy 115.199922 -270.03629) (xy 115.199427 -270.060897) (xy 115.191532 -270.109474) (xy 115.175948 -270.156155)
			(xy 115.153077 -270.199732) (xy 115.123512 -270.239076) (xy 115.088019 -270.273168) (xy 115.047516 -270.301124)
			(xy 115.003054 -270.322222) (xy 114.955783 -270.335914) (xy 114.906928 -270.341846) (xy 114.857753 -270.339865)
			(xy 114.809534 -270.330021) (xy 114.763518 -270.312569) (xy 114.720897 -270.287962) (xy 114.682776 -270.256837)
			(xy 114.650141 -270.22) (xy 114.623838 -270.178404) (xy 114.604547 -270.133128) (xy 114.59277 -270.085344)
			(xy 114.58881 -270.03629) (xy 114.260122 -270.03629) (xy 114.259627 -270.060897) (xy 114.251732 -270.109474)
			(xy 114.236148 -270.156155) (xy 114.213277 -270.199732) (xy 114.183712 -270.239076) (xy 114.148219 -270.273168)
			(xy 114.107716 -270.301124) (xy 114.063254 -270.322222) (xy 114.015983 -270.335914) (xy 113.967128 -270.341846)
			(xy 113.917953 -270.339865) (xy 113.869734 -270.330021) (xy 113.823718 -270.312569) (xy 113.781097 -270.287962)
			(xy 113.742976 -270.256837) (xy 113.710341 -270.22) (xy 113.684038 -270.178404) (xy 113.664747 -270.133128)
			(xy 113.65297 -270.085344) (xy 113.64901 -270.03629) (xy 110.506256 -270.03629) (xy 110.505761 -270.060897)
			(xy 110.497866 -270.109474) (xy 110.482282 -270.156155) (xy 110.459411 -270.199732) (xy 110.429846 -270.239076)
			(xy 110.394353 -270.273168) (xy 110.35385 -270.301124) (xy 110.309388 -270.322222) (xy 110.262117 -270.335914)
			(xy 110.213262 -270.341846) (xy 110.164087 -270.339865) (xy 110.115868 -270.330021) (xy 110.069852 -270.312569)
			(xy 110.027231 -270.287962) (xy 109.98911 -270.256837) (xy 109.956475 -270.22) (xy 109.930172 -270.178404)
			(xy 109.910881 -270.133128) (xy 109.899104 -270.085344) (xy 109.895144 -270.03629) (xy 109.566456 -270.03629)
			(xy 109.565961 -270.060897) (xy 109.558066 -270.109474) (xy 109.542482 -270.156155) (xy 109.519611 -270.199732)
			(xy 109.490046 -270.239076) (xy 109.454553 -270.273168) (xy 109.41405 -270.301124) (xy 109.369588 -270.322222)
			(xy 109.322317 -270.335914) (xy 109.273462 -270.341846) (xy 109.224287 -270.339865) (xy 109.176068 -270.330021)
			(xy 109.130052 -270.312569) (xy 109.087431 -270.287962) (xy 109.04931 -270.256837) (xy 109.016675 -270.22)
			(xy 108.990372 -270.178404) (xy 108.971081 -270.133128) (xy 108.959304 -270.085344) (xy 108.955344 -270.03629)
			(xy 108.626402 -270.03629) (xy 108.625907 -270.060897) (xy 108.618012 -270.109474) (xy 108.602428 -270.156155)
			(xy 108.579557 -270.199732) (xy 108.549992 -270.239076) (xy 108.514499 -270.273168) (xy 108.473996 -270.301124)
			(xy 108.429534 -270.322222) (xy 108.382263 -270.335914) (xy 108.333408 -270.341846) (xy 108.284233 -270.339865)
			(xy 108.236014 -270.330021) (xy 108.189998 -270.312569) (xy 108.147377 -270.287962) (xy 108.109256 -270.256837)
			(xy 108.076621 -270.22) (xy 108.050318 -270.178404) (xy 108.031027 -270.133128) (xy 108.01925 -270.085344)
			(xy 108.01529 -270.03629) (xy 107.686348 -270.03629) (xy 107.685853 -270.060897) (xy 107.677958 -270.109474)
			(xy 107.662374 -270.156155) (xy 107.639503 -270.199732) (xy 107.609938 -270.239076) (xy 107.574445 -270.273168)
			(xy 107.533942 -270.301124) (xy 107.48948 -270.322222) (xy 107.442209 -270.335914) (xy 107.393354 -270.341846)
			(xy 107.344179 -270.339865) (xy 107.29596 -270.330021) (xy 107.249944 -270.312569) (xy 107.207323 -270.287962)
			(xy 107.169202 -270.256837) (xy 107.136567 -270.22) (xy 107.110264 -270.178404) (xy 107.090973 -270.133128)
			(xy 107.079196 -270.085344) (xy 107.075236 -270.03629) (xy 106.746294 -270.03629) (xy 106.745799 -270.060897)
			(xy 106.737904 -270.109474) (xy 106.72232 -270.156155) (xy 106.699449 -270.199732) (xy 106.669884 -270.239076)
			(xy 106.634391 -270.273168) (xy 106.593888 -270.301124) (xy 106.549426 -270.322222) (xy 106.502155 -270.335914)
			(xy 106.4533 -270.341846) (xy 106.404125 -270.339865) (xy 106.355906 -270.330021) (xy 106.30989 -270.312569)
			(xy 106.267269 -270.287962) (xy 106.229148 -270.256837) (xy 106.196513 -270.22) (xy 106.17021 -270.178404)
			(xy 106.150919 -270.133128) (xy 106.139142 -270.085344) (xy 106.135182 -270.03629) (xy 105.80624 -270.03629)
			(xy 105.805745 -270.060897) (xy 105.79785 -270.109474) (xy 105.782266 -270.156155) (xy 105.759395 -270.199732)
			(xy 105.72983 -270.239076) (xy 105.694337 -270.273168) (xy 105.653834 -270.301124) (xy 105.609372 -270.322222)
			(xy 105.562101 -270.335914) (xy 105.513246 -270.341846) (xy 105.464071 -270.339865) (xy 105.415852 -270.330021)
			(xy 105.369836 -270.312569) (xy 105.327215 -270.287962) (xy 105.289094 -270.256837) (xy 105.256459 -270.22)
			(xy 105.230156 -270.178404) (xy 105.210865 -270.133128) (xy 105.199088 -270.085344) (xy 105.195128 -270.03629)
			(xy 104.86644 -270.03629) (xy 104.865945 -270.060897) (xy 104.85805 -270.109474) (xy 104.842466 -270.156155)
			(xy 104.819595 -270.199732) (xy 104.79003 -270.239076) (xy 104.754537 -270.273168) (xy 104.714034 -270.301124)
			(xy 104.669572 -270.322222) (xy 104.622301 -270.335914) (xy 104.573446 -270.341846) (xy 104.524271 -270.339865)
			(xy 104.476052 -270.330021) (xy 104.430036 -270.312569) (xy 104.387415 -270.287962) (xy 104.349294 -270.256837)
			(xy 104.316659 -270.22) (xy 104.290356 -270.178404) (xy 104.271065 -270.133128) (xy 104.259288 -270.085344)
			(xy 104.255328 -270.03629) (xy 103.926386 -270.03629) (xy 103.925891 -270.060897) (xy 103.917996 -270.109474)
			(xy 103.902412 -270.156155) (xy 103.879541 -270.199732) (xy 103.849976 -270.239076) (xy 103.814483 -270.273168)
			(xy 103.77398 -270.301124) (xy 103.729518 -270.322222) (xy 103.682247 -270.335914) (xy 103.633392 -270.341846)
			(xy 103.584217 -270.339865) (xy 103.535998 -270.330021) (xy 103.489982 -270.312569) (xy 103.447361 -270.287962)
			(xy 103.40924 -270.256837) (xy 103.376605 -270.22) (xy 103.350302 -270.178404) (xy 103.331011 -270.133128)
			(xy 103.319234 -270.085344) (xy 103.315274 -270.03629) (xy 102.986332 -270.03629) (xy 102.985837 -270.060897)
			(xy 102.977942 -270.109474) (xy 102.962358 -270.156155) (xy 102.939487 -270.199732) (xy 102.909922 -270.239076)
			(xy 102.874429 -270.273168) (xy 102.833926 -270.301124) (xy 102.789464 -270.322222) (xy 102.742193 -270.335914)
			(xy 102.693338 -270.341846) (xy 102.644163 -270.339865) (xy 102.595944 -270.330021) (xy 102.549928 -270.312569)
			(xy 102.507307 -270.287962) (xy 102.469186 -270.256837) (xy 102.436551 -270.22) (xy 102.410248 -270.178404)
			(xy 102.390957 -270.133128) (xy 102.37918 -270.085344) (xy 102.37522 -270.03629) (xy 102.046278 -270.03629)
			(xy 102.045783 -270.060897) (xy 102.037888 -270.109474) (xy 102.022304 -270.156155) (xy 101.999433 -270.199732)
			(xy 101.969868 -270.239076) (xy 101.934375 -270.273168) (xy 101.893872 -270.301124) (xy 101.84941 -270.322222)
			(xy 101.802139 -270.335914) (xy 101.753284 -270.341846) (xy 101.704109 -270.339865) (xy 101.65589 -270.330021)
			(xy 101.609874 -270.312569) (xy 101.567253 -270.287962) (xy 101.529132 -270.256837) (xy 101.496497 -270.22)
			(xy 101.470194 -270.178404) (xy 101.450903 -270.133128) (xy 101.439126 -270.085344) (xy 101.435166 -270.03629)
			(xy 101.106478 -270.03629) (xy 101.105983 -270.060897) (xy 101.098088 -270.109474) (xy 101.082504 -270.156155)
			(xy 101.059633 -270.199732) (xy 101.030068 -270.239076) (xy 100.994575 -270.273168) (xy 100.954072 -270.301124)
			(xy 100.90961 -270.322222) (xy 100.862339 -270.335914) (xy 100.813484 -270.341846) (xy 100.764309 -270.339865)
			(xy 100.71609 -270.330021) (xy 100.670074 -270.312569) (xy 100.627453 -270.287962) (xy 100.589332 -270.256837)
			(xy 100.556697 -270.22) (xy 100.530394 -270.178404) (xy 100.511103 -270.133128) (xy 100.499326 -270.085344)
			(xy 100.495366 -270.03629) (xy 100.166424 -270.03629) (xy 100.165929 -270.060897) (xy 100.158034 -270.109474)
			(xy 100.14245 -270.156155) (xy 100.119579 -270.199732) (xy 100.090014 -270.239076) (xy 100.054521 -270.273168)
			(xy 100.014018 -270.301124) (xy 99.969556 -270.322222) (xy 99.922285 -270.335914) (xy 99.87343 -270.341846)
			(xy 99.824255 -270.339865) (xy 99.776036 -270.330021) (xy 99.73002 -270.312569) (xy 99.687399 -270.287962)
			(xy 99.649278 -270.256837) (xy 99.616643 -270.22) (xy 99.59034 -270.178404) (xy 99.571049 -270.133128)
			(xy 99.559272 -270.085344) (xy 99.555312 -270.03629) (xy 99.22637 -270.03629) (xy 99.225875 -270.060897)
			(xy 99.21798 -270.109474) (xy 99.202396 -270.156155) (xy 99.179525 -270.199732) (xy 99.14996 -270.239076)
			(xy 99.114467 -270.273168) (xy 99.073964 -270.301124) (xy 99.029502 -270.322222) (xy 98.982231 -270.335914)
			(xy 98.933376 -270.341846) (xy 98.884201 -270.339865) (xy 98.835982 -270.330021) (xy 98.789966 -270.312569)
			(xy 98.747345 -270.287962) (xy 98.709224 -270.256837) (xy 98.676589 -270.22) (xy 98.650286 -270.178404)
			(xy 98.630995 -270.133128) (xy 98.619218 -270.085344) (xy 98.615258 -270.03629) (xy 98.286316 -270.03629)
			(xy 98.285821 -270.060897) (xy 98.277926 -270.109474) (xy 98.262342 -270.156155) (xy 98.239471 -270.199732)
			(xy 98.209906 -270.239076) (xy 98.174413 -270.273168) (xy 98.13391 -270.301124) (xy 98.089448 -270.322222)
			(xy 98.042177 -270.335914) (xy 97.993322 -270.341846) (xy 97.944147 -270.339865) (xy 97.895928 -270.330021)
			(xy 97.849912 -270.312569) (xy 97.807291 -270.287962) (xy 97.76917 -270.256837) (xy 97.736535 -270.22)
			(xy 97.710232 -270.178404) (xy 97.690941 -270.133128) (xy 97.679164 -270.085344) (xy 97.675204 -270.03629)
			(xy 97.346262 -270.03629) (xy 97.345767 -270.060897) (xy 97.337872 -270.109474) (xy 97.322288 -270.156155)
			(xy 97.299417 -270.199732) (xy 97.269852 -270.239076) (xy 97.234359 -270.273168) (xy 97.193856 -270.301124)
			(xy 97.149394 -270.322222) (xy 97.102123 -270.335914) (xy 97.053268 -270.341846) (xy 97.004093 -270.339865)
			(xy 96.955874 -270.330021) (xy 96.909858 -270.312569) (xy 96.867237 -270.287962) (xy 96.829116 -270.256837)
			(xy 96.796481 -270.22) (xy 96.770178 -270.178404) (xy 96.750887 -270.133128) (xy 96.73911 -270.085344)
			(xy 96.73515 -270.03629) (xy 96.416876 -270.03629) (xy 96.416364 -270.061736) (xy 96.4082 -270.11197)
			(xy 96.392084 -270.160244) (xy 96.368433 -270.205307) (xy 96.33786 -270.245993) (xy 96.301156 -270.281248)
			(xy 96.259272 -270.310158) (xy 96.213293 -270.331975) (xy 96.164409 -270.346135) (xy 96.113888 -270.352269)
			(xy 96.063036 -270.35022) (xy 96.013172 -270.34004) (xy 95.965586 -270.321993) (xy 95.921512 -270.296547)
			(xy 95.88209 -270.26436) (xy 95.848342 -270.226266) (xy 95.821141 -270.183252) (xy 95.801193 -270.136432)
			(xy 95.789014 -270.087018) (xy 95.784919 -270.03629) (xy 95.466408 -270.03629) (xy 95.465913 -270.060897)
			(xy 95.458018 -270.109474) (xy 95.442434 -270.156155) (xy 95.419563 -270.199732) (xy 95.389998 -270.239076)
			(xy 95.354505 -270.273168) (xy 95.314002 -270.301124) (xy 95.26954 -270.322222) (xy 95.222269 -270.335914)
			(xy 95.173414 -270.341846) (xy 95.124239 -270.339865) (xy 95.07602 -270.330021) (xy 95.030004 -270.312569)
			(xy 94.987383 -270.287962) (xy 94.949262 -270.256837) (xy 94.916627 -270.22) (xy 94.890324 -270.178404)
			(xy 94.871033 -270.133128) (xy 94.859256 -270.085344) (xy 94.855296 -270.03629) (xy 94.536768 -270.03629)
			(xy 94.536256 -270.061736) (xy 94.528092 -270.11197) (xy 94.511976 -270.160244) (xy 94.488325 -270.205307)
			(xy 94.457752 -270.245993) (xy 94.421048 -270.281248) (xy 94.379164 -270.310158) (xy 94.333185 -270.331975)
			(xy 94.284301 -270.346135) (xy 94.23378 -270.352269) (xy 94.182928 -270.35022) (xy 94.133064 -270.34004)
			(xy 94.085478 -270.321993) (xy 94.041404 -270.296547) (xy 94.001982 -270.26436) (xy 93.968234 -270.226266)
			(xy 93.941033 -270.183252) (xy 93.921085 -270.136432) (xy 93.908906 -270.087018) (xy 93.904811 -270.03629)
			(xy 93.5863 -270.03629) (xy 93.585835 -270.06014) (xy 93.578407 -270.107259) (xy 93.563746 -270.152651)
			(xy 93.542208 -270.195212) (xy 93.514318 -270.233909) (xy 93.480751 -270.2678) (xy 93.442325 -270.296063)
			(xy 93.399973 -270.31801) (xy 93.354725 -270.333108) (xy 93.331284 -270.337534) (xy 93.322648 -270.339058)
			(xy 93.294708 -270.359378) (xy 93.289835 -270.363131) (xy 93.281876 -270.372504) (xy 93.27896 -270.37792)
			(xy 93.248226 -270.440404) (xy 93.24721 -270.442944) (xy 93.243636 -270.452313) (xy 93.243369 -270.472349)
			(xy 93.246702 -270.481806) (xy 93.246956 -270.482568) (xy 93.250004 -270.48841) (xy 93.294708 -270.565372)
			(xy 93.305178 -270.583852) (xy 93.323612 -270.622121) (xy 93.331538 -270.641826) (xy 93.331538 -270.64208)
			(xy 93.334233 -270.64828) (xy 93.342346 -270.659088) (xy 93.34754 -270.663416) (xy 93.352874 -270.66748)
			(xy 93.365066 -270.672814) (xy 93.45803 -270.685006) (xy 93.464894 -270.685671) (xy 93.478541 -270.683732)
			(xy 93.484954 -270.681196) (xy 93.490982 -270.678396) (xy 93.501406 -270.670155) (xy 93.505528 -270.66494)
			(xy 93.505782 -270.664686) (xy 93.520287 -270.645858) (xy 93.554144 -270.612505) (xy 93.592757 -270.584797)
			(xy 93.635195 -270.563403) (xy 93.680434 -270.548838) (xy 93.727383 -270.541455) (xy 93.751146 -270.540988)
			(xy 93.776399 -270.541513) (xy 93.826216 -270.549833) (xy 93.873984 -270.566238) (xy 93.9184 -270.590281)
			(xy 93.958254 -270.621306) (xy 93.992459 -270.658468) (xy 94.020081 -270.700751) (xy 94.040367 -270.747005)
			(xy 94.052765 -270.795966) (xy 94.056935 -270.846296) (xy 94.374711 -270.846296) (xy 94.378806 -270.795568)
			(xy 94.390985 -270.746154) (xy 94.410933 -270.699334) (xy 94.438134 -270.65632) (xy 94.471882 -270.618226)
			(xy 94.511304 -270.586039) (xy 94.555378 -270.560593) (xy 94.602964 -270.542546) (xy 94.652828 -270.532366)
			(xy 94.70368 -270.530317) (xy 94.754201 -270.536451) (xy 94.803085 -270.550611) (xy 94.849064 -270.572428)
			(xy 94.890948 -270.601338) (xy 94.927652 -270.636593) (xy 94.958225 -270.677279) (xy 94.981876 -270.722342)
			(xy 94.997992 -270.770616) (xy 95.006156 -270.82085) (xy 95.006668 -270.846296) (xy 95.314765 -270.846296)
			(xy 95.31886 -270.795568) (xy 95.331039 -270.746154) (xy 95.350987 -270.699334) (xy 95.378188 -270.65632)
			(xy 95.411936 -270.618226) (xy 95.451358 -270.586039) (xy 95.495432 -270.560593) (xy 95.543018 -270.542546)
			(xy 95.592882 -270.532366) (xy 95.643734 -270.530317) (xy 95.694255 -270.536451) (xy 95.743139 -270.550611)
			(xy 95.789118 -270.572428) (xy 95.831002 -270.601338) (xy 95.867706 -270.636593) (xy 95.898279 -270.677279)
			(xy 95.92193 -270.722342) (xy 95.938046 -270.770616) (xy 95.94621 -270.82085) (xy 95.946722 -270.846296)
			(xy 96.26525 -270.846296) (xy 96.26921 -270.797242) (xy 96.280987 -270.749458) (xy 96.300278 -270.704182)
			(xy 96.326581 -270.662586) (xy 96.359216 -270.625749) (xy 96.397337 -270.594624) (xy 96.439958 -270.570017)
			(xy 96.485974 -270.552565) (xy 96.534193 -270.542721) (xy 96.583368 -270.54074) (xy 96.632223 -270.546672)
			(xy 96.679494 -270.560364) (xy 96.723956 -270.581462) (xy 96.764459 -270.609418) (xy 96.799952 -270.64351)
			(xy 96.829517 -270.682854) (xy 96.852388 -270.726431) (xy 96.867972 -270.773112) (xy 96.875867 -270.821689)
			(xy 96.876362 -270.846296) (xy 97.205304 -270.846296) (xy 97.209264 -270.797242) (xy 97.221041 -270.749458)
			(xy 97.240332 -270.704182) (xy 97.266635 -270.662586) (xy 97.29927 -270.625749) (xy 97.337391 -270.594624)
			(xy 97.380012 -270.570017) (xy 97.426028 -270.552565) (xy 97.474247 -270.542721) (xy 97.523422 -270.54074)
			(xy 97.572277 -270.546672) (xy 97.619548 -270.560364) (xy 97.66401 -270.581462) (xy 97.704513 -270.609418)
			(xy 97.740006 -270.64351) (xy 97.769571 -270.682854) (xy 97.792442 -270.726431) (xy 97.808026 -270.773112)
			(xy 97.815921 -270.821689) (xy 97.816416 -270.846296) (xy 98.145358 -270.846296) (xy 98.149318 -270.797242)
			(xy 98.161095 -270.749458) (xy 98.180386 -270.704182) (xy 98.206689 -270.662586) (xy 98.239324 -270.625749)
			(xy 98.277445 -270.594624) (xy 98.320066 -270.570017) (xy 98.366082 -270.552565) (xy 98.414301 -270.542721)
			(xy 98.463476 -270.54074) (xy 98.512331 -270.546672) (xy 98.559602 -270.560364) (xy 98.604064 -270.581462)
			(xy 98.644567 -270.609418) (xy 98.68006 -270.64351) (xy 98.709625 -270.682854) (xy 98.732496 -270.726431)
			(xy 98.74808 -270.773112) (xy 98.755975 -270.821689) (xy 98.75647 -270.846296) (xy 99.085158 -270.846296)
			(xy 99.089118 -270.797242) (xy 99.100895 -270.749458) (xy 99.120186 -270.704182) (xy 99.146489 -270.662586)
			(xy 99.179124 -270.625749) (xy 99.217245 -270.594624) (xy 99.259866 -270.570017) (xy 99.305882 -270.552565)
			(xy 99.354101 -270.542721) (xy 99.403276 -270.54074) (xy 99.452131 -270.546672) (xy 99.499402 -270.560364)
			(xy 99.543864 -270.581462) (xy 99.584367 -270.609418) (xy 99.61986 -270.64351) (xy 99.649425 -270.682854)
			(xy 99.672296 -270.726431) (xy 99.68788 -270.773112) (xy 99.695775 -270.821689) (xy 99.69627 -270.846296)
			(xy 100.025212 -270.846296) (xy 100.029172 -270.797242) (xy 100.040949 -270.749458) (xy 100.06024 -270.704182)
			(xy 100.086543 -270.662586) (xy 100.119178 -270.625749) (xy 100.157299 -270.594624) (xy 100.19992 -270.570017)
			(xy 100.245936 -270.552565) (xy 100.294155 -270.542721) (xy 100.34333 -270.54074) (xy 100.392185 -270.546672)
			(xy 100.439456 -270.560364) (xy 100.483918 -270.581462) (xy 100.524421 -270.609418) (xy 100.559914 -270.64351)
			(xy 100.589479 -270.682854) (xy 100.61235 -270.726431) (xy 100.627934 -270.773112) (xy 100.635829 -270.821689)
			(xy 100.636324 -270.846296) (xy 100.965266 -270.846296) (xy 100.969226 -270.797242) (xy 100.981003 -270.749458)
			(xy 101.000294 -270.704182) (xy 101.026597 -270.662586) (xy 101.059232 -270.625749) (xy 101.097353 -270.594624)
			(xy 101.139974 -270.570017) (xy 101.18599 -270.552565) (xy 101.234209 -270.542721) (xy 101.283384 -270.54074)
			(xy 101.332239 -270.546672) (xy 101.37951 -270.560364) (xy 101.423972 -270.581462) (xy 101.464475 -270.609418)
			(xy 101.499968 -270.64351) (xy 101.529533 -270.682854) (xy 101.552404 -270.726431) (xy 101.567988 -270.773112)
			(xy 101.575883 -270.821689) (xy 101.576378 -270.846296) (xy 101.90532 -270.846296) (xy 101.90928 -270.797242)
			(xy 101.921057 -270.749458) (xy 101.940348 -270.704182) (xy 101.966651 -270.662586) (xy 101.999286 -270.625749)
			(xy 102.037407 -270.594624) (xy 102.080028 -270.570017) (xy 102.126044 -270.552565) (xy 102.174263 -270.542721)
			(xy 102.223438 -270.54074) (xy 102.272293 -270.546672) (xy 102.319564 -270.560364) (xy 102.364026 -270.581462)
			(xy 102.404529 -270.609418) (xy 102.440022 -270.64351) (xy 102.469587 -270.682854) (xy 102.492458 -270.726431)
			(xy 102.508042 -270.773112) (xy 102.515937 -270.821689) (xy 102.516432 -270.846296) (xy 102.845374 -270.846296)
			(xy 102.849334 -270.797242) (xy 102.861111 -270.749458) (xy 102.880402 -270.704182) (xy 102.906705 -270.662586)
			(xy 102.93934 -270.625749) (xy 102.977461 -270.594624) (xy 103.020082 -270.570017) (xy 103.066098 -270.552565)
			(xy 103.114317 -270.542721) (xy 103.163492 -270.54074) (xy 103.212347 -270.546672) (xy 103.259618 -270.560364)
			(xy 103.30408 -270.581462) (xy 103.344583 -270.609418) (xy 103.380076 -270.64351) (xy 103.409641 -270.682854)
			(xy 103.432512 -270.726431) (xy 103.448096 -270.773112) (xy 103.455991 -270.821689) (xy 103.456486 -270.846296)
			(xy 103.785174 -270.846296) (xy 103.789134 -270.797242) (xy 103.800911 -270.749458) (xy 103.820202 -270.704182)
			(xy 103.846505 -270.662586) (xy 103.87914 -270.625749) (xy 103.917261 -270.594624) (xy 103.959882 -270.570017)
			(xy 104.005898 -270.552565) (xy 104.054117 -270.542721) (xy 104.103292 -270.54074) (xy 104.152147 -270.546672)
			(xy 104.199418 -270.560364) (xy 104.24388 -270.581462) (xy 104.284383 -270.609418) (xy 104.319876 -270.64351)
			(xy 104.349441 -270.682854) (xy 104.372312 -270.726431) (xy 104.387896 -270.773112) (xy 104.395791 -270.821689)
			(xy 104.396286 -270.846296) (xy 104.725228 -270.846296) (xy 104.729188 -270.797242) (xy 104.740965 -270.749458)
			(xy 104.760256 -270.704182) (xy 104.786559 -270.662586) (xy 104.819194 -270.625749) (xy 104.857315 -270.594624)
			(xy 104.899936 -270.570017) (xy 104.945952 -270.552565) (xy 104.994171 -270.542721) (xy 105.043346 -270.54074)
			(xy 105.092201 -270.546672) (xy 105.139472 -270.560364) (xy 105.183934 -270.581462) (xy 105.224437 -270.609418)
			(xy 105.25993 -270.64351) (xy 105.289495 -270.682854) (xy 105.312366 -270.726431) (xy 105.32795 -270.773112)
			(xy 105.335845 -270.821689) (xy 105.33634 -270.846296) (xy 105.665282 -270.846296) (xy 105.669242 -270.797242)
			(xy 105.681019 -270.749458) (xy 105.70031 -270.704182) (xy 105.726613 -270.662586) (xy 105.759248 -270.625749)
			(xy 105.797369 -270.594624) (xy 105.83999 -270.570017) (xy 105.886006 -270.552565) (xy 105.934225 -270.542721)
			(xy 105.9834 -270.54074) (xy 106.032255 -270.546672) (xy 106.079526 -270.560364) (xy 106.123988 -270.581462)
			(xy 106.164491 -270.609418) (xy 106.199984 -270.64351) (xy 106.229549 -270.682854) (xy 106.25242 -270.726431)
			(xy 106.268004 -270.773112) (xy 106.275899 -270.821689) (xy 106.276394 -270.846296) (xy 106.605336 -270.846296)
			(xy 106.609296 -270.797242) (xy 106.621073 -270.749458) (xy 106.640364 -270.704182) (xy 106.666667 -270.662586)
			(xy 106.699302 -270.625749) (xy 106.737423 -270.594624) (xy 106.780044 -270.570017) (xy 106.82606 -270.552565)
			(xy 106.874279 -270.542721) (xy 106.923454 -270.54074) (xy 106.972309 -270.546672) (xy 107.01958 -270.560364)
			(xy 107.064042 -270.581462) (xy 107.104545 -270.609418) (xy 107.140038 -270.64351) (xy 107.169603 -270.682854)
			(xy 107.192474 -270.726431) (xy 107.208058 -270.773112) (xy 107.215953 -270.821689) (xy 107.216448 -270.846296)
			(xy 107.545136 -270.846296) (xy 107.549096 -270.797242) (xy 107.560873 -270.749458) (xy 107.580164 -270.704182)
			(xy 107.606467 -270.662586) (xy 107.639102 -270.625749) (xy 107.677223 -270.594624) (xy 107.719844 -270.570017)
			(xy 107.76586 -270.552565) (xy 107.814079 -270.542721) (xy 107.863254 -270.54074) (xy 107.912109 -270.546672)
			(xy 107.95938 -270.560364) (xy 108.003842 -270.581462) (xy 108.044345 -270.609418) (xy 108.079838 -270.64351)
			(xy 108.109403 -270.682854) (xy 108.132274 -270.726431) (xy 108.147858 -270.773112) (xy 108.155753 -270.821689)
			(xy 108.156248 -270.846296) (xy 108.48519 -270.846296) (xy 108.48915 -270.797242) (xy 108.500927 -270.749458)
			(xy 108.520218 -270.704182) (xy 108.546521 -270.662586) (xy 108.579156 -270.625749) (xy 108.617277 -270.594624)
			(xy 108.659898 -270.570017) (xy 108.705914 -270.552565) (xy 108.754133 -270.542721) (xy 108.803308 -270.54074)
			(xy 108.852163 -270.546672) (xy 108.899434 -270.560364) (xy 108.943896 -270.581462) (xy 108.984399 -270.609418)
			(xy 109.019892 -270.64351) (xy 109.049457 -270.682854) (xy 109.072328 -270.726431) (xy 109.087912 -270.773112)
			(xy 109.095807 -270.821689) (xy 109.096302 -270.846296) (xy 109.425244 -270.846296) (xy 109.429204 -270.797242)
			(xy 109.440981 -270.749458) (xy 109.460272 -270.704182) (xy 109.486575 -270.662586) (xy 109.51921 -270.625749)
			(xy 109.557331 -270.594624) (xy 109.599952 -270.570017) (xy 109.645968 -270.552565) (xy 109.694187 -270.542721)
			(xy 109.743362 -270.54074) (xy 109.792217 -270.546672) (xy 109.839488 -270.560364) (xy 109.88395 -270.581462)
			(xy 109.924453 -270.609418) (xy 109.959946 -270.64351) (xy 109.989511 -270.682854) (xy 110.012382 -270.726431)
			(xy 110.027966 -270.773112) (xy 110.035861 -270.821689) (xy 110.036356 -270.846296) (xy 110.365298 -270.846296)
			(xy 110.369258 -270.797242) (xy 110.381035 -270.749458) (xy 110.400326 -270.704182) (xy 110.426629 -270.662586)
			(xy 110.459264 -270.625749) (xy 110.497385 -270.594624) (xy 110.540006 -270.570017) (xy 110.586022 -270.552565)
			(xy 110.634241 -270.542721) (xy 110.683416 -270.54074) (xy 110.732271 -270.546672) (xy 110.779542 -270.560364)
			(xy 110.824004 -270.581462) (xy 110.864507 -270.609418) (xy 110.9 -270.64351) (xy 110.929565 -270.682854)
			(xy 110.952436 -270.726431) (xy 110.96802 -270.773112) (xy 110.975915 -270.821689) (xy 110.97641 -270.846296)
			(xy 113.178856 -270.846296) (xy 113.182816 -270.797242) (xy 113.194593 -270.749458) (xy 113.213884 -270.704182)
			(xy 113.240187 -270.662586) (xy 113.272822 -270.625749) (xy 113.310943 -270.594624) (xy 113.353564 -270.570017)
			(xy 113.39958 -270.552565) (xy 113.447799 -270.542721) (xy 113.496974 -270.54074) (xy 113.545829 -270.546672)
			(xy 113.5931 -270.560364) (xy 113.637562 -270.581462) (xy 113.678065 -270.609418) (xy 113.713558 -270.64351)
			(xy 113.743123 -270.682854) (xy 113.765994 -270.726431) (xy 113.781578 -270.773112) (xy 113.789473 -270.821689)
			(xy 113.789968 -270.846296) (xy 114.11891 -270.846296) (xy 114.12287 -270.797242) (xy 114.134647 -270.749458)
			(xy 114.153938 -270.704182) (xy 114.180241 -270.662586) (xy 114.212876 -270.625749) (xy 114.250997 -270.594624)
			(xy 114.293618 -270.570017) (xy 114.339634 -270.552565) (xy 114.387853 -270.542721) (xy 114.437028 -270.54074)
			(xy 114.485883 -270.546672) (xy 114.533154 -270.560364) (xy 114.577616 -270.581462) (xy 114.618119 -270.609418)
			(xy 114.653612 -270.64351) (xy 114.683177 -270.682854) (xy 114.706048 -270.726431) (xy 114.721632 -270.773112)
			(xy 114.729527 -270.821689) (xy 114.730022 -270.846296) (xy 115.058964 -270.846296) (xy 115.062924 -270.797242)
			(xy 115.074701 -270.749458) (xy 115.093992 -270.704182) (xy 115.120295 -270.662586) (xy 115.15293 -270.625749)
			(xy 115.191051 -270.594624) (xy 115.233672 -270.570017) (xy 115.279688 -270.552565) (xy 115.327907 -270.542721)
			(xy 115.377082 -270.54074) (xy 115.425937 -270.546672) (xy 115.473208 -270.560364) (xy 115.51767 -270.581462)
			(xy 115.558173 -270.609418) (xy 115.593666 -270.64351) (xy 115.623231 -270.682854) (xy 115.646102 -270.726431)
			(xy 115.661686 -270.773112) (xy 115.669581 -270.821689) (xy 115.670076 -270.846296) (xy 115.999018 -270.846296)
			(xy 116.002978 -270.797242) (xy 116.014755 -270.749458) (xy 116.034046 -270.704182) (xy 116.060349 -270.662586)
			(xy 116.092984 -270.625749) (xy 116.131105 -270.594624) (xy 116.173726 -270.570017) (xy 116.219742 -270.552565)
			(xy 116.267961 -270.542721) (xy 116.317136 -270.54074) (xy 116.365991 -270.546672) (xy 116.413262 -270.560364)
			(xy 116.457724 -270.581462) (xy 116.498227 -270.609418) (xy 116.53372 -270.64351) (xy 116.563285 -270.682854)
			(xy 116.586156 -270.726431) (xy 116.60174 -270.773112) (xy 116.609635 -270.821689) (xy 116.61013 -270.846296)
			(xy 116.938818 -270.846296) (xy 116.942778 -270.797242) (xy 116.954555 -270.749458) (xy 116.973846 -270.704182)
			(xy 117.000149 -270.662586) (xy 117.032784 -270.625749) (xy 117.070905 -270.594624) (xy 117.113526 -270.570017)
			(xy 117.159542 -270.552565) (xy 117.207761 -270.542721) (xy 117.256936 -270.54074) (xy 117.305791 -270.546672)
			(xy 117.353062 -270.560364) (xy 117.397524 -270.581462) (xy 117.438027 -270.609418) (xy 117.47352 -270.64351)
			(xy 117.503085 -270.682854) (xy 117.525956 -270.726431) (xy 117.54154 -270.773112) (xy 117.549435 -270.821689)
			(xy 117.54993 -270.846296) (xy 117.878872 -270.846296) (xy 117.882832 -270.797242) (xy 117.894609 -270.749458)
			(xy 117.9139 -270.704182) (xy 117.940203 -270.662586) (xy 117.972838 -270.625749) (xy 118.010959 -270.594624)
			(xy 118.05358 -270.570017) (xy 118.099596 -270.552565) (xy 118.147815 -270.542721) (xy 118.19699 -270.54074)
			(xy 118.245845 -270.546672) (xy 118.293116 -270.560364) (xy 118.337578 -270.581462) (xy 118.378081 -270.609418)
			(xy 118.413574 -270.64351) (xy 118.443139 -270.682854) (xy 118.46601 -270.726431) (xy 118.481594 -270.773112)
			(xy 118.489489 -270.821689) (xy 118.489984 -270.846296) (xy 118.818926 -270.846296) (xy 118.822886 -270.797242)
			(xy 118.834663 -270.749458) (xy 118.853954 -270.704182) (xy 118.880257 -270.662586) (xy 118.912892 -270.625749)
			(xy 118.951013 -270.594624) (xy 118.993634 -270.570017) (xy 119.03965 -270.552565) (xy 119.087869 -270.542721)
			(xy 119.137044 -270.54074) (xy 119.185899 -270.546672) (xy 119.23317 -270.560364) (xy 119.277632 -270.581462)
			(xy 119.318135 -270.609418) (xy 119.353628 -270.64351) (xy 119.383193 -270.682854) (xy 119.406064 -270.726431)
			(xy 119.421648 -270.773112) (xy 119.429543 -270.821689) (xy 119.430038 -270.846296) (xy 119.75898 -270.846296)
			(xy 119.76294 -270.797242) (xy 119.774717 -270.749458) (xy 119.794008 -270.704182) (xy 119.820311 -270.662586)
			(xy 119.852946 -270.625749) (xy 119.891067 -270.594624) (xy 119.933688 -270.570017) (xy 119.979704 -270.552565)
			(xy 120.027923 -270.542721) (xy 120.077098 -270.54074) (xy 120.125953 -270.546672) (xy 120.173224 -270.560364)
			(xy 120.217686 -270.581462) (xy 120.258189 -270.609418) (xy 120.293682 -270.64351) (xy 120.323247 -270.682854)
			(xy 120.346118 -270.726431) (xy 120.361702 -270.773112) (xy 120.369597 -270.821689) (xy 120.370092 -270.846296)
			(xy 120.699034 -270.846296) (xy 120.702994 -270.797242) (xy 120.714771 -270.749458) (xy 120.734062 -270.704182)
			(xy 120.760365 -270.662586) (xy 120.793 -270.625749) (xy 120.831121 -270.594624) (xy 120.873742 -270.570017)
			(xy 120.919758 -270.552565) (xy 120.967977 -270.542721) (xy 121.017152 -270.54074) (xy 121.066007 -270.546672)
			(xy 121.113278 -270.560364) (xy 121.15774 -270.581462) (xy 121.198243 -270.609418) (xy 121.233736 -270.64351)
			(xy 121.263301 -270.682854) (xy 121.286172 -270.726431) (xy 121.301756 -270.773112) (xy 121.309651 -270.821689)
			(xy 121.310146 -270.846296) (xy 121.638834 -270.846296) (xy 121.642794 -270.797242) (xy 121.654571 -270.749458)
			(xy 121.673862 -270.704182) (xy 121.700165 -270.662586) (xy 121.7328 -270.625749) (xy 121.770921 -270.594624)
			(xy 121.813542 -270.570017) (xy 121.859558 -270.552565) (xy 121.907777 -270.542721) (xy 121.956952 -270.54074)
			(xy 122.005807 -270.546672) (xy 122.053078 -270.560364) (xy 122.09754 -270.581462) (xy 122.138043 -270.609418)
			(xy 122.173536 -270.64351) (xy 122.203101 -270.682854) (xy 122.225972 -270.726431) (xy 122.241556 -270.773112)
			(xy 122.249451 -270.821689) (xy 122.249946 -270.846296) (xy 122.578888 -270.846296) (xy 122.582848 -270.797242)
			(xy 122.594625 -270.749458) (xy 122.613916 -270.704182) (xy 122.640219 -270.662586) (xy 122.672854 -270.625749)
			(xy 122.710975 -270.594624) (xy 122.753596 -270.570017) (xy 122.799612 -270.552565) (xy 122.847831 -270.542721)
			(xy 122.897006 -270.54074) (xy 122.945861 -270.546672) (xy 122.993132 -270.560364) (xy 123.037594 -270.581462)
			(xy 123.078097 -270.609418) (xy 123.11359 -270.64351) (xy 123.143155 -270.682854) (xy 123.166026 -270.726431)
			(xy 123.18161 -270.773112) (xy 123.189505 -270.821689) (xy 123.19 -270.846296) (xy 123.518942 -270.846296)
			(xy 123.522902 -270.797242) (xy 123.534679 -270.749458) (xy 123.55397 -270.704182) (xy 123.580273 -270.662586)
			(xy 123.612908 -270.625749) (xy 123.651029 -270.594624) (xy 123.69365 -270.570017) (xy 123.739666 -270.552565)
			(xy 123.787885 -270.542721) (xy 123.83706 -270.54074) (xy 123.885915 -270.546672) (xy 123.933186 -270.560364)
			(xy 123.977648 -270.581462) (xy 124.018151 -270.609418) (xy 124.053644 -270.64351) (xy 124.083209 -270.682854)
			(xy 124.10608 -270.726431) (xy 124.121664 -270.773112) (xy 124.129559 -270.821689) (xy 124.130054 -270.846296)
			(xy 124.458996 -270.846296) (xy 124.462956 -270.797242) (xy 124.474733 -270.749458) (xy 124.494024 -270.704182)
			(xy 124.520327 -270.662586) (xy 124.552962 -270.625749) (xy 124.591083 -270.594624) (xy 124.633704 -270.570017)
			(xy 124.67972 -270.552565) (xy 124.727939 -270.542721) (xy 124.777114 -270.54074) (xy 124.825969 -270.546672)
			(xy 124.87324 -270.560364) (xy 124.917702 -270.581462) (xy 124.958205 -270.609418) (xy 124.993698 -270.64351)
			(xy 125.023263 -270.682854) (xy 125.046134 -270.726431) (xy 125.061718 -270.773112) (xy 125.069613 -270.821689)
			(xy 125.070108 -270.846296) (xy 125.39905 -270.846296) (xy 125.40301 -270.797242) (xy 125.414787 -270.749458)
			(xy 125.434078 -270.704182) (xy 125.460381 -270.662586) (xy 125.493016 -270.625749) (xy 125.531137 -270.594624)
			(xy 125.573758 -270.570017) (xy 125.619774 -270.552565) (xy 125.667993 -270.542721) (xy 125.717168 -270.54074)
			(xy 125.766023 -270.546672) (xy 125.813294 -270.560364) (xy 125.857756 -270.581462) (xy 125.898259 -270.609418)
			(xy 125.933752 -270.64351) (xy 125.963317 -270.682854) (xy 125.986188 -270.726431) (xy 126.001772 -270.773112)
			(xy 126.009667 -270.821689) (xy 126.010162 -270.846296) (xy 126.009667 -270.870903) (xy 126.001772 -270.91948)
			(xy 125.986188 -270.966161) (xy 125.963317 -271.009738) (xy 125.933752 -271.049082) (xy 125.898259 -271.083174)
			(xy 125.857756 -271.11113) (xy 125.813294 -271.132228) (xy 125.766023 -271.14592) (xy 125.717168 -271.151852)
			(xy 125.667993 -271.149871) (xy 125.619774 -271.140027) (xy 125.573758 -271.122575) (xy 125.531137 -271.097968)
			(xy 125.493016 -271.066843) (xy 125.460381 -271.030006) (xy 125.434078 -270.98841) (xy 125.414787 -270.943134)
			(xy 125.40301 -270.89535) (xy 125.39905 -270.846296) (xy 125.070108 -270.846296) (xy 125.069613 -270.870903)
			(xy 125.061718 -270.91948) (xy 125.046134 -270.966161) (xy 125.023263 -271.009738) (xy 124.993698 -271.049082)
			(xy 124.958205 -271.083174) (xy 124.917702 -271.11113) (xy 124.87324 -271.132228) (xy 124.825969 -271.14592)
			(xy 124.777114 -271.151852) (xy 124.727939 -271.149871) (xy 124.67972 -271.140027) (xy 124.633704 -271.122575)
			(xy 124.591083 -271.097968) (xy 124.552962 -271.066843) (xy 124.520327 -271.030006) (xy 124.494024 -270.98841)
			(xy 124.474733 -270.943134) (xy 124.462956 -270.89535) (xy 124.458996 -270.846296) (xy 124.130054 -270.846296)
			(xy 124.129559 -270.870903) (xy 124.121664 -270.91948) (xy 124.10608 -270.966161) (xy 124.083209 -271.009738)
			(xy 124.053644 -271.049082) (xy 124.018151 -271.083174) (xy 123.977648 -271.11113) (xy 123.933186 -271.132228)
			(xy 123.885915 -271.14592) (xy 123.83706 -271.151852) (xy 123.787885 -271.149871) (xy 123.739666 -271.140027)
			(xy 123.69365 -271.122575) (xy 123.651029 -271.097968) (xy 123.612908 -271.066843) (xy 123.580273 -271.030006)
			(xy 123.55397 -270.98841) (xy 123.534679 -270.943134) (xy 123.522902 -270.89535) (xy 123.518942 -270.846296)
			(xy 123.19 -270.846296) (xy 123.189505 -270.870903) (xy 123.18161 -270.91948) (xy 123.166026 -270.966161)
			(xy 123.143155 -271.009738) (xy 123.11359 -271.049082) (xy 123.078097 -271.083174) (xy 123.037594 -271.11113)
			(xy 122.993132 -271.132228) (xy 122.945861 -271.14592) (xy 122.897006 -271.151852) (xy 122.847831 -271.149871)
			(xy 122.799612 -271.140027) (xy 122.753596 -271.122575) (xy 122.710975 -271.097968) (xy 122.672854 -271.066843)
			(xy 122.640219 -271.030006) (xy 122.613916 -270.98841) (xy 122.594625 -270.943134) (xy 122.582848 -270.89535)
			(xy 122.578888 -270.846296) (xy 122.249946 -270.846296) (xy 122.249451 -270.870903) (xy 122.241556 -270.91948)
			(xy 122.225972 -270.966161) (xy 122.203101 -271.009738) (xy 122.173536 -271.049082) (xy 122.138043 -271.083174)
			(xy 122.09754 -271.11113) (xy 122.053078 -271.132228) (xy 122.005807 -271.14592) (xy 121.956952 -271.151852)
			(xy 121.907777 -271.149871) (xy 121.859558 -271.140027) (xy 121.813542 -271.122575) (xy 121.770921 -271.097968)
			(xy 121.7328 -271.066843) (xy 121.700165 -271.030006) (xy 121.673862 -270.98841) (xy 121.654571 -270.943134)
			(xy 121.642794 -270.89535) (xy 121.638834 -270.846296) (xy 121.310146 -270.846296) (xy 121.309651 -270.870903)
			(xy 121.301756 -270.91948) (xy 121.286172 -270.966161) (xy 121.263301 -271.009738) (xy 121.233736 -271.049082)
			(xy 121.198243 -271.083174) (xy 121.15774 -271.11113) (xy 121.113278 -271.132228) (xy 121.066007 -271.14592)
			(xy 121.017152 -271.151852) (xy 120.967977 -271.149871) (xy 120.919758 -271.140027) (xy 120.873742 -271.122575)
			(xy 120.831121 -271.097968) (xy 120.793 -271.066843) (xy 120.760365 -271.030006) (xy 120.734062 -270.98841)
			(xy 120.714771 -270.943134) (xy 120.702994 -270.89535) (xy 120.699034 -270.846296) (xy 120.370092 -270.846296)
			(xy 120.369597 -270.870903) (xy 120.361702 -270.91948) (xy 120.346118 -270.966161) (xy 120.323247 -271.009738)
			(xy 120.293682 -271.049082) (xy 120.258189 -271.083174) (xy 120.217686 -271.11113) (xy 120.173224 -271.132228)
			(xy 120.125953 -271.14592) (xy 120.077098 -271.151852) (xy 120.027923 -271.149871) (xy 119.979704 -271.140027)
			(xy 119.933688 -271.122575) (xy 119.891067 -271.097968) (xy 119.852946 -271.066843) (xy 119.820311 -271.030006)
			(xy 119.794008 -270.98841) (xy 119.774717 -270.943134) (xy 119.76294 -270.89535) (xy 119.75898 -270.846296)
			(xy 119.430038 -270.846296) (xy 119.429543 -270.870903) (xy 119.421648 -270.91948) (xy 119.406064 -270.966161)
			(xy 119.383193 -271.009738) (xy 119.353628 -271.049082) (xy 119.318135 -271.083174) (xy 119.277632 -271.11113)
			(xy 119.23317 -271.132228) (xy 119.185899 -271.14592) (xy 119.137044 -271.151852) (xy 119.087869 -271.149871)
			(xy 119.03965 -271.140027) (xy 118.993634 -271.122575) (xy 118.951013 -271.097968) (xy 118.912892 -271.066843)
			(xy 118.880257 -271.030006) (xy 118.853954 -270.98841) (xy 118.834663 -270.943134) (xy 118.822886 -270.89535)
			(xy 118.818926 -270.846296) (xy 118.489984 -270.846296) (xy 118.489489 -270.870903) (xy 118.481594 -270.91948)
			(xy 118.46601 -270.966161) (xy 118.443139 -271.009738) (xy 118.413574 -271.049082) (xy 118.378081 -271.083174)
			(xy 118.337578 -271.11113) (xy 118.293116 -271.132228) (xy 118.245845 -271.14592) (xy 118.19699 -271.151852)
			(xy 118.147815 -271.149871) (xy 118.099596 -271.140027) (xy 118.05358 -271.122575) (xy 118.010959 -271.097968)
			(xy 117.972838 -271.066843) (xy 117.940203 -271.030006) (xy 117.9139 -270.98841) (xy 117.894609 -270.943134)
			(xy 117.882832 -270.89535) (xy 117.878872 -270.846296) (xy 117.54993 -270.846296) (xy 117.549435 -270.870903)
			(xy 117.54154 -270.91948) (xy 117.525956 -270.966161) (xy 117.503085 -271.009738) (xy 117.47352 -271.049082)
			(xy 117.438027 -271.083174) (xy 117.397524 -271.11113) (xy 117.353062 -271.132228) (xy 117.305791 -271.14592)
			(xy 117.256936 -271.151852) (xy 117.207761 -271.149871) (xy 117.159542 -271.140027) (xy 117.113526 -271.122575)
			(xy 117.070905 -271.097968) (xy 117.032784 -271.066843) (xy 117.000149 -271.030006) (xy 116.973846 -270.98841)
			(xy 116.954555 -270.943134) (xy 116.942778 -270.89535) (xy 116.938818 -270.846296) (xy 116.61013 -270.846296)
			(xy 116.609635 -270.870903) (xy 116.60174 -270.91948) (xy 116.586156 -270.966161) (xy 116.563285 -271.009738)
			(xy 116.53372 -271.049082) (xy 116.498227 -271.083174) (xy 116.457724 -271.11113) (xy 116.413262 -271.132228)
			(xy 116.365991 -271.14592) (xy 116.317136 -271.151852) (xy 116.267961 -271.149871) (xy 116.219742 -271.140027)
			(xy 116.173726 -271.122575) (xy 116.131105 -271.097968) (xy 116.092984 -271.066843) (xy 116.060349 -271.030006)
			(xy 116.034046 -270.98841) (xy 116.014755 -270.943134) (xy 116.002978 -270.89535) (xy 115.999018 -270.846296)
			(xy 115.670076 -270.846296) (xy 115.669581 -270.870903) (xy 115.661686 -270.91948) (xy 115.646102 -270.966161)
			(xy 115.623231 -271.009738) (xy 115.593666 -271.049082) (xy 115.558173 -271.083174) (xy 115.51767 -271.11113)
			(xy 115.473208 -271.132228) (xy 115.425937 -271.14592) (xy 115.377082 -271.151852) (xy 115.327907 -271.149871)
			(xy 115.279688 -271.140027) (xy 115.233672 -271.122575) (xy 115.191051 -271.097968) (xy 115.15293 -271.066843)
			(xy 115.120295 -271.030006) (xy 115.093992 -270.98841) (xy 115.074701 -270.943134) (xy 115.062924 -270.89535)
			(xy 115.058964 -270.846296) (xy 114.730022 -270.846296) (xy 114.729527 -270.870903) (xy 114.721632 -270.91948)
			(xy 114.706048 -270.966161) (xy 114.683177 -271.009738) (xy 114.653612 -271.049082) (xy 114.618119 -271.083174)
			(xy 114.577616 -271.11113) (xy 114.533154 -271.132228) (xy 114.485883 -271.14592) (xy 114.437028 -271.151852)
			(xy 114.387853 -271.149871) (xy 114.339634 -271.140027) (xy 114.293618 -271.122575) (xy 114.250997 -271.097968)
			(xy 114.212876 -271.066843) (xy 114.180241 -271.030006) (xy 114.153938 -270.98841) (xy 114.134647 -270.943134)
			(xy 114.12287 -270.89535) (xy 114.11891 -270.846296) (xy 113.789968 -270.846296) (xy 113.789473 -270.870903)
			(xy 113.781578 -270.91948) (xy 113.765994 -270.966161) (xy 113.743123 -271.009738) (xy 113.713558 -271.049082)
			(xy 113.678065 -271.083174) (xy 113.637562 -271.11113) (xy 113.5931 -271.132228) (xy 113.545829 -271.14592)
			(xy 113.496974 -271.151852) (xy 113.447799 -271.149871) (xy 113.39958 -271.140027) (xy 113.353564 -271.122575)
			(xy 113.310943 -271.097968) (xy 113.272822 -271.066843) (xy 113.240187 -271.030006) (xy 113.213884 -270.98841)
			(xy 113.194593 -270.943134) (xy 113.182816 -270.89535) (xy 113.178856 -270.846296) (xy 110.97641 -270.846296)
			(xy 110.975915 -270.870903) (xy 110.96802 -270.91948) (xy 110.952436 -270.966161) (xy 110.929565 -271.009738)
			(xy 110.9 -271.049082) (xy 110.864507 -271.083174) (xy 110.824004 -271.11113) (xy 110.779542 -271.132228)
			(xy 110.732271 -271.14592) (xy 110.683416 -271.151852) (xy 110.634241 -271.149871) (xy 110.586022 -271.140027)
			(xy 110.540006 -271.122575) (xy 110.497385 -271.097968) (xy 110.459264 -271.066843) (xy 110.426629 -271.030006)
			(xy 110.400326 -270.98841) (xy 110.381035 -270.943134) (xy 110.369258 -270.89535) (xy 110.365298 -270.846296)
			(xy 110.036356 -270.846296) (xy 110.035861 -270.870903) (xy 110.027966 -270.91948) (xy 110.012382 -270.966161)
			(xy 109.989511 -271.009738) (xy 109.959946 -271.049082) (xy 109.924453 -271.083174) (xy 109.88395 -271.11113)
			(xy 109.839488 -271.132228) (xy 109.792217 -271.14592) (xy 109.743362 -271.151852) (xy 109.694187 -271.149871)
			(xy 109.645968 -271.140027) (xy 109.599952 -271.122575) (xy 109.557331 -271.097968) (xy 109.51921 -271.066843)
			(xy 109.486575 -271.030006) (xy 109.460272 -270.98841) (xy 109.440981 -270.943134) (xy 109.429204 -270.89535)
			(xy 109.425244 -270.846296) (xy 109.096302 -270.846296) (xy 109.095807 -270.870903) (xy 109.087912 -270.91948)
			(xy 109.072328 -270.966161) (xy 109.049457 -271.009738) (xy 109.019892 -271.049082) (xy 108.984399 -271.083174)
			(xy 108.943896 -271.11113) (xy 108.899434 -271.132228) (xy 108.852163 -271.14592) (xy 108.803308 -271.151852)
			(xy 108.754133 -271.149871) (xy 108.705914 -271.140027) (xy 108.659898 -271.122575) (xy 108.617277 -271.097968)
			(xy 108.579156 -271.066843) (xy 108.546521 -271.030006) (xy 108.520218 -270.98841) (xy 108.500927 -270.943134)
			(xy 108.48915 -270.89535) (xy 108.48519 -270.846296) (xy 108.156248 -270.846296) (xy 108.155753 -270.870903)
			(xy 108.147858 -270.91948) (xy 108.132274 -270.966161) (xy 108.109403 -271.009738) (xy 108.079838 -271.049082)
			(xy 108.044345 -271.083174) (xy 108.003842 -271.11113) (xy 107.95938 -271.132228) (xy 107.912109 -271.14592)
			(xy 107.863254 -271.151852) (xy 107.814079 -271.149871) (xy 107.76586 -271.140027) (xy 107.719844 -271.122575)
			(xy 107.677223 -271.097968) (xy 107.639102 -271.066843) (xy 107.606467 -271.030006) (xy 107.580164 -270.98841)
			(xy 107.560873 -270.943134) (xy 107.549096 -270.89535) (xy 107.545136 -270.846296) (xy 107.216448 -270.846296)
			(xy 107.215953 -270.870903) (xy 107.208058 -270.91948) (xy 107.192474 -270.966161) (xy 107.169603 -271.009738)
			(xy 107.140038 -271.049082) (xy 107.104545 -271.083174) (xy 107.064042 -271.11113) (xy 107.01958 -271.132228)
			(xy 106.972309 -271.14592) (xy 106.923454 -271.151852) (xy 106.874279 -271.149871) (xy 106.82606 -271.140027)
			(xy 106.780044 -271.122575) (xy 106.737423 -271.097968) (xy 106.699302 -271.066843) (xy 106.666667 -271.030006)
			(xy 106.640364 -270.98841) (xy 106.621073 -270.943134) (xy 106.609296 -270.89535) (xy 106.605336 -270.846296)
			(xy 106.276394 -270.846296) (xy 106.275899 -270.870903) (xy 106.268004 -270.91948) (xy 106.25242 -270.966161)
			(xy 106.229549 -271.009738) (xy 106.199984 -271.049082) (xy 106.164491 -271.083174) (xy 106.123988 -271.11113)
			(xy 106.079526 -271.132228) (xy 106.032255 -271.14592) (xy 105.9834 -271.151852) (xy 105.934225 -271.149871)
			(xy 105.886006 -271.140027) (xy 105.83999 -271.122575) (xy 105.797369 -271.097968) (xy 105.759248 -271.066843)
			(xy 105.726613 -271.030006) (xy 105.70031 -270.98841) (xy 105.681019 -270.943134) (xy 105.669242 -270.89535)
			(xy 105.665282 -270.846296) (xy 105.33634 -270.846296) (xy 105.335845 -270.870903) (xy 105.32795 -270.91948)
			(xy 105.312366 -270.966161) (xy 105.289495 -271.009738) (xy 105.25993 -271.049082) (xy 105.224437 -271.083174)
			(xy 105.183934 -271.11113) (xy 105.139472 -271.132228) (xy 105.092201 -271.14592) (xy 105.043346 -271.151852)
			(xy 104.994171 -271.149871) (xy 104.945952 -271.140027) (xy 104.899936 -271.122575) (xy 104.857315 -271.097968)
			(xy 104.819194 -271.066843) (xy 104.786559 -271.030006) (xy 104.760256 -270.98841) (xy 104.740965 -270.943134)
			(xy 104.729188 -270.89535) (xy 104.725228 -270.846296) (xy 104.396286 -270.846296) (xy 104.395791 -270.870903)
			(xy 104.387896 -270.91948) (xy 104.372312 -270.966161) (xy 104.349441 -271.009738) (xy 104.319876 -271.049082)
			(xy 104.284383 -271.083174) (xy 104.24388 -271.11113) (xy 104.199418 -271.132228) (xy 104.152147 -271.14592)
			(xy 104.103292 -271.151852) (xy 104.054117 -271.149871) (xy 104.005898 -271.140027) (xy 103.959882 -271.122575)
			(xy 103.917261 -271.097968) (xy 103.87914 -271.066843) (xy 103.846505 -271.030006) (xy 103.820202 -270.98841)
			(xy 103.800911 -270.943134) (xy 103.789134 -270.89535) (xy 103.785174 -270.846296) (xy 103.456486 -270.846296)
			(xy 103.455991 -270.870903) (xy 103.448096 -270.91948) (xy 103.432512 -270.966161) (xy 103.409641 -271.009738)
			(xy 103.380076 -271.049082) (xy 103.344583 -271.083174) (xy 103.30408 -271.11113) (xy 103.259618 -271.132228)
			(xy 103.212347 -271.14592) (xy 103.163492 -271.151852) (xy 103.114317 -271.149871) (xy 103.066098 -271.140027)
			(xy 103.020082 -271.122575) (xy 102.977461 -271.097968) (xy 102.93934 -271.066843) (xy 102.906705 -271.030006)
			(xy 102.880402 -270.98841) (xy 102.861111 -270.943134) (xy 102.849334 -270.89535) (xy 102.845374 -270.846296)
			(xy 102.516432 -270.846296) (xy 102.515937 -270.870903) (xy 102.508042 -270.91948) (xy 102.492458 -270.966161)
			(xy 102.469587 -271.009738) (xy 102.440022 -271.049082) (xy 102.404529 -271.083174) (xy 102.364026 -271.11113)
			(xy 102.319564 -271.132228) (xy 102.272293 -271.14592) (xy 102.223438 -271.151852) (xy 102.174263 -271.149871)
			(xy 102.126044 -271.140027) (xy 102.080028 -271.122575) (xy 102.037407 -271.097968) (xy 101.999286 -271.066843)
			(xy 101.966651 -271.030006) (xy 101.940348 -270.98841) (xy 101.921057 -270.943134) (xy 101.90928 -270.89535)
			(xy 101.90532 -270.846296) (xy 101.576378 -270.846296) (xy 101.575883 -270.870903) (xy 101.567988 -270.91948)
			(xy 101.552404 -270.966161) (xy 101.529533 -271.009738) (xy 101.499968 -271.049082) (xy 101.464475 -271.083174)
			(xy 101.423972 -271.11113) (xy 101.37951 -271.132228) (xy 101.332239 -271.14592) (xy 101.283384 -271.151852)
			(xy 101.234209 -271.149871) (xy 101.18599 -271.140027) (xy 101.139974 -271.122575) (xy 101.097353 -271.097968)
			(xy 101.059232 -271.066843) (xy 101.026597 -271.030006) (xy 101.000294 -270.98841) (xy 100.981003 -270.943134)
			(xy 100.969226 -270.89535) (xy 100.965266 -270.846296) (xy 100.636324 -270.846296) (xy 100.635829 -270.870903)
			(xy 100.627934 -270.91948) (xy 100.61235 -270.966161) (xy 100.589479 -271.009738) (xy 100.559914 -271.049082)
			(xy 100.524421 -271.083174) (xy 100.483918 -271.11113) (xy 100.439456 -271.132228) (xy 100.392185 -271.14592)
			(xy 100.34333 -271.151852) (xy 100.294155 -271.149871) (xy 100.245936 -271.140027) (xy 100.19992 -271.122575)
			(xy 100.157299 -271.097968) (xy 100.119178 -271.066843) (xy 100.086543 -271.030006) (xy 100.06024 -270.98841)
			(xy 100.040949 -270.943134) (xy 100.029172 -270.89535) (xy 100.025212 -270.846296) (xy 99.69627 -270.846296)
			(xy 99.695775 -270.870903) (xy 99.68788 -270.91948) (xy 99.672296 -270.966161) (xy 99.649425 -271.009738)
			(xy 99.61986 -271.049082) (xy 99.584367 -271.083174) (xy 99.543864 -271.11113) (xy 99.499402 -271.132228)
			(xy 99.452131 -271.14592) (xy 99.403276 -271.151852) (xy 99.354101 -271.149871) (xy 99.305882 -271.140027)
			(xy 99.259866 -271.122575) (xy 99.217245 -271.097968) (xy 99.179124 -271.066843) (xy 99.146489 -271.030006)
			(xy 99.120186 -270.98841) (xy 99.100895 -270.943134) (xy 99.089118 -270.89535) (xy 99.085158 -270.846296)
			(xy 98.75647 -270.846296) (xy 98.755975 -270.870903) (xy 98.74808 -270.91948) (xy 98.732496 -270.966161)
			(xy 98.709625 -271.009738) (xy 98.68006 -271.049082) (xy 98.644567 -271.083174) (xy 98.604064 -271.11113)
			(xy 98.559602 -271.132228) (xy 98.512331 -271.14592) (xy 98.463476 -271.151852) (xy 98.414301 -271.149871)
			(xy 98.366082 -271.140027) (xy 98.320066 -271.122575) (xy 98.277445 -271.097968) (xy 98.239324 -271.066843)
			(xy 98.206689 -271.030006) (xy 98.180386 -270.98841) (xy 98.161095 -270.943134) (xy 98.149318 -270.89535)
			(xy 98.145358 -270.846296) (xy 97.816416 -270.846296) (xy 97.815921 -270.870903) (xy 97.808026 -270.91948)
			(xy 97.792442 -270.966161) (xy 97.769571 -271.009738) (xy 97.740006 -271.049082) (xy 97.704513 -271.083174)
			(xy 97.66401 -271.11113) (xy 97.619548 -271.132228) (xy 97.572277 -271.14592) (xy 97.523422 -271.151852)
			(xy 97.474247 -271.149871) (xy 97.426028 -271.140027) (xy 97.380012 -271.122575) (xy 97.337391 -271.097968)
			(xy 97.29927 -271.066843) (xy 97.266635 -271.030006) (xy 97.240332 -270.98841) (xy 97.221041 -270.943134)
			(xy 97.209264 -270.89535) (xy 97.205304 -270.846296) (xy 96.876362 -270.846296) (xy 96.875867 -270.870903)
			(xy 96.867972 -270.91948) (xy 96.852388 -270.966161) (xy 96.829517 -271.009738) (xy 96.799952 -271.049082)
			(xy 96.764459 -271.083174) (xy 96.723956 -271.11113) (xy 96.679494 -271.132228) (xy 96.632223 -271.14592)
			(xy 96.583368 -271.151852) (xy 96.534193 -271.149871) (xy 96.485974 -271.140027) (xy 96.439958 -271.122575)
			(xy 96.397337 -271.097968) (xy 96.359216 -271.066843) (xy 96.326581 -271.030006) (xy 96.300278 -270.98841)
			(xy 96.280987 -270.943134) (xy 96.26921 -270.89535) (xy 96.26525 -270.846296) (xy 95.946722 -270.846296)
			(xy 95.94621 -270.871742) (xy 95.938046 -270.921976) (xy 95.92193 -270.97025) (xy 95.898279 -271.015313)
			(xy 95.867706 -271.055999) (xy 95.831002 -271.091254) (xy 95.789118 -271.120164) (xy 95.743139 -271.141981)
			(xy 95.694255 -271.156141) (xy 95.643734 -271.162275) (xy 95.592882 -271.160226) (xy 95.543018 -271.150046)
			(xy 95.495432 -271.131999) (xy 95.451358 -271.106553) (xy 95.411936 -271.074366) (xy 95.378188 -271.036272)
			(xy 95.350987 -270.993258) (xy 95.331039 -270.946438) (xy 95.31886 -270.897024) (xy 95.314765 -270.846296)
			(xy 95.006668 -270.846296) (xy 95.006156 -270.871742) (xy 94.997992 -270.921976) (xy 94.981876 -270.97025)
			(xy 94.958225 -271.015313) (xy 94.927652 -271.055999) (xy 94.890948 -271.091254) (xy 94.849064 -271.120164)
			(xy 94.803085 -271.141981) (xy 94.754201 -271.156141) (xy 94.70368 -271.162275) (xy 94.652828 -271.160226)
			(xy 94.602964 -271.150046) (xy 94.555378 -271.131999) (xy 94.511304 -271.106553) (xy 94.471882 -271.074366)
			(xy 94.438134 -271.036272) (xy 94.410933 -270.993258) (xy 94.390985 -270.946438) (xy 94.378806 -270.897024)
			(xy 94.374711 -270.846296) (xy 94.056935 -270.846296) (xy 94.056935 -270.8463) (xy 94.052765 -270.896634)
			(xy 94.040367 -270.945595) (xy 94.020081 -270.991849) (xy 93.992459 -271.034132) (xy 93.958254 -271.071294)
			(xy 93.9184 -271.102319) (xy 93.873984 -271.126362) (xy 93.826216 -271.142767) (xy 93.776399 -271.151087)
			(xy 93.751146 -271.151604) (xy 93.72738 -271.151154) (xy 93.680423 -271.14379) (xy 93.635176 -271.129233)
			(xy 93.592734 -271.107836) (xy 93.554123 -271.080116) (xy 93.520278 -271.046744) (xy 93.505782 -271.027906)
			(xy 93.505782 -271.027652) (xy 93.505528 -271.027652) (xy 93.501371 -271.022473) (xy 93.490955 -271.014241)
			(xy 93.484954 -271.011396) (xy 93.478545 -271.008851) (xy 93.464895 -271.006931) (xy 93.45803 -271.007586)
			(xy 93.372178 -271.019016) (xy 93.365418 -271.02009) (xy 93.352793 -271.025365) (xy 93.347286 -271.02943)
			(xy 93.341952 -271.033494) (xy 93.334078 -271.044162) (xy 93.331538 -271.050766) (xy 93.315987 -271.088437)
			(xy 93.275563 -271.1592) (xy 93.25102 -271.191736) (xy 93.25102 -271.19199) (xy 93.24699 -271.197396)
			(xy 93.241596 -271.209747) (xy 93.240352 -271.216374) (xy 93.238574 -271.229582) (xy 93.276928 -271.322292)
			(xy 93.279687 -271.328452) (xy 93.287933 -271.339132) (xy 93.293184 -271.343374) (xy 93.298518 -271.347438)
			(xy 93.31071 -271.352264) (xy 93.317822 -271.35328) (xy 93.342181 -271.356745) (xy 93.389433 -271.370447)
			(xy 93.433877 -271.391548) (xy 93.474363 -271.419502) (xy 93.509843 -271.453586) (xy 93.539399 -271.492917)
			(xy 93.562267 -271.536479) (xy 93.577854 -271.583143) (xy 93.585758 -271.631703) (xy 93.5863 -271.656302)
			(xy 93.904811 -271.656302) (xy 93.908906 -271.605574) (xy 93.921085 -271.55616) (xy 93.941033 -271.50934)
			(xy 93.968234 -271.466326) (xy 94.001982 -271.428232) (xy 94.041404 -271.396045) (xy 94.085478 -271.370599)
			(xy 94.133064 -271.352552) (xy 94.182928 -271.342372) (xy 94.23378 -271.340323) (xy 94.284301 -271.346457)
			(xy 94.333185 -271.360617) (xy 94.379164 -271.382434) (xy 94.421048 -271.411344) (xy 94.457752 -271.446599)
			(xy 94.488325 -271.487285) (xy 94.511976 -271.532348) (xy 94.528092 -271.580622) (xy 94.536256 -271.630856)
			(xy 94.536768 -271.656302) (xy 94.855296 -271.656302) (xy 94.859256 -271.607248) (xy 94.871033 -271.559464)
			(xy 94.890324 -271.514188) (xy 94.916627 -271.472592) (xy 94.949262 -271.435755) (xy 94.987383 -271.40463)
			(xy 95.030004 -271.380023) (xy 95.07602 -271.362571) (xy 95.124239 -271.352727) (xy 95.173414 -271.350746)
			(xy 95.222269 -271.356678) (xy 95.26954 -271.37037) (xy 95.314002 -271.391468) (xy 95.354505 -271.419424)
			(xy 95.389998 -271.453516) (xy 95.419563 -271.49286) (xy 95.442434 -271.536437) (xy 95.458018 -271.583118)
			(xy 95.465913 -271.631695) (xy 95.466408 -271.656302) (xy 95.784919 -271.656302) (xy 95.789014 -271.605574)
			(xy 95.801193 -271.55616) (xy 95.821141 -271.50934) (xy 95.848342 -271.466326) (xy 95.88209 -271.428232)
			(xy 95.921512 -271.396045) (xy 95.965586 -271.370599) (xy 96.013172 -271.352552) (xy 96.063036 -271.342372)
			(xy 96.113888 -271.340323) (xy 96.164409 -271.346457) (xy 96.213293 -271.360617) (xy 96.259272 -271.382434)
			(xy 96.301156 -271.411344) (xy 96.33786 -271.446599) (xy 96.368433 -271.487285) (xy 96.392084 -271.532348)
			(xy 96.4082 -271.580622) (xy 96.416364 -271.630856) (xy 96.416876 -271.656302) (xy 96.73515 -271.656302)
			(xy 96.73911 -271.607248) (xy 96.750887 -271.559464) (xy 96.770178 -271.514188) (xy 96.796481 -271.472592)
			(xy 96.829116 -271.435755) (xy 96.867237 -271.40463) (xy 96.909858 -271.380023) (xy 96.955874 -271.362571)
			(xy 97.004093 -271.352727) (xy 97.053268 -271.350746) (xy 97.102123 -271.356678) (xy 97.149394 -271.37037)
			(xy 97.193856 -271.391468) (xy 97.234359 -271.419424) (xy 97.269852 -271.453516) (xy 97.299417 -271.49286)
			(xy 97.322288 -271.536437) (xy 97.337872 -271.583118) (xy 97.345767 -271.631695) (xy 97.346262 -271.656302)
			(xy 97.675204 -271.656302) (xy 97.679164 -271.607248) (xy 97.690941 -271.559464) (xy 97.710232 -271.514188)
			(xy 97.736535 -271.472592) (xy 97.76917 -271.435755) (xy 97.807291 -271.40463) (xy 97.849912 -271.380023)
			(xy 97.895928 -271.362571) (xy 97.944147 -271.352727) (xy 97.993322 -271.350746) (xy 98.042177 -271.356678)
			(xy 98.089448 -271.37037) (xy 98.13391 -271.391468) (xy 98.174413 -271.419424) (xy 98.209906 -271.453516)
			(xy 98.239471 -271.49286) (xy 98.262342 -271.536437) (xy 98.277926 -271.583118) (xy 98.285821 -271.631695)
			(xy 98.286316 -271.656302) (xy 98.615258 -271.656302) (xy 98.619218 -271.607248) (xy 98.630995 -271.559464)
			(xy 98.650286 -271.514188) (xy 98.676589 -271.472592) (xy 98.709224 -271.435755) (xy 98.747345 -271.40463)
			(xy 98.789966 -271.380023) (xy 98.835982 -271.362571) (xy 98.884201 -271.352727) (xy 98.933376 -271.350746)
			(xy 98.982231 -271.356678) (xy 99.029502 -271.37037) (xy 99.073964 -271.391468) (xy 99.114467 -271.419424)
			(xy 99.14996 -271.453516) (xy 99.179525 -271.49286) (xy 99.202396 -271.536437) (xy 99.21798 -271.583118)
			(xy 99.225875 -271.631695) (xy 99.22637 -271.656302) (xy 99.555312 -271.656302) (xy 99.559272 -271.607248)
			(xy 99.571049 -271.559464) (xy 99.59034 -271.514188) (xy 99.616643 -271.472592) (xy 99.649278 -271.435755)
			(xy 99.687399 -271.40463) (xy 99.73002 -271.380023) (xy 99.776036 -271.362571) (xy 99.824255 -271.352727)
			(xy 99.87343 -271.350746) (xy 99.922285 -271.356678) (xy 99.969556 -271.37037) (xy 100.014018 -271.391468)
			(xy 100.054521 -271.419424) (xy 100.090014 -271.453516) (xy 100.119579 -271.49286) (xy 100.14245 -271.536437)
			(xy 100.158034 -271.583118) (xy 100.165929 -271.631695) (xy 100.166424 -271.656302) (xy 100.495366 -271.656302)
			(xy 100.499326 -271.607248) (xy 100.511103 -271.559464) (xy 100.530394 -271.514188) (xy 100.556697 -271.472592)
			(xy 100.589332 -271.435755) (xy 100.627453 -271.40463) (xy 100.670074 -271.380023) (xy 100.71609 -271.362571)
			(xy 100.764309 -271.352727) (xy 100.813484 -271.350746) (xy 100.862339 -271.356678) (xy 100.90961 -271.37037)
			(xy 100.954072 -271.391468) (xy 100.994575 -271.419424) (xy 101.030068 -271.453516) (xy 101.059633 -271.49286)
			(xy 101.082504 -271.536437) (xy 101.098088 -271.583118) (xy 101.105983 -271.631695) (xy 101.106478 -271.656302)
			(xy 101.435166 -271.656302) (xy 101.439126 -271.607248) (xy 101.450903 -271.559464) (xy 101.470194 -271.514188)
			(xy 101.496497 -271.472592) (xy 101.529132 -271.435755) (xy 101.567253 -271.40463) (xy 101.609874 -271.380023)
			(xy 101.65589 -271.362571) (xy 101.704109 -271.352727) (xy 101.753284 -271.350746) (xy 101.802139 -271.356678)
			(xy 101.84941 -271.37037) (xy 101.893872 -271.391468) (xy 101.934375 -271.419424) (xy 101.969868 -271.453516)
			(xy 101.999433 -271.49286) (xy 102.022304 -271.536437) (xy 102.037888 -271.583118) (xy 102.045783 -271.631695)
			(xy 102.046278 -271.656302) (xy 102.37522 -271.656302) (xy 102.37918 -271.607248) (xy 102.390957 -271.559464)
			(xy 102.410248 -271.514188) (xy 102.436551 -271.472592) (xy 102.469186 -271.435755) (xy 102.507307 -271.40463)
			(xy 102.549928 -271.380023) (xy 102.595944 -271.362571) (xy 102.644163 -271.352727) (xy 102.693338 -271.350746)
			(xy 102.742193 -271.356678) (xy 102.789464 -271.37037) (xy 102.833926 -271.391468) (xy 102.874429 -271.419424)
			(xy 102.909922 -271.453516) (xy 102.939487 -271.49286) (xy 102.962358 -271.536437) (xy 102.977942 -271.583118)
			(xy 102.985837 -271.631695) (xy 102.986332 -271.656302) (xy 103.315274 -271.656302) (xy 103.319234 -271.607248)
			(xy 103.331011 -271.559464) (xy 103.350302 -271.514188) (xy 103.376605 -271.472592) (xy 103.40924 -271.435755)
			(xy 103.447361 -271.40463) (xy 103.489982 -271.380023) (xy 103.535998 -271.362571) (xy 103.584217 -271.352727)
			(xy 103.633392 -271.350746) (xy 103.682247 -271.356678) (xy 103.729518 -271.37037) (xy 103.77398 -271.391468)
			(xy 103.814483 -271.419424) (xy 103.849976 -271.453516) (xy 103.879541 -271.49286) (xy 103.902412 -271.536437)
			(xy 103.917996 -271.583118) (xy 103.925891 -271.631695) (xy 103.926386 -271.656302) (xy 104.255328 -271.656302)
			(xy 104.259288 -271.607248) (xy 104.271065 -271.559464) (xy 104.290356 -271.514188) (xy 104.316659 -271.472592)
			(xy 104.349294 -271.435755) (xy 104.387415 -271.40463) (xy 104.430036 -271.380023) (xy 104.476052 -271.362571)
			(xy 104.524271 -271.352727) (xy 104.573446 -271.350746) (xy 104.622301 -271.356678) (xy 104.669572 -271.37037)
			(xy 104.714034 -271.391468) (xy 104.754537 -271.419424) (xy 104.79003 -271.453516) (xy 104.819595 -271.49286)
			(xy 104.842466 -271.536437) (xy 104.85805 -271.583118) (xy 104.865945 -271.631695) (xy 104.86644 -271.656302)
			(xy 105.195128 -271.656302) (xy 105.199088 -271.607248) (xy 105.210865 -271.559464) (xy 105.230156 -271.514188)
			(xy 105.256459 -271.472592) (xy 105.289094 -271.435755) (xy 105.327215 -271.40463) (xy 105.369836 -271.380023)
			(xy 105.415852 -271.362571) (xy 105.464071 -271.352727) (xy 105.513246 -271.350746) (xy 105.562101 -271.356678)
			(xy 105.609372 -271.37037) (xy 105.653834 -271.391468) (xy 105.694337 -271.419424) (xy 105.72983 -271.453516)
			(xy 105.759395 -271.49286) (xy 105.782266 -271.536437) (xy 105.79785 -271.583118) (xy 105.805745 -271.631695)
			(xy 105.80624 -271.656302) (xy 106.135182 -271.656302) (xy 106.139142 -271.607248) (xy 106.150919 -271.559464)
			(xy 106.17021 -271.514188) (xy 106.196513 -271.472592) (xy 106.229148 -271.435755) (xy 106.267269 -271.40463)
			(xy 106.30989 -271.380023) (xy 106.355906 -271.362571) (xy 106.404125 -271.352727) (xy 106.4533 -271.350746)
			(xy 106.502155 -271.356678) (xy 106.549426 -271.37037) (xy 106.593888 -271.391468) (xy 106.634391 -271.419424)
			(xy 106.669884 -271.453516) (xy 106.699449 -271.49286) (xy 106.72232 -271.536437) (xy 106.737904 -271.583118)
			(xy 106.745799 -271.631695) (xy 106.746294 -271.656302) (xy 107.075236 -271.656302) (xy 107.079196 -271.607248)
			(xy 107.090973 -271.559464) (xy 107.110264 -271.514188) (xy 107.136567 -271.472592) (xy 107.169202 -271.435755)
			(xy 107.207323 -271.40463) (xy 107.249944 -271.380023) (xy 107.29596 -271.362571) (xy 107.344179 -271.352727)
			(xy 107.393354 -271.350746) (xy 107.442209 -271.356678) (xy 107.48948 -271.37037) (xy 107.533942 -271.391468)
			(xy 107.574445 -271.419424) (xy 107.609938 -271.453516) (xy 107.639503 -271.49286) (xy 107.662374 -271.536437)
			(xy 107.677958 -271.583118) (xy 107.685853 -271.631695) (xy 107.686348 -271.656302) (xy 108.01529 -271.656302)
			(xy 108.01925 -271.607248) (xy 108.031027 -271.559464) (xy 108.050318 -271.514188) (xy 108.076621 -271.472592)
			(xy 108.109256 -271.435755) (xy 108.147377 -271.40463) (xy 108.189998 -271.380023) (xy 108.236014 -271.362571)
			(xy 108.284233 -271.352727) (xy 108.333408 -271.350746) (xy 108.382263 -271.356678) (xy 108.429534 -271.37037)
			(xy 108.473996 -271.391468) (xy 108.514499 -271.419424) (xy 108.549992 -271.453516) (xy 108.579557 -271.49286)
			(xy 108.602428 -271.536437) (xy 108.618012 -271.583118) (xy 108.625907 -271.631695) (xy 108.626402 -271.656302)
			(xy 115.528864 -271.656302) (xy 115.532824 -271.607248) (xy 115.544601 -271.559464) (xy 115.563892 -271.514188)
			(xy 115.590195 -271.472592) (xy 115.62283 -271.435755) (xy 115.660951 -271.40463) (xy 115.703572 -271.380023)
			(xy 115.749588 -271.362571) (xy 115.797807 -271.352727) (xy 115.846982 -271.350746) (xy 115.895837 -271.356678)
			(xy 115.943108 -271.37037) (xy 115.98757 -271.391468) (xy 116.028073 -271.419424) (xy 116.063566 -271.453516)
			(xy 116.093131 -271.49286) (xy 116.116002 -271.536437) (xy 116.131586 -271.583118) (xy 116.139481 -271.631695)
			(xy 116.139976 -271.656302) (xy 116.468918 -271.656302) (xy 116.472878 -271.607248) (xy 116.484655 -271.559464)
			(xy 116.503946 -271.514188) (xy 116.530249 -271.472592) (xy 116.562884 -271.435755) (xy 116.601005 -271.40463)
			(xy 116.643626 -271.380023) (xy 116.689642 -271.362571) (xy 116.737861 -271.352727) (xy 116.787036 -271.350746)
			(xy 116.835891 -271.356678) (xy 116.883162 -271.37037) (xy 116.927624 -271.391468) (xy 116.968127 -271.419424)
			(xy 117.00362 -271.453516) (xy 117.033185 -271.49286) (xy 117.056056 -271.536437) (xy 117.07164 -271.583118)
			(xy 117.079535 -271.631695) (xy 117.08003 -271.656302) (xy 117.408972 -271.656302) (xy 117.412932 -271.607248)
			(xy 117.424709 -271.559464) (xy 117.444 -271.514188) (xy 117.470303 -271.472592) (xy 117.502938 -271.435755)
			(xy 117.541059 -271.40463) (xy 117.58368 -271.380023) (xy 117.629696 -271.362571) (xy 117.677915 -271.352727)
			(xy 117.72709 -271.350746) (xy 117.775945 -271.356678) (xy 117.823216 -271.37037) (xy 117.867678 -271.391468)
			(xy 117.908181 -271.419424) (xy 117.943674 -271.453516) (xy 117.973239 -271.49286) (xy 117.99611 -271.536437)
			(xy 118.011694 -271.583118) (xy 118.019589 -271.631695) (xy 118.020084 -271.656302) (xy 118.349026 -271.656302)
			(xy 118.352986 -271.607248) (xy 118.364763 -271.559464) (xy 118.384054 -271.514188) (xy 118.410357 -271.472592)
			(xy 118.442992 -271.435755) (xy 118.481113 -271.40463) (xy 118.523734 -271.380023) (xy 118.56975 -271.362571)
			(xy 118.617969 -271.352727) (xy 118.667144 -271.350746) (xy 118.715999 -271.356678) (xy 118.76327 -271.37037)
			(xy 118.807732 -271.391468) (xy 118.848235 -271.419424) (xy 118.883728 -271.453516) (xy 118.913293 -271.49286)
			(xy 118.936164 -271.536437) (xy 118.951748 -271.583118) (xy 118.959643 -271.631695) (xy 118.960138 -271.656302)
			(xy 119.288826 -271.656302) (xy 119.292786 -271.607248) (xy 119.304563 -271.559464) (xy 119.323854 -271.514188)
			(xy 119.350157 -271.472592) (xy 119.382792 -271.435755) (xy 119.420913 -271.40463) (xy 119.463534 -271.380023)
			(xy 119.50955 -271.362571) (xy 119.557769 -271.352727) (xy 119.606944 -271.350746) (xy 119.655799 -271.356678)
			(xy 119.70307 -271.37037) (xy 119.747532 -271.391468) (xy 119.788035 -271.419424) (xy 119.823528 -271.453516)
			(xy 119.853093 -271.49286) (xy 119.875964 -271.536437) (xy 119.891548 -271.583118) (xy 119.899443 -271.631695)
			(xy 119.899938 -271.656302) (xy 120.22888 -271.656302) (xy 120.23284 -271.607248) (xy 120.244617 -271.559464)
			(xy 120.263908 -271.514188) (xy 120.290211 -271.472592) (xy 120.322846 -271.435755) (xy 120.360967 -271.40463)
			(xy 120.403588 -271.380023) (xy 120.449604 -271.362571) (xy 120.497823 -271.352727) (xy 120.546998 -271.350746)
			(xy 120.595853 -271.356678) (xy 120.643124 -271.37037) (xy 120.687586 -271.391468) (xy 120.728089 -271.419424)
			(xy 120.763582 -271.453516) (xy 120.793147 -271.49286) (xy 120.816018 -271.536437) (xy 120.831602 -271.583118)
			(xy 120.839497 -271.631695) (xy 120.839992 -271.656302) (xy 121.168934 -271.656302) (xy 121.172894 -271.607248)
			(xy 121.184671 -271.559464) (xy 121.203962 -271.514188) (xy 121.230265 -271.472592) (xy 121.2629 -271.435755)
			(xy 121.301021 -271.40463) (xy 121.343642 -271.380023) (xy 121.389658 -271.362571) (xy 121.437877 -271.352727)
			(xy 121.487052 -271.350746) (xy 121.535907 -271.356678) (xy 121.583178 -271.37037) (xy 121.62764 -271.391468)
			(xy 121.668143 -271.419424) (xy 121.703636 -271.453516) (xy 121.733201 -271.49286) (xy 121.756072 -271.536437)
			(xy 121.771656 -271.583118) (xy 121.779551 -271.631695) (xy 121.780046 -271.656302) (xy 122.108988 -271.656302)
			(xy 122.112948 -271.607248) (xy 122.124725 -271.559464) (xy 122.144016 -271.514188) (xy 122.170319 -271.472592)
			(xy 122.202954 -271.435755) (xy 122.241075 -271.40463) (xy 122.283696 -271.380023) (xy 122.329712 -271.362571)
			(xy 122.377931 -271.352727) (xy 122.427106 -271.350746) (xy 122.475961 -271.356678) (xy 122.523232 -271.37037)
			(xy 122.567694 -271.391468) (xy 122.608197 -271.419424) (xy 122.64369 -271.453516) (xy 122.673255 -271.49286)
			(xy 122.696126 -271.536437) (xy 122.71171 -271.583118) (xy 122.719605 -271.631695) (xy 122.7201 -271.656302)
			(xy 123.049042 -271.656302) (xy 123.053002 -271.607248) (xy 123.064779 -271.559464) (xy 123.08407 -271.514188)
			(xy 123.110373 -271.472592) (xy 123.143008 -271.435755) (xy 123.181129 -271.40463) (xy 123.22375 -271.380023)
			(xy 123.269766 -271.362571) (xy 123.317985 -271.352727) (xy 123.36716 -271.350746) (xy 123.416015 -271.356678)
			(xy 123.463286 -271.37037) (xy 123.507748 -271.391468) (xy 123.548251 -271.419424) (xy 123.583744 -271.453516)
			(xy 123.613309 -271.49286) (xy 123.63618 -271.536437) (xy 123.651764 -271.583118) (xy 123.659659 -271.631695)
			(xy 123.660154 -271.656302) (xy 123.988842 -271.656302) (xy 123.992802 -271.607248) (xy 124.004579 -271.559464)
			(xy 124.02387 -271.514188) (xy 124.050173 -271.472592) (xy 124.082808 -271.435755) (xy 124.120929 -271.40463)
			(xy 124.16355 -271.380023) (xy 124.209566 -271.362571) (xy 124.257785 -271.352727) (xy 124.30696 -271.350746)
			(xy 124.355815 -271.356678) (xy 124.403086 -271.37037) (xy 124.447548 -271.391468) (xy 124.488051 -271.419424)
			(xy 124.523544 -271.453516) (xy 124.553109 -271.49286) (xy 124.57598 -271.536437) (xy 124.591564 -271.583118)
			(xy 124.599459 -271.631695) (xy 124.599954 -271.656302) (xy 124.928896 -271.656302) (xy 124.932856 -271.607248)
			(xy 124.944633 -271.559464) (xy 124.963924 -271.514188) (xy 124.990227 -271.472592) (xy 125.022862 -271.435755)
			(xy 125.060983 -271.40463) (xy 125.103604 -271.380023) (xy 125.14962 -271.362571) (xy 125.197839 -271.352727)
			(xy 125.247014 -271.350746) (xy 125.295869 -271.356678) (xy 125.34314 -271.37037) (xy 125.387602 -271.391468)
			(xy 125.428105 -271.419424) (xy 125.463598 -271.453516) (xy 125.493163 -271.49286) (xy 125.516034 -271.536437)
			(xy 125.531618 -271.583118) (xy 125.539513 -271.631695) (xy 125.540008 -271.656302) (xy 125.86895 -271.656302)
			(xy 125.87291 -271.607248) (xy 125.884687 -271.559464) (xy 125.903978 -271.514188) (xy 125.930281 -271.472592)
			(xy 125.962916 -271.435755) (xy 126.001037 -271.40463) (xy 126.043658 -271.380023) (xy 126.089674 -271.362571)
			(xy 126.137893 -271.352727) (xy 126.187068 -271.350746) (xy 126.235923 -271.356678) (xy 126.283194 -271.37037)
			(xy 126.327656 -271.391468) (xy 126.368159 -271.419424) (xy 126.403652 -271.453516) (xy 126.433217 -271.49286)
			(xy 126.456088 -271.536437) (xy 126.471672 -271.583118) (xy 126.479567 -271.631695) (xy 126.480062 -271.656302)
			(xy 126.479567 -271.680909) (xy 126.471672 -271.729486) (xy 126.456088 -271.776167) (xy 126.433217 -271.819744)
			(xy 126.403652 -271.859088) (xy 126.368159 -271.89318) (xy 126.327656 -271.921136) (xy 126.283194 -271.942234)
			(xy 126.235923 -271.955926) (xy 126.187068 -271.961858) (xy 126.137893 -271.959877) (xy 126.089674 -271.950033)
			(xy 126.043658 -271.932581) (xy 126.001037 -271.907974) (xy 125.962916 -271.876849) (xy 125.930281 -271.840012)
			(xy 125.903978 -271.798416) (xy 125.884687 -271.75314) (xy 125.87291 -271.705356) (xy 125.86895 -271.656302)
			(xy 125.540008 -271.656302) (xy 125.539513 -271.680909) (xy 125.531618 -271.729486) (xy 125.516034 -271.776167)
			(xy 125.493163 -271.819744) (xy 125.463598 -271.859088) (xy 125.428105 -271.89318) (xy 125.387602 -271.921136)
			(xy 125.34314 -271.942234) (xy 125.295869 -271.955926) (xy 125.247014 -271.961858) (xy 125.197839 -271.959877)
			(xy 125.14962 -271.950033) (xy 125.103604 -271.932581) (xy 125.060983 -271.907974) (xy 125.022862 -271.876849)
			(xy 124.990227 -271.840012) (xy 124.963924 -271.798416) (xy 124.944633 -271.75314) (xy 124.932856 -271.705356)
			(xy 124.928896 -271.656302) (xy 124.599954 -271.656302) (xy 124.599459 -271.680909) (xy 124.591564 -271.729486)
			(xy 124.57598 -271.776167) (xy 124.553109 -271.819744) (xy 124.523544 -271.859088) (xy 124.488051 -271.89318)
			(xy 124.447548 -271.921136) (xy 124.403086 -271.942234) (xy 124.355815 -271.955926) (xy 124.30696 -271.961858)
			(xy 124.257785 -271.959877) (xy 124.209566 -271.950033) (xy 124.16355 -271.932581) (xy 124.120929 -271.907974)
			(xy 124.082808 -271.876849) (xy 124.050173 -271.840012) (xy 124.02387 -271.798416) (xy 124.004579 -271.75314)
			(xy 123.992802 -271.705356) (xy 123.988842 -271.656302) (xy 123.660154 -271.656302) (xy 123.659659 -271.680909)
			(xy 123.651764 -271.729486) (xy 123.63618 -271.776167) (xy 123.613309 -271.819744) (xy 123.583744 -271.859088)
			(xy 123.548251 -271.89318) (xy 123.507748 -271.921136) (xy 123.463286 -271.942234) (xy 123.416015 -271.955926)
			(xy 123.36716 -271.961858) (xy 123.317985 -271.959877) (xy 123.269766 -271.950033) (xy 123.22375 -271.932581)
			(xy 123.181129 -271.907974) (xy 123.143008 -271.876849) (xy 123.110373 -271.840012) (xy 123.08407 -271.798416)
			(xy 123.064779 -271.75314) (xy 123.053002 -271.705356) (xy 123.049042 -271.656302) (xy 122.7201 -271.656302)
			(xy 122.719605 -271.680909) (xy 122.71171 -271.729486) (xy 122.696126 -271.776167) (xy 122.673255 -271.819744)
			(xy 122.64369 -271.859088) (xy 122.608197 -271.89318) (xy 122.567694 -271.921136) (xy 122.523232 -271.942234)
			(xy 122.475961 -271.955926) (xy 122.427106 -271.961858) (xy 122.377931 -271.959877) (xy 122.329712 -271.950033)
			(xy 122.283696 -271.932581) (xy 122.241075 -271.907974) (xy 122.202954 -271.876849) (xy 122.170319 -271.840012)
			(xy 122.144016 -271.798416) (xy 122.124725 -271.75314) (xy 122.112948 -271.705356) (xy 122.108988 -271.656302)
			(xy 121.780046 -271.656302) (xy 121.779551 -271.680909) (xy 121.771656 -271.729486) (xy 121.756072 -271.776167)
			(xy 121.733201 -271.819744) (xy 121.703636 -271.859088) (xy 121.668143 -271.89318) (xy 121.62764 -271.921136)
			(xy 121.583178 -271.942234) (xy 121.535907 -271.955926) (xy 121.487052 -271.961858) (xy 121.437877 -271.959877)
			(xy 121.389658 -271.950033) (xy 121.343642 -271.932581) (xy 121.301021 -271.907974) (xy 121.2629 -271.876849)
			(xy 121.230265 -271.840012) (xy 121.203962 -271.798416) (xy 121.184671 -271.75314) (xy 121.172894 -271.705356)
			(xy 121.168934 -271.656302) (xy 120.839992 -271.656302) (xy 120.839497 -271.680909) (xy 120.831602 -271.729486)
			(xy 120.816018 -271.776167) (xy 120.793147 -271.819744) (xy 120.763582 -271.859088) (xy 120.728089 -271.89318)
			(xy 120.687586 -271.921136) (xy 120.643124 -271.942234) (xy 120.595853 -271.955926) (xy 120.546998 -271.961858)
			(xy 120.497823 -271.959877) (xy 120.449604 -271.950033) (xy 120.403588 -271.932581) (xy 120.360967 -271.907974)
			(xy 120.322846 -271.876849) (xy 120.290211 -271.840012) (xy 120.263908 -271.798416) (xy 120.244617 -271.75314)
			(xy 120.23284 -271.705356) (xy 120.22888 -271.656302) (xy 119.899938 -271.656302) (xy 119.899443 -271.680909)
			(xy 119.891548 -271.729486) (xy 119.875964 -271.776167) (xy 119.853093 -271.819744) (xy 119.823528 -271.859088)
			(xy 119.788035 -271.89318) (xy 119.747532 -271.921136) (xy 119.70307 -271.942234) (xy 119.655799 -271.955926)
			(xy 119.606944 -271.961858) (xy 119.557769 -271.959877) (xy 119.50955 -271.950033) (xy 119.463534 -271.932581)
			(xy 119.420913 -271.907974) (xy 119.382792 -271.876849) (xy 119.350157 -271.840012) (xy 119.323854 -271.798416)
			(xy 119.304563 -271.75314) (xy 119.292786 -271.705356) (xy 119.288826 -271.656302) (xy 118.960138 -271.656302)
			(xy 118.959643 -271.680909) (xy 118.951748 -271.729486) (xy 118.936164 -271.776167) (xy 118.913293 -271.819744)
			(xy 118.883728 -271.859088) (xy 118.848235 -271.89318) (xy 118.807732 -271.921136) (xy 118.76327 -271.942234)
			(xy 118.715999 -271.955926) (xy 118.667144 -271.961858) (xy 118.617969 -271.959877) (xy 118.56975 -271.950033)
			(xy 118.523734 -271.932581) (xy 118.481113 -271.907974) (xy 118.442992 -271.876849) (xy 118.410357 -271.840012)
			(xy 118.384054 -271.798416) (xy 118.364763 -271.75314) (xy 118.352986 -271.705356) (xy 118.349026 -271.656302)
			(xy 118.020084 -271.656302) (xy 118.019589 -271.680909) (xy 118.011694 -271.729486) (xy 117.99611 -271.776167)
			(xy 117.973239 -271.819744) (xy 117.943674 -271.859088) (xy 117.908181 -271.89318) (xy 117.867678 -271.921136)
			(xy 117.823216 -271.942234) (xy 117.775945 -271.955926) (xy 117.72709 -271.961858) (xy 117.677915 -271.959877)
			(xy 117.629696 -271.950033) (xy 117.58368 -271.932581) (xy 117.541059 -271.907974) (xy 117.502938 -271.876849)
			(xy 117.470303 -271.840012) (xy 117.444 -271.798416) (xy 117.424709 -271.75314) (xy 117.412932 -271.705356)
			(xy 117.408972 -271.656302) (xy 117.08003 -271.656302) (xy 117.079535 -271.680909) (xy 117.07164 -271.729486)
			(xy 117.056056 -271.776167) (xy 117.033185 -271.819744) (xy 117.00362 -271.859088) (xy 116.968127 -271.89318)
			(xy 116.927624 -271.921136) (xy 116.883162 -271.942234) (xy 116.835891 -271.955926) (xy 116.787036 -271.961858)
			(xy 116.737861 -271.959877) (xy 116.689642 -271.950033) (xy 116.643626 -271.932581) (xy 116.601005 -271.907974)
			(xy 116.562884 -271.876849) (xy 116.530249 -271.840012) (xy 116.503946 -271.798416) (xy 116.484655 -271.75314)
			(xy 116.472878 -271.705356) (xy 116.468918 -271.656302) (xy 116.139976 -271.656302) (xy 116.139481 -271.680909)
			(xy 116.131586 -271.729486) (xy 116.116002 -271.776167) (xy 116.093131 -271.819744) (xy 116.063566 -271.859088)
			(xy 116.028073 -271.89318) (xy 115.98757 -271.921136) (xy 115.943108 -271.942234) (xy 115.895837 -271.955926)
			(xy 115.846982 -271.961858) (xy 115.797807 -271.959877) (xy 115.749588 -271.950033) (xy 115.703572 -271.932581)
			(xy 115.660951 -271.907974) (xy 115.62283 -271.876849) (xy 115.590195 -271.840012) (xy 115.563892 -271.798416)
			(xy 115.544601 -271.75314) (xy 115.532824 -271.705356) (xy 115.528864 -271.656302) (xy 108.626402 -271.656302)
			(xy 108.625907 -271.680909) (xy 108.618012 -271.729486) (xy 108.602428 -271.776167) (xy 108.579557 -271.819744)
			(xy 108.549992 -271.859088) (xy 108.514499 -271.89318) (xy 108.473996 -271.921136) (xy 108.429534 -271.942234)
			(xy 108.382263 -271.955926) (xy 108.333408 -271.961858) (xy 108.284233 -271.959877) (xy 108.236014 -271.950033)
			(xy 108.189998 -271.932581) (xy 108.147377 -271.907974) (xy 108.109256 -271.876849) (xy 108.076621 -271.840012)
			(xy 108.050318 -271.798416) (xy 108.031027 -271.75314) (xy 108.01925 -271.705356) (xy 108.01529 -271.656302)
			(xy 107.686348 -271.656302) (xy 107.685853 -271.680909) (xy 107.677958 -271.729486) (xy 107.662374 -271.776167)
			(xy 107.639503 -271.819744) (xy 107.609938 -271.859088) (xy 107.574445 -271.89318) (xy 107.533942 -271.921136)
			(xy 107.48948 -271.942234) (xy 107.442209 -271.955926) (xy 107.393354 -271.961858) (xy 107.344179 -271.959877)
			(xy 107.29596 -271.950033) (xy 107.249944 -271.932581) (xy 107.207323 -271.907974) (xy 107.169202 -271.876849)
			(xy 107.136567 -271.840012) (xy 107.110264 -271.798416) (xy 107.090973 -271.75314) (xy 107.079196 -271.705356)
			(xy 107.075236 -271.656302) (xy 106.746294 -271.656302) (xy 106.745799 -271.680909) (xy 106.737904 -271.729486)
			(xy 106.72232 -271.776167) (xy 106.699449 -271.819744) (xy 106.669884 -271.859088) (xy 106.634391 -271.89318)
			(xy 106.593888 -271.921136) (xy 106.549426 -271.942234) (xy 106.502155 -271.955926) (xy 106.4533 -271.961858)
			(xy 106.404125 -271.959877) (xy 106.355906 -271.950033) (xy 106.30989 -271.932581) (xy 106.267269 -271.907974)
			(xy 106.229148 -271.876849) (xy 106.196513 -271.840012) (xy 106.17021 -271.798416) (xy 106.150919 -271.75314)
			(xy 106.139142 -271.705356) (xy 106.135182 -271.656302) (xy 105.80624 -271.656302) (xy 105.805745 -271.680909)
			(xy 105.79785 -271.729486) (xy 105.782266 -271.776167) (xy 105.759395 -271.819744) (xy 105.72983 -271.859088)
			(xy 105.694337 -271.89318) (xy 105.653834 -271.921136) (xy 105.609372 -271.942234) (xy 105.562101 -271.955926)
			(xy 105.513246 -271.961858) (xy 105.464071 -271.959877) (xy 105.415852 -271.950033) (xy 105.369836 -271.932581)
			(xy 105.327215 -271.907974) (xy 105.289094 -271.876849) (xy 105.256459 -271.840012) (xy 105.230156 -271.798416)
			(xy 105.210865 -271.75314) (xy 105.199088 -271.705356) (xy 105.195128 -271.656302) (xy 104.86644 -271.656302)
			(xy 104.865945 -271.680909) (xy 104.85805 -271.729486) (xy 104.842466 -271.776167) (xy 104.819595 -271.819744)
			(xy 104.79003 -271.859088) (xy 104.754537 -271.89318) (xy 104.714034 -271.921136) (xy 104.669572 -271.942234)
			(xy 104.622301 -271.955926) (xy 104.573446 -271.961858) (xy 104.524271 -271.959877) (xy 104.476052 -271.950033)
			(xy 104.430036 -271.932581) (xy 104.387415 -271.907974) (xy 104.349294 -271.876849) (xy 104.316659 -271.840012)
			(xy 104.290356 -271.798416) (xy 104.271065 -271.75314) (xy 104.259288 -271.705356) (xy 104.255328 -271.656302)
			(xy 103.926386 -271.656302) (xy 103.925891 -271.680909) (xy 103.917996 -271.729486) (xy 103.902412 -271.776167)
			(xy 103.879541 -271.819744) (xy 103.849976 -271.859088) (xy 103.814483 -271.89318) (xy 103.77398 -271.921136)
			(xy 103.729518 -271.942234) (xy 103.682247 -271.955926) (xy 103.633392 -271.961858) (xy 103.584217 -271.959877)
			(xy 103.535998 -271.950033) (xy 103.489982 -271.932581) (xy 103.447361 -271.907974) (xy 103.40924 -271.876849)
			(xy 103.376605 -271.840012) (xy 103.350302 -271.798416) (xy 103.331011 -271.75314) (xy 103.319234 -271.705356)
			(xy 103.315274 -271.656302) (xy 102.986332 -271.656302) (xy 102.985837 -271.680909) (xy 102.977942 -271.729486)
			(xy 102.962358 -271.776167) (xy 102.939487 -271.819744) (xy 102.909922 -271.859088) (xy 102.874429 -271.89318)
			(xy 102.833926 -271.921136) (xy 102.789464 -271.942234) (xy 102.742193 -271.955926) (xy 102.693338 -271.961858)
			(xy 102.644163 -271.959877) (xy 102.595944 -271.950033) (xy 102.549928 -271.932581) (xy 102.507307 -271.907974)
			(xy 102.469186 -271.876849) (xy 102.436551 -271.840012) (xy 102.410248 -271.798416) (xy 102.390957 -271.75314)
			(xy 102.37918 -271.705356) (xy 102.37522 -271.656302) (xy 102.046278 -271.656302) (xy 102.045783 -271.680909)
			(xy 102.037888 -271.729486) (xy 102.022304 -271.776167) (xy 101.999433 -271.819744) (xy 101.969868 -271.859088)
			(xy 101.934375 -271.89318) (xy 101.893872 -271.921136) (xy 101.84941 -271.942234) (xy 101.802139 -271.955926)
			(xy 101.753284 -271.961858) (xy 101.704109 -271.959877) (xy 101.65589 -271.950033) (xy 101.609874 -271.932581)
			(xy 101.567253 -271.907974) (xy 101.529132 -271.876849) (xy 101.496497 -271.840012) (xy 101.470194 -271.798416)
			(xy 101.450903 -271.75314) (xy 101.439126 -271.705356) (xy 101.435166 -271.656302) (xy 101.106478 -271.656302)
			(xy 101.105983 -271.680909) (xy 101.098088 -271.729486) (xy 101.082504 -271.776167) (xy 101.059633 -271.819744)
			(xy 101.030068 -271.859088) (xy 100.994575 -271.89318) (xy 100.954072 -271.921136) (xy 100.90961 -271.942234)
			(xy 100.862339 -271.955926) (xy 100.813484 -271.961858) (xy 100.764309 -271.959877) (xy 100.71609 -271.950033)
			(xy 100.670074 -271.932581) (xy 100.627453 -271.907974) (xy 100.589332 -271.876849) (xy 100.556697 -271.840012)
			(xy 100.530394 -271.798416) (xy 100.511103 -271.75314) (xy 100.499326 -271.705356) (xy 100.495366 -271.656302)
			(xy 100.166424 -271.656302) (xy 100.165929 -271.680909) (xy 100.158034 -271.729486) (xy 100.14245 -271.776167)
			(xy 100.119579 -271.819744) (xy 100.090014 -271.859088) (xy 100.054521 -271.89318) (xy 100.014018 -271.921136)
			(xy 99.969556 -271.942234) (xy 99.922285 -271.955926) (xy 99.87343 -271.961858) (xy 99.824255 -271.959877)
			(xy 99.776036 -271.950033) (xy 99.73002 -271.932581) (xy 99.687399 -271.907974) (xy 99.649278 -271.876849)
			(xy 99.616643 -271.840012) (xy 99.59034 -271.798416) (xy 99.571049 -271.75314) (xy 99.559272 -271.705356)
			(xy 99.555312 -271.656302) (xy 99.22637 -271.656302) (xy 99.225875 -271.680909) (xy 99.21798 -271.729486)
			(xy 99.202396 -271.776167) (xy 99.179525 -271.819744) (xy 99.14996 -271.859088) (xy 99.114467 -271.89318)
			(xy 99.073964 -271.921136) (xy 99.029502 -271.942234) (xy 98.982231 -271.955926) (xy 98.933376 -271.961858)
			(xy 98.884201 -271.959877) (xy 98.835982 -271.950033) (xy 98.789966 -271.932581) (xy 98.747345 -271.907974)
			(xy 98.709224 -271.876849) (xy 98.676589 -271.840012) (xy 98.650286 -271.798416) (xy 98.630995 -271.75314)
			(xy 98.619218 -271.705356) (xy 98.615258 -271.656302) (xy 98.286316 -271.656302) (xy 98.285821 -271.680909)
			(xy 98.277926 -271.729486) (xy 98.262342 -271.776167) (xy 98.239471 -271.819744) (xy 98.209906 -271.859088)
			(xy 98.174413 -271.89318) (xy 98.13391 -271.921136) (xy 98.089448 -271.942234) (xy 98.042177 -271.955926)
			(xy 97.993322 -271.961858) (xy 97.944147 -271.959877) (xy 97.895928 -271.950033) (xy 97.849912 -271.932581)
			(xy 97.807291 -271.907974) (xy 97.76917 -271.876849) (xy 97.736535 -271.840012) (xy 97.710232 -271.798416)
			(xy 97.690941 -271.75314) (xy 97.679164 -271.705356) (xy 97.675204 -271.656302) (xy 97.346262 -271.656302)
			(xy 97.345767 -271.680909) (xy 97.337872 -271.729486) (xy 97.322288 -271.776167) (xy 97.299417 -271.819744)
			(xy 97.269852 -271.859088) (xy 97.234359 -271.89318) (xy 97.193856 -271.921136) (xy 97.149394 -271.942234)
			(xy 97.102123 -271.955926) (xy 97.053268 -271.961858) (xy 97.004093 -271.959877) (xy 96.955874 -271.950033)
			(xy 96.909858 -271.932581) (xy 96.867237 -271.907974) (xy 96.829116 -271.876849) (xy 96.796481 -271.840012)
			(xy 96.770178 -271.798416) (xy 96.750887 -271.75314) (xy 96.73911 -271.705356) (xy 96.73515 -271.656302)
			(xy 96.416876 -271.656302) (xy 96.416364 -271.681748) (xy 96.4082 -271.731982) (xy 96.392084 -271.780256)
			(xy 96.368433 -271.825319) (xy 96.33786 -271.866005) (xy 96.301156 -271.90126) (xy 96.259272 -271.93017)
			(xy 96.213293 -271.951987) (xy 96.164409 -271.966147) (xy 96.113888 -271.972281) (xy 96.063036 -271.970232)
			(xy 96.013172 -271.960052) (xy 95.965586 -271.942005) (xy 95.921512 -271.916559) (xy 95.88209 -271.884372)
			(xy 95.848342 -271.846278) (xy 95.821141 -271.803264) (xy 95.801193 -271.756444) (xy 95.789014 -271.70703)
			(xy 95.784919 -271.656302) (xy 95.466408 -271.656302) (xy 95.465913 -271.680909) (xy 95.458018 -271.729486)
			(xy 95.442434 -271.776167) (xy 95.419563 -271.819744) (xy 95.389998 -271.859088) (xy 95.354505 -271.89318)
			(xy 95.314002 -271.921136) (xy 95.26954 -271.942234) (xy 95.222269 -271.955926) (xy 95.173414 -271.961858)
			(xy 95.124239 -271.959877) (xy 95.07602 -271.950033) (xy 95.030004 -271.932581) (xy 94.987383 -271.907974)
			(xy 94.949262 -271.876849) (xy 94.916627 -271.840012) (xy 94.890324 -271.798416) (xy 94.871033 -271.75314)
			(xy 94.859256 -271.705356) (xy 94.855296 -271.656302) (xy 94.536768 -271.656302) (xy 94.536256 -271.681748)
			(xy 94.528092 -271.731982) (xy 94.511976 -271.780256) (xy 94.488325 -271.825319) (xy 94.457752 -271.866005)
			(xy 94.421048 -271.90126) (xy 94.379164 -271.93017) (xy 94.333185 -271.951987) (xy 94.284301 -271.966147)
			(xy 94.23378 -271.972281) (xy 94.182928 -271.970232) (xy 94.133064 -271.960052) (xy 94.085478 -271.942005)
			(xy 94.041404 -271.916559) (xy 94.001982 -271.884372) (xy 93.968234 -271.846278) (xy 93.941033 -271.803264)
			(xy 93.921085 -271.756444) (xy 93.908906 -271.70703) (xy 93.904811 -271.656302) (xy 93.5863 -271.656302)
			(xy 93.585834 -271.680152) (xy 93.578404 -271.727269) (xy 93.563743 -271.772659) (xy 93.542204 -271.815219)
			(xy 93.514313 -271.853914) (xy 93.480747 -271.887804) (xy 93.442321 -271.916066) (xy 93.39997 -271.938011)
			(xy 93.354723 -271.953108) (xy 93.331284 -271.957546) (xy 93.322648 -271.95907) (xy 93.294708 -271.97939)
			(xy 93.289835 -271.983143) (xy 93.281879 -271.992518) (xy 93.27896 -271.997932) (xy 93.248226 -272.060416)
			(xy 93.24721 -272.062956) (xy 93.243638 -272.072325) (xy 93.243376 -272.092359) (xy 93.246702 -272.101818)
			(xy 93.246956 -272.10258) (xy 93.250004 -272.108422) (xy 93.294708 -272.185384) (xy 93.305178 -272.203864)
			(xy 93.32361 -272.242133) (xy 93.331538 -272.261838) (xy 93.331538 -272.262092) (xy 93.334235 -272.268291)
			(xy 93.342349 -272.279097) (xy 93.34754 -272.283428) (xy 93.352874 -272.287492) (xy 93.365066 -272.292826)
			(xy 93.45803 -272.305018) (xy 93.464894 -272.305682) (xy 93.478541 -272.303744) (xy 93.484954 -272.301208)
			(xy 93.490983 -272.298408) (xy 93.501408 -272.290169) (xy 93.505528 -272.284952) (xy 93.505782 -272.284698)
			(xy 93.520286 -272.265869) (xy 93.554143 -272.232515) (xy 93.592756 -272.204806) (xy 93.635194 -272.183411)
			(xy 93.680434 -272.168846) (xy 93.727383 -272.161462) (xy 93.751146 -272.161) (xy 93.776398 -272.161525)
			(xy 93.826213 -272.169845) (xy 93.873979 -272.186249) (xy 93.918394 -272.210291) (xy 93.958246 -272.241315)
			(xy 93.992449 -272.278475) (xy 94.02007 -272.320757) (xy 94.040356 -272.367009) (xy 94.052753 -272.415968)
			(xy 94.056923 -272.4663) (xy 94.056922 -272.466308) (xy 94.374711 -272.466308) (xy 94.378806 -272.41558)
			(xy 94.390985 -272.366166) (xy 94.410933 -272.319346) (xy 94.438134 -272.276332) (xy 94.471882 -272.238238)
			(xy 94.511304 -272.206051) (xy 94.555378 -272.180605) (xy 94.602964 -272.162558) (xy 94.652828 -272.152378)
			(xy 94.70368 -272.150329) (xy 94.754201 -272.156463) (xy 94.803085 -272.170623) (xy 94.849064 -272.19244)
			(xy 94.890948 -272.22135) (xy 94.927652 -272.256605) (xy 94.958225 -272.297291) (xy 94.981876 -272.342354)
			(xy 94.997992 -272.390628) (xy 95.006156 -272.440862) (xy 95.006668 -272.466308) (xy 95.314765 -272.466308)
			(xy 95.31886 -272.41558) (xy 95.331039 -272.366166) (xy 95.350987 -272.319346) (xy 95.378188 -272.276332)
			(xy 95.411936 -272.238238) (xy 95.451358 -272.206051) (xy 95.495432 -272.180605) (xy 95.543018 -272.162558)
			(xy 95.592882 -272.152378) (xy 95.643734 -272.150329) (xy 95.694255 -272.156463) (xy 95.743139 -272.170623)
			(xy 95.789118 -272.19244) (xy 95.831002 -272.22135) (xy 95.867706 -272.256605) (xy 95.898279 -272.297291)
			(xy 95.92193 -272.342354) (xy 95.938046 -272.390628) (xy 95.94621 -272.440862) (xy 95.946722 -272.466308)
			(xy 96.26525 -272.466308) (xy 96.26921 -272.417254) (xy 96.280987 -272.36947) (xy 96.300278 -272.324194)
			(xy 96.326581 -272.282598) (xy 96.359216 -272.245761) (xy 96.397337 -272.214636) (xy 96.439958 -272.190029)
			(xy 96.485974 -272.172577) (xy 96.534193 -272.162733) (xy 96.583368 -272.160752) (xy 96.632223 -272.166684)
			(xy 96.679494 -272.180376) (xy 96.723956 -272.201474) (xy 96.764459 -272.22943) (xy 96.799952 -272.263522)
			(xy 96.829517 -272.302866) (xy 96.852388 -272.346443) (xy 96.867972 -272.393124) (xy 96.875867 -272.441701)
			(xy 96.876362 -272.466308) (xy 99.085158 -272.466308) (xy 99.089118 -272.417254) (xy 99.100895 -272.36947)
			(xy 99.120186 -272.324194) (xy 99.146489 -272.282598) (xy 99.179124 -272.245761) (xy 99.217245 -272.214636)
			(xy 99.259866 -272.190029) (xy 99.305882 -272.172577) (xy 99.354101 -272.162733) (xy 99.403276 -272.160752)
			(xy 99.452131 -272.166684) (xy 99.499402 -272.180376) (xy 99.543864 -272.201474) (xy 99.584367 -272.22943)
			(xy 99.61986 -272.263522) (xy 99.649425 -272.302866) (xy 99.672296 -272.346443) (xy 99.68788 -272.393124)
			(xy 99.695775 -272.441701) (xy 99.69627 -272.466308) (xy 101.90532 -272.466308) (xy 101.90928 -272.417254)
			(xy 101.921057 -272.36947) (xy 101.940348 -272.324194) (xy 101.966651 -272.282598) (xy 101.999286 -272.245761)
			(xy 102.037407 -272.214636) (xy 102.080028 -272.190029) (xy 102.126044 -272.172577) (xy 102.174263 -272.162733)
			(xy 102.223438 -272.160752) (xy 102.272293 -272.166684) (xy 102.319564 -272.180376) (xy 102.364026 -272.201474)
			(xy 102.404529 -272.22943) (xy 102.440022 -272.263522) (xy 102.469587 -272.302866) (xy 102.492458 -272.346443)
			(xy 102.508042 -272.393124) (xy 102.515937 -272.441701) (xy 102.516432 -272.466308) (xy 104.725228 -272.466308)
			(xy 104.729188 -272.417254) (xy 104.740965 -272.36947) (xy 104.760256 -272.324194) (xy 104.786559 -272.282598)
			(xy 104.819194 -272.245761) (xy 104.857315 -272.214636) (xy 104.899936 -272.190029) (xy 104.945952 -272.172577)
			(xy 104.994171 -272.162733) (xy 105.043346 -272.160752) (xy 105.092201 -272.166684) (xy 105.139472 -272.180376)
			(xy 105.183934 -272.201474) (xy 105.224437 -272.22943) (xy 105.25993 -272.263522) (xy 105.289495 -272.302866)
			(xy 105.312366 -272.346443) (xy 105.32795 -272.393124) (xy 105.335845 -272.441701) (xy 105.33634 -272.466308)
			(xy 107.545136 -272.466308) (xy 107.549096 -272.417254) (xy 107.560873 -272.36947) (xy 107.580164 -272.324194)
			(xy 107.606467 -272.282598) (xy 107.639102 -272.245761) (xy 107.677223 -272.214636) (xy 107.719844 -272.190029)
			(xy 107.76586 -272.172577) (xy 107.814079 -272.162733) (xy 107.863254 -272.160752) (xy 107.912109 -272.166684)
			(xy 107.95938 -272.180376) (xy 108.003842 -272.201474) (xy 108.044345 -272.22943) (xy 108.079838 -272.263522)
			(xy 108.109403 -272.302866) (xy 108.132274 -272.346443) (xy 108.147858 -272.393124) (xy 108.155753 -272.441701)
			(xy 108.156248 -272.466308) (xy 108.48519 -272.466308) (xy 108.48915 -272.417254) (xy 108.500927 -272.36947)
			(xy 108.520218 -272.324194) (xy 108.546521 -272.282598) (xy 108.579156 -272.245761) (xy 108.617277 -272.214636)
			(xy 108.659898 -272.190029) (xy 108.705914 -272.172577) (xy 108.754133 -272.162733) (xy 108.803308 -272.160752)
			(xy 108.852163 -272.166684) (xy 108.899434 -272.180376) (xy 108.943896 -272.201474) (xy 108.984399 -272.22943)
			(xy 109.019892 -272.263522) (xy 109.049457 -272.302866) (xy 109.072328 -272.346443) (xy 109.087912 -272.393124)
			(xy 109.095807 -272.441701) (xy 109.096302 -272.466308) (xy 109.425244 -272.466308) (xy 109.429204 -272.417254)
			(xy 109.440981 -272.36947) (xy 109.460272 -272.324194) (xy 109.486575 -272.282598) (xy 109.51921 -272.245761)
			(xy 109.557331 -272.214636) (xy 109.599952 -272.190029) (xy 109.645968 -272.172577) (xy 109.694187 -272.162733)
			(xy 109.743362 -272.160752) (xy 109.792217 -272.166684) (xy 109.839488 -272.180376) (xy 109.88395 -272.201474)
			(xy 109.924453 -272.22943) (xy 109.959946 -272.263522) (xy 109.989511 -272.302866) (xy 110.012382 -272.346443)
			(xy 110.027966 -272.393124) (xy 110.035861 -272.441701) (xy 110.036356 -272.466308) (xy 110.365298 -272.466308)
			(xy 110.369258 -272.417254) (xy 110.381035 -272.36947) (xy 110.400326 -272.324194) (xy 110.426629 -272.282598)
			(xy 110.459264 -272.245761) (xy 110.497385 -272.214636) (xy 110.540006 -272.190029) (xy 110.586022 -272.172577)
			(xy 110.634241 -272.162733) (xy 110.683416 -272.160752) (xy 110.732271 -272.166684) (xy 110.779542 -272.180376)
			(xy 110.824004 -272.201474) (xy 110.864507 -272.22943) (xy 110.9 -272.263522) (xy 110.929565 -272.302866)
			(xy 110.952436 -272.346443) (xy 110.96802 -272.393124) (xy 110.975915 -272.441701) (xy 110.97641 -272.466308)
			(xy 113.178856 -272.466308) (xy 113.182816 -272.417254) (xy 113.194593 -272.36947) (xy 113.213884 -272.324194)
			(xy 113.240187 -272.282598) (xy 113.272822 -272.245761) (xy 113.310943 -272.214636) (xy 113.353564 -272.190029)
			(xy 113.39958 -272.172577) (xy 113.447799 -272.162733) (xy 113.496974 -272.160752) (xy 113.545829 -272.166684)
			(xy 113.5931 -272.180376) (xy 113.637562 -272.201474) (xy 113.678065 -272.22943) (xy 113.713558 -272.263522)
			(xy 113.743123 -272.302866) (xy 113.765994 -272.346443) (xy 113.781578 -272.393124) (xy 113.789473 -272.441701)
			(xy 113.789968 -272.466308) (xy 114.11891 -272.466308) (xy 114.12287 -272.417254) (xy 114.134647 -272.36947)
			(xy 114.153938 -272.324194) (xy 114.180241 -272.282598) (xy 114.212876 -272.245761) (xy 114.250997 -272.214636)
			(xy 114.293618 -272.190029) (xy 114.339634 -272.172577) (xy 114.387853 -272.162733) (xy 114.437028 -272.160752)
			(xy 114.485883 -272.166684) (xy 114.533154 -272.180376) (xy 114.577616 -272.201474) (xy 114.618119 -272.22943)
			(xy 114.653612 -272.263522) (xy 114.683177 -272.302866) (xy 114.706048 -272.346443) (xy 114.721632 -272.393124)
			(xy 114.729527 -272.441701) (xy 114.730022 -272.466308) (xy 115.058964 -272.466308) (xy 115.062924 -272.417254)
			(xy 115.074701 -272.36947) (xy 115.093992 -272.324194) (xy 115.120295 -272.282598) (xy 115.15293 -272.245761)
			(xy 115.191051 -272.214636) (xy 115.233672 -272.190029) (xy 115.279688 -272.172577) (xy 115.327907 -272.162733)
			(xy 115.377082 -272.160752) (xy 115.425937 -272.166684) (xy 115.473208 -272.180376) (xy 115.51767 -272.201474)
			(xy 115.558173 -272.22943) (xy 115.593666 -272.263522) (xy 115.623231 -272.302866) (xy 115.646102 -272.346443)
			(xy 115.661686 -272.393124) (xy 115.669581 -272.441701) (xy 115.670076 -272.466308) (xy 115.999018 -272.466308)
			(xy 116.002978 -272.417254) (xy 116.014755 -272.36947) (xy 116.034046 -272.324194) (xy 116.060349 -272.282598)
			(xy 116.092984 -272.245761) (xy 116.131105 -272.214636) (xy 116.173726 -272.190029) (xy 116.219742 -272.172577)
			(xy 116.267961 -272.162733) (xy 116.317136 -272.160752) (xy 116.365991 -272.166684) (xy 116.413262 -272.180376)
			(xy 116.457724 -272.201474) (xy 116.498227 -272.22943) (xy 116.53372 -272.263522) (xy 116.563285 -272.302866)
			(xy 116.586156 -272.346443) (xy 116.60174 -272.393124) (xy 116.609635 -272.441701) (xy 116.61013 -272.466308)
			(xy 118.818926 -272.466308) (xy 118.822886 -272.417254) (xy 118.834663 -272.36947) (xy 118.853954 -272.324194)
			(xy 118.880257 -272.282598) (xy 118.912892 -272.245761) (xy 118.951013 -272.214636) (xy 118.993634 -272.190029)
			(xy 119.03965 -272.172577) (xy 119.087869 -272.162733) (xy 119.137044 -272.160752) (xy 119.185899 -272.166684)
			(xy 119.23317 -272.180376) (xy 119.277632 -272.201474) (xy 119.318135 -272.22943) (xy 119.353628 -272.263522)
			(xy 119.383193 -272.302866) (xy 119.406064 -272.346443) (xy 119.421648 -272.393124) (xy 119.429543 -272.441701)
			(xy 119.430038 -272.466308) (xy 121.638834 -272.466308) (xy 121.642794 -272.417254) (xy 121.654571 -272.36947)
			(xy 121.673862 -272.324194) (xy 121.700165 -272.282598) (xy 121.7328 -272.245761) (xy 121.770921 -272.214636)
			(xy 121.813542 -272.190029) (xy 121.859558 -272.172577) (xy 121.907777 -272.162733) (xy 121.956952 -272.160752)
			(xy 122.005807 -272.166684) (xy 122.053078 -272.180376) (xy 122.09754 -272.201474) (xy 122.138043 -272.22943)
			(xy 122.173536 -272.263522) (xy 122.203101 -272.302866) (xy 122.225972 -272.346443) (xy 122.241556 -272.393124)
			(xy 122.249451 -272.441701) (xy 122.249946 -272.466308) (xy 124.458996 -272.466308) (xy 124.462956 -272.417254)
			(xy 124.474733 -272.36947) (xy 124.494024 -272.324194) (xy 124.520327 -272.282598) (xy 124.552962 -272.245761)
			(xy 124.591083 -272.214636) (xy 124.633704 -272.190029) (xy 124.67972 -272.172577) (xy 124.727939 -272.162733)
			(xy 124.777114 -272.160752) (xy 124.825969 -272.166684) (xy 124.87324 -272.180376) (xy 124.917702 -272.201474)
			(xy 124.958205 -272.22943) (xy 124.993698 -272.263522) (xy 125.023263 -272.302866) (xy 125.046134 -272.346443)
			(xy 125.061718 -272.393124) (xy 125.069613 -272.441701) (xy 125.070108 -272.466308) (xy 125.069613 -272.490915)
			(xy 125.061718 -272.539492) (xy 125.046134 -272.586173) (xy 125.023263 -272.62975) (xy 124.993698 -272.669094)
			(xy 124.958205 -272.703186) (xy 124.917702 -272.731142) (xy 124.87324 -272.75224) (xy 124.825969 -272.765932)
			(xy 124.777114 -272.771864) (xy 124.727939 -272.769883) (xy 124.67972 -272.760039) (xy 124.633704 -272.742587)
			(xy 124.591083 -272.71798) (xy 124.552962 -272.686855) (xy 124.520327 -272.650018) (xy 124.494024 -272.608422)
			(xy 124.474733 -272.563146) (xy 124.462956 -272.515362) (xy 124.458996 -272.466308) (xy 122.249946 -272.466308)
			(xy 122.249451 -272.490915) (xy 122.241556 -272.539492) (xy 122.225972 -272.586173) (xy 122.203101 -272.62975)
			(xy 122.173536 -272.669094) (xy 122.138043 -272.703186) (xy 122.09754 -272.731142) (xy 122.053078 -272.75224)
			(xy 122.005807 -272.765932) (xy 121.956952 -272.771864) (xy 121.907777 -272.769883) (xy 121.859558 -272.760039)
			(xy 121.813542 -272.742587) (xy 121.770921 -272.71798) (xy 121.7328 -272.686855) (xy 121.700165 -272.650018)
			(xy 121.673862 -272.608422) (xy 121.654571 -272.563146) (xy 121.642794 -272.515362) (xy 121.638834 -272.466308)
			(xy 119.430038 -272.466308) (xy 119.429543 -272.490915) (xy 119.421648 -272.539492) (xy 119.406064 -272.586173)
			(xy 119.383193 -272.62975) (xy 119.353628 -272.669094) (xy 119.318135 -272.703186) (xy 119.277632 -272.731142)
			(xy 119.23317 -272.75224) (xy 119.185899 -272.765932) (xy 119.137044 -272.771864) (xy 119.087869 -272.769883)
			(xy 119.03965 -272.760039) (xy 118.993634 -272.742587) (xy 118.951013 -272.71798) (xy 118.912892 -272.686855)
			(xy 118.880257 -272.650018) (xy 118.853954 -272.608422) (xy 118.834663 -272.563146) (xy 118.822886 -272.515362)
			(xy 118.818926 -272.466308) (xy 116.61013 -272.466308) (xy 116.609635 -272.490915) (xy 116.60174 -272.539492)
			(xy 116.586156 -272.586173) (xy 116.563285 -272.62975) (xy 116.53372 -272.669094) (xy 116.498227 -272.703186)
			(xy 116.457724 -272.731142) (xy 116.413262 -272.75224) (xy 116.365991 -272.765932) (xy 116.317136 -272.771864)
			(xy 116.267961 -272.769883) (xy 116.219742 -272.760039) (xy 116.173726 -272.742587) (xy 116.131105 -272.71798)
			(xy 116.092984 -272.686855) (xy 116.060349 -272.650018) (xy 116.034046 -272.608422) (xy 116.014755 -272.563146)
			(xy 116.002978 -272.515362) (xy 115.999018 -272.466308) (xy 115.670076 -272.466308) (xy 115.669581 -272.490915)
			(xy 115.661686 -272.539492) (xy 115.646102 -272.586173) (xy 115.623231 -272.62975) (xy 115.593666 -272.669094)
			(xy 115.558173 -272.703186) (xy 115.51767 -272.731142) (xy 115.473208 -272.75224) (xy 115.425937 -272.765932)
			(xy 115.377082 -272.771864) (xy 115.327907 -272.769883) (xy 115.279688 -272.760039) (xy 115.233672 -272.742587)
			(xy 115.191051 -272.71798) (xy 115.15293 -272.686855) (xy 115.120295 -272.650018) (xy 115.093992 -272.608422)
			(xy 115.074701 -272.563146) (xy 115.062924 -272.515362) (xy 115.058964 -272.466308) (xy 114.730022 -272.466308)
			(xy 114.729527 -272.490915) (xy 114.721632 -272.539492) (xy 114.706048 -272.586173) (xy 114.683177 -272.62975)
			(xy 114.653612 -272.669094) (xy 114.618119 -272.703186) (xy 114.577616 -272.731142) (xy 114.533154 -272.75224)
			(xy 114.485883 -272.765932) (xy 114.437028 -272.771864) (xy 114.387853 -272.769883) (xy 114.339634 -272.760039)
			(xy 114.293618 -272.742587) (xy 114.250997 -272.71798) (xy 114.212876 -272.686855) (xy 114.180241 -272.650018)
			(xy 114.153938 -272.608422) (xy 114.134647 -272.563146) (xy 114.12287 -272.515362) (xy 114.11891 -272.466308)
			(xy 113.789968 -272.466308) (xy 113.789473 -272.490915) (xy 113.781578 -272.539492) (xy 113.765994 -272.586173)
			(xy 113.743123 -272.62975) (xy 113.713558 -272.669094) (xy 113.678065 -272.703186) (xy 113.637562 -272.731142)
			(xy 113.5931 -272.75224) (xy 113.545829 -272.765932) (xy 113.496974 -272.771864) (xy 113.447799 -272.769883)
			(xy 113.39958 -272.760039) (xy 113.353564 -272.742587) (xy 113.310943 -272.71798) (xy 113.272822 -272.686855)
			(xy 113.240187 -272.650018) (xy 113.213884 -272.608422) (xy 113.194593 -272.563146) (xy 113.182816 -272.515362)
			(xy 113.178856 -272.466308) (xy 110.97641 -272.466308) (xy 110.975915 -272.490915) (xy 110.96802 -272.539492)
			(xy 110.952436 -272.586173) (xy 110.929565 -272.62975) (xy 110.9 -272.669094) (xy 110.864507 -272.703186)
			(xy 110.824004 -272.731142) (xy 110.779542 -272.75224) (xy 110.732271 -272.765932) (xy 110.683416 -272.771864)
			(xy 110.634241 -272.769883) (xy 110.586022 -272.760039) (xy 110.540006 -272.742587) (xy 110.497385 -272.71798)
			(xy 110.459264 -272.686855) (xy 110.426629 -272.650018) (xy 110.400326 -272.608422) (xy 110.381035 -272.563146)
			(xy 110.369258 -272.515362) (xy 110.365298 -272.466308) (xy 110.036356 -272.466308) (xy 110.035861 -272.490915)
			(xy 110.027966 -272.539492) (xy 110.012382 -272.586173) (xy 109.989511 -272.62975) (xy 109.959946 -272.669094)
			(xy 109.924453 -272.703186) (xy 109.88395 -272.731142) (xy 109.839488 -272.75224) (xy 109.792217 -272.765932)
			(xy 109.743362 -272.771864) (xy 109.694187 -272.769883) (xy 109.645968 -272.760039) (xy 109.599952 -272.742587)
			(xy 109.557331 -272.71798) (xy 109.51921 -272.686855) (xy 109.486575 -272.650018) (xy 109.460272 -272.608422)
			(xy 109.440981 -272.563146) (xy 109.429204 -272.515362) (xy 109.425244 -272.466308) (xy 109.096302 -272.466308)
			(xy 109.095807 -272.490915) (xy 109.087912 -272.539492) (xy 109.072328 -272.586173) (xy 109.049457 -272.62975)
			(xy 109.019892 -272.669094) (xy 108.984399 -272.703186) (xy 108.943896 -272.731142) (xy 108.899434 -272.75224)
			(xy 108.852163 -272.765932) (xy 108.803308 -272.771864) (xy 108.754133 -272.769883) (xy 108.705914 -272.760039)
			(xy 108.659898 -272.742587) (xy 108.617277 -272.71798) (xy 108.579156 -272.686855) (xy 108.546521 -272.650018)
			(xy 108.520218 -272.608422) (xy 108.500927 -272.563146) (xy 108.48915 -272.515362) (xy 108.48519 -272.466308)
			(xy 108.156248 -272.466308) (xy 108.155753 -272.490915) (xy 108.147858 -272.539492) (xy 108.132274 -272.586173)
			(xy 108.109403 -272.62975) (xy 108.079838 -272.669094) (xy 108.044345 -272.703186) (xy 108.003842 -272.731142)
			(xy 107.95938 -272.75224) (xy 107.912109 -272.765932) (xy 107.863254 -272.771864) (xy 107.814079 -272.769883)
			(xy 107.76586 -272.760039) (xy 107.719844 -272.742587) (xy 107.677223 -272.71798) (xy 107.639102 -272.686855)
			(xy 107.606467 -272.650018) (xy 107.580164 -272.608422) (xy 107.560873 -272.563146) (xy 107.549096 -272.515362)
			(xy 107.545136 -272.466308) (xy 105.33634 -272.466308) (xy 105.335845 -272.490915) (xy 105.32795 -272.539492)
			(xy 105.312366 -272.586173) (xy 105.289495 -272.62975) (xy 105.25993 -272.669094) (xy 105.224437 -272.703186)
			(xy 105.183934 -272.731142) (xy 105.139472 -272.75224) (xy 105.092201 -272.765932) (xy 105.043346 -272.771864)
			(xy 104.994171 -272.769883) (xy 104.945952 -272.760039) (xy 104.899936 -272.742587) (xy 104.857315 -272.71798)
			(xy 104.819194 -272.686855) (xy 104.786559 -272.650018) (xy 104.760256 -272.608422) (xy 104.740965 -272.563146)
			(xy 104.729188 -272.515362) (xy 104.725228 -272.466308) (xy 102.516432 -272.466308) (xy 102.515937 -272.490915)
			(xy 102.508042 -272.539492) (xy 102.492458 -272.586173) (xy 102.469587 -272.62975) (xy 102.440022 -272.669094)
			(xy 102.404529 -272.703186) (xy 102.364026 -272.731142) (xy 102.319564 -272.75224) (xy 102.272293 -272.765932)
			(xy 102.223438 -272.771864) (xy 102.174263 -272.769883) (xy 102.126044 -272.760039) (xy 102.080028 -272.742587)
			(xy 102.037407 -272.71798) (xy 101.999286 -272.686855) (xy 101.966651 -272.650018) (xy 101.940348 -272.608422)
			(xy 101.921057 -272.563146) (xy 101.90928 -272.515362) (xy 101.90532 -272.466308) (xy 99.69627 -272.466308)
			(xy 99.695775 -272.490915) (xy 99.68788 -272.539492) (xy 99.672296 -272.586173) (xy 99.649425 -272.62975)
			(xy 99.61986 -272.669094) (xy 99.584367 -272.703186) (xy 99.543864 -272.731142) (xy 99.499402 -272.75224)
			(xy 99.452131 -272.765932) (xy 99.403276 -272.771864) (xy 99.354101 -272.769883) (xy 99.305882 -272.760039)
			(xy 99.259866 -272.742587) (xy 99.217245 -272.71798) (xy 99.179124 -272.686855) (xy 99.146489 -272.650018)
			(xy 99.120186 -272.608422) (xy 99.100895 -272.563146) (xy 99.089118 -272.515362) (xy 99.085158 -272.466308)
			(xy 96.876362 -272.466308) (xy 96.875867 -272.490915) (xy 96.867972 -272.539492) (xy 96.852388 -272.586173)
			(xy 96.829517 -272.62975) (xy 96.799952 -272.669094) (xy 96.764459 -272.703186) (xy 96.723956 -272.731142)
			(xy 96.679494 -272.75224) (xy 96.632223 -272.765932) (xy 96.583368 -272.771864) (xy 96.534193 -272.769883)
			(xy 96.485974 -272.760039) (xy 96.439958 -272.742587) (xy 96.397337 -272.71798) (xy 96.359216 -272.686855)
			(xy 96.326581 -272.650018) (xy 96.300278 -272.608422) (xy 96.280987 -272.563146) (xy 96.26921 -272.515362)
			(xy 96.26525 -272.466308) (xy 95.946722 -272.466308) (xy 95.94621 -272.491754) (xy 95.938046 -272.541988)
			(xy 95.92193 -272.590262) (xy 95.898279 -272.635325) (xy 95.867706 -272.676011) (xy 95.831002 -272.711266)
			(xy 95.789118 -272.740176) (xy 95.743139 -272.761993) (xy 95.694255 -272.776153) (xy 95.643734 -272.782287)
			(xy 95.592882 -272.780238) (xy 95.543018 -272.770058) (xy 95.495432 -272.752011) (xy 95.451358 -272.726565)
			(xy 95.411936 -272.694378) (xy 95.378188 -272.656284) (xy 95.350987 -272.61327) (xy 95.331039 -272.56645)
			(xy 95.31886 -272.517036) (xy 95.314765 -272.466308) (xy 95.006668 -272.466308) (xy 95.006156 -272.491754)
			(xy 94.997992 -272.541988) (xy 94.981876 -272.590262) (xy 94.958225 -272.635325) (xy 94.927652 -272.676011)
			(xy 94.890948 -272.711266) (xy 94.849064 -272.740176) (xy 94.803085 -272.761993) (xy 94.754201 -272.776153)
			(xy 94.70368 -272.782287) (xy 94.652828 -272.780238) (xy 94.602964 -272.770058) (xy 94.555378 -272.752011)
			(xy 94.511304 -272.726565) (xy 94.471882 -272.694378) (xy 94.438134 -272.656284) (xy 94.410933 -272.61327)
			(xy 94.390985 -272.56645) (xy 94.378806 -272.517036) (xy 94.374711 -272.466308) (xy 94.056922 -272.466308)
			(xy 94.052753 -272.516632) (xy 94.040356 -272.565591) (xy 94.02007 -272.611843) (xy 93.992449 -272.654125)
			(xy 93.958246 -272.691285) (xy 93.918394 -272.722309) (xy 93.873979 -272.746351) (xy 93.826213 -272.762755)
			(xy 93.776398 -272.771075) (xy 93.751146 -272.771616) (xy 93.72738 -272.771166) (xy 93.680423 -272.763802)
			(xy 93.635175 -272.749246) (xy 93.592733 -272.727849) (xy 93.554121 -272.70013) (xy 93.520275 -272.666758)
			(xy 93.505782 -272.647918) (xy 93.505782 -272.647664) (xy 93.505528 -272.647664) (xy 93.501372 -272.642484)
			(xy 93.490956 -272.63425) (xy 93.484954 -272.631408) (xy 93.478545 -272.628862) (xy 93.464895 -272.626942)
			(xy 93.45803 -272.627598) (xy 93.372178 -272.639028) (xy 93.365418 -272.640102) (xy 93.352794 -272.645379)
			(xy 93.347286 -272.649442) (xy 93.341952 -272.653506) (xy 93.334078 -272.664174) (xy 93.331538 -272.670778)
			(xy 93.315987 -272.708449) (xy 93.275561 -272.779211) (xy 93.25102 -272.811748) (xy 93.25102 -272.812002)
			(xy 93.246981 -272.817404) (xy 93.241566 -272.829752) (xy 93.240352 -272.836386) (xy 93.238574 -272.849594)
			(xy 93.276928 -272.942304) (xy 93.279679 -272.948471) (xy 93.287914 -272.959166) (xy 93.293184 -272.963386)
			(xy 93.298518 -272.96745) (xy 93.31071 -272.972276) (xy 93.317822 -272.973292) (xy 93.342181 -272.976757)
			(xy 93.389432 -272.99046) (xy 93.433875 -273.011561) (xy 93.47436 -273.039515) (xy 93.509839 -273.073599)
			(xy 93.539393 -273.11293) (xy 93.562259 -273.156492) (xy 93.577845 -273.203156) (xy 93.585747 -273.251715)
			(xy 93.5863 -273.276314) (xy 93.904811 -273.276314) (xy 93.908906 -273.225586) (xy 93.921085 -273.176172)
			(xy 93.941033 -273.129352) (xy 93.968234 -273.086338) (xy 94.001982 -273.048244) (xy 94.041404 -273.016057)
			(xy 94.085478 -272.990611) (xy 94.133064 -272.972564) (xy 94.182928 -272.962384) (xy 94.23378 -272.960335)
			(xy 94.284301 -272.966469) (xy 94.333185 -272.980629) (xy 94.379164 -273.002446) (xy 94.421048 -273.031356)
			(xy 94.457752 -273.066611) (xy 94.488325 -273.107297) (xy 94.511976 -273.15236) (xy 94.528092 -273.200634)
			(xy 94.536256 -273.250868) (xy 94.536768 -273.276314) (xy 94.855296 -273.276314) (xy 94.859256 -273.22726)
			(xy 94.871033 -273.179476) (xy 94.890324 -273.1342) (xy 94.916627 -273.092604) (xy 94.949262 -273.055767)
			(xy 94.987383 -273.024642) (xy 95.030004 -273.000035) (xy 95.07602 -272.982583) (xy 95.124239 -272.972739)
			(xy 95.173414 -272.970758) (xy 95.222269 -272.97669) (xy 95.26954 -272.990382) (xy 95.314002 -273.01148)
			(xy 95.354505 -273.039436) (xy 95.389998 -273.073528) (xy 95.419563 -273.112872) (xy 95.442434 -273.156449)
			(xy 95.458018 -273.20313) (xy 95.465913 -273.251707) (xy 95.466408 -273.276314) (xy 95.784919 -273.276314)
			(xy 95.789014 -273.225586) (xy 95.801193 -273.176172) (xy 95.821141 -273.129352) (xy 95.848342 -273.086338)
			(xy 95.88209 -273.048244) (xy 95.921512 -273.016057) (xy 95.965586 -272.990611) (xy 96.013172 -272.972564)
			(xy 96.063036 -272.962384) (xy 96.113888 -272.960335) (xy 96.164409 -272.966469) (xy 96.213293 -272.980629)
			(xy 96.259272 -273.002446) (xy 96.301156 -273.031356) (xy 96.33786 -273.066611) (xy 96.368433 -273.107297)
			(xy 96.392084 -273.15236) (xy 96.4082 -273.200634) (xy 96.416364 -273.250868) (xy 96.416876 -273.276314)
			(xy 96.73515 -273.276314) (xy 96.73911 -273.22726) (xy 96.750887 -273.179476) (xy 96.770178 -273.1342)
			(xy 96.796481 -273.092604) (xy 96.829116 -273.055767) (xy 96.867237 -273.024642) (xy 96.909858 -273.000035)
			(xy 96.955874 -272.982583) (xy 97.004093 -272.972739) (xy 97.053268 -272.970758) (xy 97.102123 -272.97669)
			(xy 97.149394 -272.990382) (xy 97.193856 -273.01148) (xy 97.234359 -273.039436) (xy 97.269852 -273.073528)
			(xy 97.299417 -273.112872) (xy 97.322288 -273.156449) (xy 97.337872 -273.20313) (xy 97.345767 -273.251707)
			(xy 97.346262 -273.276314) (xy 97.675204 -273.276314) (xy 97.679164 -273.22726) (xy 97.690941 -273.179476)
			(xy 97.710232 -273.1342) (xy 97.736535 -273.092604) (xy 97.76917 -273.055767) (xy 97.807291 -273.024642)
			(xy 97.849912 -273.000035) (xy 97.895928 -272.982583) (xy 97.944147 -272.972739) (xy 97.993322 -272.970758)
			(xy 98.042177 -272.97669) (xy 98.089448 -272.990382) (xy 98.13391 -273.01148) (xy 98.174413 -273.039436)
			(xy 98.209906 -273.073528) (xy 98.239471 -273.112872) (xy 98.262342 -273.156449) (xy 98.277926 -273.20313)
			(xy 98.285821 -273.251707) (xy 98.286316 -273.276314) (xy 98.615258 -273.276314) (xy 98.619218 -273.22726)
			(xy 98.630995 -273.179476) (xy 98.650286 -273.1342) (xy 98.676589 -273.092604) (xy 98.709224 -273.055767)
			(xy 98.747345 -273.024642) (xy 98.789966 -273.000035) (xy 98.835982 -272.982583) (xy 98.884201 -272.972739)
			(xy 98.933376 -272.970758) (xy 98.982231 -272.97669) (xy 99.029502 -272.990382) (xy 99.073964 -273.01148)
			(xy 99.114467 -273.039436) (xy 99.14996 -273.073528) (xy 99.179525 -273.112872) (xy 99.202396 -273.156449)
			(xy 99.21798 -273.20313) (xy 99.225875 -273.251707) (xy 99.22637 -273.276314) (xy 99.555312 -273.276314)
			(xy 99.559272 -273.22726) (xy 99.571049 -273.179476) (xy 99.59034 -273.1342) (xy 99.616643 -273.092604)
			(xy 99.649278 -273.055767) (xy 99.687399 -273.024642) (xy 99.73002 -273.000035) (xy 99.776036 -272.982583)
			(xy 99.824255 -272.972739) (xy 99.87343 -272.970758) (xy 99.922285 -272.97669) (xy 99.969556 -272.990382)
			(xy 100.014018 -273.01148) (xy 100.054521 -273.039436) (xy 100.090014 -273.073528) (xy 100.119579 -273.112872)
			(xy 100.14245 -273.156449) (xy 100.158034 -273.20313) (xy 100.165929 -273.251707) (xy 100.166424 -273.276314)
			(xy 100.495366 -273.276314) (xy 100.499326 -273.22726) (xy 100.511103 -273.179476) (xy 100.530394 -273.1342)
			(xy 100.556697 -273.092604) (xy 100.589332 -273.055767) (xy 100.627453 -273.024642) (xy 100.670074 -273.000035)
			(xy 100.71609 -272.982583) (xy 100.764309 -272.972739) (xy 100.813484 -272.970758) (xy 100.862339 -272.97669)
			(xy 100.90961 -272.990382) (xy 100.954072 -273.01148) (xy 100.994575 -273.039436) (xy 101.030068 -273.073528)
			(xy 101.059633 -273.112872) (xy 101.082504 -273.156449) (xy 101.098088 -273.20313) (xy 101.105983 -273.251707)
			(xy 101.106478 -273.276314) (xy 101.435166 -273.276314) (xy 101.439126 -273.22726) (xy 101.450903 -273.179476)
			(xy 101.470194 -273.1342) (xy 101.496497 -273.092604) (xy 101.529132 -273.055767) (xy 101.567253 -273.024642)
			(xy 101.609874 -273.000035) (xy 101.65589 -272.982583) (xy 101.704109 -272.972739) (xy 101.753284 -272.970758)
			(xy 101.802139 -272.97669) (xy 101.84941 -272.990382) (xy 101.893872 -273.01148) (xy 101.934375 -273.039436)
			(xy 101.969868 -273.073528) (xy 101.999433 -273.112872) (xy 102.022304 -273.156449) (xy 102.037888 -273.20313)
			(xy 102.045783 -273.251707) (xy 102.046278 -273.276314) (xy 102.37522 -273.276314) (xy 102.37918 -273.22726)
			(xy 102.390957 -273.179476) (xy 102.410248 -273.1342) (xy 102.436551 -273.092604) (xy 102.469186 -273.055767)
			(xy 102.507307 -273.024642) (xy 102.549928 -273.000035) (xy 102.595944 -272.982583) (xy 102.644163 -272.972739)
			(xy 102.693338 -272.970758) (xy 102.742193 -272.97669) (xy 102.789464 -272.990382) (xy 102.833926 -273.01148)
			(xy 102.874429 -273.039436) (xy 102.909922 -273.073528) (xy 102.939487 -273.112872) (xy 102.962358 -273.156449)
			(xy 102.977942 -273.20313) (xy 102.985837 -273.251707) (xy 102.986332 -273.276314) (xy 103.315274 -273.276314)
			(xy 103.319234 -273.22726) (xy 103.331011 -273.179476) (xy 103.350302 -273.1342) (xy 103.376605 -273.092604)
			(xy 103.40924 -273.055767) (xy 103.447361 -273.024642) (xy 103.489982 -273.000035) (xy 103.535998 -272.982583)
			(xy 103.584217 -272.972739) (xy 103.633392 -272.970758) (xy 103.682247 -272.97669) (xy 103.729518 -272.990382)
			(xy 103.77398 -273.01148) (xy 103.814483 -273.039436) (xy 103.849976 -273.073528) (xy 103.879541 -273.112872)
			(xy 103.902412 -273.156449) (xy 103.917996 -273.20313) (xy 103.925891 -273.251707) (xy 103.926386 -273.276314)
			(xy 104.255328 -273.276314) (xy 104.259288 -273.22726) (xy 104.271065 -273.179476) (xy 104.290356 -273.1342)
			(xy 104.316659 -273.092604) (xy 104.349294 -273.055767) (xy 104.387415 -273.024642) (xy 104.430036 -273.000035)
			(xy 104.476052 -272.982583) (xy 104.524271 -272.972739) (xy 104.573446 -272.970758) (xy 104.622301 -272.97669)
			(xy 104.669572 -272.990382) (xy 104.714034 -273.01148) (xy 104.754537 -273.039436) (xy 104.79003 -273.073528)
			(xy 104.819595 -273.112872) (xy 104.842466 -273.156449) (xy 104.85805 -273.20313) (xy 104.865945 -273.251707)
			(xy 104.86644 -273.276314) (xy 105.195128 -273.276314) (xy 105.199088 -273.22726) (xy 105.210865 -273.179476)
			(xy 105.230156 -273.1342) (xy 105.256459 -273.092604) (xy 105.289094 -273.055767) (xy 105.327215 -273.024642)
			(xy 105.369836 -273.000035) (xy 105.415852 -272.982583) (xy 105.464071 -272.972739) (xy 105.513246 -272.970758)
			(xy 105.562101 -272.97669) (xy 105.609372 -272.990382) (xy 105.653834 -273.01148) (xy 105.694337 -273.039436)
			(xy 105.72983 -273.073528) (xy 105.759395 -273.112872) (xy 105.782266 -273.156449) (xy 105.79785 -273.20313)
			(xy 105.805745 -273.251707) (xy 105.80624 -273.276314) (xy 106.135182 -273.276314) (xy 106.139142 -273.22726)
			(xy 106.150919 -273.179476) (xy 106.17021 -273.1342) (xy 106.196513 -273.092604) (xy 106.229148 -273.055767)
			(xy 106.267269 -273.024642) (xy 106.30989 -273.000035) (xy 106.355906 -272.982583) (xy 106.404125 -272.972739)
			(xy 106.4533 -272.970758) (xy 106.502155 -272.97669) (xy 106.549426 -272.990382) (xy 106.593888 -273.01148)
			(xy 106.634391 -273.039436) (xy 106.669884 -273.073528) (xy 106.699449 -273.112872) (xy 106.72232 -273.156449)
			(xy 106.737904 -273.20313) (xy 106.745799 -273.251707) (xy 106.746294 -273.276314) (xy 107.075236 -273.276314)
			(xy 107.079196 -273.22726) (xy 107.090973 -273.179476) (xy 107.110264 -273.1342) (xy 107.136567 -273.092604)
			(xy 107.169202 -273.055767) (xy 107.207323 -273.024642) (xy 107.249944 -273.000035) (xy 107.29596 -272.982583)
			(xy 107.344179 -272.972739) (xy 107.393354 -272.970758) (xy 107.442209 -272.97669) (xy 107.48948 -272.990382)
			(xy 107.533942 -273.01148) (xy 107.574445 -273.039436) (xy 107.609938 -273.073528) (xy 107.639503 -273.112872)
			(xy 107.662374 -273.156449) (xy 107.677958 -273.20313) (xy 107.685853 -273.251707) (xy 107.686348 -273.276314)
			(xy 108.01529 -273.276314) (xy 108.01925 -273.22726) (xy 108.031027 -273.179476) (xy 108.050318 -273.1342)
			(xy 108.076621 -273.092604) (xy 108.109256 -273.055767) (xy 108.147377 -273.024642) (xy 108.189998 -273.000035)
			(xy 108.236014 -272.982583) (xy 108.284233 -272.972739) (xy 108.333408 -272.970758) (xy 108.382263 -272.97669)
			(xy 108.429534 -272.990382) (xy 108.473996 -273.01148) (xy 108.514499 -273.039436) (xy 108.549992 -273.073528)
			(xy 108.579557 -273.112872) (xy 108.602428 -273.156449) (xy 108.618012 -273.20313) (xy 108.625907 -273.251707)
			(xy 108.626402 -273.276314) (xy 108.955344 -273.276314) (xy 108.959304 -273.22726) (xy 108.971081 -273.179476)
			(xy 108.990372 -273.1342) (xy 109.016675 -273.092604) (xy 109.04931 -273.055767) (xy 109.087431 -273.024642)
			(xy 109.130052 -273.000035) (xy 109.176068 -272.982583) (xy 109.224287 -272.972739) (xy 109.273462 -272.970758)
			(xy 109.322317 -272.97669) (xy 109.369588 -272.990382) (xy 109.41405 -273.01148) (xy 109.454553 -273.039436)
			(xy 109.490046 -273.073528) (xy 109.519611 -273.112872) (xy 109.542482 -273.156449) (xy 109.558066 -273.20313)
			(xy 109.565961 -273.251707) (xy 109.566456 -273.276314) (xy 109.895144 -273.276314) (xy 109.899104 -273.22726)
			(xy 109.910881 -273.179476) (xy 109.930172 -273.1342) (xy 109.956475 -273.092604) (xy 109.98911 -273.055767)
			(xy 110.027231 -273.024642) (xy 110.069852 -273.000035) (xy 110.115868 -272.982583) (xy 110.164087 -272.972739)
			(xy 110.213262 -272.970758) (xy 110.262117 -272.97669) (xy 110.309388 -272.990382) (xy 110.35385 -273.01148)
			(xy 110.394353 -273.039436) (xy 110.429846 -273.073528) (xy 110.459411 -273.112872) (xy 110.482282 -273.156449)
			(xy 110.497866 -273.20313) (xy 110.505761 -273.251707) (xy 110.506256 -273.276314) (xy 113.64901 -273.276314)
			(xy 113.65297 -273.22726) (xy 113.664747 -273.179476) (xy 113.684038 -273.1342) (xy 113.710341 -273.092604)
			(xy 113.742976 -273.055767) (xy 113.781097 -273.024642) (xy 113.823718 -273.000035) (xy 113.869734 -272.982583)
			(xy 113.917953 -272.972739) (xy 113.967128 -272.970758) (xy 114.015983 -272.97669) (xy 114.063254 -272.990382)
			(xy 114.107716 -273.01148) (xy 114.148219 -273.039436) (xy 114.183712 -273.073528) (xy 114.213277 -273.112872)
			(xy 114.236148 -273.156449) (xy 114.251732 -273.20313) (xy 114.259627 -273.251707) (xy 114.260122 -273.276314)
			(xy 114.58881 -273.276314) (xy 114.59277 -273.22726) (xy 114.604547 -273.179476) (xy 114.623838 -273.1342)
			(xy 114.650141 -273.092604) (xy 114.682776 -273.055767) (xy 114.720897 -273.024642) (xy 114.763518 -273.000035)
			(xy 114.809534 -272.982583) (xy 114.857753 -272.972739) (xy 114.906928 -272.970758) (xy 114.955783 -272.97669)
			(xy 115.003054 -272.990382) (xy 115.047516 -273.01148) (xy 115.088019 -273.039436) (xy 115.123512 -273.073528)
			(xy 115.153077 -273.112872) (xy 115.175948 -273.156449) (xy 115.191532 -273.20313) (xy 115.199427 -273.251707)
			(xy 115.199922 -273.276314) (xy 115.528864 -273.276314) (xy 115.532824 -273.22726) (xy 115.544601 -273.179476)
			(xy 115.563892 -273.1342) (xy 115.590195 -273.092604) (xy 115.62283 -273.055767) (xy 115.660951 -273.024642)
			(xy 115.703572 -273.000035) (xy 115.749588 -272.982583) (xy 115.797807 -272.972739) (xy 115.846982 -272.970758)
			(xy 115.895837 -272.97669) (xy 115.943108 -272.990382) (xy 115.98757 -273.01148) (xy 116.028073 -273.039436)
			(xy 116.063566 -273.073528) (xy 116.093131 -273.112872) (xy 116.116002 -273.156449) (xy 116.131586 -273.20313)
			(xy 116.139481 -273.251707) (xy 116.139976 -273.276314) (xy 116.468918 -273.276314) (xy 116.472878 -273.22726)
			(xy 116.484655 -273.179476) (xy 116.503946 -273.1342) (xy 116.530249 -273.092604) (xy 116.562884 -273.055767)
			(xy 116.601005 -273.024642) (xy 116.643626 -273.000035) (xy 116.689642 -272.982583) (xy 116.737861 -272.972739)
			(xy 116.787036 -272.970758) (xy 116.835891 -272.97669) (xy 116.883162 -272.990382) (xy 116.927624 -273.01148)
			(xy 116.968127 -273.039436) (xy 117.00362 -273.073528) (xy 117.033185 -273.112872) (xy 117.056056 -273.156449)
			(xy 117.07164 -273.20313) (xy 117.079535 -273.251707) (xy 117.08003 -273.276314) (xy 117.408972 -273.276314)
			(xy 117.412932 -273.22726) (xy 117.424709 -273.179476) (xy 117.444 -273.1342) (xy 117.470303 -273.092604)
			(xy 117.502938 -273.055767) (xy 117.541059 -273.024642) (xy 117.58368 -273.000035) (xy 117.629696 -272.982583)
			(xy 117.677915 -272.972739) (xy 117.72709 -272.970758) (xy 117.775945 -272.97669) (xy 117.823216 -272.990382)
			(xy 117.867678 -273.01148) (xy 117.908181 -273.039436) (xy 117.943674 -273.073528) (xy 117.973239 -273.112872)
			(xy 117.99611 -273.156449) (xy 118.011694 -273.20313) (xy 118.019589 -273.251707) (xy 118.020084 -273.276314)
			(xy 118.349026 -273.276314) (xy 118.352986 -273.22726) (xy 118.364763 -273.179476) (xy 118.384054 -273.1342)
			(xy 118.410357 -273.092604) (xy 118.442992 -273.055767) (xy 118.481113 -273.024642) (xy 118.523734 -273.000035)
			(xy 118.56975 -272.982583) (xy 118.617969 -272.972739) (xy 118.667144 -272.970758) (xy 118.715999 -272.97669)
			(xy 118.76327 -272.990382) (xy 118.807732 -273.01148) (xy 118.848235 -273.039436) (xy 118.883728 -273.073528)
			(xy 118.913293 -273.112872) (xy 118.936164 -273.156449) (xy 118.951748 -273.20313) (xy 118.959643 -273.251707)
			(xy 118.960138 -273.276314) (xy 119.288826 -273.276314) (xy 119.292786 -273.22726) (xy 119.304563 -273.179476)
			(xy 119.323854 -273.1342) (xy 119.350157 -273.092604) (xy 119.382792 -273.055767) (xy 119.420913 -273.024642)
			(xy 119.463534 -273.000035) (xy 119.50955 -272.982583) (xy 119.557769 -272.972739) (xy 119.606944 -272.970758)
			(xy 119.655799 -272.97669) (xy 119.70307 -272.990382) (xy 119.747532 -273.01148) (xy 119.788035 -273.039436)
			(xy 119.823528 -273.073528) (xy 119.853093 -273.112872) (xy 119.875964 -273.156449) (xy 119.891548 -273.20313)
			(xy 119.899443 -273.251707) (xy 119.899938 -273.276314) (xy 120.22888 -273.276314) (xy 120.23284 -273.22726)
			(xy 120.244617 -273.179476) (xy 120.263908 -273.1342) (xy 120.290211 -273.092604) (xy 120.322846 -273.055767)
			(xy 120.360967 -273.024642) (xy 120.403588 -273.000035) (xy 120.449604 -272.982583) (xy 120.497823 -272.972739)
			(xy 120.546998 -272.970758) (xy 120.595853 -272.97669) (xy 120.643124 -272.990382) (xy 120.687586 -273.01148)
			(xy 120.728089 -273.039436) (xy 120.763582 -273.073528) (xy 120.793147 -273.112872) (xy 120.816018 -273.156449)
			(xy 120.831602 -273.20313) (xy 120.839497 -273.251707) (xy 120.839992 -273.276314) (xy 121.168934 -273.276314)
			(xy 121.172894 -273.22726) (xy 121.184671 -273.179476) (xy 121.203962 -273.1342) (xy 121.230265 -273.092604)
			(xy 121.2629 -273.055767) (xy 121.301021 -273.024642) (xy 121.343642 -273.000035) (xy 121.389658 -272.982583)
			(xy 121.437877 -272.972739) (xy 121.487052 -272.970758) (xy 121.535907 -272.97669) (xy 121.583178 -272.990382)
			(xy 121.62764 -273.01148) (xy 121.668143 -273.039436) (xy 121.703636 -273.073528) (xy 121.733201 -273.112872)
			(xy 121.756072 -273.156449) (xy 121.771656 -273.20313) (xy 121.779551 -273.251707) (xy 121.780046 -273.276314)
			(xy 122.108988 -273.276314) (xy 122.112948 -273.22726) (xy 122.124725 -273.179476) (xy 122.144016 -273.1342)
			(xy 122.170319 -273.092604) (xy 122.202954 -273.055767) (xy 122.241075 -273.024642) (xy 122.283696 -273.000035)
			(xy 122.329712 -272.982583) (xy 122.377931 -272.972739) (xy 122.427106 -272.970758) (xy 122.475961 -272.97669)
			(xy 122.523232 -272.990382) (xy 122.567694 -273.01148) (xy 122.608197 -273.039436) (xy 122.64369 -273.073528)
			(xy 122.673255 -273.112872) (xy 122.696126 -273.156449) (xy 122.71171 -273.20313) (xy 122.719605 -273.251707)
			(xy 122.7201 -273.276314) (xy 123.049042 -273.276314) (xy 123.053002 -273.22726) (xy 123.064779 -273.179476)
			(xy 123.08407 -273.1342) (xy 123.110373 -273.092604) (xy 123.143008 -273.055767) (xy 123.181129 -273.024642)
			(xy 123.22375 -273.000035) (xy 123.269766 -272.982583) (xy 123.317985 -272.972739) (xy 123.36716 -272.970758)
			(xy 123.416015 -272.97669) (xy 123.463286 -272.990382) (xy 123.507748 -273.01148) (xy 123.548251 -273.039436)
			(xy 123.583744 -273.073528) (xy 123.613309 -273.112872) (xy 123.63618 -273.156449) (xy 123.651764 -273.20313)
			(xy 123.659659 -273.251707) (xy 123.660154 -273.276314) (xy 123.988842 -273.276314) (xy 123.992802 -273.22726)
			(xy 124.004579 -273.179476) (xy 124.02387 -273.1342) (xy 124.050173 -273.092604) (xy 124.082808 -273.055767)
			(xy 124.120929 -273.024642) (xy 124.16355 -273.000035) (xy 124.209566 -272.982583) (xy 124.257785 -272.972739)
			(xy 124.30696 -272.970758) (xy 124.355815 -272.97669) (xy 124.403086 -272.990382) (xy 124.447548 -273.01148)
			(xy 124.488051 -273.039436) (xy 124.523544 -273.073528) (xy 124.553109 -273.112872) (xy 124.57598 -273.156449)
			(xy 124.591564 -273.20313) (xy 124.599459 -273.251707) (xy 124.599954 -273.276314) (xy 124.928896 -273.276314)
			(xy 124.932856 -273.22726) (xy 124.944633 -273.179476) (xy 124.963924 -273.1342) (xy 124.990227 -273.092604)
			(xy 125.022862 -273.055767) (xy 125.060983 -273.024642) (xy 125.103604 -273.000035) (xy 125.14962 -272.982583)
			(xy 125.197839 -272.972739) (xy 125.247014 -272.970758) (xy 125.295869 -272.97669) (xy 125.34314 -272.990382)
			(xy 125.387602 -273.01148) (xy 125.428105 -273.039436) (xy 125.463598 -273.073528) (xy 125.493163 -273.112872)
			(xy 125.516034 -273.156449) (xy 125.531618 -273.20313) (xy 125.539513 -273.251707) (xy 125.540008 -273.276314)
			(xy 125.86895 -273.276314) (xy 125.87291 -273.22726) (xy 125.884687 -273.179476) (xy 125.903978 -273.1342)
			(xy 125.930281 -273.092604) (xy 125.962916 -273.055767) (xy 126.001037 -273.024642) (xy 126.043658 -273.000035)
			(xy 126.089674 -272.982583) (xy 126.137893 -272.972739) (xy 126.187068 -272.970758) (xy 126.235923 -272.97669)
			(xy 126.283194 -272.990382) (xy 126.327656 -273.01148) (xy 126.368159 -273.039436) (xy 126.403652 -273.073528)
			(xy 126.433217 -273.112872) (xy 126.456088 -273.156449) (xy 126.471672 -273.20313) (xy 126.479567 -273.251707)
			(xy 126.480062 -273.276314) (xy 126.479567 -273.300921) (xy 126.471672 -273.349498) (xy 126.456088 -273.396179)
			(xy 126.433217 -273.439756) (xy 126.403652 -273.4791) (xy 126.368159 -273.513192) (xy 126.327656 -273.541148)
			(xy 126.283194 -273.562246) (xy 126.235923 -273.575938) (xy 126.187068 -273.58187) (xy 126.137893 -273.579889)
			(xy 126.089674 -273.570045) (xy 126.043658 -273.552593) (xy 126.001037 -273.527986) (xy 125.962916 -273.496861)
			(xy 125.930281 -273.460024) (xy 125.903978 -273.418428) (xy 125.884687 -273.373152) (xy 125.87291 -273.325368)
			(xy 125.86895 -273.276314) (xy 125.540008 -273.276314) (xy 125.539513 -273.300921) (xy 125.531618 -273.349498)
			(xy 125.516034 -273.396179) (xy 125.493163 -273.439756) (xy 125.463598 -273.4791) (xy 125.428105 -273.513192)
			(xy 125.387602 -273.541148) (xy 125.34314 -273.562246) (xy 125.295869 -273.575938) (xy 125.247014 -273.58187)
			(xy 125.197839 -273.579889) (xy 125.14962 -273.570045) (xy 125.103604 -273.552593) (xy 125.060983 -273.527986)
			(xy 125.022862 -273.496861) (xy 124.990227 -273.460024) (xy 124.963924 -273.418428) (xy 124.944633 -273.373152)
			(xy 124.932856 -273.325368) (xy 124.928896 -273.276314) (xy 124.599954 -273.276314) (xy 124.599459 -273.300921)
			(xy 124.591564 -273.349498) (xy 124.57598 -273.396179) (xy 124.553109 -273.439756) (xy 124.523544 -273.4791)
			(xy 124.488051 -273.513192) (xy 124.447548 -273.541148) (xy 124.403086 -273.562246) (xy 124.355815 -273.575938)
			(xy 124.30696 -273.58187) (xy 124.257785 -273.579889) (xy 124.209566 -273.570045) (xy 124.16355 -273.552593)
			(xy 124.120929 -273.527986) (xy 124.082808 -273.496861) (xy 124.050173 -273.460024) (xy 124.02387 -273.418428)
			(xy 124.004579 -273.373152) (xy 123.992802 -273.325368) (xy 123.988842 -273.276314) (xy 123.660154 -273.276314)
			(xy 123.659659 -273.300921) (xy 123.651764 -273.349498) (xy 123.63618 -273.396179) (xy 123.613309 -273.439756)
			(xy 123.583744 -273.4791) (xy 123.548251 -273.513192) (xy 123.507748 -273.541148) (xy 123.463286 -273.562246)
			(xy 123.416015 -273.575938) (xy 123.36716 -273.58187) (xy 123.317985 -273.579889) (xy 123.269766 -273.570045)
			(xy 123.22375 -273.552593) (xy 123.181129 -273.527986) (xy 123.143008 -273.496861) (xy 123.110373 -273.460024)
			(xy 123.08407 -273.418428) (xy 123.064779 -273.373152) (xy 123.053002 -273.325368) (xy 123.049042 -273.276314)
			(xy 122.7201 -273.276314) (xy 122.719605 -273.300921) (xy 122.71171 -273.349498) (xy 122.696126 -273.396179)
			(xy 122.673255 -273.439756) (xy 122.64369 -273.4791) (xy 122.608197 -273.513192) (xy 122.567694 -273.541148)
			(xy 122.523232 -273.562246) (xy 122.475961 -273.575938) (xy 122.427106 -273.58187) (xy 122.377931 -273.579889)
			(xy 122.329712 -273.570045) (xy 122.283696 -273.552593) (xy 122.241075 -273.527986) (xy 122.202954 -273.496861)
			(xy 122.170319 -273.460024) (xy 122.144016 -273.418428) (xy 122.124725 -273.373152) (xy 122.112948 -273.325368)
			(xy 122.108988 -273.276314) (xy 121.780046 -273.276314) (xy 121.779551 -273.300921) (xy 121.771656 -273.349498)
			(xy 121.756072 -273.396179) (xy 121.733201 -273.439756) (xy 121.703636 -273.4791) (xy 121.668143 -273.513192)
			(xy 121.62764 -273.541148) (xy 121.583178 -273.562246) (xy 121.535907 -273.575938) (xy 121.487052 -273.58187)
			(xy 121.437877 -273.579889) (xy 121.389658 -273.570045) (xy 121.343642 -273.552593) (xy 121.301021 -273.527986)
			(xy 121.2629 -273.496861) (xy 121.230265 -273.460024) (xy 121.203962 -273.418428) (xy 121.184671 -273.373152)
			(xy 121.172894 -273.325368) (xy 121.168934 -273.276314) (xy 120.839992 -273.276314) (xy 120.839497 -273.300921)
			(xy 120.831602 -273.349498) (xy 120.816018 -273.396179) (xy 120.793147 -273.439756) (xy 120.763582 -273.4791)
			(xy 120.728089 -273.513192) (xy 120.687586 -273.541148) (xy 120.643124 -273.562246) (xy 120.595853 -273.575938)
			(xy 120.546998 -273.58187) (xy 120.497823 -273.579889) (xy 120.449604 -273.570045) (xy 120.403588 -273.552593)
			(xy 120.360967 -273.527986) (xy 120.322846 -273.496861) (xy 120.290211 -273.460024) (xy 120.263908 -273.418428)
			(xy 120.244617 -273.373152) (xy 120.23284 -273.325368) (xy 120.22888 -273.276314) (xy 119.899938 -273.276314)
			(xy 119.899443 -273.300921) (xy 119.891548 -273.349498) (xy 119.875964 -273.396179) (xy 119.853093 -273.439756)
			(xy 119.823528 -273.4791) (xy 119.788035 -273.513192) (xy 119.747532 -273.541148) (xy 119.70307 -273.562246)
			(xy 119.655799 -273.575938) (xy 119.606944 -273.58187) (xy 119.557769 -273.579889) (xy 119.50955 -273.570045)
			(xy 119.463534 -273.552593) (xy 119.420913 -273.527986) (xy 119.382792 -273.496861) (xy 119.350157 -273.460024)
			(xy 119.323854 -273.418428) (xy 119.304563 -273.373152) (xy 119.292786 -273.325368) (xy 119.288826 -273.276314)
			(xy 118.960138 -273.276314) (xy 118.959643 -273.300921) (xy 118.951748 -273.349498) (xy 118.936164 -273.396179)
			(xy 118.913293 -273.439756) (xy 118.883728 -273.4791) (xy 118.848235 -273.513192) (xy 118.807732 -273.541148)
			(xy 118.76327 -273.562246) (xy 118.715999 -273.575938) (xy 118.667144 -273.58187) (xy 118.617969 -273.579889)
			(xy 118.56975 -273.570045) (xy 118.523734 -273.552593) (xy 118.481113 -273.527986) (xy 118.442992 -273.496861)
			(xy 118.410357 -273.460024) (xy 118.384054 -273.418428) (xy 118.364763 -273.373152) (xy 118.352986 -273.325368)
			(xy 118.349026 -273.276314) (xy 118.020084 -273.276314) (xy 118.019589 -273.300921) (xy 118.011694 -273.349498)
			(xy 117.99611 -273.396179) (xy 117.973239 -273.439756) (xy 117.943674 -273.4791) (xy 117.908181 -273.513192)
			(xy 117.867678 -273.541148) (xy 117.823216 -273.562246) (xy 117.775945 -273.575938) (xy 117.72709 -273.58187)
			(xy 117.677915 -273.579889) (xy 117.629696 -273.570045) (xy 117.58368 -273.552593) (xy 117.541059 -273.527986)
			(xy 117.502938 -273.496861) (xy 117.470303 -273.460024) (xy 117.444 -273.418428) (xy 117.424709 -273.373152)
			(xy 117.412932 -273.325368) (xy 117.408972 -273.276314) (xy 117.08003 -273.276314) (xy 117.079535 -273.300921)
			(xy 117.07164 -273.349498) (xy 117.056056 -273.396179) (xy 117.033185 -273.439756) (xy 117.00362 -273.4791)
			(xy 116.968127 -273.513192) (xy 116.927624 -273.541148) (xy 116.883162 -273.562246) (xy 116.835891 -273.575938)
			(xy 116.787036 -273.58187) (xy 116.737861 -273.579889) (xy 116.689642 -273.570045) (xy 116.643626 -273.552593)
			(xy 116.601005 -273.527986) (xy 116.562884 -273.496861) (xy 116.530249 -273.460024) (xy 116.503946 -273.418428)
			(xy 116.484655 -273.373152) (xy 116.472878 -273.325368) (xy 116.468918 -273.276314) (xy 116.139976 -273.276314)
			(xy 116.139481 -273.300921) (xy 116.131586 -273.349498) (xy 116.116002 -273.396179) (xy 116.093131 -273.439756)
			(xy 116.063566 -273.4791) (xy 116.028073 -273.513192) (xy 115.98757 -273.541148) (xy 115.943108 -273.562246)
			(xy 115.895837 -273.575938) (xy 115.846982 -273.58187) (xy 115.797807 -273.579889) (xy 115.749588 -273.570045)
			(xy 115.703572 -273.552593) (xy 115.660951 -273.527986) (xy 115.62283 -273.496861) (xy 115.590195 -273.460024)
			(xy 115.563892 -273.418428) (xy 115.544601 -273.373152) (xy 115.532824 -273.325368) (xy 115.528864 -273.276314)
			(xy 115.199922 -273.276314) (xy 115.199427 -273.300921) (xy 115.191532 -273.349498) (xy 115.175948 -273.396179)
			(xy 115.153077 -273.439756) (xy 115.123512 -273.4791) (xy 115.088019 -273.513192) (xy 115.047516 -273.541148)
			(xy 115.003054 -273.562246) (xy 114.955783 -273.575938) (xy 114.906928 -273.58187) (xy 114.857753 -273.579889)
			(xy 114.809534 -273.570045) (xy 114.763518 -273.552593) (xy 114.720897 -273.527986) (xy 114.682776 -273.496861)
			(xy 114.650141 -273.460024) (xy 114.623838 -273.418428) (xy 114.604547 -273.373152) (xy 114.59277 -273.325368)
			(xy 114.58881 -273.276314) (xy 114.260122 -273.276314) (xy 114.259627 -273.300921) (xy 114.251732 -273.349498)
			(xy 114.236148 -273.396179) (xy 114.213277 -273.439756) (xy 114.183712 -273.4791) (xy 114.148219 -273.513192)
			(xy 114.107716 -273.541148) (xy 114.063254 -273.562246) (xy 114.015983 -273.575938) (xy 113.967128 -273.58187)
			(xy 113.917953 -273.579889) (xy 113.869734 -273.570045) (xy 113.823718 -273.552593) (xy 113.781097 -273.527986)
			(xy 113.742976 -273.496861) (xy 113.710341 -273.460024) (xy 113.684038 -273.418428) (xy 113.664747 -273.373152)
			(xy 113.65297 -273.325368) (xy 113.64901 -273.276314) (xy 110.506256 -273.276314) (xy 110.505761 -273.300921)
			(xy 110.497866 -273.349498) (xy 110.482282 -273.396179) (xy 110.459411 -273.439756) (xy 110.429846 -273.4791)
			(xy 110.394353 -273.513192) (xy 110.35385 -273.541148) (xy 110.309388 -273.562246) (xy 110.262117 -273.575938)
			(xy 110.213262 -273.58187) (xy 110.164087 -273.579889) (xy 110.115868 -273.570045) (xy 110.069852 -273.552593)
			(xy 110.027231 -273.527986) (xy 109.98911 -273.496861) (xy 109.956475 -273.460024) (xy 109.930172 -273.418428)
			(xy 109.910881 -273.373152) (xy 109.899104 -273.325368) (xy 109.895144 -273.276314) (xy 109.566456 -273.276314)
			(xy 109.565961 -273.300921) (xy 109.558066 -273.349498) (xy 109.542482 -273.396179) (xy 109.519611 -273.439756)
			(xy 109.490046 -273.4791) (xy 109.454553 -273.513192) (xy 109.41405 -273.541148) (xy 109.369588 -273.562246)
			(xy 109.322317 -273.575938) (xy 109.273462 -273.58187) (xy 109.224287 -273.579889) (xy 109.176068 -273.570045)
			(xy 109.130052 -273.552593) (xy 109.087431 -273.527986) (xy 109.04931 -273.496861) (xy 109.016675 -273.460024)
			(xy 108.990372 -273.418428) (xy 108.971081 -273.373152) (xy 108.959304 -273.325368) (xy 108.955344 -273.276314)
			(xy 108.626402 -273.276314) (xy 108.625907 -273.300921) (xy 108.618012 -273.349498) (xy 108.602428 -273.396179)
			(xy 108.579557 -273.439756) (xy 108.549992 -273.4791) (xy 108.514499 -273.513192) (xy 108.473996 -273.541148)
			(xy 108.429534 -273.562246) (xy 108.382263 -273.575938) (xy 108.333408 -273.58187) (xy 108.284233 -273.579889)
			(xy 108.236014 -273.570045) (xy 108.189998 -273.552593) (xy 108.147377 -273.527986) (xy 108.109256 -273.496861)
			(xy 108.076621 -273.460024) (xy 108.050318 -273.418428) (xy 108.031027 -273.373152) (xy 108.01925 -273.325368)
			(xy 108.01529 -273.276314) (xy 107.686348 -273.276314) (xy 107.685853 -273.300921) (xy 107.677958 -273.349498)
			(xy 107.662374 -273.396179) (xy 107.639503 -273.439756) (xy 107.609938 -273.4791) (xy 107.574445 -273.513192)
			(xy 107.533942 -273.541148) (xy 107.48948 -273.562246) (xy 107.442209 -273.575938) (xy 107.393354 -273.58187)
			(xy 107.344179 -273.579889) (xy 107.29596 -273.570045) (xy 107.249944 -273.552593) (xy 107.207323 -273.527986)
			(xy 107.169202 -273.496861) (xy 107.136567 -273.460024) (xy 107.110264 -273.418428) (xy 107.090973 -273.373152)
			(xy 107.079196 -273.325368) (xy 107.075236 -273.276314) (xy 106.746294 -273.276314) (xy 106.745799 -273.300921)
			(xy 106.737904 -273.349498) (xy 106.72232 -273.396179) (xy 106.699449 -273.439756) (xy 106.669884 -273.4791)
			(xy 106.634391 -273.513192) (xy 106.593888 -273.541148) (xy 106.549426 -273.562246) (xy 106.502155 -273.575938)
			(xy 106.4533 -273.58187) (xy 106.404125 -273.579889) (xy 106.355906 -273.570045) (xy 106.30989 -273.552593)
			(xy 106.267269 -273.527986) (xy 106.229148 -273.496861) (xy 106.196513 -273.460024) (xy 106.17021 -273.418428)
			(xy 106.150919 -273.373152) (xy 106.139142 -273.325368) (xy 106.135182 -273.276314) (xy 105.80624 -273.276314)
			(xy 105.805745 -273.300921) (xy 105.79785 -273.349498) (xy 105.782266 -273.396179) (xy 105.759395 -273.439756)
			(xy 105.72983 -273.4791) (xy 105.694337 -273.513192) (xy 105.653834 -273.541148) (xy 105.609372 -273.562246)
			(xy 105.562101 -273.575938) (xy 105.513246 -273.58187) (xy 105.464071 -273.579889) (xy 105.415852 -273.570045)
			(xy 105.369836 -273.552593) (xy 105.327215 -273.527986) (xy 105.289094 -273.496861) (xy 105.256459 -273.460024)
			(xy 105.230156 -273.418428) (xy 105.210865 -273.373152) (xy 105.199088 -273.325368) (xy 105.195128 -273.276314)
			(xy 104.86644 -273.276314) (xy 104.865945 -273.300921) (xy 104.85805 -273.349498) (xy 104.842466 -273.396179)
			(xy 104.819595 -273.439756) (xy 104.79003 -273.4791) (xy 104.754537 -273.513192) (xy 104.714034 -273.541148)
			(xy 104.669572 -273.562246) (xy 104.622301 -273.575938) (xy 104.573446 -273.58187) (xy 104.524271 -273.579889)
			(xy 104.476052 -273.570045) (xy 104.430036 -273.552593) (xy 104.387415 -273.527986) (xy 104.349294 -273.496861)
			(xy 104.316659 -273.460024) (xy 104.290356 -273.418428) (xy 104.271065 -273.373152) (xy 104.259288 -273.325368)
			(xy 104.255328 -273.276314) (xy 103.926386 -273.276314) (xy 103.925891 -273.300921) (xy 103.917996 -273.349498)
			(xy 103.902412 -273.396179) (xy 103.879541 -273.439756) (xy 103.849976 -273.4791) (xy 103.814483 -273.513192)
			(xy 103.77398 -273.541148) (xy 103.729518 -273.562246) (xy 103.682247 -273.575938) (xy 103.633392 -273.58187)
			(xy 103.584217 -273.579889) (xy 103.535998 -273.570045) (xy 103.489982 -273.552593) (xy 103.447361 -273.527986)
			(xy 103.40924 -273.496861) (xy 103.376605 -273.460024) (xy 103.350302 -273.418428) (xy 103.331011 -273.373152)
			(xy 103.319234 -273.325368) (xy 103.315274 -273.276314) (xy 102.986332 -273.276314) (xy 102.985837 -273.300921)
			(xy 102.977942 -273.349498) (xy 102.962358 -273.396179) (xy 102.939487 -273.439756) (xy 102.909922 -273.4791)
			(xy 102.874429 -273.513192) (xy 102.833926 -273.541148) (xy 102.789464 -273.562246) (xy 102.742193 -273.575938)
			(xy 102.693338 -273.58187) (xy 102.644163 -273.579889) (xy 102.595944 -273.570045) (xy 102.549928 -273.552593)
			(xy 102.507307 -273.527986) (xy 102.469186 -273.496861) (xy 102.436551 -273.460024) (xy 102.410248 -273.418428)
			(xy 102.390957 -273.373152) (xy 102.37918 -273.325368) (xy 102.37522 -273.276314) (xy 102.046278 -273.276314)
			(xy 102.045783 -273.300921) (xy 102.037888 -273.349498) (xy 102.022304 -273.396179) (xy 101.999433 -273.439756)
			(xy 101.969868 -273.4791) (xy 101.934375 -273.513192) (xy 101.893872 -273.541148) (xy 101.84941 -273.562246)
			(xy 101.802139 -273.575938) (xy 101.753284 -273.58187) (xy 101.704109 -273.579889) (xy 101.65589 -273.570045)
			(xy 101.609874 -273.552593) (xy 101.567253 -273.527986) (xy 101.529132 -273.496861) (xy 101.496497 -273.460024)
			(xy 101.470194 -273.418428) (xy 101.450903 -273.373152) (xy 101.439126 -273.325368) (xy 101.435166 -273.276314)
			(xy 101.106478 -273.276314) (xy 101.105983 -273.300921) (xy 101.098088 -273.349498) (xy 101.082504 -273.396179)
			(xy 101.059633 -273.439756) (xy 101.030068 -273.4791) (xy 100.994575 -273.513192) (xy 100.954072 -273.541148)
			(xy 100.90961 -273.562246) (xy 100.862339 -273.575938) (xy 100.813484 -273.58187) (xy 100.764309 -273.579889)
			(xy 100.71609 -273.570045) (xy 100.670074 -273.552593) (xy 100.627453 -273.527986) (xy 100.589332 -273.496861)
			(xy 100.556697 -273.460024) (xy 100.530394 -273.418428) (xy 100.511103 -273.373152) (xy 100.499326 -273.325368)
			(xy 100.495366 -273.276314) (xy 100.166424 -273.276314) (xy 100.165929 -273.300921) (xy 100.158034 -273.349498)
			(xy 100.14245 -273.396179) (xy 100.119579 -273.439756) (xy 100.090014 -273.4791) (xy 100.054521 -273.513192)
			(xy 100.014018 -273.541148) (xy 99.969556 -273.562246) (xy 99.922285 -273.575938) (xy 99.87343 -273.58187)
			(xy 99.824255 -273.579889) (xy 99.776036 -273.570045) (xy 99.73002 -273.552593) (xy 99.687399 -273.527986)
			(xy 99.649278 -273.496861) (xy 99.616643 -273.460024) (xy 99.59034 -273.418428) (xy 99.571049 -273.373152)
			(xy 99.559272 -273.325368) (xy 99.555312 -273.276314) (xy 99.22637 -273.276314) (xy 99.225875 -273.300921)
			(xy 99.21798 -273.349498) (xy 99.202396 -273.396179) (xy 99.179525 -273.439756) (xy 99.14996 -273.4791)
			(xy 99.114467 -273.513192) (xy 99.073964 -273.541148) (xy 99.029502 -273.562246) (xy 98.982231 -273.575938)
			(xy 98.933376 -273.58187) (xy 98.884201 -273.579889) (xy 98.835982 -273.570045) (xy 98.789966 -273.552593)
			(xy 98.747345 -273.527986) (xy 98.709224 -273.496861) (xy 98.676589 -273.460024) (xy 98.650286 -273.418428)
			(xy 98.630995 -273.373152) (xy 98.619218 -273.325368) (xy 98.615258 -273.276314) (xy 98.286316 -273.276314)
			(xy 98.285821 -273.300921) (xy 98.277926 -273.349498) (xy 98.262342 -273.396179) (xy 98.239471 -273.439756)
			(xy 98.209906 -273.4791) (xy 98.174413 -273.513192) (xy 98.13391 -273.541148) (xy 98.089448 -273.562246)
			(xy 98.042177 -273.575938) (xy 97.993322 -273.58187) (xy 97.944147 -273.579889) (xy 97.895928 -273.570045)
			(xy 97.849912 -273.552593) (xy 97.807291 -273.527986) (xy 97.76917 -273.496861) (xy 97.736535 -273.460024)
			(xy 97.710232 -273.418428) (xy 97.690941 -273.373152) (xy 97.679164 -273.325368) (xy 97.675204 -273.276314)
			(xy 97.346262 -273.276314) (xy 97.345767 -273.300921) (xy 97.337872 -273.349498) (xy 97.322288 -273.396179)
			(xy 97.299417 -273.439756) (xy 97.269852 -273.4791) (xy 97.234359 -273.513192) (xy 97.193856 -273.541148)
			(xy 97.149394 -273.562246) (xy 97.102123 -273.575938) (xy 97.053268 -273.58187) (xy 97.004093 -273.579889)
			(xy 96.955874 -273.570045) (xy 96.909858 -273.552593) (xy 96.867237 -273.527986) (xy 96.829116 -273.496861)
			(xy 96.796481 -273.460024) (xy 96.770178 -273.418428) (xy 96.750887 -273.373152) (xy 96.73911 -273.325368)
			(xy 96.73515 -273.276314) (xy 96.416876 -273.276314) (xy 96.416364 -273.30176) (xy 96.4082 -273.351994)
			(xy 96.392084 -273.400268) (xy 96.368433 -273.445331) (xy 96.33786 -273.486017) (xy 96.301156 -273.521272)
			(xy 96.259272 -273.550182) (xy 96.213293 -273.571999) (xy 96.164409 -273.586159) (xy 96.113888 -273.592293)
			(xy 96.063036 -273.590244) (xy 96.013172 -273.580064) (xy 95.965586 -273.562017) (xy 95.921512 -273.536571)
			(xy 95.88209 -273.504384) (xy 95.848342 -273.46629) (xy 95.821141 -273.423276) (xy 95.801193 -273.376456)
			(xy 95.789014 -273.327042) (xy 95.784919 -273.276314) (xy 95.466408 -273.276314) (xy 95.465913 -273.300921)
			(xy 95.458018 -273.349498) (xy 95.442434 -273.396179) (xy 95.419563 -273.439756) (xy 95.389998 -273.4791)
			(xy 95.354505 -273.513192) (xy 95.314002 -273.541148) (xy 95.26954 -273.562246) (xy 95.222269 -273.575938)
			(xy 95.173414 -273.58187) (xy 95.124239 -273.579889) (xy 95.07602 -273.570045) (xy 95.030004 -273.552593)
			(xy 94.987383 -273.527986) (xy 94.949262 -273.496861) (xy 94.916627 -273.460024) (xy 94.890324 -273.418428)
			(xy 94.871033 -273.373152) (xy 94.859256 -273.325368) (xy 94.855296 -273.276314) (xy 94.536768 -273.276314)
			(xy 94.536256 -273.30176) (xy 94.528092 -273.351994) (xy 94.511976 -273.400268) (xy 94.488325 -273.445331)
			(xy 94.457752 -273.486017) (xy 94.421048 -273.521272) (xy 94.379164 -273.550182) (xy 94.333185 -273.571999)
			(xy 94.284301 -273.586159) (xy 94.23378 -273.592293) (xy 94.182928 -273.590244) (xy 94.133064 -273.580064)
			(xy 94.085478 -273.562017) (xy 94.041404 -273.536571) (xy 94.001982 -273.504384) (xy 93.968234 -273.46629)
			(xy 93.941033 -273.423276) (xy 93.921085 -273.376456) (xy 93.908906 -273.327042) (xy 93.904811 -273.276314)
			(xy 93.5863 -273.276314) (xy 93.585833 -273.300163) (xy 93.578402 -273.347279) (xy 93.563739 -273.392668)
			(xy 93.5422 -273.435226) (xy 93.514308 -273.473919) (xy 93.480742 -273.507808) (xy 93.442317 -273.536068)
			(xy 93.399967 -273.558013) (xy 93.35472 -273.573109) (xy 93.331284 -273.577558) (xy 93.322648 -273.579082)
			(xy 93.294708 -273.599402) (xy 93.289836 -273.603156) (xy 93.281882 -273.612531) (xy 93.27896 -273.617944)
			(xy 93.248226 -273.680428) (xy 93.24721 -273.682968) (xy 93.24364 -273.692337) (xy 93.243383 -273.712369)
			(xy 93.246702 -273.72183) (xy 93.246956 -273.722592) (xy 93.250004 -273.728434) (xy 93.294708 -273.805396)
			(xy 93.305177 -273.823876) (xy 93.323609 -273.862146) (xy 93.331538 -273.88185) (xy 93.331538 -273.882104)
			(xy 93.334236 -273.888302) (xy 93.342352 -273.899106) (xy 93.34754 -273.90344) (xy 93.352874 -273.907504)
			(xy 93.365066 -273.912838) (xy 93.45803 -273.92503) (xy 93.464894 -273.925695) (xy 93.47854 -273.923753)
			(xy 93.484954 -273.92122) (xy 93.490979 -273.918416) (xy 93.501393 -273.910168) (xy 93.505528 -273.904964)
			(xy 93.505782 -273.90471) (xy 93.520286 -273.885881) (xy 93.554142 -273.852525) (xy 93.592755 -273.824815)
			(xy 93.635193 -273.803419) (xy 93.680433 -273.788853) (xy 93.727383 -273.78147) (xy 93.751146 -273.781012)
			(xy 93.776397 -273.781537) (xy 93.82621 -273.789856) (xy 93.873974 -273.80626) (xy 93.918387 -273.830301)
			(xy 93.958238 -273.861324) (xy 93.99244 -273.898482) (xy 94.02006 -273.940763) (xy 94.040344 -273.987013)
			(xy 94.052741 -274.03597) (xy 94.056911 -274.0863) (xy 94.056909 -274.08632) (xy 94.374711 -274.08632)
			(xy 94.378806 -274.035592) (xy 94.390985 -273.986178) (xy 94.410933 -273.939358) (xy 94.438134 -273.896344)
			(xy 94.471882 -273.85825) (xy 94.511304 -273.826063) (xy 94.555378 -273.800617) (xy 94.602964 -273.78257)
			(xy 94.652828 -273.77239) (xy 94.70368 -273.770341) (xy 94.754201 -273.776475) (xy 94.803085 -273.790635)
			(xy 94.849064 -273.812452) (xy 94.890948 -273.841362) (xy 94.927652 -273.876617) (xy 94.958225 -273.917303)
			(xy 94.981876 -273.962366) (xy 94.997992 -274.01064) (xy 95.006156 -274.060874) (xy 95.006668 -274.08632)
			(xy 95.314765 -274.08632) (xy 95.31886 -274.035592) (xy 95.331039 -273.986178) (xy 95.350987 -273.939358)
			(xy 95.378188 -273.896344) (xy 95.411936 -273.85825) (xy 95.451358 -273.826063) (xy 95.495432 -273.800617)
			(xy 95.543018 -273.78257) (xy 95.592882 -273.77239) (xy 95.643734 -273.770341) (xy 95.694255 -273.776475)
			(xy 95.743139 -273.790635) (xy 95.789118 -273.812452) (xy 95.831002 -273.841362) (xy 95.867706 -273.876617)
			(xy 95.898279 -273.917303) (xy 95.92193 -273.962366) (xy 95.938046 -274.01064) (xy 95.94621 -274.060874)
			(xy 95.946722 -274.08632) (xy 96.26525 -274.08632) (xy 96.26921 -274.037266) (xy 96.280987 -273.989482)
			(xy 96.300278 -273.944206) (xy 96.326581 -273.90261) (xy 96.359216 -273.865773) (xy 96.397337 -273.834648)
			(xy 96.439958 -273.810041) (xy 96.485974 -273.792589) (xy 96.534193 -273.782745) (xy 96.583368 -273.780764)
			(xy 96.632223 -273.786696) (xy 96.679494 -273.800388) (xy 96.723956 -273.821486) (xy 96.764459 -273.849442)
			(xy 96.799952 -273.883534) (xy 96.829517 -273.922878) (xy 96.852388 -273.966455) (xy 96.867972 -274.013136)
			(xy 96.875867 -274.061713) (xy 96.876362 -274.08632) (xy 97.205304 -274.08632) (xy 97.209264 -274.037266)
			(xy 97.221041 -273.989482) (xy 97.240332 -273.944206) (xy 97.266635 -273.90261) (xy 97.29927 -273.865773)
			(xy 97.337391 -273.834648) (xy 97.380012 -273.810041) (xy 97.426028 -273.792589) (xy 97.474247 -273.782745)
			(xy 97.523422 -273.780764) (xy 97.572277 -273.786696) (xy 97.619548 -273.800388) (xy 97.66401 -273.821486)
			(xy 97.704513 -273.849442) (xy 97.740006 -273.883534) (xy 97.769571 -273.922878) (xy 97.792442 -273.966455)
			(xy 97.808026 -274.013136) (xy 97.815921 -274.061713) (xy 97.816416 -274.08632) (xy 98.145358 -274.08632)
			(xy 98.149318 -274.037266) (xy 98.161095 -273.989482) (xy 98.180386 -273.944206) (xy 98.206689 -273.90261)
			(xy 98.239324 -273.865773) (xy 98.277445 -273.834648) (xy 98.320066 -273.810041) (xy 98.366082 -273.792589)
			(xy 98.414301 -273.782745) (xy 98.463476 -273.780764) (xy 98.512331 -273.786696) (xy 98.559602 -273.800388)
			(xy 98.604064 -273.821486) (xy 98.644567 -273.849442) (xy 98.68006 -273.883534) (xy 98.709625 -273.922878)
			(xy 98.732496 -273.966455) (xy 98.74808 -274.013136) (xy 98.755975 -274.061713) (xy 98.75647 -274.08632)
			(xy 99.085158 -274.08632) (xy 99.089118 -274.037266) (xy 99.100895 -273.989482) (xy 99.120186 -273.944206)
			(xy 99.146489 -273.90261) (xy 99.179124 -273.865773) (xy 99.217245 -273.834648) (xy 99.259866 -273.810041)
			(xy 99.305882 -273.792589) (xy 99.354101 -273.782745) (xy 99.403276 -273.780764) (xy 99.452131 -273.786696)
			(xy 99.499402 -273.800388) (xy 99.543864 -273.821486) (xy 99.584367 -273.849442) (xy 99.61986 -273.883534)
			(xy 99.649425 -273.922878) (xy 99.672296 -273.966455) (xy 99.68788 -274.013136) (xy 99.695775 -274.061713)
			(xy 99.69627 -274.08632) (xy 100.025212 -274.08632) (xy 100.029172 -274.037266) (xy 100.040949 -273.989482)
			(xy 100.06024 -273.944206) (xy 100.086543 -273.90261) (xy 100.119178 -273.865773) (xy 100.157299 -273.834648)
			(xy 100.19992 -273.810041) (xy 100.245936 -273.792589) (xy 100.294155 -273.782745) (xy 100.34333 -273.780764)
			(xy 100.392185 -273.786696) (xy 100.439456 -273.800388) (xy 100.483918 -273.821486) (xy 100.524421 -273.849442)
			(xy 100.559914 -273.883534) (xy 100.589479 -273.922878) (xy 100.61235 -273.966455) (xy 100.627934 -274.013136)
			(xy 100.635829 -274.061713) (xy 100.636324 -274.08632) (xy 100.965266 -274.08632) (xy 100.969226 -274.037266)
			(xy 100.981003 -273.989482) (xy 101.000294 -273.944206) (xy 101.026597 -273.90261) (xy 101.059232 -273.865773)
			(xy 101.097353 -273.834648) (xy 101.139974 -273.810041) (xy 101.18599 -273.792589) (xy 101.234209 -273.782745)
			(xy 101.283384 -273.780764) (xy 101.332239 -273.786696) (xy 101.37951 -273.800388) (xy 101.423972 -273.821486)
			(xy 101.464475 -273.849442) (xy 101.499968 -273.883534) (xy 101.529533 -273.922878) (xy 101.552404 -273.966455)
			(xy 101.567988 -274.013136) (xy 101.575883 -274.061713) (xy 101.576378 -274.08632) (xy 101.90532 -274.08632)
			(xy 101.90928 -274.037266) (xy 101.921057 -273.989482) (xy 101.940348 -273.944206) (xy 101.966651 -273.90261)
			(xy 101.999286 -273.865773) (xy 102.037407 -273.834648) (xy 102.080028 -273.810041) (xy 102.126044 -273.792589)
			(xy 102.174263 -273.782745) (xy 102.223438 -273.780764) (xy 102.272293 -273.786696) (xy 102.319564 -273.800388)
			(xy 102.364026 -273.821486) (xy 102.404529 -273.849442) (xy 102.440022 -273.883534) (xy 102.469587 -273.922878)
			(xy 102.492458 -273.966455) (xy 102.508042 -274.013136) (xy 102.515937 -274.061713) (xy 102.516432 -274.08632)
			(xy 102.845374 -274.08632) (xy 102.849334 -274.037266) (xy 102.861111 -273.989482) (xy 102.880402 -273.944206)
			(xy 102.906705 -273.90261) (xy 102.93934 -273.865773) (xy 102.977461 -273.834648) (xy 103.020082 -273.810041)
			(xy 103.066098 -273.792589) (xy 103.114317 -273.782745) (xy 103.163492 -273.780764) (xy 103.212347 -273.786696)
			(xy 103.259618 -273.800388) (xy 103.30408 -273.821486) (xy 103.344583 -273.849442) (xy 103.380076 -273.883534)
			(xy 103.409641 -273.922878) (xy 103.432512 -273.966455) (xy 103.448096 -274.013136) (xy 103.455991 -274.061713)
			(xy 103.456486 -274.08632) (xy 103.785174 -274.08632) (xy 103.789134 -274.037266) (xy 103.800911 -273.989482)
			(xy 103.820202 -273.944206) (xy 103.846505 -273.90261) (xy 103.87914 -273.865773) (xy 103.917261 -273.834648)
			(xy 103.959882 -273.810041) (xy 104.005898 -273.792589) (xy 104.054117 -273.782745) (xy 104.103292 -273.780764)
			(xy 104.152147 -273.786696) (xy 104.199418 -273.800388) (xy 104.24388 -273.821486) (xy 104.284383 -273.849442)
			(xy 104.319876 -273.883534) (xy 104.349441 -273.922878) (xy 104.372312 -273.966455) (xy 104.387896 -274.013136)
			(xy 104.395791 -274.061713) (xy 104.396286 -274.08632) (xy 104.725228 -274.08632) (xy 104.729188 -274.037266)
			(xy 104.740965 -273.989482) (xy 104.760256 -273.944206) (xy 104.786559 -273.90261) (xy 104.819194 -273.865773)
			(xy 104.857315 -273.834648) (xy 104.899936 -273.810041) (xy 104.945952 -273.792589) (xy 104.994171 -273.782745)
			(xy 105.043346 -273.780764) (xy 105.092201 -273.786696) (xy 105.139472 -273.800388) (xy 105.183934 -273.821486)
			(xy 105.224437 -273.849442) (xy 105.25993 -273.883534) (xy 105.289495 -273.922878) (xy 105.312366 -273.966455)
			(xy 105.32795 -274.013136) (xy 105.335845 -274.061713) (xy 105.33634 -274.08632) (xy 105.665282 -274.08632)
			(xy 105.669242 -274.037266) (xy 105.681019 -273.989482) (xy 105.70031 -273.944206) (xy 105.726613 -273.90261)
			(xy 105.759248 -273.865773) (xy 105.797369 -273.834648) (xy 105.83999 -273.810041) (xy 105.886006 -273.792589)
			(xy 105.934225 -273.782745) (xy 105.9834 -273.780764) (xy 106.032255 -273.786696) (xy 106.079526 -273.800388)
			(xy 106.123988 -273.821486) (xy 106.164491 -273.849442) (xy 106.199984 -273.883534) (xy 106.229549 -273.922878)
			(xy 106.25242 -273.966455) (xy 106.268004 -274.013136) (xy 106.275899 -274.061713) (xy 106.276394 -274.08632)
			(xy 106.605336 -274.08632) (xy 106.609296 -274.037266) (xy 106.621073 -273.989482) (xy 106.640364 -273.944206)
			(xy 106.666667 -273.90261) (xy 106.699302 -273.865773) (xy 106.737423 -273.834648) (xy 106.780044 -273.810041)
			(xy 106.82606 -273.792589) (xy 106.874279 -273.782745) (xy 106.923454 -273.780764) (xy 106.972309 -273.786696)
			(xy 107.01958 -273.800388) (xy 107.064042 -273.821486) (xy 107.104545 -273.849442) (xy 107.140038 -273.883534)
			(xy 107.169603 -273.922878) (xy 107.192474 -273.966455) (xy 107.208058 -274.013136) (xy 107.215953 -274.061713)
			(xy 107.216448 -274.08632) (xy 107.545136 -274.08632) (xy 107.549096 -274.037266) (xy 107.560873 -273.989482)
			(xy 107.580164 -273.944206) (xy 107.606467 -273.90261) (xy 107.639102 -273.865773) (xy 107.677223 -273.834648)
			(xy 107.719844 -273.810041) (xy 107.76586 -273.792589) (xy 107.814079 -273.782745) (xy 107.863254 -273.780764)
			(xy 107.912109 -273.786696) (xy 107.95938 -273.800388) (xy 108.003842 -273.821486) (xy 108.044345 -273.849442)
			(xy 108.079838 -273.883534) (xy 108.109403 -273.922878) (xy 108.132274 -273.966455) (xy 108.147858 -274.013136)
			(xy 108.155753 -274.061713) (xy 108.156248 -274.08632) (xy 108.48519 -274.08632) (xy 108.48915 -274.037266)
			(xy 108.500927 -273.989482) (xy 108.520218 -273.944206) (xy 108.546521 -273.90261) (xy 108.579156 -273.865773)
			(xy 108.617277 -273.834648) (xy 108.659898 -273.810041) (xy 108.705914 -273.792589) (xy 108.754133 -273.782745)
			(xy 108.803308 -273.780764) (xy 108.852163 -273.786696) (xy 108.899434 -273.800388) (xy 108.943896 -273.821486)
			(xy 108.984399 -273.849442) (xy 109.019892 -273.883534) (xy 109.049457 -273.922878) (xy 109.072328 -273.966455)
			(xy 109.087912 -274.013136) (xy 109.095807 -274.061713) (xy 109.096302 -274.08632) (xy 109.425244 -274.08632)
			(xy 109.429204 -274.037266) (xy 109.440981 -273.989482) (xy 109.460272 -273.944206) (xy 109.486575 -273.90261)
			(xy 109.51921 -273.865773) (xy 109.557331 -273.834648) (xy 109.599952 -273.810041) (xy 109.645968 -273.792589)
			(xy 109.694187 -273.782745) (xy 109.743362 -273.780764) (xy 109.792217 -273.786696) (xy 109.839488 -273.800388)
			(xy 109.88395 -273.821486) (xy 109.924453 -273.849442) (xy 109.959946 -273.883534) (xy 109.989511 -273.922878)
			(xy 110.012382 -273.966455) (xy 110.027966 -274.013136) (xy 110.035861 -274.061713) (xy 110.036356 -274.08632)
			(xy 110.365298 -274.08632) (xy 110.369258 -274.037266) (xy 110.381035 -273.989482) (xy 110.400326 -273.944206)
			(xy 110.426629 -273.90261) (xy 110.459264 -273.865773) (xy 110.497385 -273.834648) (xy 110.540006 -273.810041)
			(xy 110.586022 -273.792589) (xy 110.634241 -273.782745) (xy 110.683416 -273.780764) (xy 110.732271 -273.786696)
			(xy 110.779542 -273.800388) (xy 110.824004 -273.821486) (xy 110.864507 -273.849442) (xy 110.9 -273.883534)
			(xy 110.929565 -273.922878) (xy 110.952436 -273.966455) (xy 110.96802 -274.013136) (xy 110.975915 -274.061713)
			(xy 110.97641 -274.08632) (xy 113.178856 -274.08632) (xy 113.182816 -274.037266) (xy 113.194593 -273.989482)
			(xy 113.213884 -273.944206) (xy 113.240187 -273.90261) (xy 113.272822 -273.865773) (xy 113.310943 -273.834648)
			(xy 113.353564 -273.810041) (xy 113.39958 -273.792589) (xy 113.447799 -273.782745) (xy 113.496974 -273.780764)
			(xy 113.545829 -273.786696) (xy 113.5931 -273.800388) (xy 113.637562 -273.821486) (xy 113.678065 -273.849442)
			(xy 113.713558 -273.883534) (xy 113.743123 -273.922878) (xy 113.765994 -273.966455) (xy 113.781578 -274.013136)
			(xy 113.789473 -274.061713) (xy 113.789968 -274.08632) (xy 114.11891 -274.08632) (xy 114.12287 -274.037266)
			(xy 114.134647 -273.989482) (xy 114.153938 -273.944206) (xy 114.180241 -273.90261) (xy 114.212876 -273.865773)
			(xy 114.250997 -273.834648) (xy 114.293618 -273.810041) (xy 114.339634 -273.792589) (xy 114.387853 -273.782745)
			(xy 114.437028 -273.780764) (xy 114.485883 -273.786696) (xy 114.533154 -273.800388) (xy 114.577616 -273.821486)
			(xy 114.618119 -273.849442) (xy 114.653612 -273.883534) (xy 114.683177 -273.922878) (xy 114.706048 -273.966455)
			(xy 114.721632 -274.013136) (xy 114.729527 -274.061713) (xy 114.730022 -274.08632) (xy 115.058964 -274.08632)
			(xy 115.062924 -274.037266) (xy 115.074701 -273.989482) (xy 115.093992 -273.944206) (xy 115.120295 -273.90261)
			(xy 115.15293 -273.865773) (xy 115.191051 -273.834648) (xy 115.233672 -273.810041) (xy 115.279688 -273.792589)
			(xy 115.327907 -273.782745) (xy 115.377082 -273.780764) (xy 115.425937 -273.786696) (xy 115.473208 -273.800388)
			(xy 115.51767 -273.821486) (xy 115.558173 -273.849442) (xy 115.593666 -273.883534) (xy 115.623231 -273.922878)
			(xy 115.646102 -273.966455) (xy 115.661686 -274.013136) (xy 115.669581 -274.061713) (xy 115.670076 -274.08632)
			(xy 115.999018 -274.08632) (xy 116.002978 -274.037266) (xy 116.014755 -273.989482) (xy 116.034046 -273.944206)
			(xy 116.060349 -273.90261) (xy 116.092984 -273.865773) (xy 116.131105 -273.834648) (xy 116.173726 -273.810041)
			(xy 116.219742 -273.792589) (xy 116.267961 -273.782745) (xy 116.317136 -273.780764) (xy 116.365991 -273.786696)
			(xy 116.413262 -273.800388) (xy 116.457724 -273.821486) (xy 116.498227 -273.849442) (xy 116.53372 -273.883534)
			(xy 116.563285 -273.922878) (xy 116.586156 -273.966455) (xy 116.60174 -274.013136) (xy 116.609635 -274.061713)
			(xy 116.61013 -274.08632) (xy 116.938818 -274.08632) (xy 116.942778 -274.037266) (xy 116.954555 -273.989482)
			(xy 116.973846 -273.944206) (xy 117.000149 -273.90261) (xy 117.032784 -273.865773) (xy 117.070905 -273.834648)
			(xy 117.113526 -273.810041) (xy 117.159542 -273.792589) (xy 117.207761 -273.782745) (xy 117.256936 -273.780764)
			(xy 117.305791 -273.786696) (xy 117.353062 -273.800388) (xy 117.397524 -273.821486) (xy 117.438027 -273.849442)
			(xy 117.47352 -273.883534) (xy 117.503085 -273.922878) (xy 117.525956 -273.966455) (xy 117.54154 -274.013136)
			(xy 117.549435 -274.061713) (xy 117.54993 -274.08632) (xy 117.878872 -274.08632) (xy 117.882832 -274.037266)
			(xy 117.894609 -273.989482) (xy 117.9139 -273.944206) (xy 117.940203 -273.90261) (xy 117.972838 -273.865773)
			(xy 118.010959 -273.834648) (xy 118.05358 -273.810041) (xy 118.099596 -273.792589) (xy 118.147815 -273.782745)
			(xy 118.19699 -273.780764) (xy 118.245845 -273.786696) (xy 118.293116 -273.800388) (xy 118.337578 -273.821486)
			(xy 118.378081 -273.849442) (xy 118.413574 -273.883534) (xy 118.443139 -273.922878) (xy 118.46601 -273.966455)
			(xy 118.481594 -274.013136) (xy 118.489489 -274.061713) (xy 118.489984 -274.08632) (xy 118.818926 -274.08632)
			(xy 118.822886 -274.037266) (xy 118.834663 -273.989482) (xy 118.853954 -273.944206) (xy 118.880257 -273.90261)
			(xy 118.912892 -273.865773) (xy 118.951013 -273.834648) (xy 118.993634 -273.810041) (xy 119.03965 -273.792589)
			(xy 119.087869 -273.782745) (xy 119.137044 -273.780764) (xy 119.185899 -273.786696) (xy 119.23317 -273.800388)
			(xy 119.277632 -273.821486) (xy 119.318135 -273.849442) (xy 119.353628 -273.883534) (xy 119.383193 -273.922878)
			(xy 119.406064 -273.966455) (xy 119.421648 -274.013136) (xy 119.429543 -274.061713) (xy 119.430038 -274.08632)
			(xy 119.75898 -274.08632) (xy 119.76294 -274.037266) (xy 119.774717 -273.989482) (xy 119.794008 -273.944206)
			(xy 119.820311 -273.90261) (xy 119.852946 -273.865773) (xy 119.891067 -273.834648) (xy 119.933688 -273.810041)
			(xy 119.979704 -273.792589) (xy 120.027923 -273.782745) (xy 120.077098 -273.780764) (xy 120.125953 -273.786696)
			(xy 120.173224 -273.800388) (xy 120.217686 -273.821486) (xy 120.258189 -273.849442) (xy 120.293682 -273.883534)
			(xy 120.323247 -273.922878) (xy 120.346118 -273.966455) (xy 120.361702 -274.013136) (xy 120.369597 -274.061713)
			(xy 120.370092 -274.08632) (xy 120.699034 -274.08632) (xy 120.702994 -274.037266) (xy 120.714771 -273.989482)
			(xy 120.734062 -273.944206) (xy 120.760365 -273.90261) (xy 120.793 -273.865773) (xy 120.831121 -273.834648)
			(xy 120.873742 -273.810041) (xy 120.919758 -273.792589) (xy 120.967977 -273.782745) (xy 121.017152 -273.780764)
			(xy 121.066007 -273.786696) (xy 121.113278 -273.800388) (xy 121.15774 -273.821486) (xy 121.198243 -273.849442)
			(xy 121.233736 -273.883534) (xy 121.263301 -273.922878) (xy 121.286172 -273.966455) (xy 121.301756 -274.013136)
			(xy 121.309651 -274.061713) (xy 121.310146 -274.08632) (xy 121.638834 -274.08632) (xy 121.642794 -274.037266)
			(xy 121.654571 -273.989482) (xy 121.673862 -273.944206) (xy 121.700165 -273.90261) (xy 121.7328 -273.865773)
			(xy 121.770921 -273.834648) (xy 121.813542 -273.810041) (xy 121.859558 -273.792589) (xy 121.907777 -273.782745)
			(xy 121.956952 -273.780764) (xy 122.005807 -273.786696) (xy 122.053078 -273.800388) (xy 122.09754 -273.821486)
			(xy 122.138043 -273.849442) (xy 122.173536 -273.883534) (xy 122.203101 -273.922878) (xy 122.225972 -273.966455)
			(xy 122.241556 -274.013136) (xy 122.249451 -274.061713) (xy 122.249946 -274.08632) (xy 122.578888 -274.08632)
			(xy 122.582848 -274.037266) (xy 122.594625 -273.989482) (xy 122.613916 -273.944206) (xy 122.640219 -273.90261)
			(xy 122.672854 -273.865773) (xy 122.710975 -273.834648) (xy 122.753596 -273.810041) (xy 122.799612 -273.792589)
			(xy 122.847831 -273.782745) (xy 122.897006 -273.780764) (xy 122.945861 -273.786696) (xy 122.993132 -273.800388)
			(xy 123.037594 -273.821486) (xy 123.078097 -273.849442) (xy 123.11359 -273.883534) (xy 123.143155 -273.922878)
			(xy 123.166026 -273.966455) (xy 123.18161 -274.013136) (xy 123.189505 -274.061713) (xy 123.19 -274.08632)
			(xy 123.518942 -274.08632) (xy 123.522902 -274.037266) (xy 123.534679 -273.989482) (xy 123.55397 -273.944206)
			(xy 123.580273 -273.90261) (xy 123.612908 -273.865773) (xy 123.651029 -273.834648) (xy 123.69365 -273.810041)
			(xy 123.739666 -273.792589) (xy 123.787885 -273.782745) (xy 123.83706 -273.780764) (xy 123.885915 -273.786696)
			(xy 123.933186 -273.800388) (xy 123.977648 -273.821486) (xy 124.018151 -273.849442) (xy 124.053644 -273.883534)
			(xy 124.083209 -273.922878) (xy 124.10608 -273.966455) (xy 124.121664 -274.013136) (xy 124.129559 -274.061713)
			(xy 124.130054 -274.08632) (xy 124.458996 -274.08632) (xy 124.462956 -274.037266) (xy 124.474733 -273.989482)
			(xy 124.494024 -273.944206) (xy 124.520327 -273.90261) (xy 124.552962 -273.865773) (xy 124.591083 -273.834648)
			(xy 124.633704 -273.810041) (xy 124.67972 -273.792589) (xy 124.727939 -273.782745) (xy 124.777114 -273.780764)
			(xy 124.825969 -273.786696) (xy 124.87324 -273.800388) (xy 124.917702 -273.821486) (xy 124.958205 -273.849442)
			(xy 124.993698 -273.883534) (xy 125.023263 -273.922878) (xy 125.046134 -273.966455) (xy 125.061718 -274.013136)
			(xy 125.069613 -274.061713) (xy 125.070108 -274.08632) (xy 125.39905 -274.08632) (xy 125.40301 -274.037266)
			(xy 125.414787 -273.989482) (xy 125.434078 -273.944206) (xy 125.460381 -273.90261) (xy 125.493016 -273.865773)
			(xy 125.531137 -273.834648) (xy 125.573758 -273.810041) (xy 125.619774 -273.792589) (xy 125.667993 -273.782745)
			(xy 125.717168 -273.780764) (xy 125.766023 -273.786696) (xy 125.813294 -273.800388) (xy 125.857756 -273.821486)
			(xy 125.898259 -273.849442) (xy 125.933752 -273.883534) (xy 125.963317 -273.922878) (xy 125.986188 -273.966455)
			(xy 126.001772 -274.013136) (xy 126.009667 -274.061713) (xy 126.010162 -274.08632) (xy 126.009667 -274.110927)
			(xy 126.001772 -274.159504) (xy 125.986188 -274.206185) (xy 125.963317 -274.249762) (xy 125.933752 -274.289106)
			(xy 125.898259 -274.323198) (xy 125.857756 -274.351154) (xy 125.813294 -274.372252) (xy 125.766023 -274.385944)
			(xy 125.717168 -274.391876) (xy 125.667993 -274.389895) (xy 125.619774 -274.380051) (xy 125.573758 -274.362599)
			(xy 125.531137 -274.337992) (xy 125.493016 -274.306867) (xy 125.460381 -274.27003) (xy 125.434078 -274.228434)
			(xy 125.414787 -274.183158) (xy 125.40301 -274.135374) (xy 125.39905 -274.08632) (xy 125.070108 -274.08632)
			(xy 125.069613 -274.110927) (xy 125.061718 -274.159504) (xy 125.046134 -274.206185) (xy 125.023263 -274.249762)
			(xy 124.993698 -274.289106) (xy 124.958205 -274.323198) (xy 124.917702 -274.351154) (xy 124.87324 -274.372252)
			(xy 124.825969 -274.385944) (xy 124.777114 -274.391876) (xy 124.727939 -274.389895) (xy 124.67972 -274.380051)
			(xy 124.633704 -274.362599) (xy 124.591083 -274.337992) (xy 124.552962 -274.306867) (xy 124.520327 -274.27003)
			(xy 124.494024 -274.228434) (xy 124.474733 -274.183158) (xy 124.462956 -274.135374) (xy 124.458996 -274.08632)
			(xy 124.130054 -274.08632) (xy 124.129559 -274.110927) (xy 124.121664 -274.159504) (xy 124.10608 -274.206185)
			(xy 124.083209 -274.249762) (xy 124.053644 -274.289106) (xy 124.018151 -274.323198) (xy 123.977648 -274.351154)
			(xy 123.933186 -274.372252) (xy 123.885915 -274.385944) (xy 123.83706 -274.391876) (xy 123.787885 -274.389895)
			(xy 123.739666 -274.380051) (xy 123.69365 -274.362599) (xy 123.651029 -274.337992) (xy 123.612908 -274.306867)
			(xy 123.580273 -274.27003) (xy 123.55397 -274.228434) (xy 123.534679 -274.183158) (xy 123.522902 -274.135374)
			(xy 123.518942 -274.08632) (xy 123.19 -274.08632) (xy 123.189505 -274.110927) (xy 123.18161 -274.159504)
			(xy 123.166026 -274.206185) (xy 123.143155 -274.249762) (xy 123.11359 -274.289106) (xy 123.078097 -274.323198)
			(xy 123.037594 -274.351154) (xy 122.993132 -274.372252) (xy 122.945861 -274.385944) (xy 122.897006 -274.391876)
			(xy 122.847831 -274.389895) (xy 122.799612 -274.380051) (xy 122.753596 -274.362599) (xy 122.710975 -274.337992)
			(xy 122.672854 -274.306867) (xy 122.640219 -274.27003) (xy 122.613916 -274.228434) (xy 122.594625 -274.183158)
			(xy 122.582848 -274.135374) (xy 122.578888 -274.08632) (xy 122.249946 -274.08632) (xy 122.249451 -274.110927)
			(xy 122.241556 -274.159504) (xy 122.225972 -274.206185) (xy 122.203101 -274.249762) (xy 122.173536 -274.289106)
			(xy 122.138043 -274.323198) (xy 122.09754 -274.351154) (xy 122.053078 -274.372252) (xy 122.005807 -274.385944)
			(xy 121.956952 -274.391876) (xy 121.907777 -274.389895) (xy 121.859558 -274.380051) (xy 121.813542 -274.362599)
			(xy 121.770921 -274.337992) (xy 121.7328 -274.306867) (xy 121.700165 -274.27003) (xy 121.673862 -274.228434)
			(xy 121.654571 -274.183158) (xy 121.642794 -274.135374) (xy 121.638834 -274.08632) (xy 121.310146 -274.08632)
			(xy 121.309651 -274.110927) (xy 121.301756 -274.159504) (xy 121.286172 -274.206185) (xy 121.263301 -274.249762)
			(xy 121.233736 -274.289106) (xy 121.198243 -274.323198) (xy 121.15774 -274.351154) (xy 121.113278 -274.372252)
			(xy 121.066007 -274.385944) (xy 121.017152 -274.391876) (xy 120.967977 -274.389895) (xy 120.919758 -274.380051)
			(xy 120.873742 -274.362599) (xy 120.831121 -274.337992) (xy 120.793 -274.306867) (xy 120.760365 -274.27003)
			(xy 120.734062 -274.228434) (xy 120.714771 -274.183158) (xy 120.702994 -274.135374) (xy 120.699034 -274.08632)
			(xy 120.370092 -274.08632) (xy 120.369597 -274.110927) (xy 120.361702 -274.159504) (xy 120.346118 -274.206185)
			(xy 120.323247 -274.249762) (xy 120.293682 -274.289106) (xy 120.258189 -274.323198) (xy 120.217686 -274.351154)
			(xy 120.173224 -274.372252) (xy 120.125953 -274.385944) (xy 120.077098 -274.391876) (xy 120.027923 -274.389895)
			(xy 119.979704 -274.380051) (xy 119.933688 -274.362599) (xy 119.891067 -274.337992) (xy 119.852946 -274.306867)
			(xy 119.820311 -274.27003) (xy 119.794008 -274.228434) (xy 119.774717 -274.183158) (xy 119.76294 -274.135374)
			(xy 119.75898 -274.08632) (xy 119.430038 -274.08632) (xy 119.429543 -274.110927) (xy 119.421648 -274.159504)
			(xy 119.406064 -274.206185) (xy 119.383193 -274.249762) (xy 119.353628 -274.289106) (xy 119.318135 -274.323198)
			(xy 119.277632 -274.351154) (xy 119.23317 -274.372252) (xy 119.185899 -274.385944) (xy 119.137044 -274.391876)
			(xy 119.087869 -274.389895) (xy 119.03965 -274.380051) (xy 118.993634 -274.362599) (xy 118.951013 -274.337992)
			(xy 118.912892 -274.306867) (xy 118.880257 -274.27003) (xy 118.853954 -274.228434) (xy 118.834663 -274.183158)
			(xy 118.822886 -274.135374) (xy 118.818926 -274.08632) (xy 118.489984 -274.08632) (xy 118.489489 -274.110927)
			(xy 118.481594 -274.159504) (xy 118.46601 -274.206185) (xy 118.443139 -274.249762) (xy 118.413574 -274.289106)
			(xy 118.378081 -274.323198) (xy 118.337578 -274.351154) (xy 118.293116 -274.372252) (xy 118.245845 -274.385944)
			(xy 118.19699 -274.391876) (xy 118.147815 -274.389895) (xy 118.099596 -274.380051) (xy 118.05358 -274.362599)
			(xy 118.010959 -274.337992) (xy 117.972838 -274.306867) (xy 117.940203 -274.27003) (xy 117.9139 -274.228434)
			(xy 117.894609 -274.183158) (xy 117.882832 -274.135374) (xy 117.878872 -274.08632) (xy 117.54993 -274.08632)
			(xy 117.549435 -274.110927) (xy 117.54154 -274.159504) (xy 117.525956 -274.206185) (xy 117.503085 -274.249762)
			(xy 117.47352 -274.289106) (xy 117.438027 -274.323198) (xy 117.397524 -274.351154) (xy 117.353062 -274.372252)
			(xy 117.305791 -274.385944) (xy 117.256936 -274.391876) (xy 117.207761 -274.389895) (xy 117.159542 -274.380051)
			(xy 117.113526 -274.362599) (xy 117.070905 -274.337992) (xy 117.032784 -274.306867) (xy 117.000149 -274.27003)
			(xy 116.973846 -274.228434) (xy 116.954555 -274.183158) (xy 116.942778 -274.135374) (xy 116.938818 -274.08632)
			(xy 116.61013 -274.08632) (xy 116.609635 -274.110927) (xy 116.60174 -274.159504) (xy 116.586156 -274.206185)
			(xy 116.563285 -274.249762) (xy 116.53372 -274.289106) (xy 116.498227 -274.323198) (xy 116.457724 -274.351154)
			(xy 116.413262 -274.372252) (xy 116.365991 -274.385944) (xy 116.317136 -274.391876) (xy 116.267961 -274.389895)
			(xy 116.219742 -274.380051) (xy 116.173726 -274.362599) (xy 116.131105 -274.337992) (xy 116.092984 -274.306867)
			(xy 116.060349 -274.27003) (xy 116.034046 -274.228434) (xy 116.014755 -274.183158) (xy 116.002978 -274.135374)
			(xy 115.999018 -274.08632) (xy 115.670076 -274.08632) (xy 115.669581 -274.110927) (xy 115.661686 -274.159504)
			(xy 115.646102 -274.206185) (xy 115.623231 -274.249762) (xy 115.593666 -274.289106) (xy 115.558173 -274.323198)
			(xy 115.51767 -274.351154) (xy 115.473208 -274.372252) (xy 115.425937 -274.385944) (xy 115.377082 -274.391876)
			(xy 115.327907 -274.389895) (xy 115.279688 -274.380051) (xy 115.233672 -274.362599) (xy 115.191051 -274.337992)
			(xy 115.15293 -274.306867) (xy 115.120295 -274.27003) (xy 115.093992 -274.228434) (xy 115.074701 -274.183158)
			(xy 115.062924 -274.135374) (xy 115.058964 -274.08632) (xy 114.730022 -274.08632) (xy 114.729527 -274.110927)
			(xy 114.721632 -274.159504) (xy 114.706048 -274.206185) (xy 114.683177 -274.249762) (xy 114.653612 -274.289106)
			(xy 114.618119 -274.323198) (xy 114.577616 -274.351154) (xy 114.533154 -274.372252) (xy 114.485883 -274.385944)
			(xy 114.437028 -274.391876) (xy 114.387853 -274.389895) (xy 114.339634 -274.380051) (xy 114.293618 -274.362599)
			(xy 114.250997 -274.337992) (xy 114.212876 -274.306867) (xy 114.180241 -274.27003) (xy 114.153938 -274.228434)
			(xy 114.134647 -274.183158) (xy 114.12287 -274.135374) (xy 114.11891 -274.08632) (xy 113.789968 -274.08632)
			(xy 113.789473 -274.110927) (xy 113.781578 -274.159504) (xy 113.765994 -274.206185) (xy 113.743123 -274.249762)
			(xy 113.713558 -274.289106) (xy 113.678065 -274.323198) (xy 113.637562 -274.351154) (xy 113.5931 -274.372252)
			(xy 113.545829 -274.385944) (xy 113.496974 -274.391876) (xy 113.447799 -274.389895) (xy 113.39958 -274.380051)
			(xy 113.353564 -274.362599) (xy 113.310943 -274.337992) (xy 113.272822 -274.306867) (xy 113.240187 -274.27003)
			(xy 113.213884 -274.228434) (xy 113.194593 -274.183158) (xy 113.182816 -274.135374) (xy 113.178856 -274.08632)
			(xy 110.97641 -274.08632) (xy 110.975915 -274.110927) (xy 110.96802 -274.159504) (xy 110.952436 -274.206185)
			(xy 110.929565 -274.249762) (xy 110.9 -274.289106) (xy 110.864507 -274.323198) (xy 110.824004 -274.351154)
			(xy 110.779542 -274.372252) (xy 110.732271 -274.385944) (xy 110.683416 -274.391876) (xy 110.634241 -274.389895)
			(xy 110.586022 -274.380051) (xy 110.540006 -274.362599) (xy 110.497385 -274.337992) (xy 110.459264 -274.306867)
			(xy 110.426629 -274.27003) (xy 110.400326 -274.228434) (xy 110.381035 -274.183158) (xy 110.369258 -274.135374)
			(xy 110.365298 -274.08632) (xy 110.036356 -274.08632) (xy 110.035861 -274.110927) (xy 110.027966 -274.159504)
			(xy 110.012382 -274.206185) (xy 109.989511 -274.249762) (xy 109.959946 -274.289106) (xy 109.924453 -274.323198)
			(xy 109.88395 -274.351154) (xy 109.839488 -274.372252) (xy 109.792217 -274.385944) (xy 109.743362 -274.391876)
			(xy 109.694187 -274.389895) (xy 109.645968 -274.380051) (xy 109.599952 -274.362599) (xy 109.557331 -274.337992)
			(xy 109.51921 -274.306867) (xy 109.486575 -274.27003) (xy 109.460272 -274.228434) (xy 109.440981 -274.183158)
			(xy 109.429204 -274.135374) (xy 109.425244 -274.08632) (xy 109.096302 -274.08632) (xy 109.095807 -274.110927)
			(xy 109.087912 -274.159504) (xy 109.072328 -274.206185) (xy 109.049457 -274.249762) (xy 109.019892 -274.289106)
			(xy 108.984399 -274.323198) (xy 108.943896 -274.351154) (xy 108.899434 -274.372252) (xy 108.852163 -274.385944)
			(xy 108.803308 -274.391876) (xy 108.754133 -274.389895) (xy 108.705914 -274.380051) (xy 108.659898 -274.362599)
			(xy 108.617277 -274.337992) (xy 108.579156 -274.306867) (xy 108.546521 -274.27003) (xy 108.520218 -274.228434)
			(xy 108.500927 -274.183158) (xy 108.48915 -274.135374) (xy 108.48519 -274.08632) (xy 108.156248 -274.08632)
			(xy 108.155753 -274.110927) (xy 108.147858 -274.159504) (xy 108.132274 -274.206185) (xy 108.109403 -274.249762)
			(xy 108.079838 -274.289106) (xy 108.044345 -274.323198) (xy 108.003842 -274.351154) (xy 107.95938 -274.372252)
			(xy 107.912109 -274.385944) (xy 107.863254 -274.391876) (xy 107.814079 -274.389895) (xy 107.76586 -274.380051)
			(xy 107.719844 -274.362599) (xy 107.677223 -274.337992) (xy 107.639102 -274.306867) (xy 107.606467 -274.27003)
			(xy 107.580164 -274.228434) (xy 107.560873 -274.183158) (xy 107.549096 -274.135374) (xy 107.545136 -274.08632)
			(xy 107.216448 -274.08632) (xy 107.215953 -274.110927) (xy 107.208058 -274.159504) (xy 107.192474 -274.206185)
			(xy 107.169603 -274.249762) (xy 107.140038 -274.289106) (xy 107.104545 -274.323198) (xy 107.064042 -274.351154)
			(xy 107.01958 -274.372252) (xy 106.972309 -274.385944) (xy 106.923454 -274.391876) (xy 106.874279 -274.389895)
			(xy 106.82606 -274.380051) (xy 106.780044 -274.362599) (xy 106.737423 -274.337992) (xy 106.699302 -274.306867)
			(xy 106.666667 -274.27003) (xy 106.640364 -274.228434) (xy 106.621073 -274.183158) (xy 106.609296 -274.135374)
			(xy 106.605336 -274.08632) (xy 106.276394 -274.08632) (xy 106.275899 -274.110927) (xy 106.268004 -274.159504)
			(xy 106.25242 -274.206185) (xy 106.229549 -274.249762) (xy 106.199984 -274.289106) (xy 106.164491 -274.323198)
			(xy 106.123988 -274.351154) (xy 106.079526 -274.372252) (xy 106.032255 -274.385944) (xy 105.9834 -274.391876)
			(xy 105.934225 -274.389895) (xy 105.886006 -274.380051) (xy 105.83999 -274.362599) (xy 105.797369 -274.337992)
			(xy 105.759248 -274.306867) (xy 105.726613 -274.27003) (xy 105.70031 -274.228434) (xy 105.681019 -274.183158)
			(xy 105.669242 -274.135374) (xy 105.665282 -274.08632) (xy 105.33634 -274.08632) (xy 105.335845 -274.110927)
			(xy 105.32795 -274.159504) (xy 105.312366 -274.206185) (xy 105.289495 -274.249762) (xy 105.25993 -274.289106)
			(xy 105.224437 -274.323198) (xy 105.183934 -274.351154) (xy 105.139472 -274.372252) (xy 105.092201 -274.385944)
			(xy 105.043346 -274.391876) (xy 104.994171 -274.389895) (xy 104.945952 -274.380051) (xy 104.899936 -274.362599)
			(xy 104.857315 -274.337992) (xy 104.819194 -274.306867) (xy 104.786559 -274.27003) (xy 104.760256 -274.228434)
			(xy 104.740965 -274.183158) (xy 104.729188 -274.135374) (xy 104.725228 -274.08632) (xy 104.396286 -274.08632)
			(xy 104.395791 -274.110927) (xy 104.387896 -274.159504) (xy 104.372312 -274.206185) (xy 104.349441 -274.249762)
			(xy 104.319876 -274.289106) (xy 104.284383 -274.323198) (xy 104.24388 -274.351154) (xy 104.199418 -274.372252)
			(xy 104.152147 -274.385944) (xy 104.103292 -274.391876) (xy 104.054117 -274.389895) (xy 104.005898 -274.380051)
			(xy 103.959882 -274.362599) (xy 103.917261 -274.337992) (xy 103.87914 -274.306867) (xy 103.846505 -274.27003)
			(xy 103.820202 -274.228434) (xy 103.800911 -274.183158) (xy 103.789134 -274.135374) (xy 103.785174 -274.08632)
			(xy 103.456486 -274.08632) (xy 103.455991 -274.110927) (xy 103.448096 -274.159504) (xy 103.432512 -274.206185)
			(xy 103.409641 -274.249762) (xy 103.380076 -274.289106) (xy 103.344583 -274.323198) (xy 103.30408 -274.351154)
			(xy 103.259618 -274.372252) (xy 103.212347 -274.385944) (xy 103.163492 -274.391876) (xy 103.114317 -274.389895)
			(xy 103.066098 -274.380051) (xy 103.020082 -274.362599) (xy 102.977461 -274.337992) (xy 102.93934 -274.306867)
			(xy 102.906705 -274.27003) (xy 102.880402 -274.228434) (xy 102.861111 -274.183158) (xy 102.849334 -274.135374)
			(xy 102.845374 -274.08632) (xy 102.516432 -274.08632) (xy 102.515937 -274.110927) (xy 102.508042 -274.159504)
			(xy 102.492458 -274.206185) (xy 102.469587 -274.249762) (xy 102.440022 -274.289106) (xy 102.404529 -274.323198)
			(xy 102.364026 -274.351154) (xy 102.319564 -274.372252) (xy 102.272293 -274.385944) (xy 102.223438 -274.391876)
			(xy 102.174263 -274.389895) (xy 102.126044 -274.380051) (xy 102.080028 -274.362599) (xy 102.037407 -274.337992)
			(xy 101.999286 -274.306867) (xy 101.966651 -274.27003) (xy 101.940348 -274.228434) (xy 101.921057 -274.183158)
			(xy 101.90928 -274.135374) (xy 101.90532 -274.08632) (xy 101.576378 -274.08632) (xy 101.575883 -274.110927)
			(xy 101.567988 -274.159504) (xy 101.552404 -274.206185) (xy 101.529533 -274.249762) (xy 101.499968 -274.289106)
			(xy 101.464475 -274.323198) (xy 101.423972 -274.351154) (xy 101.37951 -274.372252) (xy 101.332239 -274.385944)
			(xy 101.283384 -274.391876) (xy 101.234209 -274.389895) (xy 101.18599 -274.380051) (xy 101.139974 -274.362599)
			(xy 101.097353 -274.337992) (xy 101.059232 -274.306867) (xy 101.026597 -274.27003) (xy 101.000294 -274.228434)
			(xy 100.981003 -274.183158) (xy 100.969226 -274.135374) (xy 100.965266 -274.08632) (xy 100.636324 -274.08632)
			(xy 100.635829 -274.110927) (xy 100.627934 -274.159504) (xy 100.61235 -274.206185) (xy 100.589479 -274.249762)
			(xy 100.559914 -274.289106) (xy 100.524421 -274.323198) (xy 100.483918 -274.351154) (xy 100.439456 -274.372252)
			(xy 100.392185 -274.385944) (xy 100.34333 -274.391876) (xy 100.294155 -274.389895) (xy 100.245936 -274.380051)
			(xy 100.19992 -274.362599) (xy 100.157299 -274.337992) (xy 100.119178 -274.306867) (xy 100.086543 -274.27003)
			(xy 100.06024 -274.228434) (xy 100.040949 -274.183158) (xy 100.029172 -274.135374) (xy 100.025212 -274.08632)
			(xy 99.69627 -274.08632) (xy 99.695775 -274.110927) (xy 99.68788 -274.159504) (xy 99.672296 -274.206185)
			(xy 99.649425 -274.249762) (xy 99.61986 -274.289106) (xy 99.584367 -274.323198) (xy 99.543864 -274.351154)
			(xy 99.499402 -274.372252) (xy 99.452131 -274.385944) (xy 99.403276 -274.391876) (xy 99.354101 -274.389895)
			(xy 99.305882 -274.380051) (xy 99.259866 -274.362599) (xy 99.217245 -274.337992) (xy 99.179124 -274.306867)
			(xy 99.146489 -274.27003) (xy 99.120186 -274.228434) (xy 99.100895 -274.183158) (xy 99.089118 -274.135374)
			(xy 99.085158 -274.08632) (xy 98.75647 -274.08632) (xy 98.755975 -274.110927) (xy 98.74808 -274.159504)
			(xy 98.732496 -274.206185) (xy 98.709625 -274.249762) (xy 98.68006 -274.289106) (xy 98.644567 -274.323198)
			(xy 98.604064 -274.351154) (xy 98.559602 -274.372252) (xy 98.512331 -274.385944) (xy 98.463476 -274.391876)
			(xy 98.414301 -274.389895) (xy 98.366082 -274.380051) (xy 98.320066 -274.362599) (xy 98.277445 -274.337992)
			(xy 98.239324 -274.306867) (xy 98.206689 -274.27003) (xy 98.180386 -274.228434) (xy 98.161095 -274.183158)
			(xy 98.149318 -274.135374) (xy 98.145358 -274.08632) (xy 97.816416 -274.08632) (xy 97.815921 -274.110927)
			(xy 97.808026 -274.159504) (xy 97.792442 -274.206185) (xy 97.769571 -274.249762) (xy 97.740006 -274.289106)
			(xy 97.704513 -274.323198) (xy 97.66401 -274.351154) (xy 97.619548 -274.372252) (xy 97.572277 -274.385944)
			(xy 97.523422 -274.391876) (xy 97.474247 -274.389895) (xy 97.426028 -274.380051) (xy 97.380012 -274.362599)
			(xy 97.337391 -274.337992) (xy 97.29927 -274.306867) (xy 97.266635 -274.27003) (xy 97.240332 -274.228434)
			(xy 97.221041 -274.183158) (xy 97.209264 -274.135374) (xy 97.205304 -274.08632) (xy 96.876362 -274.08632)
			(xy 96.875867 -274.110927) (xy 96.867972 -274.159504) (xy 96.852388 -274.206185) (xy 96.829517 -274.249762)
			(xy 96.799952 -274.289106) (xy 96.764459 -274.323198) (xy 96.723956 -274.351154) (xy 96.679494 -274.372252)
			(xy 96.632223 -274.385944) (xy 96.583368 -274.391876) (xy 96.534193 -274.389895) (xy 96.485974 -274.380051)
			(xy 96.439958 -274.362599) (xy 96.397337 -274.337992) (xy 96.359216 -274.306867) (xy 96.326581 -274.27003)
			(xy 96.300278 -274.228434) (xy 96.280987 -274.183158) (xy 96.26921 -274.135374) (xy 96.26525 -274.08632)
			(xy 95.946722 -274.08632) (xy 95.94621 -274.111766) (xy 95.938046 -274.162) (xy 95.92193 -274.210274)
			(xy 95.898279 -274.255337) (xy 95.867706 -274.296023) (xy 95.831002 -274.331278) (xy 95.789118 -274.360188)
			(xy 95.743139 -274.382005) (xy 95.694255 -274.396165) (xy 95.643734 -274.402299) (xy 95.592882 -274.40025)
			(xy 95.543018 -274.39007) (xy 95.495432 -274.372023) (xy 95.451358 -274.346577) (xy 95.411936 -274.31439)
			(xy 95.378188 -274.276296) (xy 95.350987 -274.233282) (xy 95.331039 -274.186462) (xy 95.31886 -274.137048)
			(xy 95.314765 -274.08632) (xy 95.006668 -274.08632) (xy 95.006156 -274.111766) (xy 94.997992 -274.162)
			(xy 94.981876 -274.210274) (xy 94.958225 -274.255337) (xy 94.927652 -274.296023) (xy 94.890948 -274.331278)
			(xy 94.849064 -274.360188) (xy 94.803085 -274.382005) (xy 94.754201 -274.396165) (xy 94.70368 -274.402299)
			(xy 94.652828 -274.40025) (xy 94.602964 -274.39007) (xy 94.555378 -274.372023) (xy 94.511304 -274.346577)
			(xy 94.471882 -274.31439) (xy 94.438134 -274.276296) (xy 94.410933 -274.233282) (xy 94.390985 -274.186462)
			(xy 94.378806 -274.137048) (xy 94.374711 -274.08632) (xy 94.056909 -274.08632) (xy 94.052741 -274.13663)
			(xy 94.040344 -274.185587) (xy 94.02006 -274.231837) (xy 93.99244 -274.274118) (xy 93.958238 -274.311276)
			(xy 93.918387 -274.342299) (xy 93.873974 -274.36634) (xy 93.82621 -274.382744) (xy 93.776397 -274.391063)
			(xy 93.751146 -274.391628) (xy 93.72738 -274.391178) (xy 93.680422 -274.383815) (xy 93.635174 -274.369259)
			(xy 93.592731 -274.347863) (xy 93.554118 -274.320144) (xy 93.520271 -274.286773) (xy 93.505782 -274.26793)
			(xy 93.505782 -274.267676) (xy 93.505528 -274.267676) (xy 93.501372 -274.262495) (xy 93.490958 -274.25426)
			(xy 93.484954 -274.25142) (xy 93.478545 -274.248874) (xy 93.464895 -274.246953) (xy 93.45803 -274.24761)
			(xy 93.372178 -274.25904) (xy 93.365418 -274.260115) (xy 93.352795 -274.265393) (xy 93.347286 -274.269454)
			(xy 93.341952 -274.273518) (xy 93.334078 -274.284186) (xy 93.331538 -274.29079) (xy 93.315986 -274.32846)
			(xy 93.275559 -274.399222) (xy 93.25102 -274.43176) (xy 93.25102 -274.432014) (xy 93.246982 -274.437417)
			(xy 93.24157 -274.449765) (xy 93.240352 -274.456398) (xy 93.238574 -274.469606) (xy 93.276928 -274.562316)
			(xy 93.27968 -274.568482) (xy 93.287916 -274.579175) (xy 93.293184 -274.583398) (xy 93.298518 -274.587462)
			(xy 93.31071 -274.592288) (xy 93.317822 -274.593304) (xy 93.34218 -274.596769) (xy 93.389431 -274.610472)
			(xy 93.433873 -274.631573) (xy 93.474357 -274.659528) (xy 93.509834 -274.693612) (xy 93.539388 -274.732943)
			(xy 93.562252 -274.776505) (xy 93.577836 -274.823169) (xy 93.585736 -274.871727) (xy 93.5863 -274.896326)
			(xy 93.904811 -274.896326) (xy 93.908906 -274.845598) (xy 93.921085 -274.796184) (xy 93.941033 -274.749364)
			(xy 93.968234 -274.70635) (xy 94.001982 -274.668256) (xy 94.041404 -274.636069) (xy 94.085478 -274.610623)
			(xy 94.133064 -274.592576) (xy 94.182928 -274.582396) (xy 94.23378 -274.580347) (xy 94.284301 -274.586481)
			(xy 94.333185 -274.600641) (xy 94.379164 -274.622458) (xy 94.421048 -274.651368) (xy 94.457752 -274.686623)
			(xy 94.488325 -274.727309) (xy 94.511976 -274.772372) (xy 94.528092 -274.820646) (xy 94.536256 -274.87088)
			(xy 94.536768 -274.896326) (xy 94.855296 -274.896326) (xy 94.859256 -274.847272) (xy 94.871033 -274.799488)
			(xy 94.890324 -274.754212) (xy 94.916627 -274.712616) (xy 94.949262 -274.675779) (xy 94.987383 -274.644654)
			(xy 95.030004 -274.620047) (xy 95.07602 -274.602595) (xy 95.124239 -274.592751) (xy 95.173414 -274.59077)
			(xy 95.222269 -274.596702) (xy 95.26954 -274.610394) (xy 95.314002 -274.631492) (xy 95.354505 -274.659448)
			(xy 95.389998 -274.69354) (xy 95.419563 -274.732884) (xy 95.442434 -274.776461) (xy 95.458018 -274.823142)
			(xy 95.465913 -274.871719) (xy 95.466408 -274.896326) (xy 95.784919 -274.896326) (xy 95.789014 -274.845598)
			(xy 95.801193 -274.796184) (xy 95.821141 -274.749364) (xy 95.848342 -274.70635) (xy 95.88209 -274.668256)
			(xy 95.921512 -274.636069) (xy 95.965586 -274.610623) (xy 96.013172 -274.592576) (xy 96.063036 -274.582396)
			(xy 96.113888 -274.580347) (xy 96.164409 -274.586481) (xy 96.213293 -274.600641) (xy 96.259272 -274.622458)
			(xy 96.301156 -274.651368) (xy 96.33786 -274.686623) (xy 96.368433 -274.727309) (xy 96.392084 -274.772372)
			(xy 96.4082 -274.820646) (xy 96.416364 -274.87088) (xy 96.416876 -274.896326) (xy 96.73515 -274.896326)
			(xy 96.73911 -274.847272) (xy 96.750887 -274.799488) (xy 96.770178 -274.754212) (xy 96.796481 -274.712616)
			(xy 96.829116 -274.675779) (xy 96.867237 -274.644654) (xy 96.909858 -274.620047) (xy 96.955874 -274.602595)
			(xy 97.004093 -274.592751) (xy 97.053268 -274.59077) (xy 97.102123 -274.596702) (xy 97.149394 -274.610394)
			(xy 97.193856 -274.631492) (xy 97.234359 -274.659448) (xy 97.269852 -274.69354) (xy 97.299417 -274.732884)
			(xy 97.322288 -274.776461) (xy 97.337872 -274.823142) (xy 97.345767 -274.871719) (xy 97.346262 -274.896326)
			(xy 97.675204 -274.896326) (xy 97.679164 -274.847272) (xy 97.690941 -274.799488) (xy 97.710232 -274.754212)
			(xy 97.736535 -274.712616) (xy 97.76917 -274.675779) (xy 97.807291 -274.644654) (xy 97.849912 -274.620047)
			(xy 97.895928 -274.602595) (xy 97.944147 -274.592751) (xy 97.993322 -274.59077) (xy 98.042177 -274.596702)
			(xy 98.089448 -274.610394) (xy 98.13391 -274.631492) (xy 98.174413 -274.659448) (xy 98.209906 -274.69354)
			(xy 98.239471 -274.732884) (xy 98.262342 -274.776461) (xy 98.277926 -274.823142) (xy 98.285821 -274.871719)
			(xy 98.286316 -274.896326) (xy 98.615258 -274.896326) (xy 98.619218 -274.847272) (xy 98.630995 -274.799488)
			(xy 98.650286 -274.754212) (xy 98.676589 -274.712616) (xy 98.709224 -274.675779) (xy 98.747345 -274.644654)
			(xy 98.789966 -274.620047) (xy 98.835982 -274.602595) (xy 98.884201 -274.592751) (xy 98.933376 -274.59077)
			(xy 98.982231 -274.596702) (xy 99.029502 -274.610394) (xy 99.073964 -274.631492) (xy 99.114467 -274.659448)
			(xy 99.14996 -274.69354) (xy 99.179525 -274.732884) (xy 99.202396 -274.776461) (xy 99.21798 -274.823142)
			(xy 99.225875 -274.871719) (xy 99.22637 -274.896326) (xy 99.555312 -274.896326) (xy 99.559272 -274.847272)
			(xy 99.571049 -274.799488) (xy 99.59034 -274.754212) (xy 99.616643 -274.712616) (xy 99.649278 -274.675779)
			(xy 99.687399 -274.644654) (xy 99.73002 -274.620047) (xy 99.776036 -274.602595) (xy 99.824255 -274.592751)
			(xy 99.87343 -274.59077) (xy 99.922285 -274.596702) (xy 99.969556 -274.610394) (xy 100.014018 -274.631492)
			(xy 100.054521 -274.659448) (xy 100.090014 -274.69354) (xy 100.119579 -274.732884) (xy 100.14245 -274.776461)
			(xy 100.158034 -274.823142) (xy 100.165929 -274.871719) (xy 100.166424 -274.896326) (xy 100.495366 -274.896326)
			(xy 100.499326 -274.847272) (xy 100.511103 -274.799488) (xy 100.530394 -274.754212) (xy 100.556697 -274.712616)
			(xy 100.589332 -274.675779) (xy 100.627453 -274.644654) (xy 100.670074 -274.620047) (xy 100.71609 -274.602595)
			(xy 100.764309 -274.592751) (xy 100.813484 -274.59077) (xy 100.862339 -274.596702) (xy 100.90961 -274.610394)
			(xy 100.954072 -274.631492) (xy 100.994575 -274.659448) (xy 101.030068 -274.69354) (xy 101.059633 -274.732884)
			(xy 101.082504 -274.776461) (xy 101.098088 -274.823142) (xy 101.105983 -274.871719) (xy 101.106478 -274.896326)
			(xy 101.435166 -274.896326) (xy 101.439126 -274.847272) (xy 101.450903 -274.799488) (xy 101.470194 -274.754212)
			(xy 101.496497 -274.712616) (xy 101.529132 -274.675779) (xy 101.567253 -274.644654) (xy 101.609874 -274.620047)
			(xy 101.65589 -274.602595) (xy 101.704109 -274.592751) (xy 101.753284 -274.59077) (xy 101.802139 -274.596702)
			(xy 101.84941 -274.610394) (xy 101.893872 -274.631492) (xy 101.934375 -274.659448) (xy 101.969868 -274.69354)
			(xy 101.999433 -274.732884) (xy 102.022304 -274.776461) (xy 102.037888 -274.823142) (xy 102.045783 -274.871719)
			(xy 102.046278 -274.896326) (xy 102.37522 -274.896326) (xy 102.37918 -274.847272) (xy 102.390957 -274.799488)
			(xy 102.410248 -274.754212) (xy 102.436551 -274.712616) (xy 102.469186 -274.675779) (xy 102.507307 -274.644654)
			(xy 102.549928 -274.620047) (xy 102.595944 -274.602595) (xy 102.644163 -274.592751) (xy 102.693338 -274.59077)
			(xy 102.742193 -274.596702) (xy 102.789464 -274.610394) (xy 102.833926 -274.631492) (xy 102.874429 -274.659448)
			(xy 102.909922 -274.69354) (xy 102.939487 -274.732884) (xy 102.962358 -274.776461) (xy 102.977942 -274.823142)
			(xy 102.985837 -274.871719) (xy 102.986332 -274.896326) (xy 103.315274 -274.896326) (xy 103.319234 -274.847272)
			(xy 103.331011 -274.799488) (xy 103.350302 -274.754212) (xy 103.376605 -274.712616) (xy 103.40924 -274.675779)
			(xy 103.447361 -274.644654) (xy 103.489982 -274.620047) (xy 103.535998 -274.602595) (xy 103.584217 -274.592751)
			(xy 103.633392 -274.59077) (xy 103.682247 -274.596702) (xy 103.729518 -274.610394) (xy 103.77398 -274.631492)
			(xy 103.814483 -274.659448) (xy 103.849976 -274.69354) (xy 103.879541 -274.732884) (xy 103.902412 -274.776461)
			(xy 103.917996 -274.823142) (xy 103.925891 -274.871719) (xy 103.926386 -274.896326) (xy 104.255328 -274.896326)
			(xy 104.259288 -274.847272) (xy 104.271065 -274.799488) (xy 104.290356 -274.754212) (xy 104.316659 -274.712616)
			(xy 104.349294 -274.675779) (xy 104.387415 -274.644654) (xy 104.430036 -274.620047) (xy 104.476052 -274.602595)
			(xy 104.524271 -274.592751) (xy 104.573446 -274.59077) (xy 104.622301 -274.596702) (xy 104.669572 -274.610394)
			(xy 104.714034 -274.631492) (xy 104.754537 -274.659448) (xy 104.79003 -274.69354) (xy 104.819595 -274.732884)
			(xy 104.842466 -274.776461) (xy 104.85805 -274.823142) (xy 104.865945 -274.871719) (xy 104.86644 -274.896326)
			(xy 105.195128 -274.896326) (xy 105.199088 -274.847272) (xy 105.210865 -274.799488) (xy 105.230156 -274.754212)
			(xy 105.256459 -274.712616) (xy 105.289094 -274.675779) (xy 105.327215 -274.644654) (xy 105.369836 -274.620047)
			(xy 105.415852 -274.602595) (xy 105.464071 -274.592751) (xy 105.513246 -274.59077) (xy 105.562101 -274.596702)
			(xy 105.609372 -274.610394) (xy 105.653834 -274.631492) (xy 105.694337 -274.659448) (xy 105.72983 -274.69354)
			(xy 105.759395 -274.732884) (xy 105.782266 -274.776461) (xy 105.79785 -274.823142) (xy 105.805745 -274.871719)
			(xy 105.80624 -274.896326) (xy 106.135182 -274.896326) (xy 106.139142 -274.847272) (xy 106.150919 -274.799488)
			(xy 106.17021 -274.754212) (xy 106.196513 -274.712616) (xy 106.229148 -274.675779) (xy 106.267269 -274.644654)
			(xy 106.30989 -274.620047) (xy 106.355906 -274.602595) (xy 106.404125 -274.592751) (xy 106.4533 -274.59077)
			(xy 106.502155 -274.596702) (xy 106.549426 -274.610394) (xy 106.593888 -274.631492) (xy 106.634391 -274.659448)
			(xy 106.669884 -274.69354) (xy 106.699449 -274.732884) (xy 106.72232 -274.776461) (xy 106.737904 -274.823142)
			(xy 106.745799 -274.871719) (xy 106.746294 -274.896326) (xy 107.075236 -274.896326) (xy 107.079196 -274.847272)
			(xy 107.090973 -274.799488) (xy 107.110264 -274.754212) (xy 107.136567 -274.712616) (xy 107.169202 -274.675779)
			(xy 107.207323 -274.644654) (xy 107.249944 -274.620047) (xy 107.29596 -274.602595) (xy 107.344179 -274.592751)
			(xy 107.393354 -274.59077) (xy 107.442209 -274.596702) (xy 107.48948 -274.610394) (xy 107.533942 -274.631492)
			(xy 107.574445 -274.659448) (xy 107.609938 -274.69354) (xy 107.639503 -274.732884) (xy 107.662374 -274.776461)
			(xy 107.677958 -274.823142) (xy 107.685853 -274.871719) (xy 107.686348 -274.896326) (xy 108.01529 -274.896326)
			(xy 108.01925 -274.847272) (xy 108.031027 -274.799488) (xy 108.050318 -274.754212) (xy 108.076621 -274.712616)
			(xy 108.109256 -274.675779) (xy 108.147377 -274.644654) (xy 108.189998 -274.620047) (xy 108.236014 -274.602595)
			(xy 108.284233 -274.592751) (xy 108.333408 -274.59077) (xy 108.382263 -274.596702) (xy 108.429534 -274.610394)
			(xy 108.473996 -274.631492) (xy 108.514499 -274.659448) (xy 108.549992 -274.69354) (xy 108.579557 -274.732884)
			(xy 108.602428 -274.776461) (xy 108.618012 -274.823142) (xy 108.625907 -274.871719) (xy 108.626402 -274.896326)
			(xy 115.528864 -274.896326) (xy 115.532824 -274.847272) (xy 115.544601 -274.799488) (xy 115.563892 -274.754212)
			(xy 115.590195 -274.712616) (xy 115.62283 -274.675779) (xy 115.660951 -274.644654) (xy 115.703572 -274.620047)
			(xy 115.749588 -274.602595) (xy 115.797807 -274.592751) (xy 115.846982 -274.59077) (xy 115.895837 -274.596702)
			(xy 115.943108 -274.610394) (xy 115.98757 -274.631492) (xy 116.028073 -274.659448) (xy 116.063566 -274.69354)
			(xy 116.093131 -274.732884) (xy 116.116002 -274.776461) (xy 116.131586 -274.823142) (xy 116.139481 -274.871719)
			(xy 116.139976 -274.896326) (xy 116.468918 -274.896326) (xy 116.472878 -274.847272) (xy 116.484655 -274.799488)
			(xy 116.503946 -274.754212) (xy 116.530249 -274.712616) (xy 116.562884 -274.675779) (xy 116.601005 -274.644654)
			(xy 116.643626 -274.620047) (xy 116.689642 -274.602595) (xy 116.737861 -274.592751) (xy 116.787036 -274.59077)
			(xy 116.835891 -274.596702) (xy 116.883162 -274.610394) (xy 116.927624 -274.631492) (xy 116.968127 -274.659448)
			(xy 117.00362 -274.69354) (xy 117.033185 -274.732884) (xy 117.056056 -274.776461) (xy 117.07164 -274.823142)
			(xy 117.079535 -274.871719) (xy 117.08003 -274.896326) (xy 117.408972 -274.896326) (xy 117.412932 -274.847272)
			(xy 117.424709 -274.799488) (xy 117.444 -274.754212) (xy 117.470303 -274.712616) (xy 117.502938 -274.675779)
			(xy 117.541059 -274.644654) (xy 117.58368 -274.620047) (xy 117.629696 -274.602595) (xy 117.677915 -274.592751)
			(xy 117.72709 -274.59077) (xy 117.775945 -274.596702) (xy 117.823216 -274.610394) (xy 117.867678 -274.631492)
			(xy 117.908181 -274.659448) (xy 117.943674 -274.69354) (xy 117.973239 -274.732884) (xy 117.99611 -274.776461)
			(xy 118.011694 -274.823142) (xy 118.019589 -274.871719) (xy 118.020084 -274.896326) (xy 118.349026 -274.896326)
			(xy 118.352986 -274.847272) (xy 118.364763 -274.799488) (xy 118.384054 -274.754212) (xy 118.410357 -274.712616)
			(xy 118.442992 -274.675779) (xy 118.481113 -274.644654) (xy 118.523734 -274.620047) (xy 118.56975 -274.602595)
			(xy 118.617969 -274.592751) (xy 118.667144 -274.59077) (xy 118.715999 -274.596702) (xy 118.76327 -274.610394)
			(xy 118.807732 -274.631492) (xy 118.848235 -274.659448) (xy 118.883728 -274.69354) (xy 118.913293 -274.732884)
			(xy 118.936164 -274.776461) (xy 118.951748 -274.823142) (xy 118.959643 -274.871719) (xy 118.960138 -274.896326)
			(xy 119.288826 -274.896326) (xy 119.292786 -274.847272) (xy 119.304563 -274.799488) (xy 119.323854 -274.754212)
			(xy 119.350157 -274.712616) (xy 119.382792 -274.675779) (xy 119.420913 -274.644654) (xy 119.463534 -274.620047)
			(xy 119.50955 -274.602595) (xy 119.557769 -274.592751) (xy 119.606944 -274.59077) (xy 119.655799 -274.596702)
			(xy 119.70307 -274.610394) (xy 119.747532 -274.631492) (xy 119.788035 -274.659448) (xy 119.823528 -274.69354)
			(xy 119.853093 -274.732884) (xy 119.875964 -274.776461) (xy 119.891548 -274.823142) (xy 119.899443 -274.871719)
			(xy 119.899938 -274.896326) (xy 120.22888 -274.896326) (xy 120.23284 -274.847272) (xy 120.244617 -274.799488)
			(xy 120.263908 -274.754212) (xy 120.290211 -274.712616) (xy 120.322846 -274.675779) (xy 120.360967 -274.644654)
			(xy 120.403588 -274.620047) (xy 120.449604 -274.602595) (xy 120.497823 -274.592751) (xy 120.546998 -274.59077)
			(xy 120.595853 -274.596702) (xy 120.643124 -274.610394) (xy 120.687586 -274.631492) (xy 120.728089 -274.659448)
			(xy 120.763582 -274.69354) (xy 120.793147 -274.732884) (xy 120.816018 -274.776461) (xy 120.831602 -274.823142)
			(xy 120.839497 -274.871719) (xy 120.839992 -274.896326) (xy 121.168934 -274.896326) (xy 121.172894 -274.847272)
			(xy 121.184671 -274.799488) (xy 121.203962 -274.754212) (xy 121.230265 -274.712616) (xy 121.2629 -274.675779)
			(xy 121.301021 -274.644654) (xy 121.343642 -274.620047) (xy 121.389658 -274.602595) (xy 121.437877 -274.592751)
			(xy 121.487052 -274.59077) (xy 121.535907 -274.596702) (xy 121.583178 -274.610394) (xy 121.62764 -274.631492)
			(xy 121.668143 -274.659448) (xy 121.703636 -274.69354) (xy 121.733201 -274.732884) (xy 121.756072 -274.776461)
			(xy 121.771656 -274.823142) (xy 121.779551 -274.871719) (xy 121.780046 -274.896326) (xy 122.108988 -274.896326)
			(xy 122.112948 -274.847272) (xy 122.124725 -274.799488) (xy 122.144016 -274.754212) (xy 122.170319 -274.712616)
			(xy 122.202954 -274.675779) (xy 122.241075 -274.644654) (xy 122.283696 -274.620047) (xy 122.329712 -274.602595)
			(xy 122.377931 -274.592751) (xy 122.427106 -274.59077) (xy 122.475961 -274.596702) (xy 122.523232 -274.610394)
			(xy 122.567694 -274.631492) (xy 122.608197 -274.659448) (xy 122.64369 -274.69354) (xy 122.673255 -274.732884)
			(xy 122.696126 -274.776461) (xy 122.71171 -274.823142) (xy 122.719605 -274.871719) (xy 122.7201 -274.896326)
			(xy 123.049042 -274.896326) (xy 123.053002 -274.847272) (xy 123.064779 -274.799488) (xy 123.08407 -274.754212)
			(xy 123.110373 -274.712616) (xy 123.143008 -274.675779) (xy 123.181129 -274.644654) (xy 123.22375 -274.620047)
			(xy 123.269766 -274.602595) (xy 123.317985 -274.592751) (xy 123.36716 -274.59077) (xy 123.416015 -274.596702)
			(xy 123.463286 -274.610394) (xy 123.507748 -274.631492) (xy 123.548251 -274.659448) (xy 123.583744 -274.69354)
			(xy 123.613309 -274.732884) (xy 123.63618 -274.776461) (xy 123.651764 -274.823142) (xy 123.659659 -274.871719)
			(xy 123.660154 -274.896326) (xy 123.988842 -274.896326) (xy 123.992802 -274.847272) (xy 124.004579 -274.799488)
			(xy 124.02387 -274.754212) (xy 124.050173 -274.712616) (xy 124.082808 -274.675779) (xy 124.120929 -274.644654)
			(xy 124.16355 -274.620047) (xy 124.209566 -274.602595) (xy 124.257785 -274.592751) (xy 124.30696 -274.59077)
			(xy 124.355815 -274.596702) (xy 124.403086 -274.610394) (xy 124.447548 -274.631492) (xy 124.488051 -274.659448)
			(xy 124.523544 -274.69354) (xy 124.553109 -274.732884) (xy 124.57598 -274.776461) (xy 124.591564 -274.823142)
			(xy 124.599459 -274.871719) (xy 124.599954 -274.896326) (xy 124.928896 -274.896326) (xy 124.932856 -274.847272)
			(xy 124.944633 -274.799488) (xy 124.963924 -274.754212) (xy 124.990227 -274.712616) (xy 125.022862 -274.675779)
			(xy 125.060983 -274.644654) (xy 125.103604 -274.620047) (xy 125.14962 -274.602595) (xy 125.197839 -274.592751)
			(xy 125.247014 -274.59077) (xy 125.295869 -274.596702) (xy 125.34314 -274.610394) (xy 125.387602 -274.631492)
			(xy 125.428105 -274.659448) (xy 125.463598 -274.69354) (xy 125.493163 -274.732884) (xy 125.516034 -274.776461)
			(xy 125.531618 -274.823142) (xy 125.539513 -274.871719) (xy 125.540008 -274.896326) (xy 125.86895 -274.896326)
			(xy 125.87291 -274.847272) (xy 125.884687 -274.799488) (xy 125.903978 -274.754212) (xy 125.930281 -274.712616)
			(xy 125.962916 -274.675779) (xy 126.001037 -274.644654) (xy 126.043658 -274.620047) (xy 126.089674 -274.602595)
			(xy 126.137893 -274.592751) (xy 126.187068 -274.59077) (xy 126.235923 -274.596702) (xy 126.283194 -274.610394)
			(xy 126.327656 -274.631492) (xy 126.368159 -274.659448) (xy 126.403652 -274.69354) (xy 126.433217 -274.732884)
			(xy 126.456088 -274.776461) (xy 126.471672 -274.823142) (xy 126.479567 -274.871719) (xy 126.480062 -274.896326)
			(xy 126.479567 -274.920933) (xy 126.471672 -274.96951) (xy 126.456088 -275.016191) (xy 126.433217 -275.059768)
			(xy 126.403652 -275.099112) (xy 126.368159 -275.133204) (xy 126.327656 -275.16116) (xy 126.283194 -275.182258)
			(xy 126.235923 -275.19595) (xy 126.187068 -275.201882) (xy 126.137893 -275.199901) (xy 126.089674 -275.190057)
			(xy 126.043658 -275.172605) (xy 126.001037 -275.147998) (xy 125.962916 -275.116873) (xy 125.930281 -275.080036)
			(xy 125.903978 -275.03844) (xy 125.884687 -274.993164) (xy 125.87291 -274.94538) (xy 125.86895 -274.896326)
			(xy 125.540008 -274.896326) (xy 125.539513 -274.920933) (xy 125.531618 -274.96951) (xy 125.516034 -275.016191)
			(xy 125.493163 -275.059768) (xy 125.463598 -275.099112) (xy 125.428105 -275.133204) (xy 125.387602 -275.16116)
			(xy 125.34314 -275.182258) (xy 125.295869 -275.19595) (xy 125.247014 -275.201882) (xy 125.197839 -275.199901)
			(xy 125.14962 -275.190057) (xy 125.103604 -275.172605) (xy 125.060983 -275.147998) (xy 125.022862 -275.116873)
			(xy 124.990227 -275.080036) (xy 124.963924 -275.03844) (xy 124.944633 -274.993164) (xy 124.932856 -274.94538)
			(xy 124.928896 -274.896326) (xy 124.599954 -274.896326) (xy 124.599459 -274.920933) (xy 124.591564 -274.96951)
			(xy 124.57598 -275.016191) (xy 124.553109 -275.059768) (xy 124.523544 -275.099112) (xy 124.488051 -275.133204)
			(xy 124.447548 -275.16116) (xy 124.403086 -275.182258) (xy 124.355815 -275.19595) (xy 124.30696 -275.201882)
			(xy 124.257785 -275.199901) (xy 124.209566 -275.190057) (xy 124.16355 -275.172605) (xy 124.120929 -275.147998)
			(xy 124.082808 -275.116873) (xy 124.050173 -275.080036) (xy 124.02387 -275.03844) (xy 124.004579 -274.993164)
			(xy 123.992802 -274.94538) (xy 123.988842 -274.896326) (xy 123.660154 -274.896326) (xy 123.659659 -274.920933)
			(xy 123.651764 -274.96951) (xy 123.63618 -275.016191) (xy 123.613309 -275.059768) (xy 123.583744 -275.099112)
			(xy 123.548251 -275.133204) (xy 123.507748 -275.16116) (xy 123.463286 -275.182258) (xy 123.416015 -275.19595)
			(xy 123.36716 -275.201882) (xy 123.317985 -275.199901) (xy 123.269766 -275.190057) (xy 123.22375 -275.172605)
			(xy 123.181129 -275.147998) (xy 123.143008 -275.116873) (xy 123.110373 -275.080036) (xy 123.08407 -275.03844)
			(xy 123.064779 -274.993164) (xy 123.053002 -274.94538) (xy 123.049042 -274.896326) (xy 122.7201 -274.896326)
			(xy 122.719605 -274.920933) (xy 122.71171 -274.96951) (xy 122.696126 -275.016191) (xy 122.673255 -275.059768)
			(xy 122.64369 -275.099112) (xy 122.608197 -275.133204) (xy 122.567694 -275.16116) (xy 122.523232 -275.182258)
			(xy 122.475961 -275.19595) (xy 122.427106 -275.201882) (xy 122.377931 -275.199901) (xy 122.329712 -275.190057)
			(xy 122.283696 -275.172605) (xy 122.241075 -275.147998) (xy 122.202954 -275.116873) (xy 122.170319 -275.080036)
			(xy 122.144016 -275.03844) (xy 122.124725 -274.993164) (xy 122.112948 -274.94538) (xy 122.108988 -274.896326)
			(xy 121.780046 -274.896326) (xy 121.779551 -274.920933) (xy 121.771656 -274.96951) (xy 121.756072 -275.016191)
			(xy 121.733201 -275.059768) (xy 121.703636 -275.099112) (xy 121.668143 -275.133204) (xy 121.62764 -275.16116)
			(xy 121.583178 -275.182258) (xy 121.535907 -275.19595) (xy 121.487052 -275.201882) (xy 121.437877 -275.199901)
			(xy 121.389658 -275.190057) (xy 121.343642 -275.172605) (xy 121.301021 -275.147998) (xy 121.2629 -275.116873)
			(xy 121.230265 -275.080036) (xy 121.203962 -275.03844) (xy 121.184671 -274.993164) (xy 121.172894 -274.94538)
			(xy 121.168934 -274.896326) (xy 120.839992 -274.896326) (xy 120.839497 -274.920933) (xy 120.831602 -274.96951)
			(xy 120.816018 -275.016191) (xy 120.793147 -275.059768) (xy 120.763582 -275.099112) (xy 120.728089 -275.133204)
			(xy 120.687586 -275.16116) (xy 120.643124 -275.182258) (xy 120.595853 -275.19595) (xy 120.546998 -275.201882)
			(xy 120.497823 -275.199901) (xy 120.449604 -275.190057) (xy 120.403588 -275.172605) (xy 120.360967 -275.147998)
			(xy 120.322846 -275.116873) (xy 120.290211 -275.080036) (xy 120.263908 -275.03844) (xy 120.244617 -274.993164)
			(xy 120.23284 -274.94538) (xy 120.22888 -274.896326) (xy 119.899938 -274.896326) (xy 119.899443 -274.920933)
			(xy 119.891548 -274.96951) (xy 119.875964 -275.016191) (xy 119.853093 -275.059768) (xy 119.823528 -275.099112)
			(xy 119.788035 -275.133204) (xy 119.747532 -275.16116) (xy 119.70307 -275.182258) (xy 119.655799 -275.19595)
			(xy 119.606944 -275.201882) (xy 119.557769 -275.199901) (xy 119.50955 -275.190057) (xy 119.463534 -275.172605)
			(xy 119.420913 -275.147998) (xy 119.382792 -275.116873) (xy 119.350157 -275.080036) (xy 119.323854 -275.03844)
			(xy 119.304563 -274.993164) (xy 119.292786 -274.94538) (xy 119.288826 -274.896326) (xy 118.960138 -274.896326)
			(xy 118.959643 -274.920933) (xy 118.951748 -274.96951) (xy 118.936164 -275.016191) (xy 118.913293 -275.059768)
			(xy 118.883728 -275.099112) (xy 118.848235 -275.133204) (xy 118.807732 -275.16116) (xy 118.76327 -275.182258)
			(xy 118.715999 -275.19595) (xy 118.667144 -275.201882) (xy 118.617969 -275.199901) (xy 118.56975 -275.190057)
			(xy 118.523734 -275.172605) (xy 118.481113 -275.147998) (xy 118.442992 -275.116873) (xy 118.410357 -275.080036)
			(xy 118.384054 -275.03844) (xy 118.364763 -274.993164) (xy 118.352986 -274.94538) (xy 118.349026 -274.896326)
			(xy 118.020084 -274.896326) (xy 118.019589 -274.920933) (xy 118.011694 -274.96951) (xy 117.99611 -275.016191)
			(xy 117.973239 -275.059768) (xy 117.943674 -275.099112) (xy 117.908181 -275.133204) (xy 117.867678 -275.16116)
			(xy 117.823216 -275.182258) (xy 117.775945 -275.19595) (xy 117.72709 -275.201882) (xy 117.677915 -275.199901)
			(xy 117.629696 -275.190057) (xy 117.58368 -275.172605) (xy 117.541059 -275.147998) (xy 117.502938 -275.116873)
			(xy 117.470303 -275.080036) (xy 117.444 -275.03844) (xy 117.424709 -274.993164) (xy 117.412932 -274.94538)
			(xy 117.408972 -274.896326) (xy 117.08003 -274.896326) (xy 117.079535 -274.920933) (xy 117.07164 -274.96951)
			(xy 117.056056 -275.016191) (xy 117.033185 -275.059768) (xy 117.00362 -275.099112) (xy 116.968127 -275.133204)
			(xy 116.927624 -275.16116) (xy 116.883162 -275.182258) (xy 116.835891 -275.19595) (xy 116.787036 -275.201882)
			(xy 116.737861 -275.199901) (xy 116.689642 -275.190057) (xy 116.643626 -275.172605) (xy 116.601005 -275.147998)
			(xy 116.562884 -275.116873) (xy 116.530249 -275.080036) (xy 116.503946 -275.03844) (xy 116.484655 -274.993164)
			(xy 116.472878 -274.94538) (xy 116.468918 -274.896326) (xy 116.139976 -274.896326) (xy 116.139481 -274.920933)
			(xy 116.131586 -274.96951) (xy 116.116002 -275.016191) (xy 116.093131 -275.059768) (xy 116.063566 -275.099112)
			(xy 116.028073 -275.133204) (xy 115.98757 -275.16116) (xy 115.943108 -275.182258) (xy 115.895837 -275.19595)
			(xy 115.846982 -275.201882) (xy 115.797807 -275.199901) (xy 115.749588 -275.190057) (xy 115.703572 -275.172605)
			(xy 115.660951 -275.147998) (xy 115.62283 -275.116873) (xy 115.590195 -275.080036) (xy 115.563892 -275.03844)
			(xy 115.544601 -274.993164) (xy 115.532824 -274.94538) (xy 115.528864 -274.896326) (xy 108.626402 -274.896326)
			(xy 108.625907 -274.920933) (xy 108.618012 -274.96951) (xy 108.602428 -275.016191) (xy 108.579557 -275.059768)
			(xy 108.549992 -275.099112) (xy 108.514499 -275.133204) (xy 108.473996 -275.16116) (xy 108.429534 -275.182258)
			(xy 108.382263 -275.19595) (xy 108.333408 -275.201882) (xy 108.284233 -275.199901) (xy 108.236014 -275.190057)
			(xy 108.189998 -275.172605) (xy 108.147377 -275.147998) (xy 108.109256 -275.116873) (xy 108.076621 -275.080036)
			(xy 108.050318 -275.03844) (xy 108.031027 -274.993164) (xy 108.01925 -274.94538) (xy 108.01529 -274.896326)
			(xy 107.686348 -274.896326) (xy 107.685853 -274.920933) (xy 107.677958 -274.96951) (xy 107.662374 -275.016191)
			(xy 107.639503 -275.059768) (xy 107.609938 -275.099112) (xy 107.574445 -275.133204) (xy 107.533942 -275.16116)
			(xy 107.48948 -275.182258) (xy 107.442209 -275.19595) (xy 107.393354 -275.201882) (xy 107.344179 -275.199901)
			(xy 107.29596 -275.190057) (xy 107.249944 -275.172605) (xy 107.207323 -275.147998) (xy 107.169202 -275.116873)
			(xy 107.136567 -275.080036) (xy 107.110264 -275.03844) (xy 107.090973 -274.993164) (xy 107.079196 -274.94538)
			(xy 107.075236 -274.896326) (xy 106.746294 -274.896326) (xy 106.745799 -274.920933) (xy 106.737904 -274.96951)
			(xy 106.72232 -275.016191) (xy 106.699449 -275.059768) (xy 106.669884 -275.099112) (xy 106.634391 -275.133204)
			(xy 106.593888 -275.16116) (xy 106.549426 -275.182258) (xy 106.502155 -275.19595) (xy 106.4533 -275.201882)
			(xy 106.404125 -275.199901) (xy 106.355906 -275.190057) (xy 106.30989 -275.172605) (xy 106.267269 -275.147998)
			(xy 106.229148 -275.116873) (xy 106.196513 -275.080036) (xy 106.17021 -275.03844) (xy 106.150919 -274.993164)
			(xy 106.139142 -274.94538) (xy 106.135182 -274.896326) (xy 105.80624 -274.896326) (xy 105.805745 -274.920933)
			(xy 105.79785 -274.96951) (xy 105.782266 -275.016191) (xy 105.759395 -275.059768) (xy 105.72983 -275.099112)
			(xy 105.694337 -275.133204) (xy 105.653834 -275.16116) (xy 105.609372 -275.182258) (xy 105.562101 -275.19595)
			(xy 105.513246 -275.201882) (xy 105.464071 -275.199901) (xy 105.415852 -275.190057) (xy 105.369836 -275.172605)
			(xy 105.327215 -275.147998) (xy 105.289094 -275.116873) (xy 105.256459 -275.080036) (xy 105.230156 -275.03844)
			(xy 105.210865 -274.993164) (xy 105.199088 -274.94538) (xy 105.195128 -274.896326) (xy 104.86644 -274.896326)
			(xy 104.865945 -274.920933) (xy 104.85805 -274.96951) (xy 104.842466 -275.016191) (xy 104.819595 -275.059768)
			(xy 104.79003 -275.099112) (xy 104.754537 -275.133204) (xy 104.714034 -275.16116) (xy 104.669572 -275.182258)
			(xy 104.622301 -275.19595) (xy 104.573446 -275.201882) (xy 104.524271 -275.199901) (xy 104.476052 -275.190057)
			(xy 104.430036 -275.172605) (xy 104.387415 -275.147998) (xy 104.349294 -275.116873) (xy 104.316659 -275.080036)
			(xy 104.290356 -275.03844) (xy 104.271065 -274.993164) (xy 104.259288 -274.94538) (xy 104.255328 -274.896326)
			(xy 103.926386 -274.896326) (xy 103.925891 -274.920933) (xy 103.917996 -274.96951) (xy 103.902412 -275.016191)
			(xy 103.879541 -275.059768) (xy 103.849976 -275.099112) (xy 103.814483 -275.133204) (xy 103.77398 -275.16116)
			(xy 103.729518 -275.182258) (xy 103.682247 -275.19595) (xy 103.633392 -275.201882) (xy 103.584217 -275.199901)
			(xy 103.535998 -275.190057) (xy 103.489982 -275.172605) (xy 103.447361 -275.147998) (xy 103.40924 -275.116873)
			(xy 103.376605 -275.080036) (xy 103.350302 -275.03844) (xy 103.331011 -274.993164) (xy 103.319234 -274.94538)
			(xy 103.315274 -274.896326) (xy 102.986332 -274.896326) (xy 102.985837 -274.920933) (xy 102.977942 -274.96951)
			(xy 102.962358 -275.016191) (xy 102.939487 -275.059768) (xy 102.909922 -275.099112) (xy 102.874429 -275.133204)
			(xy 102.833926 -275.16116) (xy 102.789464 -275.182258) (xy 102.742193 -275.19595) (xy 102.693338 -275.201882)
			(xy 102.644163 -275.199901) (xy 102.595944 -275.190057) (xy 102.549928 -275.172605) (xy 102.507307 -275.147998)
			(xy 102.469186 -275.116873) (xy 102.436551 -275.080036) (xy 102.410248 -275.03844) (xy 102.390957 -274.993164)
			(xy 102.37918 -274.94538) (xy 102.37522 -274.896326) (xy 102.046278 -274.896326) (xy 102.045783 -274.920933)
			(xy 102.037888 -274.96951) (xy 102.022304 -275.016191) (xy 101.999433 -275.059768) (xy 101.969868 -275.099112)
			(xy 101.934375 -275.133204) (xy 101.893872 -275.16116) (xy 101.84941 -275.182258) (xy 101.802139 -275.19595)
			(xy 101.753284 -275.201882) (xy 101.704109 -275.199901) (xy 101.65589 -275.190057) (xy 101.609874 -275.172605)
			(xy 101.567253 -275.147998) (xy 101.529132 -275.116873) (xy 101.496497 -275.080036) (xy 101.470194 -275.03844)
			(xy 101.450903 -274.993164) (xy 101.439126 -274.94538) (xy 101.435166 -274.896326) (xy 101.106478 -274.896326)
			(xy 101.105983 -274.920933) (xy 101.098088 -274.96951) (xy 101.082504 -275.016191) (xy 101.059633 -275.059768)
			(xy 101.030068 -275.099112) (xy 100.994575 -275.133204) (xy 100.954072 -275.16116) (xy 100.90961 -275.182258)
			(xy 100.862339 -275.19595) (xy 100.813484 -275.201882) (xy 100.764309 -275.199901) (xy 100.71609 -275.190057)
			(xy 100.670074 -275.172605) (xy 100.627453 -275.147998) (xy 100.589332 -275.116873) (xy 100.556697 -275.080036)
			(xy 100.530394 -275.03844) (xy 100.511103 -274.993164) (xy 100.499326 -274.94538) (xy 100.495366 -274.896326)
			(xy 100.166424 -274.896326) (xy 100.165929 -274.920933) (xy 100.158034 -274.96951) (xy 100.14245 -275.016191)
			(xy 100.119579 -275.059768) (xy 100.090014 -275.099112) (xy 100.054521 -275.133204) (xy 100.014018 -275.16116)
			(xy 99.969556 -275.182258) (xy 99.922285 -275.19595) (xy 99.87343 -275.201882) (xy 99.824255 -275.199901)
			(xy 99.776036 -275.190057) (xy 99.73002 -275.172605) (xy 99.687399 -275.147998) (xy 99.649278 -275.116873)
			(xy 99.616643 -275.080036) (xy 99.59034 -275.03844) (xy 99.571049 -274.993164) (xy 99.559272 -274.94538)
			(xy 99.555312 -274.896326) (xy 99.22637 -274.896326) (xy 99.225875 -274.920933) (xy 99.21798 -274.96951)
			(xy 99.202396 -275.016191) (xy 99.179525 -275.059768) (xy 99.14996 -275.099112) (xy 99.114467 -275.133204)
			(xy 99.073964 -275.16116) (xy 99.029502 -275.182258) (xy 98.982231 -275.19595) (xy 98.933376 -275.201882)
			(xy 98.884201 -275.199901) (xy 98.835982 -275.190057) (xy 98.789966 -275.172605) (xy 98.747345 -275.147998)
			(xy 98.709224 -275.116873) (xy 98.676589 -275.080036) (xy 98.650286 -275.03844) (xy 98.630995 -274.993164)
			(xy 98.619218 -274.94538) (xy 98.615258 -274.896326) (xy 98.286316 -274.896326) (xy 98.285821 -274.920933)
			(xy 98.277926 -274.96951) (xy 98.262342 -275.016191) (xy 98.239471 -275.059768) (xy 98.209906 -275.099112)
			(xy 98.174413 -275.133204) (xy 98.13391 -275.16116) (xy 98.089448 -275.182258) (xy 98.042177 -275.19595)
			(xy 97.993322 -275.201882) (xy 97.944147 -275.199901) (xy 97.895928 -275.190057) (xy 97.849912 -275.172605)
			(xy 97.807291 -275.147998) (xy 97.76917 -275.116873) (xy 97.736535 -275.080036) (xy 97.710232 -275.03844)
			(xy 97.690941 -274.993164) (xy 97.679164 -274.94538) (xy 97.675204 -274.896326) (xy 97.346262 -274.896326)
			(xy 97.345767 -274.920933) (xy 97.337872 -274.96951) (xy 97.322288 -275.016191) (xy 97.299417 -275.059768)
			(xy 97.269852 -275.099112) (xy 97.234359 -275.133204) (xy 97.193856 -275.16116) (xy 97.149394 -275.182258)
			(xy 97.102123 -275.19595) (xy 97.053268 -275.201882) (xy 97.004093 -275.199901) (xy 96.955874 -275.190057)
			(xy 96.909858 -275.172605) (xy 96.867237 -275.147998) (xy 96.829116 -275.116873) (xy 96.796481 -275.080036)
			(xy 96.770178 -275.03844) (xy 96.750887 -274.993164) (xy 96.73911 -274.94538) (xy 96.73515 -274.896326)
			(xy 96.416876 -274.896326) (xy 96.416364 -274.921772) (xy 96.4082 -274.972006) (xy 96.392084 -275.02028)
			(xy 96.368433 -275.065343) (xy 96.33786 -275.106029) (xy 96.301156 -275.141284) (xy 96.259272 -275.170194)
			(xy 96.213293 -275.192011) (xy 96.164409 -275.206171) (xy 96.113888 -275.212305) (xy 96.063036 -275.210256)
			(xy 96.013172 -275.200076) (xy 95.965586 -275.182029) (xy 95.921512 -275.156583) (xy 95.88209 -275.124396)
			(xy 95.848342 -275.086302) (xy 95.821141 -275.043288) (xy 95.801193 -274.996468) (xy 95.789014 -274.947054)
			(xy 95.784919 -274.896326) (xy 95.466408 -274.896326) (xy 95.465913 -274.920933) (xy 95.458018 -274.96951)
			(xy 95.442434 -275.016191) (xy 95.419563 -275.059768) (xy 95.389998 -275.099112) (xy 95.354505 -275.133204)
			(xy 95.314002 -275.16116) (xy 95.26954 -275.182258) (xy 95.222269 -275.19595) (xy 95.173414 -275.201882)
			(xy 95.124239 -275.199901) (xy 95.07602 -275.190057) (xy 95.030004 -275.172605) (xy 94.987383 -275.147998)
			(xy 94.949262 -275.116873) (xy 94.916627 -275.080036) (xy 94.890324 -275.03844) (xy 94.871033 -274.993164)
			(xy 94.859256 -274.94538) (xy 94.855296 -274.896326) (xy 94.536768 -274.896326) (xy 94.536256 -274.921772)
			(xy 94.528092 -274.972006) (xy 94.511976 -275.02028) (xy 94.488325 -275.065343) (xy 94.457752 -275.106029)
			(xy 94.421048 -275.141284) (xy 94.379164 -275.170194) (xy 94.333185 -275.192011) (xy 94.284301 -275.206171)
			(xy 94.23378 -275.212305) (xy 94.182928 -275.210256) (xy 94.133064 -275.200076) (xy 94.085478 -275.182029)
			(xy 94.041404 -275.156583) (xy 94.001982 -275.124396) (xy 93.968234 -275.086302) (xy 93.941033 -275.043288)
			(xy 93.921085 -274.996468) (xy 93.908906 -274.947054) (xy 93.904811 -274.896326) (xy 93.5863 -274.896326)
			(xy 93.585832 -274.920174) (xy 93.5784 -274.967289) (xy 93.563735 -275.012676) (xy 93.542196 -275.055233)
			(xy 93.514304 -275.093925) (xy 93.480738 -275.127812) (xy 93.442313 -275.156071) (xy 93.399963 -275.178014)
			(xy 93.354718 -275.19311) (xy 93.331284 -275.19757) (xy 93.322648 -275.199094) (xy 93.294708 -275.219414)
			(xy 93.289837 -275.223169) (xy 93.281884 -275.232545) (xy 93.27896 -275.237956) (xy 93.248226 -275.30044)
			(xy 93.24721 -275.30298) (xy 93.243643 -275.312349) (xy 93.243389 -275.332379) (xy 93.246702 -275.341842)
			(xy 93.246956 -275.342604) (xy 93.250004 -275.348446) (xy 93.294708 -275.425408) (xy 93.30518 -275.443887)
			(xy 93.323618 -275.482154) (xy 93.331538 -275.501862) (xy 93.331538 -275.502116) (xy 93.334237 -275.508313)
			(xy 93.342354 -275.519115) (xy 93.34754 -275.523452) (xy 93.352874 -275.527516) (xy 93.365066 -275.53285)
			(xy 93.45803 -275.545042) (xy 93.464894 -275.545707) (xy 93.47854 -275.543766) (xy 93.484954 -275.541232)
			(xy 93.49098 -275.538429) (xy 93.501395 -275.530182) (xy 93.505528 -275.524976) (xy 93.505782 -275.524722)
			(xy 93.520286 -275.505892) (xy 93.554141 -275.472535) (xy 93.592754 -275.444824) (xy 93.635192 -275.423427)
			(xy 93.680432 -275.408861) (xy 93.727383 -275.401477) (xy 93.751146 -275.401024) (xy 93.776396 -275.401549)
			(xy 93.826207 -275.409868) (xy 93.873969 -275.426271) (xy 93.918381 -275.450311) (xy 93.95823 -275.481333)
			(xy 93.99243 -275.51849) (xy 94.020049 -275.560769) (xy 94.040333 -275.607016) (xy 94.052729 -275.655972)
			(xy 94.056899 -275.7063) (xy 94.056896 -275.706332) (xy 94.374711 -275.706332) (xy 94.378806 -275.655604)
			(xy 94.390985 -275.60619) (xy 94.410933 -275.55937) (xy 94.438134 -275.516356) (xy 94.471882 -275.478262)
			(xy 94.511304 -275.446075) (xy 94.555378 -275.420629) (xy 94.602964 -275.402582) (xy 94.652828 -275.392402)
			(xy 94.70368 -275.390353) (xy 94.754201 -275.396487) (xy 94.803085 -275.410647) (xy 94.849064 -275.432464)
			(xy 94.890948 -275.461374) (xy 94.927652 -275.496629) (xy 94.958225 -275.537315) (xy 94.981876 -275.582378)
			(xy 94.997992 -275.630652) (xy 95.006156 -275.680886) (xy 95.006668 -275.706332) (xy 95.314765 -275.706332)
			(xy 95.31886 -275.655604) (xy 95.331039 -275.60619) (xy 95.350987 -275.55937) (xy 95.378188 -275.516356)
			(xy 95.411936 -275.478262) (xy 95.451358 -275.446075) (xy 95.495432 -275.420629) (xy 95.543018 -275.402582)
			(xy 95.592882 -275.392402) (xy 95.643734 -275.390353) (xy 95.694255 -275.396487) (xy 95.743139 -275.410647)
			(xy 95.789118 -275.432464) (xy 95.831002 -275.461374) (xy 95.867706 -275.496629) (xy 95.898279 -275.537315)
			(xy 95.92193 -275.582378) (xy 95.938046 -275.630652) (xy 95.94621 -275.680886) (xy 95.946722 -275.706332)
			(xy 96.26525 -275.706332) (xy 96.26921 -275.657278) (xy 96.280987 -275.609494) (xy 96.300278 -275.564218)
			(xy 96.326581 -275.522622) (xy 96.359216 -275.485785) (xy 96.397337 -275.45466) (xy 96.439958 -275.430053)
			(xy 96.485974 -275.412601) (xy 96.534193 -275.402757) (xy 96.583368 -275.400776) (xy 96.632223 -275.406708)
			(xy 96.679494 -275.4204) (xy 96.723956 -275.441498) (xy 96.764459 -275.469454) (xy 96.799952 -275.503546)
			(xy 96.829517 -275.54289) (xy 96.852388 -275.586467) (xy 96.867972 -275.633148) (xy 96.875867 -275.681725)
			(xy 96.876362 -275.706332) (xy 99.085158 -275.706332) (xy 99.089118 -275.657278) (xy 99.100895 -275.609494)
			(xy 99.120186 -275.564218) (xy 99.146489 -275.522622) (xy 99.179124 -275.485785) (xy 99.217245 -275.45466)
			(xy 99.259866 -275.430053) (xy 99.305882 -275.412601) (xy 99.354101 -275.402757) (xy 99.403276 -275.400776)
			(xy 99.452131 -275.406708) (xy 99.499402 -275.4204) (xy 99.543864 -275.441498) (xy 99.584367 -275.469454)
			(xy 99.61986 -275.503546) (xy 99.649425 -275.54289) (xy 99.672296 -275.586467) (xy 99.68788 -275.633148)
			(xy 99.695775 -275.681725) (xy 99.69627 -275.706332) (xy 101.90532 -275.706332) (xy 101.90928 -275.657278)
			(xy 101.921057 -275.609494) (xy 101.940348 -275.564218) (xy 101.966651 -275.522622) (xy 101.999286 -275.485785)
			(xy 102.037407 -275.45466) (xy 102.080028 -275.430053) (xy 102.126044 -275.412601) (xy 102.174263 -275.402757)
			(xy 102.223438 -275.400776) (xy 102.272293 -275.406708) (xy 102.319564 -275.4204) (xy 102.364026 -275.441498)
			(xy 102.404529 -275.469454) (xy 102.440022 -275.503546) (xy 102.469587 -275.54289) (xy 102.492458 -275.586467)
			(xy 102.508042 -275.633148) (xy 102.515937 -275.681725) (xy 102.516432 -275.706332) (xy 104.725228 -275.706332)
			(xy 104.729188 -275.657278) (xy 104.740965 -275.609494) (xy 104.760256 -275.564218) (xy 104.786559 -275.522622)
			(xy 104.819194 -275.485785) (xy 104.857315 -275.45466) (xy 104.899936 -275.430053) (xy 104.945952 -275.412601)
			(xy 104.994171 -275.402757) (xy 105.043346 -275.400776) (xy 105.092201 -275.406708) (xy 105.139472 -275.4204)
			(xy 105.183934 -275.441498) (xy 105.224437 -275.469454) (xy 105.25993 -275.503546) (xy 105.289495 -275.54289)
			(xy 105.312366 -275.586467) (xy 105.32795 -275.633148) (xy 105.335845 -275.681725) (xy 105.33634 -275.706332)
			(xy 107.545136 -275.706332) (xy 107.549096 -275.657278) (xy 107.560873 -275.609494) (xy 107.580164 -275.564218)
			(xy 107.606467 -275.522622) (xy 107.639102 -275.485785) (xy 107.677223 -275.45466) (xy 107.719844 -275.430053)
			(xy 107.76586 -275.412601) (xy 107.814079 -275.402757) (xy 107.863254 -275.400776) (xy 107.912109 -275.406708)
			(xy 107.95938 -275.4204) (xy 108.003842 -275.441498) (xy 108.044345 -275.469454) (xy 108.079838 -275.503546)
			(xy 108.109403 -275.54289) (xy 108.132274 -275.586467) (xy 108.147858 -275.633148) (xy 108.155753 -275.681725)
			(xy 108.156248 -275.706332) (xy 108.48519 -275.706332) (xy 108.48915 -275.657278) (xy 108.500927 -275.609494)
			(xy 108.520218 -275.564218) (xy 108.546521 -275.522622) (xy 108.579156 -275.485785) (xy 108.617277 -275.45466)
			(xy 108.659898 -275.430053) (xy 108.705914 -275.412601) (xy 108.754133 -275.402757) (xy 108.803308 -275.400776)
			(xy 108.852163 -275.406708) (xy 108.899434 -275.4204) (xy 108.943896 -275.441498) (xy 108.984399 -275.469454)
			(xy 109.019892 -275.503546) (xy 109.049457 -275.54289) (xy 109.072328 -275.586467) (xy 109.087912 -275.633148)
			(xy 109.095807 -275.681725) (xy 109.096302 -275.706332) (xy 109.425244 -275.706332) (xy 109.429204 -275.657278)
			(xy 109.440981 -275.609494) (xy 109.460272 -275.564218) (xy 109.486575 -275.522622) (xy 109.51921 -275.485785)
			(xy 109.557331 -275.45466) (xy 109.599952 -275.430053) (xy 109.645968 -275.412601) (xy 109.694187 -275.402757)
			(xy 109.743362 -275.400776) (xy 109.792217 -275.406708) (xy 109.839488 -275.4204) (xy 109.88395 -275.441498)
			(xy 109.924453 -275.469454) (xy 109.959946 -275.503546) (xy 109.989511 -275.54289) (xy 110.012382 -275.586467)
			(xy 110.027966 -275.633148) (xy 110.035861 -275.681725) (xy 110.036356 -275.706332) (xy 110.365298 -275.706332)
			(xy 110.369258 -275.657278) (xy 110.381035 -275.609494) (xy 110.400326 -275.564218) (xy 110.426629 -275.522622)
			(xy 110.459264 -275.485785) (xy 110.497385 -275.45466) (xy 110.540006 -275.430053) (xy 110.586022 -275.412601)
			(xy 110.634241 -275.402757) (xy 110.683416 -275.400776) (xy 110.732271 -275.406708) (xy 110.779542 -275.4204)
			(xy 110.824004 -275.441498) (xy 110.864507 -275.469454) (xy 110.9 -275.503546) (xy 110.929565 -275.54289)
			(xy 110.952436 -275.586467) (xy 110.96802 -275.633148) (xy 110.975915 -275.681725) (xy 110.97641 -275.706332)
			(xy 113.178856 -275.706332) (xy 113.182816 -275.657278) (xy 113.194593 -275.609494) (xy 113.213884 -275.564218)
			(xy 113.240187 -275.522622) (xy 113.272822 -275.485785) (xy 113.310943 -275.45466) (xy 113.353564 -275.430053)
			(xy 113.39958 -275.412601) (xy 113.447799 -275.402757) (xy 113.496974 -275.400776) (xy 113.545829 -275.406708)
			(xy 113.5931 -275.4204) (xy 113.637562 -275.441498) (xy 113.678065 -275.469454) (xy 113.713558 -275.503546)
			(xy 113.743123 -275.54289) (xy 113.765994 -275.586467) (xy 113.781578 -275.633148) (xy 113.789473 -275.681725)
			(xy 113.789968 -275.706332) (xy 114.11891 -275.706332) (xy 114.12287 -275.657278) (xy 114.134647 -275.609494)
			(xy 114.153938 -275.564218) (xy 114.180241 -275.522622) (xy 114.212876 -275.485785) (xy 114.250997 -275.45466)
			(xy 114.293618 -275.430053) (xy 114.339634 -275.412601) (xy 114.387853 -275.402757) (xy 114.437028 -275.400776)
			(xy 114.485883 -275.406708) (xy 114.533154 -275.4204) (xy 114.577616 -275.441498) (xy 114.618119 -275.469454)
			(xy 114.653612 -275.503546) (xy 114.683177 -275.54289) (xy 114.706048 -275.586467) (xy 114.721632 -275.633148)
			(xy 114.729527 -275.681725) (xy 114.730022 -275.706332) (xy 115.058964 -275.706332) (xy 115.062924 -275.657278)
			(xy 115.074701 -275.609494) (xy 115.093992 -275.564218) (xy 115.120295 -275.522622) (xy 115.15293 -275.485785)
			(xy 115.191051 -275.45466) (xy 115.233672 -275.430053) (xy 115.279688 -275.412601) (xy 115.327907 -275.402757)
			(xy 115.377082 -275.400776) (xy 115.425937 -275.406708) (xy 115.473208 -275.4204) (xy 115.51767 -275.441498)
			(xy 115.558173 -275.469454) (xy 115.593666 -275.503546) (xy 115.623231 -275.54289) (xy 115.646102 -275.586467)
			(xy 115.661686 -275.633148) (xy 115.669581 -275.681725) (xy 115.670076 -275.706332) (xy 115.999018 -275.706332)
			(xy 116.002978 -275.657278) (xy 116.014755 -275.609494) (xy 116.034046 -275.564218) (xy 116.060349 -275.522622)
			(xy 116.092984 -275.485785) (xy 116.131105 -275.45466) (xy 116.173726 -275.430053) (xy 116.219742 -275.412601)
			(xy 116.267961 -275.402757) (xy 116.317136 -275.400776) (xy 116.365991 -275.406708) (xy 116.413262 -275.4204)
			(xy 116.457724 -275.441498) (xy 116.498227 -275.469454) (xy 116.53372 -275.503546) (xy 116.563285 -275.54289)
			(xy 116.586156 -275.586467) (xy 116.60174 -275.633148) (xy 116.609635 -275.681725) (xy 116.61013 -275.706332)
			(xy 118.818926 -275.706332) (xy 118.822886 -275.657278) (xy 118.834663 -275.609494) (xy 118.853954 -275.564218)
			(xy 118.880257 -275.522622) (xy 118.912892 -275.485785) (xy 118.951013 -275.45466) (xy 118.993634 -275.430053)
			(xy 119.03965 -275.412601) (xy 119.087869 -275.402757) (xy 119.137044 -275.400776) (xy 119.185899 -275.406708)
			(xy 119.23317 -275.4204) (xy 119.277632 -275.441498) (xy 119.318135 -275.469454) (xy 119.353628 -275.503546)
			(xy 119.383193 -275.54289) (xy 119.406064 -275.586467) (xy 119.421648 -275.633148) (xy 119.429543 -275.681725)
			(xy 119.430038 -275.706332) (xy 121.638834 -275.706332) (xy 121.642794 -275.657278) (xy 121.654571 -275.609494)
			(xy 121.673862 -275.564218) (xy 121.700165 -275.522622) (xy 121.7328 -275.485785) (xy 121.770921 -275.45466)
			(xy 121.813542 -275.430053) (xy 121.859558 -275.412601) (xy 121.907777 -275.402757) (xy 121.956952 -275.400776)
			(xy 122.005807 -275.406708) (xy 122.053078 -275.4204) (xy 122.09754 -275.441498) (xy 122.138043 -275.469454)
			(xy 122.173536 -275.503546) (xy 122.203101 -275.54289) (xy 122.225972 -275.586467) (xy 122.241556 -275.633148)
			(xy 122.249451 -275.681725) (xy 122.249946 -275.706332) (xy 124.458996 -275.706332) (xy 124.462956 -275.657278)
			(xy 124.474733 -275.609494) (xy 124.494024 -275.564218) (xy 124.520327 -275.522622) (xy 124.552962 -275.485785)
			(xy 124.591083 -275.45466) (xy 124.633704 -275.430053) (xy 124.67972 -275.412601) (xy 124.727939 -275.402757)
			(xy 124.777114 -275.400776) (xy 124.825969 -275.406708) (xy 124.87324 -275.4204) (xy 124.917702 -275.441498)
			(xy 124.958205 -275.469454) (xy 124.993698 -275.503546) (xy 125.023263 -275.54289) (xy 125.046134 -275.586467)
			(xy 125.061718 -275.633148) (xy 125.069613 -275.681725) (xy 125.070108 -275.706332) (xy 125.069613 -275.730939)
			(xy 125.061718 -275.779516) (xy 125.046134 -275.826197) (xy 125.023263 -275.869774) (xy 124.993698 -275.909118)
			(xy 124.958205 -275.94321) (xy 124.917702 -275.971166) (xy 124.87324 -275.992264) (xy 124.825969 -276.005956)
			(xy 124.777114 -276.011888) (xy 124.727939 -276.009907) (xy 124.67972 -276.000063) (xy 124.633704 -275.982611)
			(xy 124.591083 -275.958004) (xy 124.552962 -275.926879) (xy 124.520327 -275.890042) (xy 124.494024 -275.848446)
			(xy 124.474733 -275.80317) (xy 124.462956 -275.755386) (xy 124.458996 -275.706332) (xy 122.249946 -275.706332)
			(xy 122.249451 -275.730939) (xy 122.241556 -275.779516) (xy 122.225972 -275.826197) (xy 122.203101 -275.869774)
			(xy 122.173536 -275.909118) (xy 122.138043 -275.94321) (xy 122.09754 -275.971166) (xy 122.053078 -275.992264)
			(xy 122.005807 -276.005956) (xy 121.956952 -276.011888) (xy 121.907777 -276.009907) (xy 121.859558 -276.000063)
			(xy 121.813542 -275.982611) (xy 121.770921 -275.958004) (xy 121.7328 -275.926879) (xy 121.700165 -275.890042)
			(xy 121.673862 -275.848446) (xy 121.654571 -275.80317) (xy 121.642794 -275.755386) (xy 121.638834 -275.706332)
			(xy 119.430038 -275.706332) (xy 119.429543 -275.730939) (xy 119.421648 -275.779516) (xy 119.406064 -275.826197)
			(xy 119.383193 -275.869774) (xy 119.353628 -275.909118) (xy 119.318135 -275.94321) (xy 119.277632 -275.971166)
			(xy 119.23317 -275.992264) (xy 119.185899 -276.005956) (xy 119.137044 -276.011888) (xy 119.087869 -276.009907)
			(xy 119.03965 -276.000063) (xy 118.993634 -275.982611) (xy 118.951013 -275.958004) (xy 118.912892 -275.926879)
			(xy 118.880257 -275.890042) (xy 118.853954 -275.848446) (xy 118.834663 -275.80317) (xy 118.822886 -275.755386)
			(xy 118.818926 -275.706332) (xy 116.61013 -275.706332) (xy 116.609635 -275.730939) (xy 116.60174 -275.779516)
			(xy 116.586156 -275.826197) (xy 116.563285 -275.869774) (xy 116.53372 -275.909118) (xy 116.498227 -275.94321)
			(xy 116.457724 -275.971166) (xy 116.413262 -275.992264) (xy 116.365991 -276.005956) (xy 116.317136 -276.011888)
			(xy 116.267961 -276.009907) (xy 116.219742 -276.000063) (xy 116.173726 -275.982611) (xy 116.131105 -275.958004)
			(xy 116.092984 -275.926879) (xy 116.060349 -275.890042) (xy 116.034046 -275.848446) (xy 116.014755 -275.80317)
			(xy 116.002978 -275.755386) (xy 115.999018 -275.706332) (xy 115.670076 -275.706332) (xy 115.669581 -275.730939)
			(xy 115.661686 -275.779516) (xy 115.646102 -275.826197) (xy 115.623231 -275.869774) (xy 115.593666 -275.909118)
			(xy 115.558173 -275.94321) (xy 115.51767 -275.971166) (xy 115.473208 -275.992264) (xy 115.425937 -276.005956)
			(xy 115.377082 -276.011888) (xy 115.327907 -276.009907) (xy 115.279688 -276.000063) (xy 115.233672 -275.982611)
			(xy 115.191051 -275.958004) (xy 115.15293 -275.926879) (xy 115.120295 -275.890042) (xy 115.093992 -275.848446)
			(xy 115.074701 -275.80317) (xy 115.062924 -275.755386) (xy 115.058964 -275.706332) (xy 114.730022 -275.706332)
			(xy 114.729527 -275.730939) (xy 114.721632 -275.779516) (xy 114.706048 -275.826197) (xy 114.683177 -275.869774)
			(xy 114.653612 -275.909118) (xy 114.618119 -275.94321) (xy 114.577616 -275.971166) (xy 114.533154 -275.992264)
			(xy 114.485883 -276.005956) (xy 114.437028 -276.011888) (xy 114.387853 -276.009907) (xy 114.339634 -276.000063)
			(xy 114.293618 -275.982611) (xy 114.250997 -275.958004) (xy 114.212876 -275.926879) (xy 114.180241 -275.890042)
			(xy 114.153938 -275.848446) (xy 114.134647 -275.80317) (xy 114.12287 -275.755386) (xy 114.11891 -275.706332)
			(xy 113.789968 -275.706332) (xy 113.789473 -275.730939) (xy 113.781578 -275.779516) (xy 113.765994 -275.826197)
			(xy 113.743123 -275.869774) (xy 113.713558 -275.909118) (xy 113.678065 -275.94321) (xy 113.637562 -275.971166)
			(xy 113.5931 -275.992264) (xy 113.545829 -276.005956) (xy 113.496974 -276.011888) (xy 113.447799 -276.009907)
			(xy 113.39958 -276.000063) (xy 113.353564 -275.982611) (xy 113.310943 -275.958004) (xy 113.272822 -275.926879)
			(xy 113.240187 -275.890042) (xy 113.213884 -275.848446) (xy 113.194593 -275.80317) (xy 113.182816 -275.755386)
			(xy 113.178856 -275.706332) (xy 110.97641 -275.706332) (xy 110.975915 -275.730939) (xy 110.96802 -275.779516)
			(xy 110.952436 -275.826197) (xy 110.929565 -275.869774) (xy 110.9 -275.909118) (xy 110.864507 -275.94321)
			(xy 110.824004 -275.971166) (xy 110.779542 -275.992264) (xy 110.732271 -276.005956) (xy 110.683416 -276.011888)
			(xy 110.634241 -276.009907) (xy 110.586022 -276.000063) (xy 110.540006 -275.982611) (xy 110.497385 -275.958004)
			(xy 110.459264 -275.926879) (xy 110.426629 -275.890042) (xy 110.400326 -275.848446) (xy 110.381035 -275.80317)
			(xy 110.369258 -275.755386) (xy 110.365298 -275.706332) (xy 110.036356 -275.706332) (xy 110.035861 -275.730939)
			(xy 110.027966 -275.779516) (xy 110.012382 -275.826197) (xy 109.989511 -275.869774) (xy 109.959946 -275.909118)
			(xy 109.924453 -275.94321) (xy 109.88395 -275.971166) (xy 109.839488 -275.992264) (xy 109.792217 -276.005956)
			(xy 109.743362 -276.011888) (xy 109.694187 -276.009907) (xy 109.645968 -276.000063) (xy 109.599952 -275.982611)
			(xy 109.557331 -275.958004) (xy 109.51921 -275.926879) (xy 109.486575 -275.890042) (xy 109.460272 -275.848446)
			(xy 109.440981 -275.80317) (xy 109.429204 -275.755386) (xy 109.425244 -275.706332) (xy 109.096302 -275.706332)
			(xy 109.095807 -275.730939) (xy 109.087912 -275.779516) (xy 109.072328 -275.826197) (xy 109.049457 -275.869774)
			(xy 109.019892 -275.909118) (xy 108.984399 -275.94321) (xy 108.943896 -275.971166) (xy 108.899434 -275.992264)
			(xy 108.852163 -276.005956) (xy 108.803308 -276.011888) (xy 108.754133 -276.009907) (xy 108.705914 -276.000063)
			(xy 108.659898 -275.982611) (xy 108.617277 -275.958004) (xy 108.579156 -275.926879) (xy 108.546521 -275.890042)
			(xy 108.520218 -275.848446) (xy 108.500927 -275.80317) (xy 108.48915 -275.755386) (xy 108.48519 -275.706332)
			(xy 108.156248 -275.706332) (xy 108.155753 -275.730939) (xy 108.147858 -275.779516) (xy 108.132274 -275.826197)
			(xy 108.109403 -275.869774) (xy 108.079838 -275.909118) (xy 108.044345 -275.94321) (xy 108.003842 -275.971166)
			(xy 107.95938 -275.992264) (xy 107.912109 -276.005956) (xy 107.863254 -276.011888) (xy 107.814079 -276.009907)
			(xy 107.76586 -276.000063) (xy 107.719844 -275.982611) (xy 107.677223 -275.958004) (xy 107.639102 -275.926879)
			(xy 107.606467 -275.890042) (xy 107.580164 -275.848446) (xy 107.560873 -275.80317) (xy 107.549096 -275.755386)
			(xy 107.545136 -275.706332) (xy 105.33634 -275.706332) (xy 105.335845 -275.730939) (xy 105.32795 -275.779516)
			(xy 105.312366 -275.826197) (xy 105.289495 -275.869774) (xy 105.25993 -275.909118) (xy 105.224437 -275.94321)
			(xy 105.183934 -275.971166) (xy 105.139472 -275.992264) (xy 105.092201 -276.005956) (xy 105.043346 -276.011888)
			(xy 104.994171 -276.009907) (xy 104.945952 -276.000063) (xy 104.899936 -275.982611) (xy 104.857315 -275.958004)
			(xy 104.819194 -275.926879) (xy 104.786559 -275.890042) (xy 104.760256 -275.848446) (xy 104.740965 -275.80317)
			(xy 104.729188 -275.755386) (xy 104.725228 -275.706332) (xy 102.516432 -275.706332) (xy 102.515937 -275.730939)
			(xy 102.508042 -275.779516) (xy 102.492458 -275.826197) (xy 102.469587 -275.869774) (xy 102.440022 -275.909118)
			(xy 102.404529 -275.94321) (xy 102.364026 -275.971166) (xy 102.319564 -275.992264) (xy 102.272293 -276.005956)
			(xy 102.223438 -276.011888) (xy 102.174263 -276.009907) (xy 102.126044 -276.000063) (xy 102.080028 -275.982611)
			(xy 102.037407 -275.958004) (xy 101.999286 -275.926879) (xy 101.966651 -275.890042) (xy 101.940348 -275.848446)
			(xy 101.921057 -275.80317) (xy 101.90928 -275.755386) (xy 101.90532 -275.706332) (xy 99.69627 -275.706332)
			(xy 99.695775 -275.730939) (xy 99.68788 -275.779516) (xy 99.672296 -275.826197) (xy 99.649425 -275.869774)
			(xy 99.61986 -275.909118) (xy 99.584367 -275.94321) (xy 99.543864 -275.971166) (xy 99.499402 -275.992264)
			(xy 99.452131 -276.005956) (xy 99.403276 -276.011888) (xy 99.354101 -276.009907) (xy 99.305882 -276.000063)
			(xy 99.259866 -275.982611) (xy 99.217245 -275.958004) (xy 99.179124 -275.926879) (xy 99.146489 -275.890042)
			(xy 99.120186 -275.848446) (xy 99.100895 -275.80317) (xy 99.089118 -275.755386) (xy 99.085158 -275.706332)
			(xy 96.876362 -275.706332) (xy 96.875867 -275.730939) (xy 96.867972 -275.779516) (xy 96.852388 -275.826197)
			(xy 96.829517 -275.869774) (xy 96.799952 -275.909118) (xy 96.764459 -275.94321) (xy 96.723956 -275.971166)
			(xy 96.679494 -275.992264) (xy 96.632223 -276.005956) (xy 96.583368 -276.011888) (xy 96.534193 -276.009907)
			(xy 96.485974 -276.000063) (xy 96.439958 -275.982611) (xy 96.397337 -275.958004) (xy 96.359216 -275.926879)
			(xy 96.326581 -275.890042) (xy 96.300278 -275.848446) (xy 96.280987 -275.80317) (xy 96.26921 -275.755386)
			(xy 96.26525 -275.706332) (xy 95.946722 -275.706332) (xy 95.94621 -275.731778) (xy 95.938046 -275.782012)
			(xy 95.92193 -275.830286) (xy 95.898279 -275.875349) (xy 95.867706 -275.916035) (xy 95.831002 -275.95129)
			(xy 95.789118 -275.9802) (xy 95.743139 -276.002017) (xy 95.694255 -276.016177) (xy 95.643734 -276.022311)
			(xy 95.592882 -276.020262) (xy 95.543018 -276.010082) (xy 95.495432 -275.992035) (xy 95.451358 -275.966589)
			(xy 95.411936 -275.934402) (xy 95.378188 -275.896308) (xy 95.350987 -275.853294) (xy 95.331039 -275.806474)
			(xy 95.31886 -275.75706) (xy 95.314765 -275.706332) (xy 95.006668 -275.706332) (xy 95.006156 -275.731778)
			(xy 94.997992 -275.782012) (xy 94.981876 -275.830286) (xy 94.958225 -275.875349) (xy 94.927652 -275.916035)
			(xy 94.890948 -275.95129) (xy 94.849064 -275.9802) (xy 94.803085 -276.002017) (xy 94.754201 -276.016177)
			(xy 94.70368 -276.022311) (xy 94.652828 -276.020262) (xy 94.602964 -276.010082) (xy 94.555378 -275.992035)
			(xy 94.511304 -275.966589) (xy 94.471882 -275.934402) (xy 94.438134 -275.896308) (xy 94.410933 -275.853294)
			(xy 94.390985 -275.806474) (xy 94.378806 -275.75706) (xy 94.374711 -275.706332) (xy 94.056896 -275.706332)
			(xy 94.052729 -275.756628) (xy 94.040333 -275.805584) (xy 94.020049 -275.851831) (xy 93.99243 -275.89411)
			(xy 93.95823 -275.931267) (xy 93.918381 -275.962289) (xy 93.873969 -275.986329) (xy 93.826207 -276.002732)
			(xy 93.776396 -276.011051) (xy 93.751146 -276.01164) (xy 93.72738 -276.01119) (xy 93.680422 -276.003827)
			(xy 93.635174 -275.989272) (xy 93.592729 -275.967876) (xy 93.554116 -275.940158) (xy 93.520268 -275.906788)
			(xy 93.505782 -275.887942) (xy 93.505782 -275.887688) (xy 93.505528 -275.887688) (xy 93.501373 -275.882506)
			(xy 93.490959 -275.874269) (xy 93.484954 -275.871432) (xy 93.478545 -275.868885) (xy 93.464895 -275.866964)
			(xy 93.45803 -275.867622) (xy 93.372178 -275.879052) (xy 93.365418 -275.880127) (xy 93.352796 -275.885406)
			(xy 93.347286 -275.889466) (xy 93.341952 -275.89353) (xy 93.334078 -275.904198) (xy 93.331538 -275.910802)
			(xy 93.315991 -275.948475) (xy 93.275573 -276.019243) (xy 93.25102 -276.051772) (xy 93.25102 -276.052026)
			(xy 93.246984 -276.057429) (xy 93.241574 -276.069778) (xy 93.240352 -276.07641) (xy 93.238574 -276.089618)
			(xy 93.276928 -276.182328) (xy 93.279681 -276.188493) (xy 93.287919 -276.199184) (xy 93.293184 -276.20341)
			(xy 93.298518 -276.207474) (xy 93.31071 -276.2123) (xy 93.317822 -276.213316) (xy 93.34218 -276.216781)
			(xy 93.38943 -276.230484) (xy 93.433871 -276.251586) (xy 93.474353 -276.279541) (xy 93.50983 -276.313625)
			(xy 93.539382 -276.352957) (xy 93.562245 -276.396518) (xy 93.577827 -276.443181) (xy 93.585725 -276.49174)
			(xy 93.5863 -276.516338) (xy 93.904811 -276.516338) (xy 93.908906 -276.46561) (xy 93.921085 -276.416196)
			(xy 93.941033 -276.369376) (xy 93.968234 -276.326362) (xy 94.001982 -276.288268) (xy 94.041404 -276.256081)
			(xy 94.085478 -276.230635) (xy 94.133064 -276.212588) (xy 94.182928 -276.202408) (xy 94.23378 -276.200359)
			(xy 94.284301 -276.206493) (xy 94.333185 -276.220653) (xy 94.379164 -276.24247) (xy 94.421048 -276.27138)
			(xy 94.457752 -276.306635) (xy 94.488325 -276.347321) (xy 94.511976 -276.392384) (xy 94.528092 -276.440658)
			(xy 94.536256 -276.490892) (xy 94.536768 -276.516338) (xy 94.855296 -276.516338) (xy 94.859256 -276.467284)
			(xy 94.871033 -276.4195) (xy 94.890324 -276.374224) (xy 94.916627 -276.332628) (xy 94.949262 -276.295791)
			(xy 94.987383 -276.264666) (xy 95.030004 -276.240059) (xy 95.07602 -276.222607) (xy 95.124239 -276.212763)
			(xy 95.173414 -276.210782) (xy 95.222269 -276.216714) (xy 95.26954 -276.230406) (xy 95.314002 -276.251504)
			(xy 95.354505 -276.27946) (xy 95.389998 -276.313552) (xy 95.419563 -276.352896) (xy 95.442434 -276.396473)
			(xy 95.458018 -276.443154) (xy 95.465913 -276.491731) (xy 95.466408 -276.516338) (xy 95.784919 -276.516338)
			(xy 95.789014 -276.46561) (xy 95.801193 -276.416196) (xy 95.821141 -276.369376) (xy 95.848342 -276.326362)
			(xy 95.88209 -276.288268) (xy 95.921512 -276.256081) (xy 95.965586 -276.230635) (xy 96.013172 -276.212588)
			(xy 96.063036 -276.202408) (xy 96.113888 -276.200359) (xy 96.164409 -276.206493) (xy 96.213293 -276.220653)
			(xy 96.259272 -276.24247) (xy 96.301156 -276.27138) (xy 96.33786 -276.306635) (xy 96.368433 -276.347321)
			(xy 96.392084 -276.392384) (xy 96.4082 -276.440658) (xy 96.416364 -276.490892) (xy 96.416876 -276.516338)
			(xy 96.73515 -276.516338) (xy 96.73911 -276.467284) (xy 96.750887 -276.4195) (xy 96.770178 -276.374224)
			(xy 96.796481 -276.332628) (xy 96.829116 -276.295791) (xy 96.867237 -276.264666) (xy 96.909858 -276.240059)
			(xy 96.955874 -276.222607) (xy 97.004093 -276.212763) (xy 97.053268 -276.210782) (xy 97.102123 -276.216714)
			(xy 97.149394 -276.230406) (xy 97.193856 -276.251504) (xy 97.234359 -276.27946) (xy 97.269852 -276.313552)
			(xy 97.299417 -276.352896) (xy 97.322288 -276.396473) (xy 97.337872 -276.443154) (xy 97.345767 -276.491731)
			(xy 97.346262 -276.516338) (xy 97.675204 -276.516338) (xy 97.679164 -276.467284) (xy 97.690941 -276.4195)
			(xy 97.710232 -276.374224) (xy 97.736535 -276.332628) (xy 97.76917 -276.295791) (xy 97.807291 -276.264666)
			(xy 97.849912 -276.240059) (xy 97.895928 -276.222607) (xy 97.944147 -276.212763) (xy 97.993322 -276.210782)
			(xy 98.042177 -276.216714) (xy 98.089448 -276.230406) (xy 98.13391 -276.251504) (xy 98.174413 -276.27946)
			(xy 98.209906 -276.313552) (xy 98.239471 -276.352896) (xy 98.262342 -276.396473) (xy 98.277926 -276.443154)
			(xy 98.285821 -276.491731) (xy 98.286316 -276.516338) (xy 98.615258 -276.516338) (xy 98.619218 -276.467284)
			(xy 98.630995 -276.4195) (xy 98.650286 -276.374224) (xy 98.676589 -276.332628) (xy 98.709224 -276.295791)
			(xy 98.747345 -276.264666) (xy 98.789966 -276.240059) (xy 98.835982 -276.222607) (xy 98.884201 -276.212763)
			(xy 98.933376 -276.210782) (xy 98.982231 -276.216714) (xy 99.029502 -276.230406) (xy 99.073964 -276.251504)
			(xy 99.114467 -276.27946) (xy 99.14996 -276.313552) (xy 99.179525 -276.352896) (xy 99.202396 -276.396473)
			(xy 99.21798 -276.443154) (xy 99.225875 -276.491731) (xy 99.22637 -276.516338) (xy 99.555312 -276.516338)
			(xy 99.559272 -276.467284) (xy 99.571049 -276.4195) (xy 99.59034 -276.374224) (xy 99.616643 -276.332628)
			(xy 99.649278 -276.295791) (xy 99.687399 -276.264666) (xy 99.73002 -276.240059) (xy 99.776036 -276.222607)
			(xy 99.824255 -276.212763) (xy 99.87343 -276.210782) (xy 99.922285 -276.216714) (xy 99.969556 -276.230406)
			(xy 100.014018 -276.251504) (xy 100.054521 -276.27946) (xy 100.090014 -276.313552) (xy 100.119579 -276.352896)
			(xy 100.14245 -276.396473) (xy 100.158034 -276.443154) (xy 100.165929 -276.491731) (xy 100.166424 -276.516338)
			(xy 100.495366 -276.516338) (xy 100.499326 -276.467284) (xy 100.511103 -276.4195) (xy 100.530394 -276.374224)
			(xy 100.556697 -276.332628) (xy 100.589332 -276.295791) (xy 100.627453 -276.264666) (xy 100.670074 -276.240059)
			(xy 100.71609 -276.222607) (xy 100.764309 -276.212763) (xy 100.813484 -276.210782) (xy 100.862339 -276.216714)
			(xy 100.90961 -276.230406) (xy 100.954072 -276.251504) (xy 100.994575 -276.27946) (xy 101.030068 -276.313552)
			(xy 101.059633 -276.352896) (xy 101.082504 -276.396473) (xy 101.098088 -276.443154) (xy 101.105983 -276.491731)
			(xy 101.106478 -276.516338) (xy 101.435166 -276.516338) (xy 101.439126 -276.467284) (xy 101.450903 -276.4195)
			(xy 101.470194 -276.374224) (xy 101.496497 -276.332628) (xy 101.529132 -276.295791) (xy 101.567253 -276.264666)
			(xy 101.609874 -276.240059) (xy 101.65589 -276.222607) (xy 101.704109 -276.212763) (xy 101.753284 -276.210782)
			(xy 101.802139 -276.216714) (xy 101.84941 -276.230406) (xy 101.893872 -276.251504) (xy 101.934375 -276.27946)
			(xy 101.969868 -276.313552) (xy 101.999433 -276.352896) (xy 102.022304 -276.396473) (xy 102.037888 -276.443154)
			(xy 102.045783 -276.491731) (xy 102.046278 -276.516338) (xy 102.37522 -276.516338) (xy 102.37918 -276.467284)
			(xy 102.390957 -276.4195) (xy 102.410248 -276.374224) (xy 102.436551 -276.332628) (xy 102.469186 -276.295791)
			(xy 102.507307 -276.264666) (xy 102.549928 -276.240059) (xy 102.595944 -276.222607) (xy 102.644163 -276.212763)
			(xy 102.693338 -276.210782) (xy 102.742193 -276.216714) (xy 102.789464 -276.230406) (xy 102.833926 -276.251504)
			(xy 102.874429 -276.27946) (xy 102.909922 -276.313552) (xy 102.939487 -276.352896) (xy 102.962358 -276.396473)
			(xy 102.977942 -276.443154) (xy 102.985837 -276.491731) (xy 102.986332 -276.516338) (xy 103.315274 -276.516338)
			(xy 103.319234 -276.467284) (xy 103.331011 -276.4195) (xy 103.350302 -276.374224) (xy 103.376605 -276.332628)
			(xy 103.40924 -276.295791) (xy 103.447361 -276.264666) (xy 103.489982 -276.240059) (xy 103.535998 -276.222607)
			(xy 103.584217 -276.212763) (xy 103.633392 -276.210782) (xy 103.682247 -276.216714) (xy 103.729518 -276.230406)
			(xy 103.77398 -276.251504) (xy 103.814483 -276.27946) (xy 103.849976 -276.313552) (xy 103.879541 -276.352896)
			(xy 103.902412 -276.396473) (xy 103.917996 -276.443154) (xy 103.925891 -276.491731) (xy 103.926386 -276.516338)
			(xy 104.255328 -276.516338) (xy 104.259288 -276.467284) (xy 104.271065 -276.4195) (xy 104.290356 -276.374224)
			(xy 104.316659 -276.332628) (xy 104.349294 -276.295791) (xy 104.387415 -276.264666) (xy 104.430036 -276.240059)
			(xy 104.476052 -276.222607) (xy 104.524271 -276.212763) (xy 104.573446 -276.210782) (xy 104.622301 -276.216714)
			(xy 104.669572 -276.230406) (xy 104.714034 -276.251504) (xy 104.754537 -276.27946) (xy 104.79003 -276.313552)
			(xy 104.819595 -276.352896) (xy 104.842466 -276.396473) (xy 104.85805 -276.443154) (xy 104.865945 -276.491731)
			(xy 104.86644 -276.516338) (xy 105.195128 -276.516338) (xy 105.199088 -276.467284) (xy 105.210865 -276.4195)
			(xy 105.230156 -276.374224) (xy 105.256459 -276.332628) (xy 105.289094 -276.295791) (xy 105.327215 -276.264666)
			(xy 105.369836 -276.240059) (xy 105.415852 -276.222607) (xy 105.464071 -276.212763) (xy 105.513246 -276.210782)
			(xy 105.562101 -276.216714) (xy 105.609372 -276.230406) (xy 105.653834 -276.251504) (xy 105.694337 -276.27946)
			(xy 105.72983 -276.313552) (xy 105.759395 -276.352896) (xy 105.782266 -276.396473) (xy 105.79785 -276.443154)
			(xy 105.805745 -276.491731) (xy 105.80624 -276.516338) (xy 106.135182 -276.516338) (xy 106.139142 -276.467284)
			(xy 106.150919 -276.4195) (xy 106.17021 -276.374224) (xy 106.196513 -276.332628) (xy 106.229148 -276.295791)
			(xy 106.267269 -276.264666) (xy 106.30989 -276.240059) (xy 106.355906 -276.222607) (xy 106.404125 -276.212763)
			(xy 106.4533 -276.210782) (xy 106.502155 -276.216714) (xy 106.549426 -276.230406) (xy 106.593888 -276.251504)
			(xy 106.634391 -276.27946) (xy 106.669884 -276.313552) (xy 106.699449 -276.352896) (xy 106.72232 -276.396473)
			(xy 106.737904 -276.443154) (xy 106.745799 -276.491731) (xy 106.746294 -276.516338) (xy 107.075236 -276.516338)
			(xy 107.079196 -276.467284) (xy 107.090973 -276.4195) (xy 107.110264 -276.374224) (xy 107.136567 -276.332628)
			(xy 107.169202 -276.295791) (xy 107.207323 -276.264666) (xy 107.249944 -276.240059) (xy 107.29596 -276.222607)
			(xy 107.344179 -276.212763) (xy 107.393354 -276.210782) (xy 107.442209 -276.216714) (xy 107.48948 -276.230406)
			(xy 107.533942 -276.251504) (xy 107.574445 -276.27946) (xy 107.609938 -276.313552) (xy 107.639503 -276.352896)
			(xy 107.662374 -276.396473) (xy 107.677958 -276.443154) (xy 107.685853 -276.491731) (xy 107.686348 -276.516338)
			(xy 108.01529 -276.516338) (xy 108.01925 -276.467284) (xy 108.031027 -276.4195) (xy 108.050318 -276.374224)
			(xy 108.076621 -276.332628) (xy 108.109256 -276.295791) (xy 108.147377 -276.264666) (xy 108.189998 -276.240059)
			(xy 108.236014 -276.222607) (xy 108.284233 -276.212763) (xy 108.333408 -276.210782) (xy 108.382263 -276.216714)
			(xy 108.429534 -276.230406) (xy 108.473996 -276.251504) (xy 108.514499 -276.27946) (xy 108.549992 -276.313552)
			(xy 108.579557 -276.352896) (xy 108.602428 -276.396473) (xy 108.618012 -276.443154) (xy 108.625907 -276.491731)
			(xy 108.626402 -276.516338) (xy 108.955344 -276.516338) (xy 108.959304 -276.467284) (xy 108.971081 -276.4195)
			(xy 108.990372 -276.374224) (xy 109.016675 -276.332628) (xy 109.04931 -276.295791) (xy 109.087431 -276.264666)
			(xy 109.130052 -276.240059) (xy 109.176068 -276.222607) (xy 109.224287 -276.212763) (xy 109.273462 -276.210782)
			(xy 109.322317 -276.216714) (xy 109.369588 -276.230406) (xy 109.41405 -276.251504) (xy 109.454553 -276.27946)
			(xy 109.490046 -276.313552) (xy 109.519611 -276.352896) (xy 109.542482 -276.396473) (xy 109.558066 -276.443154)
			(xy 109.565961 -276.491731) (xy 109.566456 -276.516338) (xy 109.895144 -276.516338) (xy 109.899104 -276.467284)
			(xy 109.910881 -276.4195) (xy 109.930172 -276.374224) (xy 109.956475 -276.332628) (xy 109.98911 -276.295791)
			(xy 110.027231 -276.264666) (xy 110.069852 -276.240059) (xy 110.115868 -276.222607) (xy 110.164087 -276.212763)
			(xy 110.213262 -276.210782) (xy 110.262117 -276.216714) (xy 110.309388 -276.230406) (xy 110.35385 -276.251504)
			(xy 110.394353 -276.27946) (xy 110.429846 -276.313552) (xy 110.459411 -276.352896) (xy 110.482282 -276.396473)
			(xy 110.497866 -276.443154) (xy 110.505761 -276.491731) (xy 110.506256 -276.516338) (xy 113.64901 -276.516338)
			(xy 113.65297 -276.467284) (xy 113.664747 -276.4195) (xy 113.684038 -276.374224) (xy 113.710341 -276.332628)
			(xy 113.742976 -276.295791) (xy 113.781097 -276.264666) (xy 113.823718 -276.240059) (xy 113.869734 -276.222607)
			(xy 113.917953 -276.212763) (xy 113.967128 -276.210782) (xy 114.015983 -276.216714) (xy 114.063254 -276.230406)
			(xy 114.107716 -276.251504) (xy 114.148219 -276.27946) (xy 114.183712 -276.313552) (xy 114.213277 -276.352896)
			(xy 114.236148 -276.396473) (xy 114.251732 -276.443154) (xy 114.259627 -276.491731) (xy 114.260122 -276.516338)
			(xy 114.58881 -276.516338) (xy 114.59277 -276.467284) (xy 114.604547 -276.4195) (xy 114.623838 -276.374224)
			(xy 114.650141 -276.332628) (xy 114.682776 -276.295791) (xy 114.720897 -276.264666) (xy 114.763518 -276.240059)
			(xy 114.809534 -276.222607) (xy 114.857753 -276.212763) (xy 114.906928 -276.210782) (xy 114.955783 -276.216714)
			(xy 115.003054 -276.230406) (xy 115.047516 -276.251504) (xy 115.088019 -276.27946) (xy 115.123512 -276.313552)
			(xy 115.153077 -276.352896) (xy 115.175948 -276.396473) (xy 115.191532 -276.443154) (xy 115.199427 -276.491731)
			(xy 115.199922 -276.516338) (xy 115.528864 -276.516338) (xy 115.532824 -276.467284) (xy 115.544601 -276.4195)
			(xy 115.563892 -276.374224) (xy 115.590195 -276.332628) (xy 115.62283 -276.295791) (xy 115.660951 -276.264666)
			(xy 115.703572 -276.240059) (xy 115.749588 -276.222607) (xy 115.797807 -276.212763) (xy 115.846982 -276.210782)
			(xy 115.895837 -276.216714) (xy 115.943108 -276.230406) (xy 115.98757 -276.251504) (xy 116.028073 -276.27946)
			(xy 116.063566 -276.313552) (xy 116.093131 -276.352896) (xy 116.116002 -276.396473) (xy 116.131586 -276.443154)
			(xy 116.139481 -276.491731) (xy 116.139976 -276.516338) (xy 116.468918 -276.516338) (xy 116.472878 -276.467284)
			(xy 116.484655 -276.4195) (xy 116.503946 -276.374224) (xy 116.530249 -276.332628) (xy 116.562884 -276.295791)
			(xy 116.601005 -276.264666) (xy 116.643626 -276.240059) (xy 116.689642 -276.222607) (xy 116.737861 -276.212763)
			(xy 116.787036 -276.210782) (xy 116.835891 -276.216714) (xy 116.883162 -276.230406) (xy 116.927624 -276.251504)
			(xy 116.968127 -276.27946) (xy 117.00362 -276.313552) (xy 117.033185 -276.352896) (xy 117.056056 -276.396473)
			(xy 117.07164 -276.443154) (xy 117.079535 -276.491731) (xy 117.08003 -276.516338) (xy 117.408972 -276.516338)
			(xy 117.412932 -276.467284) (xy 117.424709 -276.4195) (xy 117.444 -276.374224) (xy 117.470303 -276.332628)
			(xy 117.502938 -276.295791) (xy 117.541059 -276.264666) (xy 117.58368 -276.240059) (xy 117.629696 -276.222607)
			(xy 117.677915 -276.212763) (xy 117.72709 -276.210782) (xy 117.775945 -276.216714) (xy 117.823216 -276.230406)
			(xy 117.867678 -276.251504) (xy 117.908181 -276.27946) (xy 117.943674 -276.313552) (xy 117.973239 -276.352896)
			(xy 117.99611 -276.396473) (xy 118.011694 -276.443154) (xy 118.019589 -276.491731) (xy 118.020084 -276.516338)
			(xy 118.349026 -276.516338) (xy 118.352986 -276.467284) (xy 118.364763 -276.4195) (xy 118.384054 -276.374224)
			(xy 118.410357 -276.332628) (xy 118.442992 -276.295791) (xy 118.481113 -276.264666) (xy 118.523734 -276.240059)
			(xy 118.56975 -276.222607) (xy 118.617969 -276.212763) (xy 118.667144 -276.210782) (xy 118.715999 -276.216714)
			(xy 118.76327 -276.230406) (xy 118.807732 -276.251504) (xy 118.848235 -276.27946) (xy 118.883728 -276.313552)
			(xy 118.913293 -276.352896) (xy 118.936164 -276.396473) (xy 118.951748 -276.443154) (xy 118.959643 -276.491731)
			(xy 118.960138 -276.516338) (xy 119.288826 -276.516338) (xy 119.292786 -276.467284) (xy 119.304563 -276.4195)
			(xy 119.323854 -276.374224) (xy 119.350157 -276.332628) (xy 119.382792 -276.295791) (xy 119.420913 -276.264666)
			(xy 119.463534 -276.240059) (xy 119.50955 -276.222607) (xy 119.557769 -276.212763) (xy 119.606944 -276.210782)
			(xy 119.655799 -276.216714) (xy 119.70307 -276.230406) (xy 119.747532 -276.251504) (xy 119.788035 -276.27946)
			(xy 119.823528 -276.313552) (xy 119.853093 -276.352896) (xy 119.875964 -276.396473) (xy 119.891548 -276.443154)
			(xy 119.899443 -276.491731) (xy 119.899938 -276.516338) (xy 120.22888 -276.516338) (xy 120.23284 -276.467284)
			(xy 120.244617 -276.4195) (xy 120.263908 -276.374224) (xy 120.290211 -276.332628) (xy 120.322846 -276.295791)
			(xy 120.360967 -276.264666) (xy 120.403588 -276.240059) (xy 120.449604 -276.222607) (xy 120.497823 -276.212763)
			(xy 120.546998 -276.210782) (xy 120.595853 -276.216714) (xy 120.643124 -276.230406) (xy 120.687586 -276.251504)
			(xy 120.728089 -276.27946) (xy 120.763582 -276.313552) (xy 120.793147 -276.352896) (xy 120.816018 -276.396473)
			(xy 120.831602 -276.443154) (xy 120.839497 -276.491731) (xy 120.839992 -276.516338) (xy 121.168934 -276.516338)
			(xy 121.172894 -276.467284) (xy 121.184671 -276.4195) (xy 121.203962 -276.374224) (xy 121.230265 -276.332628)
			(xy 121.2629 -276.295791) (xy 121.301021 -276.264666) (xy 121.343642 -276.240059) (xy 121.389658 -276.222607)
			(xy 121.437877 -276.212763) (xy 121.487052 -276.210782) (xy 121.535907 -276.216714) (xy 121.583178 -276.230406)
			(xy 121.62764 -276.251504) (xy 121.668143 -276.27946) (xy 121.703636 -276.313552) (xy 121.733201 -276.352896)
			(xy 121.756072 -276.396473) (xy 121.771656 -276.443154) (xy 121.779551 -276.491731) (xy 121.780046 -276.516338)
			(xy 122.108988 -276.516338) (xy 122.112948 -276.467284) (xy 122.124725 -276.4195) (xy 122.144016 -276.374224)
			(xy 122.170319 -276.332628) (xy 122.202954 -276.295791) (xy 122.241075 -276.264666) (xy 122.283696 -276.240059)
			(xy 122.329712 -276.222607) (xy 122.377931 -276.212763) (xy 122.427106 -276.210782) (xy 122.475961 -276.216714)
			(xy 122.523232 -276.230406) (xy 122.567694 -276.251504) (xy 122.608197 -276.27946) (xy 122.64369 -276.313552)
			(xy 122.673255 -276.352896) (xy 122.696126 -276.396473) (xy 122.71171 -276.443154) (xy 122.719605 -276.491731)
			(xy 122.7201 -276.516338) (xy 123.049042 -276.516338) (xy 123.053002 -276.467284) (xy 123.064779 -276.4195)
			(xy 123.08407 -276.374224) (xy 123.110373 -276.332628) (xy 123.143008 -276.295791) (xy 123.181129 -276.264666)
			(xy 123.22375 -276.240059) (xy 123.269766 -276.222607) (xy 123.317985 -276.212763) (xy 123.36716 -276.210782)
			(xy 123.416015 -276.216714) (xy 123.463286 -276.230406) (xy 123.507748 -276.251504) (xy 123.548251 -276.27946)
			(xy 123.583744 -276.313552) (xy 123.613309 -276.352896) (xy 123.63618 -276.396473) (xy 123.651764 -276.443154)
			(xy 123.659659 -276.491731) (xy 123.660154 -276.516338) (xy 123.988842 -276.516338) (xy 123.992802 -276.467284)
			(xy 124.004579 -276.4195) (xy 124.02387 -276.374224) (xy 124.050173 -276.332628) (xy 124.082808 -276.295791)
			(xy 124.120929 -276.264666) (xy 124.16355 -276.240059) (xy 124.209566 -276.222607) (xy 124.257785 -276.212763)
			(xy 124.30696 -276.210782) (xy 124.355815 -276.216714) (xy 124.403086 -276.230406) (xy 124.447548 -276.251504)
			(xy 124.488051 -276.27946) (xy 124.523544 -276.313552) (xy 124.553109 -276.352896) (xy 124.57598 -276.396473)
			(xy 124.591564 -276.443154) (xy 124.599459 -276.491731) (xy 124.599954 -276.516338) (xy 124.928896 -276.516338)
			(xy 124.932856 -276.467284) (xy 124.944633 -276.4195) (xy 124.963924 -276.374224) (xy 124.990227 -276.332628)
			(xy 125.022862 -276.295791) (xy 125.060983 -276.264666) (xy 125.103604 -276.240059) (xy 125.14962 -276.222607)
			(xy 125.197839 -276.212763) (xy 125.247014 -276.210782) (xy 125.295869 -276.216714) (xy 125.34314 -276.230406)
			(xy 125.387602 -276.251504) (xy 125.428105 -276.27946) (xy 125.463598 -276.313552) (xy 125.493163 -276.352896)
			(xy 125.516034 -276.396473) (xy 125.531618 -276.443154) (xy 125.539513 -276.491731) (xy 125.540008 -276.516338)
			(xy 125.86895 -276.516338) (xy 125.87291 -276.467284) (xy 125.884687 -276.4195) (xy 125.903978 -276.374224)
			(xy 125.930281 -276.332628) (xy 125.962916 -276.295791) (xy 126.001037 -276.264666) (xy 126.043658 -276.240059)
			(xy 126.089674 -276.222607) (xy 126.137893 -276.212763) (xy 126.187068 -276.210782) (xy 126.235923 -276.216714)
			(xy 126.283194 -276.230406) (xy 126.327656 -276.251504) (xy 126.368159 -276.27946) (xy 126.403652 -276.313552)
			(xy 126.433217 -276.352896) (xy 126.456088 -276.396473) (xy 126.471672 -276.443154) (xy 126.479567 -276.491731)
			(xy 126.480062 -276.516338) (xy 126.479567 -276.540945) (xy 126.471672 -276.589522) (xy 126.456088 -276.636203)
			(xy 126.433217 -276.67978) (xy 126.403652 -276.719124) (xy 126.368159 -276.753216) (xy 126.327656 -276.781172)
			(xy 126.283194 -276.80227) (xy 126.235923 -276.815962) (xy 126.187068 -276.821894) (xy 126.137893 -276.819913)
			(xy 126.089674 -276.810069) (xy 126.043658 -276.792617) (xy 126.001037 -276.76801) (xy 125.962916 -276.736885)
			(xy 125.930281 -276.700048) (xy 125.903978 -276.658452) (xy 125.884687 -276.613176) (xy 125.87291 -276.565392)
			(xy 125.86895 -276.516338) (xy 125.540008 -276.516338) (xy 125.539513 -276.540945) (xy 125.531618 -276.589522)
			(xy 125.516034 -276.636203) (xy 125.493163 -276.67978) (xy 125.463598 -276.719124) (xy 125.428105 -276.753216)
			(xy 125.387602 -276.781172) (xy 125.34314 -276.80227) (xy 125.295869 -276.815962) (xy 125.247014 -276.821894)
			(xy 125.197839 -276.819913) (xy 125.14962 -276.810069) (xy 125.103604 -276.792617) (xy 125.060983 -276.76801)
			(xy 125.022862 -276.736885) (xy 124.990227 -276.700048) (xy 124.963924 -276.658452) (xy 124.944633 -276.613176)
			(xy 124.932856 -276.565392) (xy 124.928896 -276.516338) (xy 124.599954 -276.516338) (xy 124.599459 -276.540945)
			(xy 124.591564 -276.589522) (xy 124.57598 -276.636203) (xy 124.553109 -276.67978) (xy 124.523544 -276.719124)
			(xy 124.488051 -276.753216) (xy 124.447548 -276.781172) (xy 124.403086 -276.80227) (xy 124.355815 -276.815962)
			(xy 124.30696 -276.821894) (xy 124.257785 -276.819913) (xy 124.209566 -276.810069) (xy 124.16355 -276.792617)
			(xy 124.120929 -276.76801) (xy 124.082808 -276.736885) (xy 124.050173 -276.700048) (xy 124.02387 -276.658452)
			(xy 124.004579 -276.613176) (xy 123.992802 -276.565392) (xy 123.988842 -276.516338) (xy 123.660154 -276.516338)
			(xy 123.659659 -276.540945) (xy 123.651764 -276.589522) (xy 123.63618 -276.636203) (xy 123.613309 -276.67978)
			(xy 123.583744 -276.719124) (xy 123.548251 -276.753216) (xy 123.507748 -276.781172) (xy 123.463286 -276.80227)
			(xy 123.416015 -276.815962) (xy 123.36716 -276.821894) (xy 123.317985 -276.819913) (xy 123.269766 -276.810069)
			(xy 123.22375 -276.792617) (xy 123.181129 -276.76801) (xy 123.143008 -276.736885) (xy 123.110373 -276.700048)
			(xy 123.08407 -276.658452) (xy 123.064779 -276.613176) (xy 123.053002 -276.565392) (xy 123.049042 -276.516338)
			(xy 122.7201 -276.516338) (xy 122.719605 -276.540945) (xy 122.71171 -276.589522) (xy 122.696126 -276.636203)
			(xy 122.673255 -276.67978) (xy 122.64369 -276.719124) (xy 122.608197 -276.753216) (xy 122.567694 -276.781172)
			(xy 122.523232 -276.80227) (xy 122.475961 -276.815962) (xy 122.427106 -276.821894) (xy 122.377931 -276.819913)
			(xy 122.329712 -276.810069) (xy 122.283696 -276.792617) (xy 122.241075 -276.76801) (xy 122.202954 -276.736885)
			(xy 122.170319 -276.700048) (xy 122.144016 -276.658452) (xy 122.124725 -276.613176) (xy 122.112948 -276.565392)
			(xy 122.108988 -276.516338) (xy 121.780046 -276.516338) (xy 121.779551 -276.540945) (xy 121.771656 -276.589522)
			(xy 121.756072 -276.636203) (xy 121.733201 -276.67978) (xy 121.703636 -276.719124) (xy 121.668143 -276.753216)
			(xy 121.62764 -276.781172) (xy 121.583178 -276.80227) (xy 121.535907 -276.815962) (xy 121.487052 -276.821894)
			(xy 121.437877 -276.819913) (xy 121.389658 -276.810069) (xy 121.343642 -276.792617) (xy 121.301021 -276.76801)
			(xy 121.2629 -276.736885) (xy 121.230265 -276.700048) (xy 121.203962 -276.658452) (xy 121.184671 -276.613176)
			(xy 121.172894 -276.565392) (xy 121.168934 -276.516338) (xy 120.839992 -276.516338) (xy 120.839497 -276.540945)
			(xy 120.831602 -276.589522) (xy 120.816018 -276.636203) (xy 120.793147 -276.67978) (xy 120.763582 -276.719124)
			(xy 120.728089 -276.753216) (xy 120.687586 -276.781172) (xy 120.643124 -276.80227) (xy 120.595853 -276.815962)
			(xy 120.546998 -276.821894) (xy 120.497823 -276.819913) (xy 120.449604 -276.810069) (xy 120.403588 -276.792617)
			(xy 120.360967 -276.76801) (xy 120.322846 -276.736885) (xy 120.290211 -276.700048) (xy 120.263908 -276.658452)
			(xy 120.244617 -276.613176) (xy 120.23284 -276.565392) (xy 120.22888 -276.516338) (xy 119.899938 -276.516338)
			(xy 119.899443 -276.540945) (xy 119.891548 -276.589522) (xy 119.875964 -276.636203) (xy 119.853093 -276.67978)
			(xy 119.823528 -276.719124) (xy 119.788035 -276.753216) (xy 119.747532 -276.781172) (xy 119.70307 -276.80227)
			(xy 119.655799 -276.815962) (xy 119.606944 -276.821894) (xy 119.557769 -276.819913) (xy 119.50955 -276.810069)
			(xy 119.463534 -276.792617) (xy 119.420913 -276.76801) (xy 119.382792 -276.736885) (xy 119.350157 -276.700048)
			(xy 119.323854 -276.658452) (xy 119.304563 -276.613176) (xy 119.292786 -276.565392) (xy 119.288826 -276.516338)
			(xy 118.960138 -276.516338) (xy 118.959643 -276.540945) (xy 118.951748 -276.589522) (xy 118.936164 -276.636203)
			(xy 118.913293 -276.67978) (xy 118.883728 -276.719124) (xy 118.848235 -276.753216) (xy 118.807732 -276.781172)
			(xy 118.76327 -276.80227) (xy 118.715999 -276.815962) (xy 118.667144 -276.821894) (xy 118.617969 -276.819913)
			(xy 118.56975 -276.810069) (xy 118.523734 -276.792617) (xy 118.481113 -276.76801) (xy 118.442992 -276.736885)
			(xy 118.410357 -276.700048) (xy 118.384054 -276.658452) (xy 118.364763 -276.613176) (xy 118.352986 -276.565392)
			(xy 118.349026 -276.516338) (xy 118.020084 -276.516338) (xy 118.019589 -276.540945) (xy 118.011694 -276.589522)
			(xy 117.99611 -276.636203) (xy 117.973239 -276.67978) (xy 117.943674 -276.719124) (xy 117.908181 -276.753216)
			(xy 117.867678 -276.781172) (xy 117.823216 -276.80227) (xy 117.775945 -276.815962) (xy 117.72709 -276.821894)
			(xy 117.677915 -276.819913) (xy 117.629696 -276.810069) (xy 117.58368 -276.792617) (xy 117.541059 -276.76801)
			(xy 117.502938 -276.736885) (xy 117.470303 -276.700048) (xy 117.444 -276.658452) (xy 117.424709 -276.613176)
			(xy 117.412932 -276.565392) (xy 117.408972 -276.516338) (xy 117.08003 -276.516338) (xy 117.079535 -276.540945)
			(xy 117.07164 -276.589522) (xy 117.056056 -276.636203) (xy 117.033185 -276.67978) (xy 117.00362 -276.719124)
			(xy 116.968127 -276.753216) (xy 116.927624 -276.781172) (xy 116.883162 -276.80227) (xy 116.835891 -276.815962)
			(xy 116.787036 -276.821894) (xy 116.737861 -276.819913) (xy 116.689642 -276.810069) (xy 116.643626 -276.792617)
			(xy 116.601005 -276.76801) (xy 116.562884 -276.736885) (xy 116.530249 -276.700048) (xy 116.503946 -276.658452)
			(xy 116.484655 -276.613176) (xy 116.472878 -276.565392) (xy 116.468918 -276.516338) (xy 116.139976 -276.516338)
			(xy 116.139481 -276.540945) (xy 116.131586 -276.589522) (xy 116.116002 -276.636203) (xy 116.093131 -276.67978)
			(xy 116.063566 -276.719124) (xy 116.028073 -276.753216) (xy 115.98757 -276.781172) (xy 115.943108 -276.80227)
			(xy 115.895837 -276.815962) (xy 115.846982 -276.821894) (xy 115.797807 -276.819913) (xy 115.749588 -276.810069)
			(xy 115.703572 -276.792617) (xy 115.660951 -276.76801) (xy 115.62283 -276.736885) (xy 115.590195 -276.700048)
			(xy 115.563892 -276.658452) (xy 115.544601 -276.613176) (xy 115.532824 -276.565392) (xy 115.528864 -276.516338)
			(xy 115.199922 -276.516338) (xy 115.199427 -276.540945) (xy 115.191532 -276.589522) (xy 115.175948 -276.636203)
			(xy 115.153077 -276.67978) (xy 115.123512 -276.719124) (xy 115.088019 -276.753216) (xy 115.047516 -276.781172)
			(xy 115.003054 -276.80227) (xy 114.955783 -276.815962) (xy 114.906928 -276.821894) (xy 114.857753 -276.819913)
			(xy 114.809534 -276.810069) (xy 114.763518 -276.792617) (xy 114.720897 -276.76801) (xy 114.682776 -276.736885)
			(xy 114.650141 -276.700048) (xy 114.623838 -276.658452) (xy 114.604547 -276.613176) (xy 114.59277 -276.565392)
			(xy 114.58881 -276.516338) (xy 114.260122 -276.516338) (xy 114.259627 -276.540945) (xy 114.251732 -276.589522)
			(xy 114.236148 -276.636203) (xy 114.213277 -276.67978) (xy 114.183712 -276.719124) (xy 114.148219 -276.753216)
			(xy 114.107716 -276.781172) (xy 114.063254 -276.80227) (xy 114.015983 -276.815962) (xy 113.967128 -276.821894)
			(xy 113.917953 -276.819913) (xy 113.869734 -276.810069) (xy 113.823718 -276.792617) (xy 113.781097 -276.76801)
			(xy 113.742976 -276.736885) (xy 113.710341 -276.700048) (xy 113.684038 -276.658452) (xy 113.664747 -276.613176)
			(xy 113.65297 -276.565392) (xy 113.64901 -276.516338) (xy 110.506256 -276.516338) (xy 110.505761 -276.540945)
			(xy 110.497866 -276.589522) (xy 110.482282 -276.636203) (xy 110.459411 -276.67978) (xy 110.429846 -276.719124)
			(xy 110.394353 -276.753216) (xy 110.35385 -276.781172) (xy 110.309388 -276.80227) (xy 110.262117 -276.815962)
			(xy 110.213262 -276.821894) (xy 110.164087 -276.819913) (xy 110.115868 -276.810069) (xy 110.069852 -276.792617)
			(xy 110.027231 -276.76801) (xy 109.98911 -276.736885) (xy 109.956475 -276.700048) (xy 109.930172 -276.658452)
			(xy 109.910881 -276.613176) (xy 109.899104 -276.565392) (xy 109.895144 -276.516338) (xy 109.566456 -276.516338)
			(xy 109.565961 -276.540945) (xy 109.558066 -276.589522) (xy 109.542482 -276.636203) (xy 109.519611 -276.67978)
			(xy 109.490046 -276.719124) (xy 109.454553 -276.753216) (xy 109.41405 -276.781172) (xy 109.369588 -276.80227)
			(xy 109.322317 -276.815962) (xy 109.273462 -276.821894) (xy 109.224287 -276.819913) (xy 109.176068 -276.810069)
			(xy 109.130052 -276.792617) (xy 109.087431 -276.76801) (xy 109.04931 -276.736885) (xy 109.016675 -276.700048)
			(xy 108.990372 -276.658452) (xy 108.971081 -276.613176) (xy 108.959304 -276.565392) (xy 108.955344 -276.516338)
			(xy 108.626402 -276.516338) (xy 108.625907 -276.540945) (xy 108.618012 -276.589522) (xy 108.602428 -276.636203)
			(xy 108.579557 -276.67978) (xy 108.549992 -276.719124) (xy 108.514499 -276.753216) (xy 108.473996 -276.781172)
			(xy 108.429534 -276.80227) (xy 108.382263 -276.815962) (xy 108.333408 -276.821894) (xy 108.284233 -276.819913)
			(xy 108.236014 -276.810069) (xy 108.189998 -276.792617) (xy 108.147377 -276.76801) (xy 108.109256 -276.736885)
			(xy 108.076621 -276.700048) (xy 108.050318 -276.658452) (xy 108.031027 -276.613176) (xy 108.01925 -276.565392)
			(xy 108.01529 -276.516338) (xy 107.686348 -276.516338) (xy 107.685853 -276.540945) (xy 107.677958 -276.589522)
			(xy 107.662374 -276.636203) (xy 107.639503 -276.67978) (xy 107.609938 -276.719124) (xy 107.574445 -276.753216)
			(xy 107.533942 -276.781172) (xy 107.48948 -276.80227) (xy 107.442209 -276.815962) (xy 107.393354 -276.821894)
			(xy 107.344179 -276.819913) (xy 107.29596 -276.810069) (xy 107.249944 -276.792617) (xy 107.207323 -276.76801)
			(xy 107.169202 -276.736885) (xy 107.136567 -276.700048) (xy 107.110264 -276.658452) (xy 107.090973 -276.613176)
			(xy 107.079196 -276.565392) (xy 107.075236 -276.516338) (xy 106.746294 -276.516338) (xy 106.745799 -276.540945)
			(xy 106.737904 -276.589522) (xy 106.72232 -276.636203) (xy 106.699449 -276.67978) (xy 106.669884 -276.719124)
			(xy 106.634391 -276.753216) (xy 106.593888 -276.781172) (xy 106.549426 -276.80227) (xy 106.502155 -276.815962)
			(xy 106.4533 -276.821894) (xy 106.404125 -276.819913) (xy 106.355906 -276.810069) (xy 106.30989 -276.792617)
			(xy 106.267269 -276.76801) (xy 106.229148 -276.736885) (xy 106.196513 -276.700048) (xy 106.17021 -276.658452)
			(xy 106.150919 -276.613176) (xy 106.139142 -276.565392) (xy 106.135182 -276.516338) (xy 105.80624 -276.516338)
			(xy 105.805745 -276.540945) (xy 105.79785 -276.589522) (xy 105.782266 -276.636203) (xy 105.759395 -276.67978)
			(xy 105.72983 -276.719124) (xy 105.694337 -276.753216) (xy 105.653834 -276.781172) (xy 105.609372 -276.80227)
			(xy 105.562101 -276.815962) (xy 105.513246 -276.821894) (xy 105.464071 -276.819913) (xy 105.415852 -276.810069)
			(xy 105.369836 -276.792617) (xy 105.327215 -276.76801) (xy 105.289094 -276.736885) (xy 105.256459 -276.700048)
			(xy 105.230156 -276.658452) (xy 105.210865 -276.613176) (xy 105.199088 -276.565392) (xy 105.195128 -276.516338)
			(xy 104.86644 -276.516338) (xy 104.865945 -276.540945) (xy 104.85805 -276.589522) (xy 104.842466 -276.636203)
			(xy 104.819595 -276.67978) (xy 104.79003 -276.719124) (xy 104.754537 -276.753216) (xy 104.714034 -276.781172)
			(xy 104.669572 -276.80227) (xy 104.622301 -276.815962) (xy 104.573446 -276.821894) (xy 104.524271 -276.819913)
			(xy 104.476052 -276.810069) (xy 104.430036 -276.792617) (xy 104.387415 -276.76801) (xy 104.349294 -276.736885)
			(xy 104.316659 -276.700048) (xy 104.290356 -276.658452) (xy 104.271065 -276.613176) (xy 104.259288 -276.565392)
			(xy 104.255328 -276.516338) (xy 103.926386 -276.516338) (xy 103.925891 -276.540945) (xy 103.917996 -276.589522)
			(xy 103.902412 -276.636203) (xy 103.879541 -276.67978) (xy 103.849976 -276.719124) (xy 103.814483 -276.753216)
			(xy 103.77398 -276.781172) (xy 103.729518 -276.80227) (xy 103.682247 -276.815962) (xy 103.633392 -276.821894)
			(xy 103.584217 -276.819913) (xy 103.535998 -276.810069) (xy 103.489982 -276.792617) (xy 103.447361 -276.76801)
			(xy 103.40924 -276.736885) (xy 103.376605 -276.700048) (xy 103.350302 -276.658452) (xy 103.331011 -276.613176)
			(xy 103.319234 -276.565392) (xy 103.315274 -276.516338) (xy 102.986332 -276.516338) (xy 102.985837 -276.540945)
			(xy 102.977942 -276.589522) (xy 102.962358 -276.636203) (xy 102.939487 -276.67978) (xy 102.909922 -276.719124)
			(xy 102.874429 -276.753216) (xy 102.833926 -276.781172) (xy 102.789464 -276.80227) (xy 102.742193 -276.815962)
			(xy 102.693338 -276.821894) (xy 102.644163 -276.819913) (xy 102.595944 -276.810069) (xy 102.549928 -276.792617)
			(xy 102.507307 -276.76801) (xy 102.469186 -276.736885) (xy 102.436551 -276.700048) (xy 102.410248 -276.658452)
			(xy 102.390957 -276.613176) (xy 102.37918 -276.565392) (xy 102.37522 -276.516338) (xy 102.046278 -276.516338)
			(xy 102.045783 -276.540945) (xy 102.037888 -276.589522) (xy 102.022304 -276.636203) (xy 101.999433 -276.67978)
			(xy 101.969868 -276.719124) (xy 101.934375 -276.753216) (xy 101.893872 -276.781172) (xy 101.84941 -276.80227)
			(xy 101.802139 -276.815962) (xy 101.753284 -276.821894) (xy 101.704109 -276.819913) (xy 101.65589 -276.810069)
			(xy 101.609874 -276.792617) (xy 101.567253 -276.76801) (xy 101.529132 -276.736885) (xy 101.496497 -276.700048)
			(xy 101.470194 -276.658452) (xy 101.450903 -276.613176) (xy 101.439126 -276.565392) (xy 101.435166 -276.516338)
			(xy 101.106478 -276.516338) (xy 101.105983 -276.540945) (xy 101.098088 -276.589522) (xy 101.082504 -276.636203)
			(xy 101.059633 -276.67978) (xy 101.030068 -276.719124) (xy 100.994575 -276.753216) (xy 100.954072 -276.781172)
			(xy 100.90961 -276.80227) (xy 100.862339 -276.815962) (xy 100.813484 -276.821894) (xy 100.764309 -276.819913)
			(xy 100.71609 -276.810069) (xy 100.670074 -276.792617) (xy 100.627453 -276.76801) (xy 100.589332 -276.736885)
			(xy 100.556697 -276.700048) (xy 100.530394 -276.658452) (xy 100.511103 -276.613176) (xy 100.499326 -276.565392)
			(xy 100.495366 -276.516338) (xy 100.166424 -276.516338) (xy 100.165929 -276.540945) (xy 100.158034 -276.589522)
			(xy 100.14245 -276.636203) (xy 100.119579 -276.67978) (xy 100.090014 -276.719124) (xy 100.054521 -276.753216)
			(xy 100.014018 -276.781172) (xy 99.969556 -276.80227) (xy 99.922285 -276.815962) (xy 99.87343 -276.821894)
			(xy 99.824255 -276.819913) (xy 99.776036 -276.810069) (xy 99.73002 -276.792617) (xy 99.687399 -276.76801)
			(xy 99.649278 -276.736885) (xy 99.616643 -276.700048) (xy 99.59034 -276.658452) (xy 99.571049 -276.613176)
			(xy 99.559272 -276.565392) (xy 99.555312 -276.516338) (xy 99.22637 -276.516338) (xy 99.225875 -276.540945)
			(xy 99.21798 -276.589522) (xy 99.202396 -276.636203) (xy 99.179525 -276.67978) (xy 99.14996 -276.719124)
			(xy 99.114467 -276.753216) (xy 99.073964 -276.781172) (xy 99.029502 -276.80227) (xy 98.982231 -276.815962)
			(xy 98.933376 -276.821894) (xy 98.884201 -276.819913) (xy 98.835982 -276.810069) (xy 98.789966 -276.792617)
			(xy 98.747345 -276.76801) (xy 98.709224 -276.736885) (xy 98.676589 -276.700048) (xy 98.650286 -276.658452)
			(xy 98.630995 -276.613176) (xy 98.619218 -276.565392) (xy 98.615258 -276.516338) (xy 98.286316 -276.516338)
			(xy 98.285821 -276.540945) (xy 98.277926 -276.589522) (xy 98.262342 -276.636203) (xy 98.239471 -276.67978)
			(xy 98.209906 -276.719124) (xy 98.174413 -276.753216) (xy 98.13391 -276.781172) (xy 98.089448 -276.80227)
			(xy 98.042177 -276.815962) (xy 97.993322 -276.821894) (xy 97.944147 -276.819913) (xy 97.895928 -276.810069)
			(xy 97.849912 -276.792617) (xy 97.807291 -276.76801) (xy 97.76917 -276.736885) (xy 97.736535 -276.700048)
			(xy 97.710232 -276.658452) (xy 97.690941 -276.613176) (xy 97.679164 -276.565392) (xy 97.675204 -276.516338)
			(xy 97.346262 -276.516338) (xy 97.345767 -276.540945) (xy 97.337872 -276.589522) (xy 97.322288 -276.636203)
			(xy 97.299417 -276.67978) (xy 97.269852 -276.719124) (xy 97.234359 -276.753216) (xy 97.193856 -276.781172)
			(xy 97.149394 -276.80227) (xy 97.102123 -276.815962) (xy 97.053268 -276.821894) (xy 97.004093 -276.819913)
			(xy 96.955874 -276.810069) (xy 96.909858 -276.792617) (xy 96.867237 -276.76801) (xy 96.829116 -276.736885)
			(xy 96.796481 -276.700048) (xy 96.770178 -276.658452) (xy 96.750887 -276.613176) (xy 96.73911 -276.565392)
			(xy 96.73515 -276.516338) (xy 96.416876 -276.516338) (xy 96.416364 -276.541784) (xy 96.4082 -276.592018)
			(xy 96.392084 -276.640292) (xy 96.368433 -276.685355) (xy 96.33786 -276.726041) (xy 96.301156 -276.761296)
			(xy 96.259272 -276.790206) (xy 96.213293 -276.812023) (xy 96.164409 -276.826183) (xy 96.113888 -276.832317)
			(xy 96.063036 -276.830268) (xy 96.013172 -276.820088) (xy 95.965586 -276.802041) (xy 95.921512 -276.776595)
			(xy 95.88209 -276.744408) (xy 95.848342 -276.706314) (xy 95.821141 -276.6633) (xy 95.801193 -276.61648)
			(xy 95.789014 -276.567066) (xy 95.784919 -276.516338) (xy 95.466408 -276.516338) (xy 95.465913 -276.540945)
			(xy 95.458018 -276.589522) (xy 95.442434 -276.636203) (xy 95.419563 -276.67978) (xy 95.389998 -276.719124)
			(xy 95.354505 -276.753216) (xy 95.314002 -276.781172) (xy 95.26954 -276.80227) (xy 95.222269 -276.815962)
			(xy 95.173414 -276.821894) (xy 95.124239 -276.819913) (xy 95.07602 -276.810069) (xy 95.030004 -276.792617)
			(xy 94.987383 -276.76801) (xy 94.949262 -276.736885) (xy 94.916627 -276.700048) (xy 94.890324 -276.658452)
			(xy 94.871033 -276.613176) (xy 94.859256 -276.565392) (xy 94.855296 -276.516338) (xy 94.536768 -276.516338)
			(xy 94.536256 -276.541784) (xy 94.528092 -276.592018) (xy 94.511976 -276.640292) (xy 94.488325 -276.685355)
			(xy 94.457752 -276.726041) (xy 94.421048 -276.761296) (xy 94.379164 -276.790206) (xy 94.333185 -276.812023)
			(xy 94.284301 -276.826183) (xy 94.23378 -276.832317) (xy 94.182928 -276.830268) (xy 94.133064 -276.820088)
			(xy 94.085478 -276.802041) (xy 94.041404 -276.776595) (xy 94.001982 -276.744408) (xy 93.968234 -276.706314)
			(xy 93.941033 -276.6633) (xy 93.921085 -276.61648) (xy 93.908906 -276.567066) (xy 93.904811 -276.516338)
			(xy 93.5863 -276.516338) (xy 93.585838 -276.540191) (xy 93.578417 -276.587315) (xy 93.563761 -276.632714)
			(xy 93.542227 -276.675282) (xy 93.514337 -276.713986) (xy 93.48077 -276.747884) (xy 93.442343 -276.776152)
			(xy 93.399988 -276.798104) (xy 93.354736 -276.813205) (xy 93.331284 -276.817582) (xy 93.322648 -276.819106)
			(xy 93.294708 -276.839426) (xy 93.289838 -276.843181) (xy 93.281887 -276.852559) (xy 93.27896 -276.857968)
			(xy 93.248226 -276.920452) (xy 93.24721 -276.922992) (xy 93.243645 -276.932361) (xy 93.243396 -276.95239)
			(xy 93.246702 -276.961854) (xy 93.246956 -276.962616) (xy 93.250004 -276.968458) (xy 93.294708 -277.04542)
			(xy 93.305179 -277.063899) (xy 93.323616 -277.102167) (xy 93.331538 -277.121874) (xy 93.331538 -277.122128)
			(xy 93.334238 -277.128324) (xy 93.342357 -277.139124) (xy 93.34754 -277.143464) (xy 93.352874 -277.147528)
			(xy 93.365066 -277.152862) (xy 93.45803 -277.165054) (xy 93.464894 -277.165718) (xy 93.47854 -277.163778)
			(xy 93.484954 -277.161244) (xy 93.49098 -277.158442) (xy 93.501397 -277.150195) (xy 93.505528 -277.144988)
			(xy 93.505782 -277.144734) (xy 93.520285 -277.125903) (xy 93.55414 -277.092545) (xy 93.592752 -277.064833)
			(xy 93.635191 -277.043435) (xy 93.680432 -277.028868) (xy 93.727382 -277.021484) (xy 93.751146 -277.021036)
			(xy 93.776395 -277.021561) (xy 93.826204 -277.02988) (xy 93.873964 -277.046282) (xy 93.918374 -277.070321)
			(xy 93.958222 -277.101342) (xy 93.992421 -277.138497) (xy 94.020039 -277.180774) (xy 94.040322 -277.22702)
			(xy 94.052717 -277.275974) (xy 94.056887 -277.3263) (xy 94.056883 -277.326344) (xy 94.374711 -277.326344)
			(xy 94.378806 -277.275616) (xy 94.390985 -277.226202) (xy 94.410933 -277.179382) (xy 94.438134 -277.136368)
			(xy 94.471882 -277.098274) (xy 94.511304 -277.066087) (xy 94.555378 -277.040641) (xy 94.602964 -277.022594)
			(xy 94.652828 -277.012414) (xy 94.70368 -277.010365) (xy 94.754201 -277.016499) (xy 94.803085 -277.030659)
			(xy 94.849064 -277.052476) (xy 94.890948 -277.081386) (xy 94.927652 -277.116641) (xy 94.958225 -277.157327)
			(xy 94.981876 -277.20239) (xy 94.997992 -277.250664) (xy 95.006156 -277.300898) (xy 95.006668 -277.326344)
			(xy 95.314765 -277.326344) (xy 95.31886 -277.275616) (xy 95.331039 -277.226202) (xy 95.350987 -277.179382)
			(xy 95.378188 -277.136368) (xy 95.411936 -277.098274) (xy 95.451358 -277.066087) (xy 95.495432 -277.040641)
			(xy 95.543018 -277.022594) (xy 95.592882 -277.012414) (xy 95.643734 -277.010365) (xy 95.694255 -277.016499)
			(xy 95.743139 -277.030659) (xy 95.789118 -277.052476) (xy 95.831002 -277.081386) (xy 95.867706 -277.116641)
			(xy 95.898279 -277.157327) (xy 95.92193 -277.20239) (xy 95.938046 -277.250664) (xy 95.94621 -277.300898)
			(xy 95.946722 -277.326344) (xy 96.26525 -277.326344) (xy 96.26921 -277.27729) (xy 96.280987 -277.229506)
			(xy 96.300278 -277.18423) (xy 96.326581 -277.142634) (xy 96.359216 -277.105797) (xy 96.397337 -277.074672)
			(xy 96.439958 -277.050065) (xy 96.485974 -277.032613) (xy 96.534193 -277.022769) (xy 96.583368 -277.020788)
			(xy 96.632223 -277.02672) (xy 96.679494 -277.040412) (xy 96.723956 -277.06151) (xy 96.764459 -277.089466)
			(xy 96.799952 -277.123558) (xy 96.829517 -277.162902) (xy 96.852388 -277.206479) (xy 96.867972 -277.25316)
			(xy 96.875867 -277.301737) (xy 96.876362 -277.326344) (xy 97.205304 -277.326344) (xy 97.209264 -277.27729)
			(xy 97.221041 -277.229506) (xy 97.240332 -277.18423) (xy 97.266635 -277.142634) (xy 97.29927 -277.105797)
			(xy 97.337391 -277.074672) (xy 97.380012 -277.050065) (xy 97.426028 -277.032613) (xy 97.474247 -277.022769)
			(xy 97.523422 -277.020788) (xy 97.572277 -277.02672) (xy 97.619548 -277.040412) (xy 97.66401 -277.06151)
			(xy 97.704513 -277.089466) (xy 97.740006 -277.123558) (xy 97.769571 -277.162902) (xy 97.792442 -277.206479)
			(xy 97.808026 -277.25316) (xy 97.815921 -277.301737) (xy 97.816416 -277.326344) (xy 98.145358 -277.326344)
			(xy 98.149318 -277.27729) (xy 98.161095 -277.229506) (xy 98.180386 -277.18423) (xy 98.206689 -277.142634)
			(xy 98.239324 -277.105797) (xy 98.277445 -277.074672) (xy 98.320066 -277.050065) (xy 98.366082 -277.032613)
			(xy 98.414301 -277.022769) (xy 98.463476 -277.020788) (xy 98.512331 -277.02672) (xy 98.559602 -277.040412)
			(xy 98.604064 -277.06151) (xy 98.644567 -277.089466) (xy 98.68006 -277.123558) (xy 98.709625 -277.162902)
			(xy 98.732496 -277.206479) (xy 98.74808 -277.25316) (xy 98.755975 -277.301737) (xy 98.75647 -277.326344)
			(xy 99.085158 -277.326344) (xy 99.089118 -277.27729) (xy 99.100895 -277.229506) (xy 99.120186 -277.18423)
			(xy 99.146489 -277.142634) (xy 99.179124 -277.105797) (xy 99.217245 -277.074672) (xy 99.259866 -277.050065)
			(xy 99.305882 -277.032613) (xy 99.354101 -277.022769) (xy 99.403276 -277.020788) (xy 99.452131 -277.02672)
			(xy 99.499402 -277.040412) (xy 99.543864 -277.06151) (xy 99.584367 -277.089466) (xy 99.61986 -277.123558)
			(xy 99.649425 -277.162902) (xy 99.672296 -277.206479) (xy 99.68788 -277.25316) (xy 99.695775 -277.301737)
			(xy 99.69627 -277.326344) (xy 100.025212 -277.326344) (xy 100.029172 -277.27729) (xy 100.040949 -277.229506)
			(xy 100.06024 -277.18423) (xy 100.086543 -277.142634) (xy 100.119178 -277.105797) (xy 100.157299 -277.074672)
			(xy 100.19992 -277.050065) (xy 100.245936 -277.032613) (xy 100.294155 -277.022769) (xy 100.34333 -277.020788)
			(xy 100.392185 -277.02672) (xy 100.439456 -277.040412) (xy 100.483918 -277.06151) (xy 100.524421 -277.089466)
			(xy 100.559914 -277.123558) (xy 100.589479 -277.162902) (xy 100.61235 -277.206479) (xy 100.627934 -277.25316)
			(xy 100.635829 -277.301737) (xy 100.636324 -277.326344) (xy 100.965266 -277.326344) (xy 100.969226 -277.27729)
			(xy 100.981003 -277.229506) (xy 101.000294 -277.18423) (xy 101.026597 -277.142634) (xy 101.059232 -277.105797)
			(xy 101.097353 -277.074672) (xy 101.139974 -277.050065) (xy 101.18599 -277.032613) (xy 101.234209 -277.022769)
			(xy 101.283384 -277.020788) (xy 101.332239 -277.02672) (xy 101.37951 -277.040412) (xy 101.423972 -277.06151)
			(xy 101.464475 -277.089466) (xy 101.499968 -277.123558) (xy 101.529533 -277.162902) (xy 101.552404 -277.206479)
			(xy 101.567988 -277.25316) (xy 101.575883 -277.301737) (xy 101.576378 -277.326344) (xy 101.90532 -277.326344)
			(xy 101.90928 -277.27729) (xy 101.921057 -277.229506) (xy 101.940348 -277.18423) (xy 101.966651 -277.142634)
			(xy 101.999286 -277.105797) (xy 102.037407 -277.074672) (xy 102.080028 -277.050065) (xy 102.126044 -277.032613)
			(xy 102.174263 -277.022769) (xy 102.223438 -277.020788) (xy 102.272293 -277.02672) (xy 102.319564 -277.040412)
			(xy 102.364026 -277.06151) (xy 102.404529 -277.089466) (xy 102.440022 -277.123558) (xy 102.469587 -277.162902)
			(xy 102.492458 -277.206479) (xy 102.508042 -277.25316) (xy 102.515937 -277.301737) (xy 102.516432 -277.326344)
			(xy 102.845374 -277.326344) (xy 102.849334 -277.27729) (xy 102.861111 -277.229506) (xy 102.880402 -277.18423)
			(xy 102.906705 -277.142634) (xy 102.93934 -277.105797) (xy 102.977461 -277.074672) (xy 103.020082 -277.050065)
			(xy 103.066098 -277.032613) (xy 103.114317 -277.022769) (xy 103.163492 -277.020788) (xy 103.212347 -277.02672)
			(xy 103.259618 -277.040412) (xy 103.30408 -277.06151) (xy 103.344583 -277.089466) (xy 103.380076 -277.123558)
			(xy 103.409641 -277.162902) (xy 103.432512 -277.206479) (xy 103.448096 -277.25316) (xy 103.455991 -277.301737)
			(xy 103.456486 -277.326344) (xy 103.785174 -277.326344) (xy 103.789134 -277.27729) (xy 103.800911 -277.229506)
			(xy 103.820202 -277.18423) (xy 103.846505 -277.142634) (xy 103.87914 -277.105797) (xy 103.917261 -277.074672)
			(xy 103.959882 -277.050065) (xy 104.005898 -277.032613) (xy 104.054117 -277.022769) (xy 104.103292 -277.020788)
			(xy 104.152147 -277.02672) (xy 104.199418 -277.040412) (xy 104.24388 -277.06151) (xy 104.284383 -277.089466)
			(xy 104.319876 -277.123558) (xy 104.349441 -277.162902) (xy 104.372312 -277.206479) (xy 104.387896 -277.25316)
			(xy 104.395791 -277.301737) (xy 104.396286 -277.326344) (xy 104.725228 -277.326344) (xy 104.729188 -277.27729)
			(xy 104.740965 -277.229506) (xy 104.760256 -277.18423) (xy 104.786559 -277.142634) (xy 104.819194 -277.105797)
			(xy 104.857315 -277.074672) (xy 104.899936 -277.050065) (xy 104.945952 -277.032613) (xy 104.994171 -277.022769)
			(xy 105.043346 -277.020788) (xy 105.092201 -277.02672) (xy 105.139472 -277.040412) (xy 105.183934 -277.06151)
			(xy 105.224437 -277.089466) (xy 105.25993 -277.123558) (xy 105.289495 -277.162902) (xy 105.312366 -277.206479)
			(xy 105.32795 -277.25316) (xy 105.335845 -277.301737) (xy 105.33634 -277.326344) (xy 105.665282 -277.326344)
			(xy 105.669242 -277.27729) (xy 105.681019 -277.229506) (xy 105.70031 -277.18423) (xy 105.726613 -277.142634)
			(xy 105.759248 -277.105797) (xy 105.797369 -277.074672) (xy 105.83999 -277.050065) (xy 105.886006 -277.032613)
			(xy 105.934225 -277.022769) (xy 105.9834 -277.020788) (xy 106.032255 -277.02672) (xy 106.079526 -277.040412)
			(xy 106.123988 -277.06151) (xy 106.164491 -277.089466) (xy 106.199984 -277.123558) (xy 106.229549 -277.162902)
			(xy 106.25242 -277.206479) (xy 106.268004 -277.25316) (xy 106.275899 -277.301737) (xy 106.276394 -277.326344)
			(xy 106.605336 -277.326344) (xy 106.609296 -277.27729) (xy 106.621073 -277.229506) (xy 106.640364 -277.18423)
			(xy 106.666667 -277.142634) (xy 106.699302 -277.105797) (xy 106.737423 -277.074672) (xy 106.780044 -277.050065)
			(xy 106.82606 -277.032613) (xy 106.874279 -277.022769) (xy 106.923454 -277.020788) (xy 106.972309 -277.02672)
			(xy 107.01958 -277.040412) (xy 107.064042 -277.06151) (xy 107.104545 -277.089466) (xy 107.140038 -277.123558)
			(xy 107.169603 -277.162902) (xy 107.192474 -277.206479) (xy 107.208058 -277.25316) (xy 107.215953 -277.301737)
			(xy 107.216448 -277.326344) (xy 107.545136 -277.326344) (xy 107.549096 -277.27729) (xy 107.560873 -277.229506)
			(xy 107.580164 -277.18423) (xy 107.606467 -277.142634) (xy 107.639102 -277.105797) (xy 107.677223 -277.074672)
			(xy 107.719844 -277.050065) (xy 107.76586 -277.032613) (xy 107.814079 -277.022769) (xy 107.863254 -277.020788)
			(xy 107.912109 -277.02672) (xy 107.95938 -277.040412) (xy 108.003842 -277.06151) (xy 108.044345 -277.089466)
			(xy 108.079838 -277.123558) (xy 108.109403 -277.162902) (xy 108.132274 -277.206479) (xy 108.147858 -277.25316)
			(xy 108.155753 -277.301737) (xy 108.156248 -277.326344) (xy 108.48519 -277.326344) (xy 108.48915 -277.27729)
			(xy 108.500927 -277.229506) (xy 108.520218 -277.18423) (xy 108.546521 -277.142634) (xy 108.579156 -277.105797)
			(xy 108.617277 -277.074672) (xy 108.659898 -277.050065) (xy 108.705914 -277.032613) (xy 108.754133 -277.022769)
			(xy 108.803308 -277.020788) (xy 108.852163 -277.02672) (xy 108.899434 -277.040412) (xy 108.943896 -277.06151)
			(xy 108.984399 -277.089466) (xy 109.019892 -277.123558) (xy 109.049457 -277.162902) (xy 109.072328 -277.206479)
			(xy 109.087912 -277.25316) (xy 109.095807 -277.301737) (xy 109.096302 -277.326344) (xy 109.425244 -277.326344)
			(xy 109.429204 -277.27729) (xy 109.440981 -277.229506) (xy 109.460272 -277.18423) (xy 109.486575 -277.142634)
			(xy 109.51921 -277.105797) (xy 109.557331 -277.074672) (xy 109.599952 -277.050065) (xy 109.645968 -277.032613)
			(xy 109.694187 -277.022769) (xy 109.743362 -277.020788) (xy 109.792217 -277.02672) (xy 109.839488 -277.040412)
			(xy 109.88395 -277.06151) (xy 109.924453 -277.089466) (xy 109.959946 -277.123558) (xy 109.989511 -277.162902)
			(xy 110.012382 -277.206479) (xy 110.027966 -277.25316) (xy 110.035861 -277.301737) (xy 110.036356 -277.326344)
			(xy 110.365298 -277.326344) (xy 110.369258 -277.27729) (xy 110.381035 -277.229506) (xy 110.400326 -277.18423)
			(xy 110.426629 -277.142634) (xy 110.459264 -277.105797) (xy 110.497385 -277.074672) (xy 110.540006 -277.050065)
			(xy 110.586022 -277.032613) (xy 110.634241 -277.022769) (xy 110.683416 -277.020788) (xy 110.732271 -277.02672)
			(xy 110.779542 -277.040412) (xy 110.824004 -277.06151) (xy 110.864507 -277.089466) (xy 110.9 -277.123558)
			(xy 110.929565 -277.162902) (xy 110.952436 -277.206479) (xy 110.96802 -277.25316) (xy 110.975915 -277.301737)
			(xy 110.97641 -277.326344) (xy 113.178856 -277.326344) (xy 113.182816 -277.27729) (xy 113.194593 -277.229506)
			(xy 113.213884 -277.18423) (xy 113.240187 -277.142634) (xy 113.272822 -277.105797) (xy 113.310943 -277.074672)
			(xy 113.353564 -277.050065) (xy 113.39958 -277.032613) (xy 113.447799 -277.022769) (xy 113.496974 -277.020788)
			(xy 113.545829 -277.02672) (xy 113.5931 -277.040412) (xy 113.637562 -277.06151) (xy 113.678065 -277.089466)
			(xy 113.713558 -277.123558) (xy 113.743123 -277.162902) (xy 113.765994 -277.206479) (xy 113.781578 -277.25316)
			(xy 113.789473 -277.301737) (xy 113.789968 -277.326344) (xy 114.11891 -277.326344) (xy 114.12287 -277.27729)
			(xy 114.134647 -277.229506) (xy 114.153938 -277.18423) (xy 114.180241 -277.142634) (xy 114.212876 -277.105797)
			(xy 114.250997 -277.074672) (xy 114.293618 -277.050065) (xy 114.339634 -277.032613) (xy 114.387853 -277.022769)
			(xy 114.437028 -277.020788) (xy 114.485883 -277.02672) (xy 114.533154 -277.040412) (xy 114.577616 -277.06151)
			(xy 114.618119 -277.089466) (xy 114.653612 -277.123558) (xy 114.683177 -277.162902) (xy 114.706048 -277.206479)
			(xy 114.721632 -277.25316) (xy 114.729527 -277.301737) (xy 114.730022 -277.326344) (xy 115.058964 -277.326344)
			(xy 115.062924 -277.27729) (xy 115.074701 -277.229506) (xy 115.093992 -277.18423) (xy 115.120295 -277.142634)
			(xy 115.15293 -277.105797) (xy 115.191051 -277.074672) (xy 115.233672 -277.050065) (xy 115.279688 -277.032613)
			(xy 115.327907 -277.022769) (xy 115.377082 -277.020788) (xy 115.425937 -277.02672) (xy 115.473208 -277.040412)
			(xy 115.51767 -277.06151) (xy 115.558173 -277.089466) (xy 115.593666 -277.123558) (xy 115.623231 -277.162902)
			(xy 115.646102 -277.206479) (xy 115.661686 -277.25316) (xy 115.669581 -277.301737) (xy 115.670076 -277.326344)
			(xy 115.999018 -277.326344) (xy 116.002978 -277.27729) (xy 116.014755 -277.229506) (xy 116.034046 -277.18423)
			(xy 116.060349 -277.142634) (xy 116.092984 -277.105797) (xy 116.131105 -277.074672) (xy 116.173726 -277.050065)
			(xy 116.219742 -277.032613) (xy 116.267961 -277.022769) (xy 116.317136 -277.020788) (xy 116.365991 -277.02672)
			(xy 116.413262 -277.040412) (xy 116.457724 -277.06151) (xy 116.498227 -277.089466) (xy 116.53372 -277.123558)
			(xy 116.563285 -277.162902) (xy 116.586156 -277.206479) (xy 116.60174 -277.25316) (xy 116.609635 -277.301737)
			(xy 116.61013 -277.326344) (xy 116.938818 -277.326344) (xy 116.942778 -277.27729) (xy 116.954555 -277.229506)
			(xy 116.973846 -277.18423) (xy 117.000149 -277.142634) (xy 117.032784 -277.105797) (xy 117.070905 -277.074672)
			(xy 117.113526 -277.050065) (xy 117.159542 -277.032613) (xy 117.207761 -277.022769) (xy 117.256936 -277.020788)
			(xy 117.305791 -277.02672) (xy 117.353062 -277.040412) (xy 117.397524 -277.06151) (xy 117.438027 -277.089466)
			(xy 117.47352 -277.123558) (xy 117.503085 -277.162902) (xy 117.525956 -277.206479) (xy 117.54154 -277.25316)
			(xy 117.549435 -277.301737) (xy 117.54993 -277.326344) (xy 117.878872 -277.326344) (xy 117.882832 -277.27729)
			(xy 117.894609 -277.229506) (xy 117.9139 -277.18423) (xy 117.940203 -277.142634) (xy 117.972838 -277.105797)
			(xy 118.010959 -277.074672) (xy 118.05358 -277.050065) (xy 118.099596 -277.032613) (xy 118.147815 -277.022769)
			(xy 118.19699 -277.020788) (xy 118.245845 -277.02672) (xy 118.293116 -277.040412) (xy 118.337578 -277.06151)
			(xy 118.378081 -277.089466) (xy 118.413574 -277.123558) (xy 118.443139 -277.162902) (xy 118.46601 -277.206479)
			(xy 118.481594 -277.25316) (xy 118.489489 -277.301737) (xy 118.489984 -277.326344) (xy 118.818926 -277.326344)
			(xy 118.822886 -277.27729) (xy 118.834663 -277.229506) (xy 118.853954 -277.18423) (xy 118.880257 -277.142634)
			(xy 118.912892 -277.105797) (xy 118.951013 -277.074672) (xy 118.993634 -277.050065) (xy 119.03965 -277.032613)
			(xy 119.087869 -277.022769) (xy 119.137044 -277.020788) (xy 119.185899 -277.02672) (xy 119.23317 -277.040412)
			(xy 119.277632 -277.06151) (xy 119.318135 -277.089466) (xy 119.353628 -277.123558) (xy 119.383193 -277.162902)
			(xy 119.406064 -277.206479) (xy 119.421648 -277.25316) (xy 119.429543 -277.301737) (xy 119.430038 -277.326344)
			(xy 119.75898 -277.326344) (xy 119.76294 -277.27729) (xy 119.774717 -277.229506) (xy 119.794008 -277.18423)
			(xy 119.820311 -277.142634) (xy 119.852946 -277.105797) (xy 119.891067 -277.074672) (xy 119.933688 -277.050065)
			(xy 119.979704 -277.032613) (xy 120.027923 -277.022769) (xy 120.077098 -277.020788) (xy 120.125953 -277.02672)
			(xy 120.173224 -277.040412) (xy 120.217686 -277.06151) (xy 120.258189 -277.089466) (xy 120.293682 -277.123558)
			(xy 120.323247 -277.162902) (xy 120.346118 -277.206479) (xy 120.361702 -277.25316) (xy 120.369597 -277.301737)
			(xy 120.370092 -277.326344) (xy 120.699034 -277.326344) (xy 120.702994 -277.27729) (xy 120.714771 -277.229506)
			(xy 120.734062 -277.18423) (xy 120.760365 -277.142634) (xy 120.793 -277.105797) (xy 120.831121 -277.074672)
			(xy 120.873742 -277.050065) (xy 120.919758 -277.032613) (xy 120.967977 -277.022769) (xy 121.017152 -277.020788)
			(xy 121.066007 -277.02672) (xy 121.113278 -277.040412) (xy 121.15774 -277.06151) (xy 121.198243 -277.089466)
			(xy 121.233736 -277.123558) (xy 121.263301 -277.162902) (xy 121.286172 -277.206479) (xy 121.301756 -277.25316)
			(xy 121.309651 -277.301737) (xy 121.310146 -277.326344) (xy 121.638834 -277.326344) (xy 121.642794 -277.27729)
			(xy 121.654571 -277.229506) (xy 121.673862 -277.18423) (xy 121.700165 -277.142634) (xy 121.7328 -277.105797)
			(xy 121.770921 -277.074672) (xy 121.813542 -277.050065) (xy 121.859558 -277.032613) (xy 121.907777 -277.022769)
			(xy 121.956952 -277.020788) (xy 122.005807 -277.02672) (xy 122.053078 -277.040412) (xy 122.09754 -277.06151)
			(xy 122.138043 -277.089466) (xy 122.173536 -277.123558) (xy 122.203101 -277.162902) (xy 122.225972 -277.206479)
			(xy 122.241556 -277.25316) (xy 122.249451 -277.301737) (xy 122.249946 -277.326344) (xy 122.578888 -277.326344)
			(xy 122.582848 -277.27729) (xy 122.594625 -277.229506) (xy 122.613916 -277.18423) (xy 122.640219 -277.142634)
			(xy 122.672854 -277.105797) (xy 122.710975 -277.074672) (xy 122.753596 -277.050065) (xy 122.799612 -277.032613)
			(xy 122.847831 -277.022769) (xy 122.897006 -277.020788) (xy 122.945861 -277.02672) (xy 122.993132 -277.040412)
			(xy 123.037594 -277.06151) (xy 123.078097 -277.089466) (xy 123.11359 -277.123558) (xy 123.143155 -277.162902)
			(xy 123.166026 -277.206479) (xy 123.18161 -277.25316) (xy 123.189505 -277.301737) (xy 123.19 -277.326344)
			(xy 123.518942 -277.326344) (xy 123.522902 -277.27729) (xy 123.534679 -277.229506) (xy 123.55397 -277.18423)
			(xy 123.580273 -277.142634) (xy 123.612908 -277.105797) (xy 123.651029 -277.074672) (xy 123.69365 -277.050065)
			(xy 123.739666 -277.032613) (xy 123.787885 -277.022769) (xy 123.83706 -277.020788) (xy 123.885915 -277.02672)
			(xy 123.933186 -277.040412) (xy 123.977648 -277.06151) (xy 124.018151 -277.089466) (xy 124.053644 -277.123558)
			(xy 124.083209 -277.162902) (xy 124.10608 -277.206479) (xy 124.121664 -277.25316) (xy 124.129559 -277.301737)
			(xy 124.130054 -277.326344) (xy 124.458996 -277.326344) (xy 124.462956 -277.27729) (xy 124.474733 -277.229506)
			(xy 124.494024 -277.18423) (xy 124.520327 -277.142634) (xy 124.552962 -277.105797) (xy 124.591083 -277.074672)
			(xy 124.633704 -277.050065) (xy 124.67972 -277.032613) (xy 124.727939 -277.022769) (xy 124.777114 -277.020788)
			(xy 124.825969 -277.02672) (xy 124.87324 -277.040412) (xy 124.917702 -277.06151) (xy 124.958205 -277.089466)
			(xy 124.993698 -277.123558) (xy 125.023263 -277.162902) (xy 125.046134 -277.206479) (xy 125.061718 -277.25316)
			(xy 125.069613 -277.301737) (xy 125.070108 -277.326344) (xy 125.39905 -277.326344) (xy 125.40301 -277.27729)
			(xy 125.414787 -277.229506) (xy 125.434078 -277.18423) (xy 125.460381 -277.142634) (xy 125.493016 -277.105797)
			(xy 125.531137 -277.074672) (xy 125.573758 -277.050065) (xy 125.619774 -277.032613) (xy 125.667993 -277.022769)
			(xy 125.717168 -277.020788) (xy 125.766023 -277.02672) (xy 125.813294 -277.040412) (xy 125.857756 -277.06151)
			(xy 125.898259 -277.089466) (xy 125.933752 -277.123558) (xy 125.963317 -277.162902) (xy 125.986188 -277.206479)
			(xy 126.001772 -277.25316) (xy 126.009667 -277.301737) (xy 126.010162 -277.326344) (xy 126.009667 -277.350951)
			(xy 126.001772 -277.399528) (xy 125.986188 -277.446209) (xy 125.963317 -277.489786) (xy 125.933752 -277.52913)
			(xy 125.898259 -277.563222) (xy 125.857756 -277.591178) (xy 125.813294 -277.612276) (xy 125.766023 -277.625968)
			(xy 125.717168 -277.6319) (xy 125.667993 -277.629919) (xy 125.619774 -277.620075) (xy 125.573758 -277.602623)
			(xy 125.531137 -277.578016) (xy 125.493016 -277.546891) (xy 125.460381 -277.510054) (xy 125.434078 -277.468458)
			(xy 125.414787 -277.423182) (xy 125.40301 -277.375398) (xy 125.39905 -277.326344) (xy 125.070108 -277.326344)
			(xy 125.069613 -277.350951) (xy 125.061718 -277.399528) (xy 125.046134 -277.446209) (xy 125.023263 -277.489786)
			(xy 124.993698 -277.52913) (xy 124.958205 -277.563222) (xy 124.917702 -277.591178) (xy 124.87324 -277.612276)
			(xy 124.825969 -277.625968) (xy 124.777114 -277.6319) (xy 124.727939 -277.629919) (xy 124.67972 -277.620075)
			(xy 124.633704 -277.602623) (xy 124.591083 -277.578016) (xy 124.552962 -277.546891) (xy 124.520327 -277.510054)
			(xy 124.494024 -277.468458) (xy 124.474733 -277.423182) (xy 124.462956 -277.375398) (xy 124.458996 -277.326344)
			(xy 124.130054 -277.326344) (xy 124.129559 -277.350951) (xy 124.121664 -277.399528) (xy 124.10608 -277.446209)
			(xy 124.083209 -277.489786) (xy 124.053644 -277.52913) (xy 124.018151 -277.563222) (xy 123.977648 -277.591178)
			(xy 123.933186 -277.612276) (xy 123.885915 -277.625968) (xy 123.83706 -277.6319) (xy 123.787885 -277.629919)
			(xy 123.739666 -277.620075) (xy 123.69365 -277.602623) (xy 123.651029 -277.578016) (xy 123.612908 -277.546891)
			(xy 123.580273 -277.510054) (xy 123.55397 -277.468458) (xy 123.534679 -277.423182) (xy 123.522902 -277.375398)
			(xy 123.518942 -277.326344) (xy 123.19 -277.326344) (xy 123.189505 -277.350951) (xy 123.18161 -277.399528)
			(xy 123.166026 -277.446209) (xy 123.143155 -277.489786) (xy 123.11359 -277.52913) (xy 123.078097 -277.563222)
			(xy 123.037594 -277.591178) (xy 122.993132 -277.612276) (xy 122.945861 -277.625968) (xy 122.897006 -277.6319)
			(xy 122.847831 -277.629919) (xy 122.799612 -277.620075) (xy 122.753596 -277.602623) (xy 122.710975 -277.578016)
			(xy 122.672854 -277.546891) (xy 122.640219 -277.510054) (xy 122.613916 -277.468458) (xy 122.594625 -277.423182)
			(xy 122.582848 -277.375398) (xy 122.578888 -277.326344) (xy 122.249946 -277.326344) (xy 122.249451 -277.350951)
			(xy 122.241556 -277.399528) (xy 122.225972 -277.446209) (xy 122.203101 -277.489786) (xy 122.173536 -277.52913)
			(xy 122.138043 -277.563222) (xy 122.09754 -277.591178) (xy 122.053078 -277.612276) (xy 122.005807 -277.625968)
			(xy 121.956952 -277.6319) (xy 121.907777 -277.629919) (xy 121.859558 -277.620075) (xy 121.813542 -277.602623)
			(xy 121.770921 -277.578016) (xy 121.7328 -277.546891) (xy 121.700165 -277.510054) (xy 121.673862 -277.468458)
			(xy 121.654571 -277.423182) (xy 121.642794 -277.375398) (xy 121.638834 -277.326344) (xy 121.310146 -277.326344)
			(xy 121.309651 -277.350951) (xy 121.301756 -277.399528) (xy 121.286172 -277.446209) (xy 121.263301 -277.489786)
			(xy 121.233736 -277.52913) (xy 121.198243 -277.563222) (xy 121.15774 -277.591178) (xy 121.113278 -277.612276)
			(xy 121.066007 -277.625968) (xy 121.017152 -277.6319) (xy 120.967977 -277.629919) (xy 120.919758 -277.620075)
			(xy 120.873742 -277.602623) (xy 120.831121 -277.578016) (xy 120.793 -277.546891) (xy 120.760365 -277.510054)
			(xy 120.734062 -277.468458) (xy 120.714771 -277.423182) (xy 120.702994 -277.375398) (xy 120.699034 -277.326344)
			(xy 120.370092 -277.326344) (xy 120.369597 -277.350951) (xy 120.361702 -277.399528) (xy 120.346118 -277.446209)
			(xy 120.323247 -277.489786) (xy 120.293682 -277.52913) (xy 120.258189 -277.563222) (xy 120.217686 -277.591178)
			(xy 120.173224 -277.612276) (xy 120.125953 -277.625968) (xy 120.077098 -277.6319) (xy 120.027923 -277.629919)
			(xy 119.979704 -277.620075) (xy 119.933688 -277.602623) (xy 119.891067 -277.578016) (xy 119.852946 -277.546891)
			(xy 119.820311 -277.510054) (xy 119.794008 -277.468458) (xy 119.774717 -277.423182) (xy 119.76294 -277.375398)
			(xy 119.75898 -277.326344) (xy 119.430038 -277.326344) (xy 119.429543 -277.350951) (xy 119.421648 -277.399528)
			(xy 119.406064 -277.446209) (xy 119.383193 -277.489786) (xy 119.353628 -277.52913) (xy 119.318135 -277.563222)
			(xy 119.277632 -277.591178) (xy 119.23317 -277.612276) (xy 119.185899 -277.625968) (xy 119.137044 -277.6319)
			(xy 119.087869 -277.629919) (xy 119.03965 -277.620075) (xy 118.993634 -277.602623) (xy 118.951013 -277.578016)
			(xy 118.912892 -277.546891) (xy 118.880257 -277.510054) (xy 118.853954 -277.468458) (xy 118.834663 -277.423182)
			(xy 118.822886 -277.375398) (xy 118.818926 -277.326344) (xy 118.489984 -277.326344) (xy 118.489489 -277.350951)
			(xy 118.481594 -277.399528) (xy 118.46601 -277.446209) (xy 118.443139 -277.489786) (xy 118.413574 -277.52913)
			(xy 118.378081 -277.563222) (xy 118.337578 -277.591178) (xy 118.293116 -277.612276) (xy 118.245845 -277.625968)
			(xy 118.19699 -277.6319) (xy 118.147815 -277.629919) (xy 118.099596 -277.620075) (xy 118.05358 -277.602623)
			(xy 118.010959 -277.578016) (xy 117.972838 -277.546891) (xy 117.940203 -277.510054) (xy 117.9139 -277.468458)
			(xy 117.894609 -277.423182) (xy 117.882832 -277.375398) (xy 117.878872 -277.326344) (xy 117.54993 -277.326344)
			(xy 117.549435 -277.350951) (xy 117.54154 -277.399528) (xy 117.525956 -277.446209) (xy 117.503085 -277.489786)
			(xy 117.47352 -277.52913) (xy 117.438027 -277.563222) (xy 117.397524 -277.591178) (xy 117.353062 -277.612276)
			(xy 117.305791 -277.625968) (xy 117.256936 -277.6319) (xy 117.207761 -277.629919) (xy 117.159542 -277.620075)
			(xy 117.113526 -277.602623) (xy 117.070905 -277.578016) (xy 117.032784 -277.546891) (xy 117.000149 -277.510054)
			(xy 116.973846 -277.468458) (xy 116.954555 -277.423182) (xy 116.942778 -277.375398) (xy 116.938818 -277.326344)
			(xy 116.61013 -277.326344) (xy 116.609635 -277.350951) (xy 116.60174 -277.399528) (xy 116.586156 -277.446209)
			(xy 116.563285 -277.489786) (xy 116.53372 -277.52913) (xy 116.498227 -277.563222) (xy 116.457724 -277.591178)
			(xy 116.413262 -277.612276) (xy 116.365991 -277.625968) (xy 116.317136 -277.6319) (xy 116.267961 -277.629919)
			(xy 116.219742 -277.620075) (xy 116.173726 -277.602623) (xy 116.131105 -277.578016) (xy 116.092984 -277.546891)
			(xy 116.060349 -277.510054) (xy 116.034046 -277.468458) (xy 116.014755 -277.423182) (xy 116.002978 -277.375398)
			(xy 115.999018 -277.326344) (xy 115.670076 -277.326344) (xy 115.669581 -277.350951) (xy 115.661686 -277.399528)
			(xy 115.646102 -277.446209) (xy 115.623231 -277.489786) (xy 115.593666 -277.52913) (xy 115.558173 -277.563222)
			(xy 115.51767 -277.591178) (xy 115.473208 -277.612276) (xy 115.425937 -277.625968) (xy 115.377082 -277.6319)
			(xy 115.327907 -277.629919) (xy 115.279688 -277.620075) (xy 115.233672 -277.602623) (xy 115.191051 -277.578016)
			(xy 115.15293 -277.546891) (xy 115.120295 -277.510054) (xy 115.093992 -277.468458) (xy 115.074701 -277.423182)
			(xy 115.062924 -277.375398) (xy 115.058964 -277.326344) (xy 114.730022 -277.326344) (xy 114.729527 -277.350951)
			(xy 114.721632 -277.399528) (xy 114.706048 -277.446209) (xy 114.683177 -277.489786) (xy 114.653612 -277.52913)
			(xy 114.618119 -277.563222) (xy 114.577616 -277.591178) (xy 114.533154 -277.612276) (xy 114.485883 -277.625968)
			(xy 114.437028 -277.6319) (xy 114.387853 -277.629919) (xy 114.339634 -277.620075) (xy 114.293618 -277.602623)
			(xy 114.250997 -277.578016) (xy 114.212876 -277.546891) (xy 114.180241 -277.510054) (xy 114.153938 -277.468458)
			(xy 114.134647 -277.423182) (xy 114.12287 -277.375398) (xy 114.11891 -277.326344) (xy 113.789968 -277.326344)
			(xy 113.789473 -277.350951) (xy 113.781578 -277.399528) (xy 113.765994 -277.446209) (xy 113.743123 -277.489786)
			(xy 113.713558 -277.52913) (xy 113.678065 -277.563222) (xy 113.637562 -277.591178) (xy 113.5931 -277.612276)
			(xy 113.545829 -277.625968) (xy 113.496974 -277.6319) (xy 113.447799 -277.629919) (xy 113.39958 -277.620075)
			(xy 113.353564 -277.602623) (xy 113.310943 -277.578016) (xy 113.272822 -277.546891) (xy 113.240187 -277.510054)
			(xy 113.213884 -277.468458) (xy 113.194593 -277.423182) (xy 113.182816 -277.375398) (xy 113.178856 -277.326344)
			(xy 110.97641 -277.326344) (xy 110.975915 -277.350951) (xy 110.96802 -277.399528) (xy 110.952436 -277.446209)
			(xy 110.929565 -277.489786) (xy 110.9 -277.52913) (xy 110.864507 -277.563222) (xy 110.824004 -277.591178)
			(xy 110.779542 -277.612276) (xy 110.732271 -277.625968) (xy 110.683416 -277.6319) (xy 110.634241 -277.629919)
			(xy 110.586022 -277.620075) (xy 110.540006 -277.602623) (xy 110.497385 -277.578016) (xy 110.459264 -277.546891)
			(xy 110.426629 -277.510054) (xy 110.400326 -277.468458) (xy 110.381035 -277.423182) (xy 110.369258 -277.375398)
			(xy 110.365298 -277.326344) (xy 110.036356 -277.326344) (xy 110.035861 -277.350951) (xy 110.027966 -277.399528)
			(xy 110.012382 -277.446209) (xy 109.989511 -277.489786) (xy 109.959946 -277.52913) (xy 109.924453 -277.563222)
			(xy 109.88395 -277.591178) (xy 109.839488 -277.612276) (xy 109.792217 -277.625968) (xy 109.743362 -277.6319)
			(xy 109.694187 -277.629919) (xy 109.645968 -277.620075) (xy 109.599952 -277.602623) (xy 109.557331 -277.578016)
			(xy 109.51921 -277.546891) (xy 109.486575 -277.510054) (xy 109.460272 -277.468458) (xy 109.440981 -277.423182)
			(xy 109.429204 -277.375398) (xy 109.425244 -277.326344) (xy 109.096302 -277.326344) (xy 109.095807 -277.350951)
			(xy 109.087912 -277.399528) (xy 109.072328 -277.446209) (xy 109.049457 -277.489786) (xy 109.019892 -277.52913)
			(xy 108.984399 -277.563222) (xy 108.943896 -277.591178) (xy 108.899434 -277.612276) (xy 108.852163 -277.625968)
			(xy 108.803308 -277.6319) (xy 108.754133 -277.629919) (xy 108.705914 -277.620075) (xy 108.659898 -277.602623)
			(xy 108.617277 -277.578016) (xy 108.579156 -277.546891) (xy 108.546521 -277.510054) (xy 108.520218 -277.468458)
			(xy 108.500927 -277.423182) (xy 108.48915 -277.375398) (xy 108.48519 -277.326344) (xy 108.156248 -277.326344)
			(xy 108.155753 -277.350951) (xy 108.147858 -277.399528) (xy 108.132274 -277.446209) (xy 108.109403 -277.489786)
			(xy 108.079838 -277.52913) (xy 108.044345 -277.563222) (xy 108.003842 -277.591178) (xy 107.95938 -277.612276)
			(xy 107.912109 -277.625968) (xy 107.863254 -277.6319) (xy 107.814079 -277.629919) (xy 107.76586 -277.620075)
			(xy 107.719844 -277.602623) (xy 107.677223 -277.578016) (xy 107.639102 -277.546891) (xy 107.606467 -277.510054)
			(xy 107.580164 -277.468458) (xy 107.560873 -277.423182) (xy 107.549096 -277.375398) (xy 107.545136 -277.326344)
			(xy 107.216448 -277.326344) (xy 107.215953 -277.350951) (xy 107.208058 -277.399528) (xy 107.192474 -277.446209)
			(xy 107.169603 -277.489786) (xy 107.140038 -277.52913) (xy 107.104545 -277.563222) (xy 107.064042 -277.591178)
			(xy 107.01958 -277.612276) (xy 106.972309 -277.625968) (xy 106.923454 -277.6319) (xy 106.874279 -277.629919)
			(xy 106.82606 -277.620075) (xy 106.780044 -277.602623) (xy 106.737423 -277.578016) (xy 106.699302 -277.546891)
			(xy 106.666667 -277.510054) (xy 106.640364 -277.468458) (xy 106.621073 -277.423182) (xy 106.609296 -277.375398)
			(xy 106.605336 -277.326344) (xy 106.276394 -277.326344) (xy 106.275899 -277.350951) (xy 106.268004 -277.399528)
			(xy 106.25242 -277.446209) (xy 106.229549 -277.489786) (xy 106.199984 -277.52913) (xy 106.164491 -277.563222)
			(xy 106.123988 -277.591178) (xy 106.079526 -277.612276) (xy 106.032255 -277.625968) (xy 105.9834 -277.6319)
			(xy 105.934225 -277.629919) (xy 105.886006 -277.620075) (xy 105.83999 -277.602623) (xy 105.797369 -277.578016)
			(xy 105.759248 -277.546891) (xy 105.726613 -277.510054) (xy 105.70031 -277.468458) (xy 105.681019 -277.423182)
			(xy 105.669242 -277.375398) (xy 105.665282 -277.326344) (xy 105.33634 -277.326344) (xy 105.335845 -277.350951)
			(xy 105.32795 -277.399528) (xy 105.312366 -277.446209) (xy 105.289495 -277.489786) (xy 105.25993 -277.52913)
			(xy 105.224437 -277.563222) (xy 105.183934 -277.591178) (xy 105.139472 -277.612276) (xy 105.092201 -277.625968)
			(xy 105.043346 -277.6319) (xy 104.994171 -277.629919) (xy 104.945952 -277.620075) (xy 104.899936 -277.602623)
			(xy 104.857315 -277.578016) (xy 104.819194 -277.546891) (xy 104.786559 -277.510054) (xy 104.760256 -277.468458)
			(xy 104.740965 -277.423182) (xy 104.729188 -277.375398) (xy 104.725228 -277.326344) (xy 104.396286 -277.326344)
			(xy 104.395791 -277.350951) (xy 104.387896 -277.399528) (xy 104.372312 -277.446209) (xy 104.349441 -277.489786)
			(xy 104.319876 -277.52913) (xy 104.284383 -277.563222) (xy 104.24388 -277.591178) (xy 104.199418 -277.612276)
			(xy 104.152147 -277.625968) (xy 104.103292 -277.6319) (xy 104.054117 -277.629919) (xy 104.005898 -277.620075)
			(xy 103.959882 -277.602623) (xy 103.917261 -277.578016) (xy 103.87914 -277.546891) (xy 103.846505 -277.510054)
			(xy 103.820202 -277.468458) (xy 103.800911 -277.423182) (xy 103.789134 -277.375398) (xy 103.785174 -277.326344)
			(xy 103.456486 -277.326344) (xy 103.455991 -277.350951) (xy 103.448096 -277.399528) (xy 103.432512 -277.446209)
			(xy 103.409641 -277.489786) (xy 103.380076 -277.52913) (xy 103.344583 -277.563222) (xy 103.30408 -277.591178)
			(xy 103.259618 -277.612276) (xy 103.212347 -277.625968) (xy 103.163492 -277.6319) (xy 103.114317 -277.629919)
			(xy 103.066098 -277.620075) (xy 103.020082 -277.602623) (xy 102.977461 -277.578016) (xy 102.93934 -277.546891)
			(xy 102.906705 -277.510054) (xy 102.880402 -277.468458) (xy 102.861111 -277.423182) (xy 102.849334 -277.375398)
			(xy 102.845374 -277.326344) (xy 102.516432 -277.326344) (xy 102.515937 -277.350951) (xy 102.508042 -277.399528)
			(xy 102.492458 -277.446209) (xy 102.469587 -277.489786) (xy 102.440022 -277.52913) (xy 102.404529 -277.563222)
			(xy 102.364026 -277.591178) (xy 102.319564 -277.612276) (xy 102.272293 -277.625968) (xy 102.223438 -277.6319)
			(xy 102.174263 -277.629919) (xy 102.126044 -277.620075) (xy 102.080028 -277.602623) (xy 102.037407 -277.578016)
			(xy 101.999286 -277.546891) (xy 101.966651 -277.510054) (xy 101.940348 -277.468458) (xy 101.921057 -277.423182)
			(xy 101.90928 -277.375398) (xy 101.90532 -277.326344) (xy 101.576378 -277.326344) (xy 101.575883 -277.350951)
			(xy 101.567988 -277.399528) (xy 101.552404 -277.446209) (xy 101.529533 -277.489786) (xy 101.499968 -277.52913)
			(xy 101.464475 -277.563222) (xy 101.423972 -277.591178) (xy 101.37951 -277.612276) (xy 101.332239 -277.625968)
			(xy 101.283384 -277.6319) (xy 101.234209 -277.629919) (xy 101.18599 -277.620075) (xy 101.139974 -277.602623)
			(xy 101.097353 -277.578016) (xy 101.059232 -277.546891) (xy 101.026597 -277.510054) (xy 101.000294 -277.468458)
			(xy 100.981003 -277.423182) (xy 100.969226 -277.375398) (xy 100.965266 -277.326344) (xy 100.636324 -277.326344)
			(xy 100.635829 -277.350951) (xy 100.627934 -277.399528) (xy 100.61235 -277.446209) (xy 100.589479 -277.489786)
			(xy 100.559914 -277.52913) (xy 100.524421 -277.563222) (xy 100.483918 -277.591178) (xy 100.439456 -277.612276)
			(xy 100.392185 -277.625968) (xy 100.34333 -277.6319) (xy 100.294155 -277.629919) (xy 100.245936 -277.620075)
			(xy 100.19992 -277.602623) (xy 100.157299 -277.578016) (xy 100.119178 -277.546891) (xy 100.086543 -277.510054)
			(xy 100.06024 -277.468458) (xy 100.040949 -277.423182) (xy 100.029172 -277.375398) (xy 100.025212 -277.326344)
			(xy 99.69627 -277.326344) (xy 99.695775 -277.350951) (xy 99.68788 -277.399528) (xy 99.672296 -277.446209)
			(xy 99.649425 -277.489786) (xy 99.61986 -277.52913) (xy 99.584367 -277.563222) (xy 99.543864 -277.591178)
			(xy 99.499402 -277.612276) (xy 99.452131 -277.625968) (xy 99.403276 -277.6319) (xy 99.354101 -277.629919)
			(xy 99.305882 -277.620075) (xy 99.259866 -277.602623) (xy 99.217245 -277.578016) (xy 99.179124 -277.546891)
			(xy 99.146489 -277.510054) (xy 99.120186 -277.468458) (xy 99.100895 -277.423182) (xy 99.089118 -277.375398)
			(xy 99.085158 -277.326344) (xy 98.75647 -277.326344) (xy 98.755975 -277.350951) (xy 98.74808 -277.399528)
			(xy 98.732496 -277.446209) (xy 98.709625 -277.489786) (xy 98.68006 -277.52913) (xy 98.644567 -277.563222)
			(xy 98.604064 -277.591178) (xy 98.559602 -277.612276) (xy 98.512331 -277.625968) (xy 98.463476 -277.6319)
			(xy 98.414301 -277.629919) (xy 98.366082 -277.620075) (xy 98.320066 -277.602623) (xy 98.277445 -277.578016)
			(xy 98.239324 -277.546891) (xy 98.206689 -277.510054) (xy 98.180386 -277.468458) (xy 98.161095 -277.423182)
			(xy 98.149318 -277.375398) (xy 98.145358 -277.326344) (xy 97.816416 -277.326344) (xy 97.815921 -277.350951)
			(xy 97.808026 -277.399528) (xy 97.792442 -277.446209) (xy 97.769571 -277.489786) (xy 97.740006 -277.52913)
			(xy 97.704513 -277.563222) (xy 97.66401 -277.591178) (xy 97.619548 -277.612276) (xy 97.572277 -277.625968)
			(xy 97.523422 -277.6319) (xy 97.474247 -277.629919) (xy 97.426028 -277.620075) (xy 97.380012 -277.602623)
			(xy 97.337391 -277.578016) (xy 97.29927 -277.546891) (xy 97.266635 -277.510054) (xy 97.240332 -277.468458)
			(xy 97.221041 -277.423182) (xy 97.209264 -277.375398) (xy 97.205304 -277.326344) (xy 96.876362 -277.326344)
			(xy 96.875867 -277.350951) (xy 96.867972 -277.399528) (xy 96.852388 -277.446209) (xy 96.829517 -277.489786)
			(xy 96.799952 -277.52913) (xy 96.764459 -277.563222) (xy 96.723956 -277.591178) (xy 96.679494 -277.612276)
			(xy 96.632223 -277.625968) (xy 96.583368 -277.6319) (xy 96.534193 -277.629919) (xy 96.485974 -277.620075)
			(xy 96.439958 -277.602623) (xy 96.397337 -277.578016) (xy 96.359216 -277.546891) (xy 96.326581 -277.510054)
			(xy 96.300278 -277.468458) (xy 96.280987 -277.423182) (xy 96.26921 -277.375398) (xy 96.26525 -277.326344)
			(xy 95.946722 -277.326344) (xy 95.94621 -277.35179) (xy 95.938046 -277.402024) (xy 95.92193 -277.450298)
			(xy 95.898279 -277.495361) (xy 95.867706 -277.536047) (xy 95.831002 -277.571302) (xy 95.789118 -277.600212)
			(xy 95.743139 -277.622029) (xy 95.694255 -277.636189) (xy 95.643734 -277.642323) (xy 95.592882 -277.640274)
			(xy 95.543018 -277.630094) (xy 95.495432 -277.612047) (xy 95.451358 -277.586601) (xy 95.411936 -277.554414)
			(xy 95.378188 -277.51632) (xy 95.350987 -277.473306) (xy 95.331039 -277.426486) (xy 95.31886 -277.377072)
			(xy 95.314765 -277.326344) (xy 95.006668 -277.326344) (xy 95.006156 -277.35179) (xy 94.997992 -277.402024)
			(xy 94.981876 -277.450298) (xy 94.958225 -277.495361) (xy 94.927652 -277.536047) (xy 94.890948 -277.571302)
			(xy 94.849064 -277.600212) (xy 94.803085 -277.622029) (xy 94.754201 -277.636189) (xy 94.70368 -277.642323)
			(xy 94.652828 -277.640274) (xy 94.602964 -277.630094) (xy 94.555378 -277.612047) (xy 94.511304 -277.586601)
			(xy 94.471882 -277.554414) (xy 94.438134 -277.51632) (xy 94.410933 -277.473306) (xy 94.390985 -277.426486)
			(xy 94.378806 -277.377072) (xy 94.374711 -277.326344) (xy 94.056883 -277.326344) (xy 94.052717 -277.376626)
			(xy 94.040322 -277.42558) (xy 94.020039 -277.471826) (xy 93.992421 -277.514103) (xy 93.958222 -277.551258)
			(xy 93.918374 -277.582279) (xy 93.873964 -277.606318) (xy 93.826204 -277.62272) (xy 93.776395 -277.631039)
			(xy 93.751146 -277.631652) (xy 93.727381 -277.631201) (xy 93.680425 -277.623837) (xy 93.63518 -277.609279)
			(xy 93.59274 -277.587879) (xy 93.554133 -277.560156) (xy 93.520292 -277.526781) (xy 93.505782 -277.507954)
			(xy 93.505782 -277.5077) (xy 93.505528 -277.5077) (xy 93.501374 -277.502517) (xy 93.490961 -277.494278)
			(xy 93.484954 -277.491444) (xy 93.478545 -277.488897) (xy 93.464895 -277.486975) (xy 93.45803 -277.487634)
			(xy 93.372178 -277.499064) (xy 93.365419 -277.50014) (xy 93.352797 -277.505419) (xy 93.347286 -277.509478)
			(xy 93.341952 -277.513542) (xy 93.334078 -277.52421) (xy 93.331538 -277.530814) (xy 93.31599 -277.568487)
			(xy 93.275571 -277.639254) (xy 93.25102 -277.671784) (xy 93.25102 -277.672038) (xy 93.246985 -277.677441)
			(xy 93.241578 -277.689791) (xy 93.240352 -277.696422) (xy 93.238574 -277.70963) (xy 93.276928 -277.80234)
			(xy 93.279682 -277.808504) (xy 93.287922 -277.819193) (xy 93.293184 -277.823422) (xy 93.298518 -277.827486)
			(xy 93.31071 -277.832312) (xy 93.317822 -277.833328) (xy 93.342183 -277.836792) (xy 93.389439 -277.850494)
			(xy 93.433887 -277.871594) (xy 93.474377 -277.899547) (xy 93.509863 -277.93363) (xy 93.539425 -277.972961)
			(xy 93.562299 -278.016522) (xy 93.577894 -278.063187) (xy 93.585806 -278.111749) (xy 93.5863 -278.13635)
			(xy 93.904811 -278.13635) (xy 93.908906 -278.085622) (xy 93.921085 -278.036208) (xy 93.941033 -277.989388)
			(xy 93.968234 -277.946374) (xy 94.001982 -277.90828) (xy 94.041404 -277.876093) (xy 94.085478 -277.850647)
			(xy 94.133064 -277.8326) (xy 94.182928 -277.82242) (xy 94.23378 -277.820371) (xy 94.284301 -277.826505)
			(xy 94.333185 -277.840665) (xy 94.379164 -277.862482) (xy 94.421048 -277.891392) (xy 94.457752 -277.926647)
			(xy 94.488325 -277.967333) (xy 94.511976 -278.012396) (xy 94.528092 -278.06067) (xy 94.536256 -278.110904)
			(xy 94.536768 -278.13635) (xy 94.855296 -278.13635) (xy 94.859256 -278.087296) (xy 94.871033 -278.039512)
			(xy 94.890324 -277.994236) (xy 94.916627 -277.95264) (xy 94.949262 -277.915803) (xy 94.987383 -277.884678)
			(xy 95.030004 -277.860071) (xy 95.07602 -277.842619) (xy 95.124239 -277.832775) (xy 95.173414 -277.830794)
			(xy 95.222269 -277.836726) (xy 95.26954 -277.850418) (xy 95.314002 -277.871516) (xy 95.354505 -277.899472)
			(xy 95.389998 -277.933564) (xy 95.419563 -277.972908) (xy 95.442434 -278.016485) (xy 95.458018 -278.063166)
			(xy 95.465913 -278.111743) (xy 95.466408 -278.13635) (xy 95.784919 -278.13635) (xy 95.789014 -278.085622)
			(xy 95.801193 -278.036208) (xy 95.821141 -277.989388) (xy 95.848342 -277.946374) (xy 95.88209 -277.90828)
			(xy 95.921512 -277.876093) (xy 95.965586 -277.850647) (xy 96.013172 -277.8326) (xy 96.063036 -277.82242)
			(xy 96.113888 -277.820371) (xy 96.164409 -277.826505) (xy 96.213293 -277.840665) (xy 96.259272 -277.862482)
			(xy 96.301156 -277.891392) (xy 96.33786 -277.926647) (xy 96.368433 -277.967333) (xy 96.392084 -278.012396)
			(xy 96.4082 -278.06067) (xy 96.416364 -278.110904) (xy 96.416876 -278.13635) (xy 96.73515 -278.13635)
			(xy 96.73911 -278.087296) (xy 96.750887 -278.039512) (xy 96.770178 -277.994236) (xy 96.796481 -277.95264)
			(xy 96.829116 -277.915803) (xy 96.867237 -277.884678) (xy 96.909858 -277.860071) (xy 96.955874 -277.842619)
			(xy 97.004093 -277.832775) (xy 97.053268 -277.830794) (xy 97.102123 -277.836726) (xy 97.149394 -277.850418)
			(xy 97.193856 -277.871516) (xy 97.234359 -277.899472) (xy 97.269852 -277.933564) (xy 97.299417 -277.972908)
			(xy 97.322288 -278.016485) (xy 97.337872 -278.063166) (xy 97.345767 -278.111743) (xy 97.346262 -278.13635)
			(xy 97.675204 -278.13635) (xy 97.679164 -278.087296) (xy 97.690941 -278.039512) (xy 97.710232 -277.994236)
			(xy 97.736535 -277.95264) (xy 97.76917 -277.915803) (xy 97.807291 -277.884678) (xy 97.849912 -277.860071)
			(xy 97.895928 -277.842619) (xy 97.944147 -277.832775) (xy 97.993322 -277.830794) (xy 98.042177 -277.836726)
			(xy 98.089448 -277.850418) (xy 98.13391 -277.871516) (xy 98.174413 -277.899472) (xy 98.209906 -277.933564)
			(xy 98.239471 -277.972908) (xy 98.262342 -278.016485) (xy 98.277926 -278.063166) (xy 98.285821 -278.111743)
			(xy 98.286316 -278.13635) (xy 98.615258 -278.13635) (xy 98.619218 -278.087296) (xy 98.630995 -278.039512)
			(xy 98.650286 -277.994236) (xy 98.676589 -277.95264) (xy 98.709224 -277.915803) (xy 98.747345 -277.884678)
			(xy 98.789966 -277.860071) (xy 98.835982 -277.842619) (xy 98.884201 -277.832775) (xy 98.933376 -277.830794)
			(xy 98.982231 -277.836726) (xy 99.029502 -277.850418) (xy 99.073964 -277.871516) (xy 99.114467 -277.899472)
			(xy 99.14996 -277.933564) (xy 99.179525 -277.972908) (xy 99.202396 -278.016485) (xy 99.21798 -278.063166)
			(xy 99.225875 -278.111743) (xy 99.22637 -278.13635) (xy 99.555312 -278.13635) (xy 99.559272 -278.087296)
			(xy 99.571049 -278.039512) (xy 99.59034 -277.994236) (xy 99.616643 -277.95264) (xy 99.649278 -277.915803)
			(xy 99.687399 -277.884678) (xy 99.73002 -277.860071) (xy 99.776036 -277.842619) (xy 99.824255 -277.832775)
			(xy 99.87343 -277.830794) (xy 99.922285 -277.836726) (xy 99.969556 -277.850418) (xy 100.014018 -277.871516)
			(xy 100.054521 -277.899472) (xy 100.090014 -277.933564) (xy 100.119579 -277.972908) (xy 100.14245 -278.016485)
			(xy 100.158034 -278.063166) (xy 100.165929 -278.111743) (xy 100.166424 -278.13635) (xy 100.495366 -278.13635)
			(xy 100.499326 -278.087296) (xy 100.511103 -278.039512) (xy 100.530394 -277.994236) (xy 100.556697 -277.95264)
			(xy 100.589332 -277.915803) (xy 100.627453 -277.884678) (xy 100.670074 -277.860071) (xy 100.71609 -277.842619)
			(xy 100.764309 -277.832775) (xy 100.813484 -277.830794) (xy 100.862339 -277.836726) (xy 100.90961 -277.850418)
			(xy 100.954072 -277.871516) (xy 100.994575 -277.899472) (xy 101.030068 -277.933564) (xy 101.059633 -277.972908)
			(xy 101.082504 -278.016485) (xy 101.098088 -278.063166) (xy 101.105983 -278.111743) (xy 101.106478 -278.13635)
			(xy 101.435166 -278.13635) (xy 101.439126 -278.087296) (xy 101.450903 -278.039512) (xy 101.470194 -277.994236)
			(xy 101.496497 -277.95264) (xy 101.529132 -277.915803) (xy 101.567253 -277.884678) (xy 101.609874 -277.860071)
			(xy 101.65589 -277.842619) (xy 101.704109 -277.832775) (xy 101.753284 -277.830794) (xy 101.802139 -277.836726)
			(xy 101.84941 -277.850418) (xy 101.893872 -277.871516) (xy 101.934375 -277.899472) (xy 101.969868 -277.933564)
			(xy 101.999433 -277.972908) (xy 102.022304 -278.016485) (xy 102.037888 -278.063166) (xy 102.045783 -278.111743)
			(xy 102.046278 -278.13635) (xy 102.37522 -278.13635) (xy 102.37918 -278.087296) (xy 102.390957 -278.039512)
			(xy 102.410248 -277.994236) (xy 102.436551 -277.95264) (xy 102.469186 -277.915803) (xy 102.507307 -277.884678)
			(xy 102.549928 -277.860071) (xy 102.595944 -277.842619) (xy 102.644163 -277.832775) (xy 102.693338 -277.830794)
			(xy 102.742193 -277.836726) (xy 102.789464 -277.850418) (xy 102.833926 -277.871516) (xy 102.874429 -277.899472)
			(xy 102.909922 -277.933564) (xy 102.939487 -277.972908) (xy 102.962358 -278.016485) (xy 102.977942 -278.063166)
			(xy 102.985837 -278.111743) (xy 102.986332 -278.13635) (xy 103.315274 -278.13635) (xy 103.319234 -278.087296)
			(xy 103.331011 -278.039512) (xy 103.350302 -277.994236) (xy 103.376605 -277.95264) (xy 103.40924 -277.915803)
			(xy 103.447361 -277.884678) (xy 103.489982 -277.860071) (xy 103.535998 -277.842619) (xy 103.584217 -277.832775)
			(xy 103.633392 -277.830794) (xy 103.682247 -277.836726) (xy 103.729518 -277.850418) (xy 103.77398 -277.871516)
			(xy 103.814483 -277.899472) (xy 103.849976 -277.933564) (xy 103.879541 -277.972908) (xy 103.902412 -278.016485)
			(xy 103.917996 -278.063166) (xy 103.925891 -278.111743) (xy 103.926386 -278.13635) (xy 104.255328 -278.13635)
			(xy 104.259288 -278.087296) (xy 104.271065 -278.039512) (xy 104.290356 -277.994236) (xy 104.316659 -277.95264)
			(xy 104.349294 -277.915803) (xy 104.387415 -277.884678) (xy 104.430036 -277.860071) (xy 104.476052 -277.842619)
			(xy 104.524271 -277.832775) (xy 104.573446 -277.830794) (xy 104.622301 -277.836726) (xy 104.669572 -277.850418)
			(xy 104.714034 -277.871516) (xy 104.754537 -277.899472) (xy 104.79003 -277.933564) (xy 104.819595 -277.972908)
			(xy 104.842466 -278.016485) (xy 104.85805 -278.063166) (xy 104.865945 -278.111743) (xy 104.86644 -278.13635)
			(xy 105.195128 -278.13635) (xy 105.199088 -278.087296) (xy 105.210865 -278.039512) (xy 105.230156 -277.994236)
			(xy 105.256459 -277.95264) (xy 105.289094 -277.915803) (xy 105.327215 -277.884678) (xy 105.369836 -277.860071)
			(xy 105.415852 -277.842619) (xy 105.464071 -277.832775) (xy 105.513246 -277.830794) (xy 105.562101 -277.836726)
			(xy 105.609372 -277.850418) (xy 105.653834 -277.871516) (xy 105.694337 -277.899472) (xy 105.72983 -277.933564)
			(xy 105.759395 -277.972908) (xy 105.782266 -278.016485) (xy 105.79785 -278.063166) (xy 105.805745 -278.111743)
			(xy 105.80624 -278.13635) (xy 106.135182 -278.13635) (xy 106.139142 -278.087296) (xy 106.150919 -278.039512)
			(xy 106.17021 -277.994236) (xy 106.196513 -277.95264) (xy 106.229148 -277.915803) (xy 106.267269 -277.884678)
			(xy 106.30989 -277.860071) (xy 106.355906 -277.842619) (xy 106.404125 -277.832775) (xy 106.4533 -277.830794)
			(xy 106.502155 -277.836726) (xy 106.549426 -277.850418) (xy 106.593888 -277.871516) (xy 106.634391 -277.899472)
			(xy 106.669884 -277.933564) (xy 106.699449 -277.972908) (xy 106.72232 -278.016485) (xy 106.737904 -278.063166)
			(xy 106.745799 -278.111743) (xy 106.746294 -278.13635) (xy 107.075236 -278.13635) (xy 107.079196 -278.087296)
			(xy 107.090973 -278.039512) (xy 107.110264 -277.994236) (xy 107.136567 -277.95264) (xy 107.169202 -277.915803)
			(xy 107.207323 -277.884678) (xy 107.249944 -277.860071) (xy 107.29596 -277.842619) (xy 107.344179 -277.832775)
			(xy 107.393354 -277.830794) (xy 107.442209 -277.836726) (xy 107.48948 -277.850418) (xy 107.533942 -277.871516)
			(xy 107.574445 -277.899472) (xy 107.609938 -277.933564) (xy 107.639503 -277.972908) (xy 107.662374 -278.016485)
			(xy 107.677958 -278.063166) (xy 107.685853 -278.111743) (xy 107.686348 -278.13635) (xy 108.01529 -278.13635)
			(xy 108.01925 -278.087296) (xy 108.031027 -278.039512) (xy 108.050318 -277.994236) (xy 108.076621 -277.95264)
			(xy 108.109256 -277.915803) (xy 108.147377 -277.884678) (xy 108.189998 -277.860071) (xy 108.236014 -277.842619)
			(xy 108.284233 -277.832775) (xy 108.333408 -277.830794) (xy 108.382263 -277.836726) (xy 108.429534 -277.850418)
			(xy 108.473996 -277.871516) (xy 108.514499 -277.899472) (xy 108.549992 -277.933564) (xy 108.579557 -277.972908)
			(xy 108.602428 -278.016485) (xy 108.618012 -278.063166) (xy 108.625907 -278.111743) (xy 108.626402 -278.13635)
			(xy 115.528864 -278.13635) (xy 115.532824 -278.087296) (xy 115.544601 -278.039512) (xy 115.563892 -277.994236)
			(xy 115.590195 -277.95264) (xy 115.62283 -277.915803) (xy 115.660951 -277.884678) (xy 115.703572 -277.860071)
			(xy 115.749588 -277.842619) (xy 115.797807 -277.832775) (xy 115.846982 -277.830794) (xy 115.895837 -277.836726)
			(xy 115.943108 -277.850418) (xy 115.98757 -277.871516) (xy 116.028073 -277.899472) (xy 116.063566 -277.933564)
			(xy 116.093131 -277.972908) (xy 116.116002 -278.016485) (xy 116.131586 -278.063166) (xy 116.139481 -278.111743)
			(xy 116.139976 -278.13635) (xy 116.468918 -278.13635) (xy 116.472878 -278.087296) (xy 116.484655 -278.039512)
			(xy 116.503946 -277.994236) (xy 116.530249 -277.95264) (xy 116.562884 -277.915803) (xy 116.601005 -277.884678)
			(xy 116.643626 -277.860071) (xy 116.689642 -277.842619) (xy 116.737861 -277.832775) (xy 116.787036 -277.830794)
			(xy 116.835891 -277.836726) (xy 116.883162 -277.850418) (xy 116.927624 -277.871516) (xy 116.968127 -277.899472)
			(xy 117.00362 -277.933564) (xy 117.033185 -277.972908) (xy 117.056056 -278.016485) (xy 117.07164 -278.063166)
			(xy 117.079535 -278.111743) (xy 117.08003 -278.13635) (xy 117.408972 -278.13635) (xy 117.412932 -278.087296)
			(xy 117.424709 -278.039512) (xy 117.444 -277.994236) (xy 117.470303 -277.95264) (xy 117.502938 -277.915803)
			(xy 117.541059 -277.884678) (xy 117.58368 -277.860071) (xy 117.629696 -277.842619) (xy 117.677915 -277.832775)
			(xy 117.72709 -277.830794) (xy 117.775945 -277.836726) (xy 117.823216 -277.850418) (xy 117.867678 -277.871516)
			(xy 117.908181 -277.899472) (xy 117.943674 -277.933564) (xy 117.973239 -277.972908) (xy 117.99611 -278.016485)
			(xy 118.011694 -278.063166) (xy 118.019589 -278.111743) (xy 118.020084 -278.13635) (xy 118.349026 -278.13635)
			(xy 118.352986 -278.087296) (xy 118.364763 -278.039512) (xy 118.384054 -277.994236) (xy 118.410357 -277.95264)
			(xy 118.442992 -277.915803) (xy 118.481113 -277.884678) (xy 118.523734 -277.860071) (xy 118.56975 -277.842619)
			(xy 118.617969 -277.832775) (xy 118.667144 -277.830794) (xy 118.715999 -277.836726) (xy 118.76327 -277.850418)
			(xy 118.807732 -277.871516) (xy 118.848235 -277.899472) (xy 118.883728 -277.933564) (xy 118.913293 -277.972908)
			(xy 118.936164 -278.016485) (xy 118.951748 -278.063166) (xy 118.959643 -278.111743) (xy 118.960138 -278.13635)
			(xy 119.288826 -278.13635) (xy 119.292786 -278.087296) (xy 119.304563 -278.039512) (xy 119.323854 -277.994236)
			(xy 119.350157 -277.95264) (xy 119.382792 -277.915803) (xy 119.420913 -277.884678) (xy 119.463534 -277.860071)
			(xy 119.50955 -277.842619) (xy 119.557769 -277.832775) (xy 119.606944 -277.830794) (xy 119.655799 -277.836726)
			(xy 119.70307 -277.850418) (xy 119.747532 -277.871516) (xy 119.788035 -277.899472) (xy 119.823528 -277.933564)
			(xy 119.853093 -277.972908) (xy 119.875964 -278.016485) (xy 119.891548 -278.063166) (xy 119.899443 -278.111743)
			(xy 119.899938 -278.13635) (xy 120.22888 -278.13635) (xy 120.23284 -278.087296) (xy 120.244617 -278.039512)
			(xy 120.263908 -277.994236) (xy 120.290211 -277.95264) (xy 120.322846 -277.915803) (xy 120.360967 -277.884678)
			(xy 120.403588 -277.860071) (xy 120.449604 -277.842619) (xy 120.497823 -277.832775) (xy 120.546998 -277.830794)
			(xy 120.595853 -277.836726) (xy 120.643124 -277.850418) (xy 120.687586 -277.871516) (xy 120.728089 -277.899472)
			(xy 120.763582 -277.933564) (xy 120.793147 -277.972908) (xy 120.816018 -278.016485) (xy 120.831602 -278.063166)
			(xy 120.839497 -278.111743) (xy 120.839992 -278.13635) (xy 121.168934 -278.13635) (xy 121.172894 -278.087296)
			(xy 121.184671 -278.039512) (xy 121.203962 -277.994236) (xy 121.230265 -277.95264) (xy 121.2629 -277.915803)
			(xy 121.301021 -277.884678) (xy 121.343642 -277.860071) (xy 121.389658 -277.842619) (xy 121.437877 -277.832775)
			(xy 121.487052 -277.830794) (xy 121.535907 -277.836726) (xy 121.583178 -277.850418) (xy 121.62764 -277.871516)
			(xy 121.668143 -277.899472) (xy 121.703636 -277.933564) (xy 121.733201 -277.972908) (xy 121.756072 -278.016485)
			(xy 121.771656 -278.063166) (xy 121.779551 -278.111743) (xy 121.780046 -278.13635) (xy 122.108988 -278.13635)
			(xy 122.112948 -278.087296) (xy 122.124725 -278.039512) (xy 122.144016 -277.994236) (xy 122.170319 -277.95264)
			(xy 122.202954 -277.915803) (xy 122.241075 -277.884678) (xy 122.283696 -277.860071) (xy 122.329712 -277.842619)
			(xy 122.377931 -277.832775) (xy 122.427106 -277.830794) (xy 122.475961 -277.836726) (xy 122.523232 -277.850418)
			(xy 122.567694 -277.871516) (xy 122.608197 -277.899472) (xy 122.64369 -277.933564) (xy 122.673255 -277.972908)
			(xy 122.696126 -278.016485) (xy 122.71171 -278.063166) (xy 122.719605 -278.111743) (xy 122.7201 -278.13635)
			(xy 123.049042 -278.13635) (xy 123.053002 -278.087296) (xy 123.064779 -278.039512) (xy 123.08407 -277.994236)
			(xy 123.110373 -277.95264) (xy 123.143008 -277.915803) (xy 123.181129 -277.884678) (xy 123.22375 -277.860071)
			(xy 123.269766 -277.842619) (xy 123.317985 -277.832775) (xy 123.36716 -277.830794) (xy 123.416015 -277.836726)
			(xy 123.463286 -277.850418) (xy 123.507748 -277.871516) (xy 123.548251 -277.899472) (xy 123.583744 -277.933564)
			(xy 123.613309 -277.972908) (xy 123.63618 -278.016485) (xy 123.651764 -278.063166) (xy 123.659659 -278.111743)
			(xy 123.660154 -278.13635) (xy 123.988842 -278.13635) (xy 123.992802 -278.087296) (xy 124.004579 -278.039512)
			(xy 124.02387 -277.994236) (xy 124.050173 -277.95264) (xy 124.082808 -277.915803) (xy 124.120929 -277.884678)
			(xy 124.16355 -277.860071) (xy 124.209566 -277.842619) (xy 124.257785 -277.832775) (xy 124.30696 -277.830794)
			(xy 124.355815 -277.836726) (xy 124.403086 -277.850418) (xy 124.447548 -277.871516) (xy 124.488051 -277.899472)
			(xy 124.523544 -277.933564) (xy 124.553109 -277.972908) (xy 124.57598 -278.016485) (xy 124.591564 -278.063166)
			(xy 124.599459 -278.111743) (xy 124.599954 -278.13635) (xy 124.599459 -278.160957) (xy 124.591564 -278.209534)
			(xy 124.57598 -278.256215) (xy 124.553109 -278.299792) (xy 124.523544 -278.339136) (xy 124.488051 -278.373228)
			(xy 124.447548 -278.401184) (xy 124.403086 -278.422282) (xy 124.355815 -278.435974) (xy 124.30696 -278.441906)
			(xy 124.257785 -278.439925) (xy 124.209566 -278.430081) (xy 124.16355 -278.412629) (xy 124.120929 -278.388022)
			(xy 124.082808 -278.356897) (xy 124.050173 -278.32006) (xy 124.02387 -278.278464) (xy 124.004579 -278.233188)
			(xy 123.992802 -278.185404) (xy 123.988842 -278.13635) (xy 123.660154 -278.13635) (xy 123.659659 -278.160957)
			(xy 123.651764 -278.209534) (xy 123.63618 -278.256215) (xy 123.613309 -278.299792) (xy 123.583744 -278.339136)
			(xy 123.548251 -278.373228) (xy 123.507748 -278.401184) (xy 123.463286 -278.422282) (xy 123.416015 -278.435974)
			(xy 123.36716 -278.441906) (xy 123.317985 -278.439925) (xy 123.269766 -278.430081) (xy 123.22375 -278.412629)
			(xy 123.181129 -278.388022) (xy 123.143008 -278.356897) (xy 123.110373 -278.32006) (xy 123.08407 -278.278464)
			(xy 123.064779 -278.233188) (xy 123.053002 -278.185404) (xy 123.049042 -278.13635) (xy 122.7201 -278.13635)
			(xy 122.719605 -278.160957) (xy 122.71171 -278.209534) (xy 122.696126 -278.256215) (xy 122.673255 -278.299792)
			(xy 122.64369 -278.339136) (xy 122.608197 -278.373228) (xy 122.567694 -278.401184) (xy 122.523232 -278.422282)
			(xy 122.475961 -278.435974) (xy 122.427106 -278.441906) (xy 122.377931 -278.439925) (xy 122.329712 -278.430081)
			(xy 122.283696 -278.412629) (xy 122.241075 -278.388022) (xy 122.202954 -278.356897) (xy 122.170319 -278.32006)
			(xy 122.144016 -278.278464) (xy 122.124725 -278.233188) (xy 122.112948 -278.185404) (xy 122.108988 -278.13635)
			(xy 121.780046 -278.13635) (xy 121.779551 -278.160957) (xy 121.771656 -278.209534) (xy 121.756072 -278.256215)
			(xy 121.733201 -278.299792) (xy 121.703636 -278.339136) (xy 121.668143 -278.373228) (xy 121.62764 -278.401184)
			(xy 121.583178 -278.422282) (xy 121.535907 -278.435974) (xy 121.487052 -278.441906) (xy 121.437877 -278.439925)
			(xy 121.389658 -278.430081) (xy 121.343642 -278.412629) (xy 121.301021 -278.388022) (xy 121.2629 -278.356897)
			(xy 121.230265 -278.32006) (xy 121.203962 -278.278464) (xy 121.184671 -278.233188) (xy 121.172894 -278.185404)
			(xy 121.168934 -278.13635) (xy 120.839992 -278.13635) (xy 120.839497 -278.160957) (xy 120.831602 -278.209534)
			(xy 120.816018 -278.256215) (xy 120.793147 -278.299792) (xy 120.763582 -278.339136) (xy 120.728089 -278.373228)
			(xy 120.687586 -278.401184) (xy 120.643124 -278.422282) (xy 120.595853 -278.435974) (xy 120.546998 -278.441906)
			(xy 120.497823 -278.439925) (xy 120.449604 -278.430081) (xy 120.403588 -278.412629) (xy 120.360967 -278.388022)
			(xy 120.322846 -278.356897) (xy 120.290211 -278.32006) (xy 120.263908 -278.278464) (xy 120.244617 -278.233188)
			(xy 120.23284 -278.185404) (xy 120.22888 -278.13635) (xy 119.899938 -278.13635) (xy 119.899443 -278.160957)
			(xy 119.891548 -278.209534) (xy 119.875964 -278.256215) (xy 119.853093 -278.299792) (xy 119.823528 -278.339136)
			(xy 119.788035 -278.373228) (xy 119.747532 -278.401184) (xy 119.70307 -278.422282) (xy 119.655799 -278.435974)
			(xy 119.606944 -278.441906) (xy 119.557769 -278.439925) (xy 119.50955 -278.430081) (xy 119.463534 -278.412629)
			(xy 119.420913 -278.388022) (xy 119.382792 -278.356897) (xy 119.350157 -278.32006) (xy 119.323854 -278.278464)
			(xy 119.304563 -278.233188) (xy 119.292786 -278.185404) (xy 119.288826 -278.13635) (xy 118.960138 -278.13635)
			(xy 118.959643 -278.160957) (xy 118.951748 -278.209534) (xy 118.936164 -278.256215) (xy 118.913293 -278.299792)
			(xy 118.883728 -278.339136) (xy 118.848235 -278.373228) (xy 118.807732 -278.401184) (xy 118.76327 -278.422282)
			(xy 118.715999 -278.435974) (xy 118.667144 -278.441906) (xy 118.617969 -278.439925) (xy 118.56975 -278.430081)
			(xy 118.523734 -278.412629) (xy 118.481113 -278.388022) (xy 118.442992 -278.356897) (xy 118.410357 -278.32006)
			(xy 118.384054 -278.278464) (xy 118.364763 -278.233188) (xy 118.352986 -278.185404) (xy 118.349026 -278.13635)
			(xy 118.020084 -278.13635) (xy 118.019589 -278.160957) (xy 118.011694 -278.209534) (xy 117.99611 -278.256215)
			(xy 117.973239 -278.299792) (xy 117.943674 -278.339136) (xy 117.908181 -278.373228) (xy 117.867678 -278.401184)
			(xy 117.823216 -278.422282) (xy 117.775945 -278.435974) (xy 117.72709 -278.441906) (xy 117.677915 -278.439925)
			(xy 117.629696 -278.430081) (xy 117.58368 -278.412629) (xy 117.541059 -278.388022) (xy 117.502938 -278.356897)
			(xy 117.470303 -278.32006) (xy 117.444 -278.278464) (xy 117.424709 -278.233188) (xy 117.412932 -278.185404)
			(xy 117.408972 -278.13635) (xy 117.08003 -278.13635) (xy 117.079535 -278.160957) (xy 117.07164 -278.209534)
			(xy 117.056056 -278.256215) (xy 117.033185 -278.299792) (xy 117.00362 -278.339136) (xy 116.968127 -278.373228)
			(xy 116.927624 -278.401184) (xy 116.883162 -278.422282) (xy 116.835891 -278.435974) (xy 116.787036 -278.441906)
			(xy 116.737861 -278.439925) (xy 116.689642 -278.430081) (xy 116.643626 -278.412629) (xy 116.601005 -278.388022)
			(xy 116.562884 -278.356897) (xy 116.530249 -278.32006) (xy 116.503946 -278.278464) (xy 116.484655 -278.233188)
			(xy 116.472878 -278.185404) (xy 116.468918 -278.13635) (xy 116.139976 -278.13635) (xy 116.139481 -278.160957)
			(xy 116.131586 -278.209534) (xy 116.116002 -278.256215) (xy 116.093131 -278.299792) (xy 116.063566 -278.339136)
			(xy 116.028073 -278.373228) (xy 115.98757 -278.401184) (xy 115.943108 -278.422282) (xy 115.895837 -278.435974)
			(xy 115.846982 -278.441906) (xy 115.797807 -278.439925) (xy 115.749588 -278.430081) (xy 115.703572 -278.412629)
			(xy 115.660951 -278.388022) (xy 115.62283 -278.356897) (xy 115.590195 -278.32006) (xy 115.563892 -278.278464)
			(xy 115.544601 -278.233188) (xy 115.532824 -278.185404) (xy 115.528864 -278.13635) (xy 108.626402 -278.13635)
			(xy 108.625907 -278.160957) (xy 108.618012 -278.209534) (xy 108.602428 -278.256215) (xy 108.579557 -278.299792)
			(xy 108.549992 -278.339136) (xy 108.514499 -278.373228) (xy 108.473996 -278.401184) (xy 108.429534 -278.422282)
			(xy 108.382263 -278.435974) (xy 108.333408 -278.441906) (xy 108.284233 -278.439925) (xy 108.236014 -278.430081)
			(xy 108.189998 -278.412629) (xy 108.147377 -278.388022) (xy 108.109256 -278.356897) (xy 108.076621 -278.32006)
			(xy 108.050318 -278.278464) (xy 108.031027 -278.233188) (xy 108.01925 -278.185404) (xy 108.01529 -278.13635)
			(xy 107.686348 -278.13635) (xy 107.685853 -278.160957) (xy 107.677958 -278.209534) (xy 107.662374 -278.256215)
			(xy 107.639503 -278.299792) (xy 107.609938 -278.339136) (xy 107.574445 -278.373228) (xy 107.533942 -278.401184)
			(xy 107.48948 -278.422282) (xy 107.442209 -278.435974) (xy 107.393354 -278.441906) (xy 107.344179 -278.439925)
			(xy 107.29596 -278.430081) (xy 107.249944 -278.412629) (xy 107.207323 -278.388022) (xy 107.169202 -278.356897)
			(xy 107.136567 -278.32006) (xy 107.110264 -278.278464) (xy 107.090973 -278.233188) (xy 107.079196 -278.185404)
			(xy 107.075236 -278.13635) (xy 106.746294 -278.13635) (xy 106.745799 -278.160957) (xy 106.737904 -278.209534)
			(xy 106.72232 -278.256215) (xy 106.699449 -278.299792) (xy 106.669884 -278.339136) (xy 106.634391 -278.373228)
			(xy 106.593888 -278.401184) (xy 106.549426 -278.422282) (xy 106.502155 -278.435974) (xy 106.4533 -278.441906)
			(xy 106.404125 -278.439925) (xy 106.355906 -278.430081) (xy 106.30989 -278.412629) (xy 106.267269 -278.388022)
			(xy 106.229148 -278.356897) (xy 106.196513 -278.32006) (xy 106.17021 -278.278464) (xy 106.150919 -278.233188)
			(xy 106.139142 -278.185404) (xy 106.135182 -278.13635) (xy 105.80624 -278.13635) (xy 105.805745 -278.160957)
			(xy 105.79785 -278.209534) (xy 105.782266 -278.256215) (xy 105.759395 -278.299792) (xy 105.72983 -278.339136)
			(xy 105.694337 -278.373228) (xy 105.653834 -278.401184) (xy 105.609372 -278.422282) (xy 105.562101 -278.435974)
			(xy 105.513246 -278.441906) (xy 105.464071 -278.439925) (xy 105.415852 -278.430081) (xy 105.369836 -278.412629)
			(xy 105.327215 -278.388022) (xy 105.289094 -278.356897) (xy 105.256459 -278.32006) (xy 105.230156 -278.278464)
			(xy 105.210865 -278.233188) (xy 105.199088 -278.185404) (xy 105.195128 -278.13635) (xy 104.86644 -278.13635)
			(xy 104.865945 -278.160957) (xy 104.85805 -278.209534) (xy 104.842466 -278.256215) (xy 104.819595 -278.299792)
			(xy 104.79003 -278.339136) (xy 104.754537 -278.373228) (xy 104.714034 -278.401184) (xy 104.669572 -278.422282)
			(xy 104.622301 -278.435974) (xy 104.573446 -278.441906) (xy 104.524271 -278.439925) (xy 104.476052 -278.430081)
			(xy 104.430036 -278.412629) (xy 104.387415 -278.388022) (xy 104.349294 -278.356897) (xy 104.316659 -278.32006)
			(xy 104.290356 -278.278464) (xy 104.271065 -278.233188) (xy 104.259288 -278.185404) (xy 104.255328 -278.13635)
			(xy 103.926386 -278.13635) (xy 103.925891 -278.160957) (xy 103.917996 -278.209534) (xy 103.902412 -278.256215)
			(xy 103.879541 -278.299792) (xy 103.849976 -278.339136) (xy 103.814483 -278.373228) (xy 103.77398 -278.401184)
			(xy 103.729518 -278.422282) (xy 103.682247 -278.435974) (xy 103.633392 -278.441906) (xy 103.584217 -278.439925)
			(xy 103.535998 -278.430081) (xy 103.489982 -278.412629) (xy 103.447361 -278.388022) (xy 103.40924 -278.356897)
			(xy 103.376605 -278.32006) (xy 103.350302 -278.278464) (xy 103.331011 -278.233188) (xy 103.319234 -278.185404)
			(xy 103.315274 -278.13635) (xy 102.986332 -278.13635) (xy 102.985837 -278.160957) (xy 102.977942 -278.209534)
			(xy 102.962358 -278.256215) (xy 102.939487 -278.299792) (xy 102.909922 -278.339136) (xy 102.874429 -278.373228)
			(xy 102.833926 -278.401184) (xy 102.789464 -278.422282) (xy 102.742193 -278.435974) (xy 102.693338 -278.441906)
			(xy 102.644163 -278.439925) (xy 102.595944 -278.430081) (xy 102.549928 -278.412629) (xy 102.507307 -278.388022)
			(xy 102.469186 -278.356897) (xy 102.436551 -278.32006) (xy 102.410248 -278.278464) (xy 102.390957 -278.233188)
			(xy 102.37918 -278.185404) (xy 102.37522 -278.13635) (xy 102.046278 -278.13635) (xy 102.045783 -278.160957)
			(xy 102.037888 -278.209534) (xy 102.022304 -278.256215) (xy 101.999433 -278.299792) (xy 101.969868 -278.339136)
			(xy 101.934375 -278.373228) (xy 101.893872 -278.401184) (xy 101.84941 -278.422282) (xy 101.802139 -278.435974)
			(xy 101.753284 -278.441906) (xy 101.704109 -278.439925) (xy 101.65589 -278.430081) (xy 101.609874 -278.412629)
			(xy 101.567253 -278.388022) (xy 101.529132 -278.356897) (xy 101.496497 -278.32006) (xy 101.470194 -278.278464)
			(xy 101.450903 -278.233188) (xy 101.439126 -278.185404) (xy 101.435166 -278.13635) (xy 101.106478 -278.13635)
			(xy 101.105983 -278.160957) (xy 101.098088 -278.209534) (xy 101.082504 -278.256215) (xy 101.059633 -278.299792)
			(xy 101.030068 -278.339136) (xy 100.994575 -278.373228) (xy 100.954072 -278.401184) (xy 100.90961 -278.422282)
			(xy 100.862339 -278.435974) (xy 100.813484 -278.441906) (xy 100.764309 -278.439925) (xy 100.71609 -278.430081)
			(xy 100.670074 -278.412629) (xy 100.627453 -278.388022) (xy 100.589332 -278.356897) (xy 100.556697 -278.32006)
			(xy 100.530394 -278.278464) (xy 100.511103 -278.233188) (xy 100.499326 -278.185404) (xy 100.495366 -278.13635)
			(xy 100.166424 -278.13635) (xy 100.165929 -278.160957) (xy 100.158034 -278.209534) (xy 100.14245 -278.256215)
			(xy 100.119579 -278.299792) (xy 100.090014 -278.339136) (xy 100.054521 -278.373228) (xy 100.014018 -278.401184)
			(xy 99.969556 -278.422282) (xy 99.922285 -278.435974) (xy 99.87343 -278.441906) (xy 99.824255 -278.439925)
			(xy 99.776036 -278.430081) (xy 99.73002 -278.412629) (xy 99.687399 -278.388022) (xy 99.649278 -278.356897)
			(xy 99.616643 -278.32006) (xy 99.59034 -278.278464) (xy 99.571049 -278.233188) (xy 99.559272 -278.185404)
			(xy 99.555312 -278.13635) (xy 99.22637 -278.13635) (xy 99.225875 -278.160957) (xy 99.21798 -278.209534)
			(xy 99.202396 -278.256215) (xy 99.179525 -278.299792) (xy 99.14996 -278.339136) (xy 99.114467 -278.373228)
			(xy 99.073964 -278.401184) (xy 99.029502 -278.422282) (xy 98.982231 -278.435974) (xy 98.933376 -278.441906)
			(xy 98.884201 -278.439925) (xy 98.835982 -278.430081) (xy 98.789966 -278.412629) (xy 98.747345 -278.388022)
			(xy 98.709224 -278.356897) (xy 98.676589 -278.32006) (xy 98.650286 -278.278464) (xy 98.630995 -278.233188)
			(xy 98.619218 -278.185404) (xy 98.615258 -278.13635) (xy 98.286316 -278.13635) (xy 98.285821 -278.160957)
			(xy 98.277926 -278.209534) (xy 98.262342 -278.256215) (xy 98.239471 -278.299792) (xy 98.209906 -278.339136)
			(xy 98.174413 -278.373228) (xy 98.13391 -278.401184) (xy 98.089448 -278.422282) (xy 98.042177 -278.435974)
			(xy 97.993322 -278.441906) (xy 97.944147 -278.439925) (xy 97.895928 -278.430081) (xy 97.849912 -278.412629)
			(xy 97.807291 -278.388022) (xy 97.76917 -278.356897) (xy 97.736535 -278.32006) (xy 97.710232 -278.278464)
			(xy 97.690941 -278.233188) (xy 97.679164 -278.185404) (xy 97.675204 -278.13635) (xy 97.346262 -278.13635)
			(xy 97.345767 -278.160957) (xy 97.337872 -278.209534) (xy 97.322288 -278.256215) (xy 97.299417 -278.299792)
			(xy 97.269852 -278.339136) (xy 97.234359 -278.373228) (xy 97.193856 -278.401184) (xy 97.149394 -278.422282)
			(xy 97.102123 -278.435974) (xy 97.053268 -278.441906) (xy 97.004093 -278.439925) (xy 96.955874 -278.430081)
			(xy 96.909858 -278.412629) (xy 96.867237 -278.388022) (xy 96.829116 -278.356897) (xy 96.796481 -278.32006)
			(xy 96.770178 -278.278464) (xy 96.750887 -278.233188) (xy 96.73911 -278.185404) (xy 96.73515 -278.13635)
			(xy 96.416876 -278.13635) (xy 96.416364 -278.161796) (xy 96.4082 -278.21203) (xy 96.392084 -278.260304)
			(xy 96.368433 -278.305367) (xy 96.33786 -278.346053) (xy 96.301156 -278.381308) (xy 96.259272 -278.410218)
			(xy 96.213293 -278.432035) (xy 96.164409 -278.446195) (xy 96.113888 -278.452329) (xy 96.063036 -278.45028)
			(xy 96.013172 -278.4401) (xy 95.965586 -278.422053) (xy 95.921512 -278.396607) (xy 95.88209 -278.36442)
			(xy 95.848342 -278.326326) (xy 95.821141 -278.283312) (xy 95.801193 -278.236492) (xy 95.789014 -278.187078)
			(xy 95.784919 -278.13635) (xy 95.466408 -278.13635) (xy 95.465913 -278.160957) (xy 95.458018 -278.209534)
			(xy 95.442434 -278.256215) (xy 95.419563 -278.299792) (xy 95.389998 -278.339136) (xy 95.354505 -278.373228)
			(xy 95.314002 -278.401184) (xy 95.26954 -278.422282) (xy 95.222269 -278.435974) (xy 95.173414 -278.441906)
			(xy 95.124239 -278.439925) (xy 95.07602 -278.430081) (xy 95.030004 -278.412629) (xy 94.987383 -278.388022)
			(xy 94.949262 -278.356897) (xy 94.916627 -278.32006) (xy 94.890324 -278.278464) (xy 94.871033 -278.233188)
			(xy 94.859256 -278.185404) (xy 94.855296 -278.13635) (xy 94.536768 -278.13635) (xy 94.536256 -278.161796)
			(xy 94.528092 -278.21203) (xy 94.511976 -278.260304) (xy 94.488325 -278.305367) (xy 94.457752 -278.346053)
			(xy 94.421048 -278.381308) (xy 94.379164 -278.410218) (xy 94.333185 -278.432035) (xy 94.284301 -278.446195)
			(xy 94.23378 -278.452329) (xy 94.182928 -278.45028) (xy 94.133064 -278.4401) (xy 94.085478 -278.422053)
			(xy 94.041404 -278.396607) (xy 94.001982 -278.36442) (xy 93.968234 -278.326326) (xy 93.941033 -278.283312)
			(xy 93.921085 -278.236492) (xy 93.908906 -278.187078) (xy 93.904811 -278.13635) (xy 93.5863 -278.13635)
			(xy 93.585837 -278.160202) (xy 93.578415 -278.207325) (xy 93.563758 -278.252722) (xy 93.542223 -278.295289)
			(xy 93.514333 -278.333991) (xy 93.480766 -278.367887) (xy 93.442339 -278.396155) (xy 93.399985 -278.418105)
			(xy 93.354733 -278.433206) (xy 93.331284 -278.437594) (xy 93.322648 -278.439118) (xy 93.294708 -278.459438)
			(xy 93.289839 -278.463194) (xy 93.28189 -278.472572) (xy 93.27896 -278.47798) (xy 93.248226 -278.540464)
			(xy 93.24721 -278.543004) (xy 93.243647 -278.552373) (xy 93.243403 -278.5724) (xy 93.246702 -278.581866)
			(xy 93.246956 -278.582628) (xy 93.250004 -278.58847) (xy 93.294708 -278.665432) (xy 93.305179 -278.683911)
			(xy 93.323615 -278.722179) (xy 93.331538 -278.741886) (xy 93.331538 -278.74214) (xy 93.33423 -278.748343)
			(xy 93.342337 -278.759157) (xy 93.34754 -278.763476) (xy 93.352874 -278.76754) (xy 93.365066 -278.772874)
			(xy 93.45803 -278.785066) (xy 93.464894 -278.785731) (xy 93.47854 -278.783791) (xy 93.484954 -278.781256)
			(xy 93.490981 -278.778454) (xy 93.501399 -278.770209) (xy 93.505528 -278.765) (xy 93.505782 -278.764746)
			(xy 93.520285 -278.745915) (xy 93.554139 -278.712556) (xy 93.592751 -278.684842) (xy 93.63519 -278.663444)
			(xy 93.680431 -278.648876) (xy 93.727382 -278.641491) (xy 93.751146 -278.641048) (xy 93.776403 -278.641573)
			(xy 93.826226 -278.649894) (xy 93.874 -278.666301) (xy 93.918422 -278.690347) (xy 93.958282 -278.721377)
			(xy 93.992491 -278.758543) (xy 94.020116 -278.800832) (xy 94.040405 -278.847092) (xy 94.052805 -278.896059)
			(xy 94.056972 -278.946356) (xy 94.374711 -278.946356) (xy 94.378806 -278.895628) (xy 94.390985 -278.846214)
			(xy 94.410933 -278.799394) (xy 94.438134 -278.75638) (xy 94.471882 -278.718286) (xy 94.511304 -278.686099)
			(xy 94.555378 -278.660653) (xy 94.602964 -278.642606) (xy 94.652828 -278.632426) (xy 94.70368 -278.630377)
			(xy 94.754201 -278.636511) (xy 94.803085 -278.650671) (xy 94.849064 -278.672488) (xy 94.890948 -278.701398)
			(xy 94.927652 -278.736653) (xy 94.958225 -278.777339) (xy 94.981876 -278.822402) (xy 94.997992 -278.870676)
			(xy 95.006156 -278.92091) (xy 95.006668 -278.946356) (xy 95.314765 -278.946356) (xy 95.31886 -278.895628)
			(xy 95.331039 -278.846214) (xy 95.350987 -278.799394) (xy 95.378188 -278.75638) (xy 95.411936 -278.718286)
			(xy 95.451358 -278.686099) (xy 95.495432 -278.660653) (xy 95.543018 -278.642606) (xy 95.592882 -278.632426)
			(xy 95.643734 -278.630377) (xy 95.694255 -278.636511) (xy 95.743139 -278.650671) (xy 95.789118 -278.672488)
			(xy 95.831002 -278.701398) (xy 95.867706 -278.736653) (xy 95.898279 -278.777339) (xy 95.92193 -278.822402)
			(xy 95.938046 -278.870676) (xy 95.94621 -278.92091) (xy 95.946722 -278.946356) (xy 96.26525 -278.946356)
			(xy 96.26921 -278.897302) (xy 96.280987 -278.849518) (xy 96.300278 -278.804242) (xy 96.326581 -278.762646)
			(xy 96.359216 -278.725809) (xy 96.397337 -278.694684) (xy 96.439958 -278.670077) (xy 96.485974 -278.652625)
			(xy 96.534193 -278.642781) (xy 96.583368 -278.6408) (xy 96.632223 -278.646732) (xy 96.679494 -278.660424)
			(xy 96.723956 -278.681522) (xy 96.764459 -278.709478) (xy 96.799952 -278.74357) (xy 96.829517 -278.782914)
			(xy 96.852388 -278.826491) (xy 96.867972 -278.873172) (xy 96.875867 -278.921749) (xy 96.876362 -278.946356)
			(xy 99.085158 -278.946356) (xy 99.089118 -278.897302) (xy 99.100895 -278.849518) (xy 99.120186 -278.804242)
			(xy 99.146489 -278.762646) (xy 99.179124 -278.725809) (xy 99.217245 -278.694684) (xy 99.259866 -278.670077)
			(xy 99.305882 -278.652625) (xy 99.354101 -278.642781) (xy 99.403276 -278.6408) (xy 99.452131 -278.646732)
			(xy 99.499402 -278.660424) (xy 99.543864 -278.681522) (xy 99.584367 -278.709478) (xy 99.61986 -278.74357)
			(xy 99.649425 -278.782914) (xy 99.672296 -278.826491) (xy 99.68788 -278.873172) (xy 99.695775 -278.921749)
			(xy 99.69627 -278.946356) (xy 101.90532 -278.946356) (xy 101.90928 -278.897302) (xy 101.921057 -278.849518)
			(xy 101.940348 -278.804242) (xy 101.966651 -278.762646) (xy 101.999286 -278.725809) (xy 102.037407 -278.694684)
			(xy 102.080028 -278.670077) (xy 102.126044 -278.652625) (xy 102.174263 -278.642781) (xy 102.223438 -278.6408)
			(xy 102.272293 -278.646732) (xy 102.319564 -278.660424) (xy 102.364026 -278.681522) (xy 102.404529 -278.709478)
			(xy 102.440022 -278.74357) (xy 102.469587 -278.782914) (xy 102.492458 -278.826491) (xy 102.508042 -278.873172)
			(xy 102.515937 -278.921749) (xy 102.516432 -278.946356) (xy 104.725228 -278.946356) (xy 104.729188 -278.897302)
			(xy 104.740965 -278.849518) (xy 104.760256 -278.804242) (xy 104.786559 -278.762646) (xy 104.819194 -278.725809)
			(xy 104.857315 -278.694684) (xy 104.899936 -278.670077) (xy 104.945952 -278.652625) (xy 104.994171 -278.642781)
			(xy 105.043346 -278.6408) (xy 105.092201 -278.646732) (xy 105.139472 -278.660424) (xy 105.183934 -278.681522)
			(xy 105.224437 -278.709478) (xy 105.25993 -278.74357) (xy 105.289495 -278.782914) (xy 105.312366 -278.826491)
			(xy 105.32795 -278.873172) (xy 105.335845 -278.921749) (xy 105.33634 -278.946356) (xy 107.545136 -278.946356)
			(xy 107.549096 -278.897302) (xy 107.560873 -278.849518) (xy 107.580164 -278.804242) (xy 107.606467 -278.762646)
			(xy 107.639102 -278.725809) (xy 107.677223 -278.694684) (xy 107.719844 -278.670077) (xy 107.76586 -278.652625)
			(xy 107.814079 -278.642781) (xy 107.863254 -278.6408) (xy 107.912109 -278.646732) (xy 107.95938 -278.660424)
			(xy 108.003842 -278.681522) (xy 108.044345 -278.709478) (xy 108.079838 -278.74357) (xy 108.109403 -278.782914)
			(xy 108.132274 -278.826491) (xy 108.147858 -278.873172) (xy 108.155753 -278.921749) (xy 108.156248 -278.946356)
			(xy 108.48519 -278.946356) (xy 108.48915 -278.897302) (xy 108.500927 -278.849518) (xy 108.520218 -278.804242)
			(xy 108.546521 -278.762646) (xy 108.579156 -278.725809) (xy 108.617277 -278.694684) (xy 108.659898 -278.670077)
			(xy 108.705914 -278.652625) (xy 108.754133 -278.642781) (xy 108.803308 -278.6408) (xy 108.852163 -278.646732)
			(xy 108.899434 -278.660424) (xy 108.943896 -278.681522) (xy 108.984399 -278.709478) (xy 109.019892 -278.74357)
			(xy 109.049457 -278.782914) (xy 109.072328 -278.826491) (xy 109.087912 -278.873172) (xy 109.095807 -278.921749)
			(xy 109.096302 -278.946356) (xy 109.425244 -278.946356) (xy 109.429204 -278.897302) (xy 109.440981 -278.849518)
			(xy 109.460272 -278.804242) (xy 109.486575 -278.762646) (xy 109.51921 -278.725809) (xy 109.557331 -278.694684)
			(xy 109.599952 -278.670077) (xy 109.645968 -278.652625) (xy 109.694187 -278.642781) (xy 109.743362 -278.6408)
			(xy 109.792217 -278.646732) (xy 109.839488 -278.660424) (xy 109.88395 -278.681522) (xy 109.924453 -278.709478)
			(xy 109.959946 -278.74357) (xy 109.989511 -278.782914) (xy 110.012382 -278.826491) (xy 110.027966 -278.873172)
			(xy 110.035861 -278.921749) (xy 110.036356 -278.946356) (xy 110.365298 -278.946356) (xy 110.369258 -278.897302)
			(xy 110.381035 -278.849518) (xy 110.400326 -278.804242) (xy 110.426629 -278.762646) (xy 110.459264 -278.725809)
			(xy 110.497385 -278.694684) (xy 110.540006 -278.670077) (xy 110.586022 -278.652625) (xy 110.634241 -278.642781)
			(xy 110.683416 -278.6408) (xy 110.732271 -278.646732) (xy 110.779542 -278.660424) (xy 110.824004 -278.681522)
			(xy 110.864507 -278.709478) (xy 110.9 -278.74357) (xy 110.929565 -278.782914) (xy 110.952436 -278.826491)
			(xy 110.96802 -278.873172) (xy 110.975915 -278.921749) (xy 110.97641 -278.946356) (xy 113.178856 -278.946356)
			(xy 113.182816 -278.897302) (xy 113.194593 -278.849518) (xy 113.213884 -278.804242) (xy 113.240187 -278.762646)
			(xy 113.272822 -278.725809) (xy 113.310943 -278.694684) (xy 113.353564 -278.670077) (xy 113.39958 -278.652625)
			(xy 113.447799 -278.642781) (xy 113.496974 -278.6408) (xy 113.545829 -278.646732) (xy 113.5931 -278.660424)
			(xy 113.637562 -278.681522) (xy 113.678065 -278.709478) (xy 113.713558 -278.74357) (xy 113.743123 -278.782914)
			(xy 113.765994 -278.826491) (xy 113.781578 -278.873172) (xy 113.789473 -278.921749) (xy 113.789968 -278.946356)
			(xy 114.11891 -278.946356) (xy 114.12287 -278.897302) (xy 114.134647 -278.849518) (xy 114.153938 -278.804242)
			(xy 114.180241 -278.762646) (xy 114.212876 -278.725809) (xy 114.250997 -278.694684) (xy 114.293618 -278.670077)
			(xy 114.339634 -278.652625) (xy 114.387853 -278.642781) (xy 114.437028 -278.6408) (xy 114.485883 -278.646732)
			(xy 114.533154 -278.660424) (xy 114.577616 -278.681522) (xy 114.618119 -278.709478) (xy 114.653612 -278.74357)
			(xy 114.683177 -278.782914) (xy 114.706048 -278.826491) (xy 114.721632 -278.873172) (xy 114.729527 -278.921749)
			(xy 114.730022 -278.946356) (xy 115.058964 -278.946356) (xy 115.062924 -278.897302) (xy 115.074701 -278.849518)
			(xy 115.093992 -278.804242) (xy 115.120295 -278.762646) (xy 115.15293 -278.725809) (xy 115.191051 -278.694684)
			(xy 115.233672 -278.670077) (xy 115.279688 -278.652625) (xy 115.327907 -278.642781) (xy 115.377082 -278.6408)
			(xy 115.425937 -278.646732) (xy 115.473208 -278.660424) (xy 115.51767 -278.681522) (xy 115.558173 -278.709478)
			(xy 115.593666 -278.74357) (xy 115.623231 -278.782914) (xy 115.646102 -278.826491) (xy 115.661686 -278.873172)
			(xy 115.669581 -278.921749) (xy 115.670076 -278.946356) (xy 115.999018 -278.946356) (xy 116.002978 -278.897302)
			(xy 116.014755 -278.849518) (xy 116.034046 -278.804242) (xy 116.060349 -278.762646) (xy 116.092984 -278.725809)
			(xy 116.131105 -278.694684) (xy 116.173726 -278.670077) (xy 116.219742 -278.652625) (xy 116.267961 -278.642781)
			(xy 116.317136 -278.6408) (xy 116.365991 -278.646732) (xy 116.413262 -278.660424) (xy 116.457724 -278.681522)
			(xy 116.498227 -278.709478) (xy 116.53372 -278.74357) (xy 116.563285 -278.782914) (xy 116.586156 -278.826491)
			(xy 116.60174 -278.873172) (xy 116.609635 -278.921749) (xy 116.61013 -278.946356) (xy 118.818926 -278.946356)
			(xy 118.822886 -278.897302) (xy 118.834663 -278.849518) (xy 118.853954 -278.804242) (xy 118.880257 -278.762646)
			(xy 118.912892 -278.725809) (xy 118.951013 -278.694684) (xy 118.993634 -278.670077) (xy 119.03965 -278.652625)
			(xy 119.087869 -278.642781) (xy 119.137044 -278.6408) (xy 119.185899 -278.646732) (xy 119.23317 -278.660424)
			(xy 119.277632 -278.681522) (xy 119.318135 -278.709478) (xy 119.353628 -278.74357) (xy 119.383193 -278.782914)
			(xy 119.406064 -278.826491) (xy 119.421648 -278.873172) (xy 119.429543 -278.921749) (xy 119.430038 -278.946356)
			(xy 121.638834 -278.946356) (xy 121.642794 -278.897302) (xy 121.654571 -278.849518) (xy 121.673862 -278.804242)
			(xy 121.700165 -278.762646) (xy 121.7328 -278.725809) (xy 121.770921 -278.694684) (xy 121.813542 -278.670077)
			(xy 121.859558 -278.652625) (xy 121.907777 -278.642781) (xy 121.956952 -278.6408) (xy 122.005807 -278.646732)
			(xy 122.053078 -278.660424) (xy 122.09754 -278.681522) (xy 122.138043 -278.709478) (xy 122.173536 -278.74357)
			(xy 122.203101 -278.782914) (xy 122.225972 -278.826491) (xy 122.241556 -278.873172) (xy 122.249451 -278.921749)
			(xy 122.249946 -278.946356) (xy 124.458996 -278.946356) (xy 124.462956 -278.897302) (xy 124.474733 -278.849518)
			(xy 124.494024 -278.804242) (xy 124.520327 -278.762646) (xy 124.552962 -278.725809) (xy 124.591083 -278.694684)
			(xy 124.633704 -278.670077) (xy 124.67972 -278.652625) (xy 124.727939 -278.642781) (xy 124.777114 -278.6408)
			(xy 124.825969 -278.646732) (xy 124.87324 -278.660424) (xy 124.917702 -278.681522) (xy 124.958205 -278.709478)
			(xy 124.993698 -278.74357) (xy 125.023263 -278.782914) (xy 125.046134 -278.826491) (xy 125.061718 -278.873172)
			(xy 125.069613 -278.921749) (xy 125.070108 -278.946356) (xy 125.069613 -278.970963) (xy 125.061718 -279.01954)
			(xy 125.046134 -279.066221) (xy 125.023263 -279.109798) (xy 124.993698 -279.149142) (xy 124.958205 -279.183234)
			(xy 124.917702 -279.21119) (xy 124.87324 -279.232288) (xy 124.825969 -279.24598) (xy 124.777114 -279.251912)
			(xy 124.727939 -279.249931) (xy 124.67972 -279.240087) (xy 124.633704 -279.222635) (xy 124.591083 -279.198028)
			(xy 124.552962 -279.166903) (xy 124.520327 -279.130066) (xy 124.494024 -279.08847) (xy 124.474733 -279.043194)
			(xy 124.462956 -278.99541) (xy 124.458996 -278.946356) (xy 122.249946 -278.946356) (xy 122.249451 -278.970963)
			(xy 122.241556 -279.01954) (xy 122.225972 -279.066221) (xy 122.203101 -279.109798) (xy 122.173536 -279.149142)
			(xy 122.138043 -279.183234) (xy 122.09754 -279.21119) (xy 122.053078 -279.232288) (xy 122.005807 -279.24598)
			(xy 121.956952 -279.251912) (xy 121.907777 -279.249931) (xy 121.859558 -279.240087) (xy 121.813542 -279.222635)
			(xy 121.770921 -279.198028) (xy 121.7328 -279.166903) (xy 121.700165 -279.130066) (xy 121.673862 -279.08847)
			(xy 121.654571 -279.043194) (xy 121.642794 -278.99541) (xy 121.638834 -278.946356) (xy 119.430038 -278.946356)
			(xy 119.429543 -278.970963) (xy 119.421648 -279.01954) (xy 119.406064 -279.066221) (xy 119.383193 -279.109798)
			(xy 119.353628 -279.149142) (xy 119.318135 -279.183234) (xy 119.277632 -279.21119) (xy 119.23317 -279.232288)
			(xy 119.185899 -279.24598) (xy 119.137044 -279.251912) (xy 119.087869 -279.249931) (xy 119.03965 -279.240087)
			(xy 118.993634 -279.222635) (xy 118.951013 -279.198028) (xy 118.912892 -279.166903) (xy 118.880257 -279.130066)
			(xy 118.853954 -279.08847) (xy 118.834663 -279.043194) (xy 118.822886 -278.99541) (xy 118.818926 -278.946356)
			(xy 116.61013 -278.946356) (xy 116.609635 -278.970963) (xy 116.60174 -279.01954) (xy 116.586156 -279.066221)
			(xy 116.563285 -279.109798) (xy 116.53372 -279.149142) (xy 116.498227 -279.183234) (xy 116.457724 -279.21119)
			(xy 116.413262 -279.232288) (xy 116.365991 -279.24598) (xy 116.317136 -279.251912) (xy 116.267961 -279.249931)
			(xy 116.219742 -279.240087) (xy 116.173726 -279.222635) (xy 116.131105 -279.198028) (xy 116.092984 -279.166903)
			(xy 116.060349 -279.130066) (xy 116.034046 -279.08847) (xy 116.014755 -279.043194) (xy 116.002978 -278.99541)
			(xy 115.999018 -278.946356) (xy 115.670076 -278.946356) (xy 115.669581 -278.970963) (xy 115.661686 -279.01954)
			(xy 115.646102 -279.066221) (xy 115.623231 -279.109798) (xy 115.593666 -279.149142) (xy 115.558173 -279.183234)
			(xy 115.51767 -279.21119) (xy 115.473208 -279.232288) (xy 115.425937 -279.24598) (xy 115.377082 -279.251912)
			(xy 115.327907 -279.249931) (xy 115.279688 -279.240087) (xy 115.233672 -279.222635) (xy 115.191051 -279.198028)
			(xy 115.15293 -279.166903) (xy 115.120295 -279.130066) (xy 115.093992 -279.08847) (xy 115.074701 -279.043194)
			(xy 115.062924 -278.99541) (xy 115.058964 -278.946356) (xy 114.730022 -278.946356) (xy 114.729527 -278.970963)
			(xy 114.721632 -279.01954) (xy 114.706048 -279.066221) (xy 114.683177 -279.109798) (xy 114.653612 -279.149142)
			(xy 114.618119 -279.183234) (xy 114.577616 -279.21119) (xy 114.533154 -279.232288) (xy 114.485883 -279.24598)
			(xy 114.437028 -279.251912) (xy 114.387853 -279.249931) (xy 114.339634 -279.240087) (xy 114.293618 -279.222635)
			(xy 114.250997 -279.198028) (xy 114.212876 -279.166903) (xy 114.180241 -279.130066) (xy 114.153938 -279.08847)
			(xy 114.134647 -279.043194) (xy 114.12287 -278.99541) (xy 114.11891 -278.946356) (xy 113.789968 -278.946356)
			(xy 113.789473 -278.970963) (xy 113.781578 -279.01954) (xy 113.765994 -279.066221) (xy 113.743123 -279.109798)
			(xy 113.713558 -279.149142) (xy 113.678065 -279.183234) (xy 113.637562 -279.21119) (xy 113.5931 -279.232288)
			(xy 113.545829 -279.24598) (xy 113.496974 -279.251912) (xy 113.447799 -279.249931) (xy 113.39958 -279.240087)
			(xy 113.353564 -279.222635) (xy 113.310943 -279.198028) (xy 113.272822 -279.166903) (xy 113.240187 -279.130066)
			(xy 113.213884 -279.08847) (xy 113.194593 -279.043194) (xy 113.182816 -278.99541) (xy 113.178856 -278.946356)
			(xy 110.97641 -278.946356) (xy 110.975915 -278.970963) (xy 110.96802 -279.01954) (xy 110.952436 -279.066221)
			(xy 110.929565 -279.109798) (xy 110.9 -279.149142) (xy 110.864507 -279.183234) (xy 110.824004 -279.21119)
			(xy 110.779542 -279.232288) (xy 110.732271 -279.24598) (xy 110.683416 -279.251912) (xy 110.634241 -279.249931)
			(xy 110.586022 -279.240087) (xy 110.540006 -279.222635) (xy 110.497385 -279.198028) (xy 110.459264 -279.166903)
			(xy 110.426629 -279.130066) (xy 110.400326 -279.08847) (xy 110.381035 -279.043194) (xy 110.369258 -278.99541)
			(xy 110.365298 -278.946356) (xy 110.036356 -278.946356) (xy 110.035861 -278.970963) (xy 110.027966 -279.01954)
			(xy 110.012382 -279.066221) (xy 109.989511 -279.109798) (xy 109.959946 -279.149142) (xy 109.924453 -279.183234)
			(xy 109.88395 -279.21119) (xy 109.839488 -279.232288) (xy 109.792217 -279.24598) (xy 109.743362 -279.251912)
			(xy 109.694187 -279.249931) (xy 109.645968 -279.240087) (xy 109.599952 -279.222635) (xy 109.557331 -279.198028)
			(xy 109.51921 -279.166903) (xy 109.486575 -279.130066) (xy 109.460272 -279.08847) (xy 109.440981 -279.043194)
			(xy 109.429204 -278.99541) (xy 109.425244 -278.946356) (xy 109.096302 -278.946356) (xy 109.095807 -278.970963)
			(xy 109.087912 -279.01954) (xy 109.072328 -279.066221) (xy 109.049457 -279.109798) (xy 109.019892 -279.149142)
			(xy 108.984399 -279.183234) (xy 108.943896 -279.21119) (xy 108.899434 -279.232288) (xy 108.852163 -279.24598)
			(xy 108.803308 -279.251912) (xy 108.754133 -279.249931) (xy 108.705914 -279.240087) (xy 108.659898 -279.222635)
			(xy 108.617277 -279.198028) (xy 108.579156 -279.166903) (xy 108.546521 -279.130066) (xy 108.520218 -279.08847)
			(xy 108.500927 -279.043194) (xy 108.48915 -278.99541) (xy 108.48519 -278.946356) (xy 108.156248 -278.946356)
			(xy 108.155753 -278.970963) (xy 108.147858 -279.01954) (xy 108.132274 -279.066221) (xy 108.109403 -279.109798)
			(xy 108.079838 -279.149142) (xy 108.044345 -279.183234) (xy 108.003842 -279.21119) (xy 107.95938 -279.232288)
			(xy 107.912109 -279.24598) (xy 107.863254 -279.251912) (xy 107.814079 -279.249931) (xy 107.76586 -279.240087)
			(xy 107.719844 -279.222635) (xy 107.677223 -279.198028) (xy 107.639102 -279.166903) (xy 107.606467 -279.130066)
			(xy 107.580164 -279.08847) (xy 107.560873 -279.043194) (xy 107.549096 -278.99541) (xy 107.545136 -278.946356)
			(xy 105.33634 -278.946356) (xy 105.335845 -278.970963) (xy 105.32795 -279.01954) (xy 105.312366 -279.066221)
			(xy 105.289495 -279.109798) (xy 105.25993 -279.149142) (xy 105.224437 -279.183234) (xy 105.183934 -279.21119)
			(xy 105.139472 -279.232288) (xy 105.092201 -279.24598) (xy 105.043346 -279.251912) (xy 104.994171 -279.249931)
			(xy 104.945952 -279.240087) (xy 104.899936 -279.222635) (xy 104.857315 -279.198028) (xy 104.819194 -279.166903)
			(xy 104.786559 -279.130066) (xy 104.760256 -279.08847) (xy 104.740965 -279.043194) (xy 104.729188 -278.99541)
			(xy 104.725228 -278.946356) (xy 102.516432 -278.946356) (xy 102.515937 -278.970963) (xy 102.508042 -279.01954)
			(xy 102.492458 -279.066221) (xy 102.469587 -279.109798) (xy 102.440022 -279.149142) (xy 102.404529 -279.183234)
			(xy 102.364026 -279.21119) (xy 102.319564 -279.232288) (xy 102.272293 -279.24598) (xy 102.223438 -279.251912)
			(xy 102.174263 -279.249931) (xy 102.126044 -279.240087) (xy 102.080028 -279.222635) (xy 102.037407 -279.198028)
			(xy 101.999286 -279.166903) (xy 101.966651 -279.130066) (xy 101.940348 -279.08847) (xy 101.921057 -279.043194)
			(xy 101.90928 -278.99541) (xy 101.90532 -278.946356) (xy 99.69627 -278.946356) (xy 99.695775 -278.970963)
			(xy 99.68788 -279.01954) (xy 99.672296 -279.066221) (xy 99.649425 -279.109798) (xy 99.61986 -279.149142)
			(xy 99.584367 -279.183234) (xy 99.543864 -279.21119) (xy 99.499402 -279.232288) (xy 99.452131 -279.24598)
			(xy 99.403276 -279.251912) (xy 99.354101 -279.249931) (xy 99.305882 -279.240087) (xy 99.259866 -279.222635)
			(xy 99.217245 -279.198028) (xy 99.179124 -279.166903) (xy 99.146489 -279.130066) (xy 99.120186 -279.08847)
			(xy 99.100895 -279.043194) (xy 99.089118 -278.99541) (xy 99.085158 -278.946356) (xy 96.876362 -278.946356)
			(xy 96.875867 -278.970963) (xy 96.867972 -279.01954) (xy 96.852388 -279.066221) (xy 96.829517 -279.109798)
			(xy 96.799952 -279.149142) (xy 96.764459 -279.183234) (xy 96.723956 -279.21119) (xy 96.679494 -279.232288)
			(xy 96.632223 -279.24598) (xy 96.583368 -279.251912) (xy 96.534193 -279.249931) (xy 96.485974 -279.240087)
			(xy 96.439958 -279.222635) (xy 96.397337 -279.198028) (xy 96.359216 -279.166903) (xy 96.326581 -279.130066)
			(xy 96.300278 -279.08847) (xy 96.280987 -279.043194) (xy 96.26921 -278.99541) (xy 96.26525 -278.946356)
			(xy 95.946722 -278.946356) (xy 95.94621 -278.971802) (xy 95.938046 -279.022036) (xy 95.92193 -279.07031)
			(xy 95.898279 -279.115373) (xy 95.867706 -279.156059) (xy 95.831002 -279.191314) (xy 95.789118 -279.220224)
			(xy 95.743139 -279.242041) (xy 95.694255 -279.256201) (xy 95.643734 -279.262335) (xy 95.592882 -279.260286)
			(xy 95.543018 -279.250106) (xy 95.495432 -279.232059) (xy 95.451358 -279.206613) (xy 95.411936 -279.174426)
			(xy 95.378188 -279.136332) (xy 95.350987 -279.093318) (xy 95.331039 -279.046498) (xy 95.31886 -278.997084)
			(xy 95.314765 -278.946356) (xy 95.006668 -278.946356) (xy 95.006156 -278.971802) (xy 94.997992 -279.022036)
			(xy 94.981876 -279.07031) (xy 94.958225 -279.115373) (xy 94.927652 -279.156059) (xy 94.890948 -279.191314)
			(xy 94.849064 -279.220224) (xy 94.803085 -279.242041) (xy 94.754201 -279.256201) (xy 94.70368 -279.262335)
			(xy 94.652828 -279.260286) (xy 94.602964 -279.250106) (xy 94.555378 -279.232059) (xy 94.511304 -279.206613)
			(xy 94.471882 -279.174426) (xy 94.438134 -279.136332) (xy 94.410933 -279.093318) (xy 94.390985 -279.046498)
			(xy 94.378806 -278.997084) (xy 94.374711 -278.946356) (xy 94.056972 -278.946356) (xy 94.056976 -278.9464)
			(xy 94.052805 -278.996741) (xy 94.040405 -279.045708) (xy 94.020116 -279.091968) (xy 93.992491 -279.134257)
			(xy 93.958282 -279.171423) (xy 93.918422 -279.202453) (xy 93.874 -279.226499) (xy 93.826226 -279.242906)
			(xy 93.776403 -279.251227) (xy 93.751146 -279.251664) (xy 93.727381 -279.251213) (xy 93.680425 -279.243849)
			(xy 93.635179 -279.229291) (xy 93.592739 -279.207892) (xy 93.55413 -279.18017) (xy 93.520289 -279.146795)
			(xy 93.505782 -279.127966) (xy 93.505782 -279.127712) (xy 93.505528 -279.127712) (xy 93.501374 -279.122528)
			(xy 93.490962 -279.114287) (xy 93.484954 -279.111456) (xy 93.478545 -279.108913) (xy 93.464896 -279.106994)
			(xy 93.45803 -279.107646) (xy 93.372178 -279.119076) (xy 93.365419 -279.120152) (xy 93.352798 -279.125432)
			(xy 93.347286 -279.12949) (xy 93.341952 -279.133554) (xy 93.334078 -279.144222) (xy 93.331538 -279.150826)
			(xy 93.31599 -279.188498) (xy 93.275569 -279.259265) (xy 93.25102 -279.291796) (xy 93.25102 -279.29205)
			(xy 93.246986 -279.297454) (xy 93.241582 -279.309804) (xy 93.240352 -279.316434) (xy 93.238574 -279.329642)
			(xy 93.276928 -279.422352) (xy 93.279683 -279.428515) (xy 93.287924 -279.439202) (xy 93.293184 -279.443434)
			(xy 93.298518 -279.447498) (xy 93.31071 -279.452324) (xy 93.317822 -279.45334) (xy 93.342183 -279.456804)
			(xy 93.389438 -279.470506) (xy 93.433885 -279.491606) (xy 93.474374 -279.51956) (xy 93.509858 -279.553643)
			(xy 93.539419 -279.592974) (xy 93.562292 -279.636535) (xy 93.577885 -279.6832) (xy 93.585795 -279.731762)
			(xy 93.5863 -279.756362) (xy 93.904811 -279.756362) (xy 93.908906 -279.705634) (xy 93.921085 -279.65622)
			(xy 93.941033 -279.6094) (xy 93.968234 -279.566386) (xy 94.001982 -279.528292) (xy 94.041404 -279.496105)
			(xy 94.085478 -279.470659) (xy 94.133064 -279.452612) (xy 94.182928 -279.442432) (xy 94.23378 -279.440383)
			(xy 94.284301 -279.446517) (xy 94.333185 -279.460677) (xy 94.379164 -279.482494) (xy 94.421048 -279.511404)
			(xy 94.457752 -279.546659) (xy 94.488325 -279.587345) (xy 94.511976 -279.632408) (xy 94.528092 -279.680682)
			(xy 94.536256 -279.730916) (xy 94.536768 -279.756362) (xy 94.855296 -279.756362) (xy 94.859256 -279.707308)
			(xy 94.871033 -279.659524) (xy 94.890324 -279.614248) (xy 94.916627 -279.572652) (xy 94.949262 -279.535815)
			(xy 94.987383 -279.50469) (xy 95.030004 -279.480083) (xy 95.07602 -279.462631) (xy 95.124239 -279.452787)
			(xy 95.173414 -279.450806) (xy 95.222269 -279.456738) (xy 95.26954 -279.47043) (xy 95.314002 -279.491528)
			(xy 95.354505 -279.519484) (xy 95.389998 -279.553576) (xy 95.419563 -279.59292) (xy 95.442434 -279.636497)
			(xy 95.458018 -279.683178) (xy 95.465913 -279.731755) (xy 95.466408 -279.756362) (xy 95.784919 -279.756362)
			(xy 95.789014 -279.705634) (xy 95.801193 -279.65622) (xy 95.821141 -279.6094) (xy 95.848342 -279.566386)
			(xy 95.88209 -279.528292) (xy 95.921512 -279.496105) (xy 95.965586 -279.470659) (xy 96.013172 -279.452612)
			(xy 96.063036 -279.442432) (xy 96.113888 -279.440383) (xy 96.164409 -279.446517) (xy 96.213293 -279.460677)
			(xy 96.259272 -279.482494) (xy 96.301156 -279.511404) (xy 96.33786 -279.546659) (xy 96.368433 -279.587345)
			(xy 96.392084 -279.632408) (xy 96.4082 -279.680682) (xy 96.416364 -279.730916) (xy 96.416876 -279.756362)
			(xy 96.73515 -279.756362) (xy 96.73911 -279.707308) (xy 96.750887 -279.659524) (xy 96.770178 -279.614248)
			(xy 96.796481 -279.572652) (xy 96.829116 -279.535815) (xy 96.867237 -279.50469) (xy 96.909858 -279.480083)
			(xy 96.955874 -279.462631) (xy 97.004093 -279.452787) (xy 97.053268 -279.450806) (xy 97.102123 -279.456738)
			(xy 97.149394 -279.47043) (xy 97.193856 -279.491528) (xy 97.234359 -279.519484) (xy 97.269852 -279.553576)
			(xy 97.299417 -279.59292) (xy 97.322288 -279.636497) (xy 97.337872 -279.683178) (xy 97.345767 -279.731755)
			(xy 97.346262 -279.756362) (xy 97.675204 -279.756362) (xy 97.679164 -279.707308) (xy 97.690941 -279.659524)
			(xy 97.710232 -279.614248) (xy 97.736535 -279.572652) (xy 97.76917 -279.535815) (xy 97.807291 -279.50469)
			(xy 97.849912 -279.480083) (xy 97.895928 -279.462631) (xy 97.944147 -279.452787) (xy 97.993322 -279.450806)
			(xy 98.042177 -279.456738) (xy 98.089448 -279.47043) (xy 98.13391 -279.491528) (xy 98.174413 -279.519484)
			(xy 98.209906 -279.553576) (xy 98.239471 -279.59292) (xy 98.262342 -279.636497) (xy 98.277926 -279.683178)
			(xy 98.285821 -279.731755) (xy 98.286316 -279.756362) (xy 98.615258 -279.756362) (xy 98.619218 -279.707308)
			(xy 98.630995 -279.659524) (xy 98.650286 -279.614248) (xy 98.676589 -279.572652) (xy 98.709224 -279.535815)
			(xy 98.747345 -279.50469) (xy 98.789966 -279.480083) (xy 98.835982 -279.462631) (xy 98.884201 -279.452787)
			(xy 98.933376 -279.450806) (xy 98.982231 -279.456738) (xy 99.029502 -279.47043) (xy 99.073964 -279.491528)
			(xy 99.114467 -279.519484) (xy 99.14996 -279.553576) (xy 99.179525 -279.59292) (xy 99.202396 -279.636497)
			(xy 99.21798 -279.683178) (xy 99.225875 -279.731755) (xy 99.22637 -279.756362) (xy 99.555312 -279.756362)
			(xy 99.559272 -279.707308) (xy 99.571049 -279.659524) (xy 99.59034 -279.614248) (xy 99.616643 -279.572652)
			(xy 99.649278 -279.535815) (xy 99.687399 -279.50469) (xy 99.73002 -279.480083) (xy 99.776036 -279.462631)
			(xy 99.824255 -279.452787) (xy 99.87343 -279.450806) (xy 99.922285 -279.456738) (xy 99.969556 -279.47043)
			(xy 100.014018 -279.491528) (xy 100.054521 -279.519484) (xy 100.090014 -279.553576) (xy 100.119579 -279.59292)
			(xy 100.14245 -279.636497) (xy 100.158034 -279.683178) (xy 100.165929 -279.731755) (xy 100.166424 -279.756362)
			(xy 100.495366 -279.756362) (xy 100.499326 -279.707308) (xy 100.511103 -279.659524) (xy 100.530394 -279.614248)
			(xy 100.556697 -279.572652) (xy 100.589332 -279.535815) (xy 100.627453 -279.50469) (xy 100.670074 -279.480083)
			(xy 100.71609 -279.462631) (xy 100.764309 -279.452787) (xy 100.813484 -279.450806) (xy 100.862339 -279.456738)
			(xy 100.90961 -279.47043) (xy 100.954072 -279.491528) (xy 100.994575 -279.519484) (xy 101.030068 -279.553576)
			(xy 101.059633 -279.59292) (xy 101.082504 -279.636497) (xy 101.098088 -279.683178) (xy 101.105983 -279.731755)
			(xy 101.106478 -279.756362) (xy 101.435166 -279.756362) (xy 101.439126 -279.707308) (xy 101.450903 -279.659524)
			(xy 101.470194 -279.614248) (xy 101.496497 -279.572652) (xy 101.529132 -279.535815) (xy 101.567253 -279.50469)
			(xy 101.609874 -279.480083) (xy 101.65589 -279.462631) (xy 101.704109 -279.452787) (xy 101.753284 -279.450806)
			(xy 101.802139 -279.456738) (xy 101.84941 -279.47043) (xy 101.893872 -279.491528) (xy 101.934375 -279.519484)
			(xy 101.969868 -279.553576) (xy 101.999433 -279.59292) (xy 102.022304 -279.636497) (xy 102.037888 -279.683178)
			(xy 102.045783 -279.731755) (xy 102.046278 -279.756362) (xy 102.37522 -279.756362) (xy 102.37918 -279.707308)
			(xy 102.390957 -279.659524) (xy 102.410248 -279.614248) (xy 102.436551 -279.572652) (xy 102.469186 -279.535815)
			(xy 102.507307 -279.50469) (xy 102.549928 -279.480083) (xy 102.595944 -279.462631) (xy 102.644163 -279.452787)
			(xy 102.693338 -279.450806) (xy 102.742193 -279.456738) (xy 102.789464 -279.47043) (xy 102.833926 -279.491528)
			(xy 102.874429 -279.519484) (xy 102.909922 -279.553576) (xy 102.939487 -279.59292) (xy 102.962358 -279.636497)
			(xy 102.977942 -279.683178) (xy 102.985837 -279.731755) (xy 102.986332 -279.756362) (xy 103.315274 -279.756362)
			(xy 103.319234 -279.707308) (xy 103.331011 -279.659524) (xy 103.350302 -279.614248) (xy 103.376605 -279.572652)
			(xy 103.40924 -279.535815) (xy 103.447361 -279.50469) (xy 103.489982 -279.480083) (xy 103.535998 -279.462631)
			(xy 103.584217 -279.452787) (xy 103.633392 -279.450806) (xy 103.682247 -279.456738) (xy 103.729518 -279.47043)
			(xy 103.77398 -279.491528) (xy 103.814483 -279.519484) (xy 103.849976 -279.553576) (xy 103.879541 -279.59292)
			(xy 103.902412 -279.636497) (xy 103.917996 -279.683178) (xy 103.925891 -279.731755) (xy 103.926386 -279.756362)
			(xy 104.255328 -279.756362) (xy 104.259288 -279.707308) (xy 104.271065 -279.659524) (xy 104.290356 -279.614248)
			(xy 104.316659 -279.572652) (xy 104.349294 -279.535815) (xy 104.387415 -279.50469) (xy 104.430036 -279.480083)
			(xy 104.476052 -279.462631) (xy 104.524271 -279.452787) (xy 104.573446 -279.450806) (xy 104.622301 -279.456738)
			(xy 104.669572 -279.47043) (xy 104.714034 -279.491528) (xy 104.754537 -279.519484) (xy 104.79003 -279.553576)
			(xy 104.819595 -279.59292) (xy 104.842466 -279.636497) (xy 104.85805 -279.683178) (xy 104.865945 -279.731755)
			(xy 104.86644 -279.756362) (xy 105.195128 -279.756362) (xy 105.199088 -279.707308) (xy 105.210865 -279.659524)
			(xy 105.230156 -279.614248) (xy 105.256459 -279.572652) (xy 105.289094 -279.535815) (xy 105.327215 -279.50469)
			(xy 105.369836 -279.480083) (xy 105.415852 -279.462631) (xy 105.464071 -279.452787) (xy 105.513246 -279.450806)
			(xy 105.562101 -279.456738) (xy 105.609372 -279.47043) (xy 105.653834 -279.491528) (xy 105.694337 -279.519484)
			(xy 105.72983 -279.553576) (xy 105.759395 -279.59292) (xy 105.782266 -279.636497) (xy 105.79785 -279.683178)
			(xy 105.805745 -279.731755) (xy 105.80624 -279.756362) (xy 106.135182 -279.756362) (xy 106.139142 -279.707308)
			(xy 106.150919 -279.659524) (xy 106.17021 -279.614248) (xy 106.196513 -279.572652) (xy 106.229148 -279.535815)
			(xy 106.267269 -279.50469) (xy 106.30989 -279.480083) (xy 106.355906 -279.462631) (xy 106.404125 -279.452787)
			(xy 106.4533 -279.450806) (xy 106.502155 -279.456738) (xy 106.549426 -279.47043) (xy 106.593888 -279.491528)
			(xy 106.634391 -279.519484) (xy 106.669884 -279.553576) (xy 106.699449 -279.59292) (xy 106.72232 -279.636497)
			(xy 106.737904 -279.683178) (xy 106.745799 -279.731755) (xy 106.746294 -279.756362) (xy 107.075236 -279.756362)
			(xy 107.079196 -279.707308) (xy 107.090973 -279.659524) (xy 107.110264 -279.614248) (xy 107.136567 -279.572652)
			(xy 107.169202 -279.535815) (xy 107.207323 -279.50469) (xy 107.249944 -279.480083) (xy 107.29596 -279.462631)
			(xy 107.344179 -279.452787) (xy 107.393354 -279.450806) (xy 107.442209 -279.456738) (xy 107.48948 -279.47043)
			(xy 107.533942 -279.491528) (xy 107.574445 -279.519484) (xy 107.609938 -279.553576) (xy 107.639503 -279.59292)
			(xy 107.662374 -279.636497) (xy 107.677958 -279.683178) (xy 107.685853 -279.731755) (xy 107.686348 -279.756362)
			(xy 108.01529 -279.756362) (xy 108.01925 -279.707308) (xy 108.031027 -279.659524) (xy 108.050318 -279.614248)
			(xy 108.076621 -279.572652) (xy 108.109256 -279.535815) (xy 108.147377 -279.50469) (xy 108.189998 -279.480083)
			(xy 108.236014 -279.462631) (xy 108.284233 -279.452787) (xy 108.333408 -279.450806) (xy 108.382263 -279.456738)
			(xy 108.429534 -279.47043) (xy 108.473996 -279.491528) (xy 108.514499 -279.519484) (xy 108.549992 -279.553576)
			(xy 108.579557 -279.59292) (xy 108.602428 -279.636497) (xy 108.618012 -279.683178) (xy 108.625907 -279.731755)
			(xy 108.626402 -279.756362) (xy 108.955344 -279.756362) (xy 108.959304 -279.707308) (xy 108.971081 -279.659524)
			(xy 108.990372 -279.614248) (xy 109.016675 -279.572652) (xy 109.04931 -279.535815) (xy 109.087431 -279.50469)
			(xy 109.130052 -279.480083) (xy 109.176068 -279.462631) (xy 109.224287 -279.452787) (xy 109.273462 -279.450806)
			(xy 109.322317 -279.456738) (xy 109.369588 -279.47043) (xy 109.41405 -279.491528) (xy 109.454553 -279.519484)
			(xy 109.490046 -279.553576) (xy 109.519611 -279.59292) (xy 109.542482 -279.636497) (xy 109.558066 -279.683178)
			(xy 109.565961 -279.731755) (xy 109.566456 -279.756362) (xy 109.895144 -279.756362) (xy 109.899104 -279.707308)
			(xy 109.910881 -279.659524) (xy 109.930172 -279.614248) (xy 109.956475 -279.572652) (xy 109.98911 -279.535815)
			(xy 110.027231 -279.50469) (xy 110.069852 -279.480083) (xy 110.115868 -279.462631) (xy 110.164087 -279.452787)
			(xy 110.213262 -279.450806) (xy 110.262117 -279.456738) (xy 110.309388 -279.47043) (xy 110.35385 -279.491528)
			(xy 110.394353 -279.519484) (xy 110.429846 -279.553576) (xy 110.459411 -279.59292) (xy 110.482282 -279.636497)
			(xy 110.497866 -279.683178) (xy 110.505761 -279.731755) (xy 110.506256 -279.756362) (xy 113.64901 -279.756362)
			(xy 113.65297 -279.707308) (xy 113.664747 -279.659524) (xy 113.684038 -279.614248) (xy 113.710341 -279.572652)
			(xy 113.742976 -279.535815) (xy 113.781097 -279.50469) (xy 113.823718 -279.480083) (xy 113.869734 -279.462631)
			(xy 113.917953 -279.452787) (xy 113.967128 -279.450806) (xy 114.015983 -279.456738) (xy 114.063254 -279.47043)
			(xy 114.107716 -279.491528) (xy 114.148219 -279.519484) (xy 114.183712 -279.553576) (xy 114.213277 -279.59292)
			(xy 114.236148 -279.636497) (xy 114.251732 -279.683178) (xy 114.259627 -279.731755) (xy 114.260122 -279.756362)
			(xy 114.58881 -279.756362) (xy 114.59277 -279.707308) (xy 114.604547 -279.659524) (xy 114.623838 -279.614248)
			(xy 114.650141 -279.572652) (xy 114.682776 -279.535815) (xy 114.720897 -279.50469) (xy 114.763518 -279.480083)
			(xy 114.809534 -279.462631) (xy 114.857753 -279.452787) (xy 114.906928 -279.450806) (xy 114.955783 -279.456738)
			(xy 115.003054 -279.47043) (xy 115.047516 -279.491528) (xy 115.088019 -279.519484) (xy 115.123512 -279.553576)
			(xy 115.153077 -279.59292) (xy 115.175948 -279.636497) (xy 115.191532 -279.683178) (xy 115.199427 -279.731755)
			(xy 115.199922 -279.756362) (xy 115.528864 -279.756362) (xy 115.532824 -279.707308) (xy 115.544601 -279.659524)
			(xy 115.563892 -279.614248) (xy 115.590195 -279.572652) (xy 115.62283 -279.535815) (xy 115.660951 -279.50469)
			(xy 115.703572 -279.480083) (xy 115.749588 -279.462631) (xy 115.797807 -279.452787) (xy 115.846982 -279.450806)
			(xy 115.895837 -279.456738) (xy 115.943108 -279.47043) (xy 115.98757 -279.491528) (xy 116.028073 -279.519484)
			(xy 116.063566 -279.553576) (xy 116.093131 -279.59292) (xy 116.116002 -279.636497) (xy 116.131586 -279.683178)
			(xy 116.139481 -279.731755) (xy 116.139976 -279.756362) (xy 116.468918 -279.756362) (xy 116.472878 -279.707308)
			(xy 116.484655 -279.659524) (xy 116.503946 -279.614248) (xy 116.530249 -279.572652) (xy 116.562884 -279.535815)
			(xy 116.601005 -279.50469) (xy 116.643626 -279.480083) (xy 116.689642 -279.462631) (xy 116.737861 -279.452787)
			(xy 116.787036 -279.450806) (xy 116.835891 -279.456738) (xy 116.883162 -279.47043) (xy 116.927624 -279.491528)
			(xy 116.968127 -279.519484) (xy 117.00362 -279.553576) (xy 117.033185 -279.59292) (xy 117.056056 -279.636497)
			(xy 117.07164 -279.683178) (xy 117.079535 -279.731755) (xy 117.08003 -279.756362) (xy 117.408972 -279.756362)
			(xy 117.412932 -279.707308) (xy 117.424709 -279.659524) (xy 117.444 -279.614248) (xy 117.470303 -279.572652)
			(xy 117.502938 -279.535815) (xy 117.541059 -279.50469) (xy 117.58368 -279.480083) (xy 117.629696 -279.462631)
			(xy 117.677915 -279.452787) (xy 117.72709 -279.450806) (xy 117.775945 -279.456738) (xy 117.823216 -279.47043)
			(xy 117.867678 -279.491528) (xy 117.908181 -279.519484) (xy 117.943674 -279.553576) (xy 117.973239 -279.59292)
			(xy 117.99611 -279.636497) (xy 118.011694 -279.683178) (xy 118.019589 -279.731755) (xy 118.020084 -279.756362)
			(xy 118.349026 -279.756362) (xy 118.352986 -279.707308) (xy 118.364763 -279.659524) (xy 118.384054 -279.614248)
			(xy 118.410357 -279.572652) (xy 118.442992 -279.535815) (xy 118.481113 -279.50469) (xy 118.523734 -279.480083)
			(xy 118.56975 -279.462631) (xy 118.617969 -279.452787) (xy 118.667144 -279.450806) (xy 118.715999 -279.456738)
			(xy 118.76327 -279.47043) (xy 118.807732 -279.491528) (xy 118.848235 -279.519484) (xy 118.883728 -279.553576)
			(xy 118.913293 -279.59292) (xy 118.936164 -279.636497) (xy 118.951748 -279.683178) (xy 118.959643 -279.731755)
			(xy 118.960138 -279.756362) (xy 119.288826 -279.756362) (xy 119.292786 -279.707308) (xy 119.304563 -279.659524)
			(xy 119.323854 -279.614248) (xy 119.350157 -279.572652) (xy 119.382792 -279.535815) (xy 119.420913 -279.50469)
			(xy 119.463534 -279.480083) (xy 119.50955 -279.462631) (xy 119.557769 -279.452787) (xy 119.606944 -279.450806)
			(xy 119.655799 -279.456738) (xy 119.70307 -279.47043) (xy 119.747532 -279.491528) (xy 119.788035 -279.519484)
			(xy 119.823528 -279.553576) (xy 119.853093 -279.59292) (xy 119.875964 -279.636497) (xy 119.891548 -279.683178)
			(xy 119.899443 -279.731755) (xy 119.899938 -279.756362) (xy 120.22888 -279.756362) (xy 120.23284 -279.707308)
			(xy 120.244617 -279.659524) (xy 120.263908 -279.614248) (xy 120.290211 -279.572652) (xy 120.322846 -279.535815)
			(xy 120.360967 -279.50469) (xy 120.403588 -279.480083) (xy 120.449604 -279.462631) (xy 120.497823 -279.452787)
			(xy 120.546998 -279.450806) (xy 120.595853 -279.456738) (xy 120.643124 -279.47043) (xy 120.687586 -279.491528)
			(xy 120.728089 -279.519484) (xy 120.763582 -279.553576) (xy 120.793147 -279.59292) (xy 120.816018 -279.636497)
			(xy 120.831602 -279.683178) (xy 120.839497 -279.731755) (xy 120.839992 -279.756362) (xy 121.168934 -279.756362)
			(xy 121.172894 -279.707308) (xy 121.184671 -279.659524) (xy 121.203962 -279.614248) (xy 121.230265 -279.572652)
			(xy 121.2629 -279.535815) (xy 121.301021 -279.50469) (xy 121.343642 -279.480083) (xy 121.389658 -279.462631)
			(xy 121.437877 -279.452787) (xy 121.487052 -279.450806) (xy 121.535907 -279.456738) (xy 121.583178 -279.47043)
			(xy 121.62764 -279.491528) (xy 121.668143 -279.519484) (xy 121.703636 -279.553576) (xy 121.733201 -279.59292)
			(xy 121.756072 -279.636497) (xy 121.771656 -279.683178) (xy 121.779551 -279.731755) (xy 121.780046 -279.756362)
			(xy 122.108988 -279.756362) (xy 122.112948 -279.707308) (xy 122.124725 -279.659524) (xy 122.144016 -279.614248)
			(xy 122.170319 -279.572652) (xy 122.202954 -279.535815) (xy 122.241075 -279.50469) (xy 122.283696 -279.480083)
			(xy 122.329712 -279.462631) (xy 122.377931 -279.452787) (xy 122.427106 -279.450806) (xy 122.475961 -279.456738)
			(xy 122.523232 -279.47043) (xy 122.567694 -279.491528) (xy 122.608197 -279.519484) (xy 122.64369 -279.553576)
			(xy 122.673255 -279.59292) (xy 122.696126 -279.636497) (xy 122.71171 -279.683178) (xy 122.719605 -279.731755)
			(xy 122.7201 -279.756362) (xy 123.049042 -279.756362) (xy 123.053002 -279.707308) (xy 123.064779 -279.659524)
			(xy 123.08407 -279.614248) (xy 123.110373 -279.572652) (xy 123.143008 -279.535815) (xy 123.181129 -279.50469)
			(xy 123.22375 -279.480083) (xy 123.269766 -279.462631) (xy 123.317985 -279.452787) (xy 123.36716 -279.450806)
			(xy 123.416015 -279.456738) (xy 123.463286 -279.47043) (xy 123.507748 -279.491528) (xy 123.548251 -279.519484)
			(xy 123.583744 -279.553576) (xy 123.613309 -279.59292) (xy 123.63618 -279.636497) (xy 123.651764 -279.683178)
			(xy 123.659659 -279.731755) (xy 123.660154 -279.756362) (xy 123.988842 -279.756362) (xy 123.992802 -279.707308)
			(xy 124.004579 -279.659524) (xy 124.02387 -279.614248) (xy 124.050173 -279.572652) (xy 124.082808 -279.535815)
			(xy 124.120929 -279.50469) (xy 124.16355 -279.480083) (xy 124.209566 -279.462631) (xy 124.257785 -279.452787)
			(xy 124.30696 -279.450806) (xy 124.355815 -279.456738) (xy 124.403086 -279.47043) (xy 124.447548 -279.491528)
			(xy 124.488051 -279.519484) (xy 124.523544 -279.553576) (xy 124.553109 -279.59292) (xy 124.57598 -279.636497)
			(xy 124.591564 -279.683178) (xy 124.599459 -279.731755) (xy 124.599954 -279.756362) (xy 124.928896 -279.756362)
			(xy 124.932856 -279.707308) (xy 124.944633 -279.659524) (xy 124.963924 -279.614248) (xy 124.990227 -279.572652)
			(xy 125.022862 -279.535815) (xy 125.060983 -279.50469) (xy 125.103604 -279.480083) (xy 125.14962 -279.462631)
			(xy 125.197839 -279.452787) (xy 125.247014 -279.450806) (xy 125.295869 -279.456738) (xy 125.34314 -279.47043)
			(xy 125.387602 -279.491528) (xy 125.428105 -279.519484) (xy 125.463598 -279.553576) (xy 125.493163 -279.59292)
			(xy 125.516034 -279.636497) (xy 125.531618 -279.683178) (xy 125.539513 -279.731755) (xy 125.540008 -279.756362)
			(xy 125.539513 -279.780969) (xy 125.531618 -279.829546) (xy 125.516034 -279.876227) (xy 125.493163 -279.919804)
			(xy 125.463598 -279.959148) (xy 125.428105 -279.99324) (xy 125.387602 -280.021196) (xy 125.34314 -280.042294)
			(xy 125.295869 -280.055986) (xy 125.247014 -280.061918) (xy 125.197839 -280.059937) (xy 125.14962 -280.050093)
			(xy 125.103604 -280.032641) (xy 125.060983 -280.008034) (xy 125.022862 -279.976909) (xy 124.990227 -279.940072)
			(xy 124.963924 -279.898476) (xy 124.944633 -279.8532) (xy 124.932856 -279.805416) (xy 124.928896 -279.756362)
			(xy 124.599954 -279.756362) (xy 124.599459 -279.780969) (xy 124.591564 -279.829546) (xy 124.57598 -279.876227)
			(xy 124.553109 -279.919804) (xy 124.523544 -279.959148) (xy 124.488051 -279.99324) (xy 124.447548 -280.021196)
			(xy 124.403086 -280.042294) (xy 124.355815 -280.055986) (xy 124.30696 -280.061918) (xy 124.257785 -280.059937)
			(xy 124.209566 -280.050093) (xy 124.16355 -280.032641) (xy 124.120929 -280.008034) (xy 124.082808 -279.976909)
			(xy 124.050173 -279.940072) (xy 124.02387 -279.898476) (xy 124.004579 -279.8532) (xy 123.992802 -279.805416)
			(xy 123.988842 -279.756362) (xy 123.660154 -279.756362) (xy 123.659659 -279.780969) (xy 123.651764 -279.829546)
			(xy 123.63618 -279.876227) (xy 123.613309 -279.919804) (xy 123.583744 -279.959148) (xy 123.548251 -279.99324)
			(xy 123.507748 -280.021196) (xy 123.463286 -280.042294) (xy 123.416015 -280.055986) (xy 123.36716 -280.061918)
			(xy 123.317985 -280.059937) (xy 123.269766 -280.050093) (xy 123.22375 -280.032641) (xy 123.181129 -280.008034)
			(xy 123.143008 -279.976909) (xy 123.110373 -279.940072) (xy 123.08407 -279.898476) (xy 123.064779 -279.8532)
			(xy 123.053002 -279.805416) (xy 123.049042 -279.756362) (xy 122.7201 -279.756362) (xy 122.719605 -279.780969)
			(xy 122.71171 -279.829546) (xy 122.696126 -279.876227) (xy 122.673255 -279.919804) (xy 122.64369 -279.959148)
			(xy 122.608197 -279.99324) (xy 122.567694 -280.021196) (xy 122.523232 -280.042294) (xy 122.475961 -280.055986)
			(xy 122.427106 -280.061918) (xy 122.377931 -280.059937) (xy 122.329712 -280.050093) (xy 122.283696 -280.032641)
			(xy 122.241075 -280.008034) (xy 122.202954 -279.976909) (xy 122.170319 -279.940072) (xy 122.144016 -279.898476)
			(xy 122.124725 -279.8532) (xy 122.112948 -279.805416) (xy 122.108988 -279.756362) (xy 121.780046 -279.756362)
			(xy 121.779551 -279.780969) (xy 121.771656 -279.829546) (xy 121.756072 -279.876227) (xy 121.733201 -279.919804)
			(xy 121.703636 -279.959148) (xy 121.668143 -279.99324) (xy 121.62764 -280.021196) (xy 121.583178 -280.042294)
			(xy 121.535907 -280.055986) (xy 121.487052 -280.061918) (xy 121.437877 -280.059937) (xy 121.389658 -280.050093)
			(xy 121.343642 -280.032641) (xy 121.301021 -280.008034) (xy 121.2629 -279.976909) (xy 121.230265 -279.940072)
			(xy 121.203962 -279.898476) (xy 121.184671 -279.8532) (xy 121.172894 -279.805416) (xy 121.168934 -279.756362)
			(xy 120.839992 -279.756362) (xy 120.839497 -279.780969) (xy 120.831602 -279.829546) (xy 120.816018 -279.876227)
			(xy 120.793147 -279.919804) (xy 120.763582 -279.959148) (xy 120.728089 -279.99324) (xy 120.687586 -280.021196)
			(xy 120.643124 -280.042294) (xy 120.595853 -280.055986) (xy 120.546998 -280.061918) (xy 120.497823 -280.059937)
			(xy 120.449604 -280.050093) (xy 120.403588 -280.032641) (xy 120.360967 -280.008034) (xy 120.322846 -279.976909)
			(xy 120.290211 -279.940072) (xy 120.263908 -279.898476) (xy 120.244617 -279.8532) (xy 120.23284 -279.805416)
			(xy 120.22888 -279.756362) (xy 119.899938 -279.756362) (xy 119.899443 -279.780969) (xy 119.891548 -279.829546)
			(xy 119.875964 -279.876227) (xy 119.853093 -279.919804) (xy 119.823528 -279.959148) (xy 119.788035 -279.99324)
			(xy 119.747532 -280.021196) (xy 119.70307 -280.042294) (xy 119.655799 -280.055986) (xy 119.606944 -280.061918)
			(xy 119.557769 -280.059937) (xy 119.50955 -280.050093) (xy 119.463534 -280.032641) (xy 119.420913 -280.008034)
			(xy 119.382792 -279.976909) (xy 119.350157 -279.940072) (xy 119.323854 -279.898476) (xy 119.304563 -279.8532)
			(xy 119.292786 -279.805416) (xy 119.288826 -279.756362) (xy 118.960138 -279.756362) (xy 118.959643 -279.780969)
			(xy 118.951748 -279.829546) (xy 118.936164 -279.876227) (xy 118.913293 -279.919804) (xy 118.883728 -279.959148)
			(xy 118.848235 -279.99324) (xy 118.807732 -280.021196) (xy 118.76327 -280.042294) (xy 118.715999 -280.055986)
			(xy 118.667144 -280.061918) (xy 118.617969 -280.059937) (xy 118.56975 -280.050093) (xy 118.523734 -280.032641)
			(xy 118.481113 -280.008034) (xy 118.442992 -279.976909) (xy 118.410357 -279.940072) (xy 118.384054 -279.898476)
			(xy 118.364763 -279.8532) (xy 118.352986 -279.805416) (xy 118.349026 -279.756362) (xy 118.020084 -279.756362)
			(xy 118.019589 -279.780969) (xy 118.011694 -279.829546) (xy 117.99611 -279.876227) (xy 117.973239 -279.919804)
			(xy 117.943674 -279.959148) (xy 117.908181 -279.99324) (xy 117.867678 -280.021196) (xy 117.823216 -280.042294)
			(xy 117.775945 -280.055986) (xy 117.72709 -280.061918) (xy 117.677915 -280.059937) (xy 117.629696 -280.050093)
			(xy 117.58368 -280.032641) (xy 117.541059 -280.008034) (xy 117.502938 -279.976909) (xy 117.470303 -279.940072)
			(xy 117.444 -279.898476) (xy 117.424709 -279.8532) (xy 117.412932 -279.805416) (xy 117.408972 -279.756362)
			(xy 117.08003 -279.756362) (xy 117.079535 -279.780969) (xy 117.07164 -279.829546) (xy 117.056056 -279.876227)
			(xy 117.033185 -279.919804) (xy 117.00362 -279.959148) (xy 116.968127 -279.99324) (xy 116.927624 -280.021196)
			(xy 116.883162 -280.042294) (xy 116.835891 -280.055986) (xy 116.787036 -280.061918) (xy 116.737861 -280.059937)
			(xy 116.689642 -280.050093) (xy 116.643626 -280.032641) (xy 116.601005 -280.008034) (xy 116.562884 -279.976909)
			(xy 116.530249 -279.940072) (xy 116.503946 -279.898476) (xy 116.484655 -279.8532) (xy 116.472878 -279.805416)
			(xy 116.468918 -279.756362) (xy 116.139976 -279.756362) (xy 116.139481 -279.780969) (xy 116.131586 -279.829546)
			(xy 116.116002 -279.876227) (xy 116.093131 -279.919804) (xy 116.063566 -279.959148) (xy 116.028073 -279.99324)
			(xy 115.98757 -280.021196) (xy 115.943108 -280.042294) (xy 115.895837 -280.055986) (xy 115.846982 -280.061918)
			(xy 115.797807 -280.059937) (xy 115.749588 -280.050093) (xy 115.703572 -280.032641) (xy 115.660951 -280.008034)
			(xy 115.62283 -279.976909) (xy 115.590195 -279.940072) (xy 115.563892 -279.898476) (xy 115.544601 -279.8532)
			(xy 115.532824 -279.805416) (xy 115.528864 -279.756362) (xy 115.199922 -279.756362) (xy 115.199427 -279.780969)
			(xy 115.191532 -279.829546) (xy 115.175948 -279.876227) (xy 115.153077 -279.919804) (xy 115.123512 -279.959148)
			(xy 115.088019 -279.99324) (xy 115.047516 -280.021196) (xy 115.003054 -280.042294) (xy 114.955783 -280.055986)
			(xy 114.906928 -280.061918) (xy 114.857753 -280.059937) (xy 114.809534 -280.050093) (xy 114.763518 -280.032641)
			(xy 114.720897 -280.008034) (xy 114.682776 -279.976909) (xy 114.650141 -279.940072) (xy 114.623838 -279.898476)
			(xy 114.604547 -279.8532) (xy 114.59277 -279.805416) (xy 114.58881 -279.756362) (xy 114.260122 -279.756362)
			(xy 114.259627 -279.780969) (xy 114.251732 -279.829546) (xy 114.236148 -279.876227) (xy 114.213277 -279.919804)
			(xy 114.183712 -279.959148) (xy 114.148219 -279.99324) (xy 114.107716 -280.021196) (xy 114.063254 -280.042294)
			(xy 114.015983 -280.055986) (xy 113.967128 -280.061918) (xy 113.917953 -280.059937) (xy 113.869734 -280.050093)
			(xy 113.823718 -280.032641) (xy 113.781097 -280.008034) (xy 113.742976 -279.976909) (xy 113.710341 -279.940072)
			(xy 113.684038 -279.898476) (xy 113.664747 -279.8532) (xy 113.65297 -279.805416) (xy 113.64901 -279.756362)
			(xy 110.506256 -279.756362) (xy 110.505761 -279.780969) (xy 110.497866 -279.829546) (xy 110.482282 -279.876227)
			(xy 110.459411 -279.919804) (xy 110.429846 -279.959148) (xy 110.394353 -279.99324) (xy 110.35385 -280.021196)
			(xy 110.309388 -280.042294) (xy 110.262117 -280.055986) (xy 110.213262 -280.061918) (xy 110.164087 -280.059937)
			(xy 110.115868 -280.050093) (xy 110.069852 -280.032641) (xy 110.027231 -280.008034) (xy 109.98911 -279.976909)
			(xy 109.956475 -279.940072) (xy 109.930172 -279.898476) (xy 109.910881 -279.8532) (xy 109.899104 -279.805416)
			(xy 109.895144 -279.756362) (xy 109.566456 -279.756362) (xy 109.565961 -279.780969) (xy 109.558066 -279.829546)
			(xy 109.542482 -279.876227) (xy 109.519611 -279.919804) (xy 109.490046 -279.959148) (xy 109.454553 -279.99324)
			(xy 109.41405 -280.021196) (xy 109.369588 -280.042294) (xy 109.322317 -280.055986) (xy 109.273462 -280.061918)
			(xy 109.224287 -280.059937) (xy 109.176068 -280.050093) (xy 109.130052 -280.032641) (xy 109.087431 -280.008034)
			(xy 109.04931 -279.976909) (xy 109.016675 -279.940072) (xy 108.990372 -279.898476) (xy 108.971081 -279.8532)
			(xy 108.959304 -279.805416) (xy 108.955344 -279.756362) (xy 108.626402 -279.756362) (xy 108.625907 -279.780969)
			(xy 108.618012 -279.829546) (xy 108.602428 -279.876227) (xy 108.579557 -279.919804) (xy 108.549992 -279.959148)
			(xy 108.514499 -279.99324) (xy 108.473996 -280.021196) (xy 108.429534 -280.042294) (xy 108.382263 -280.055986)
			(xy 108.333408 -280.061918) (xy 108.284233 -280.059937) (xy 108.236014 -280.050093) (xy 108.189998 -280.032641)
			(xy 108.147377 -280.008034) (xy 108.109256 -279.976909) (xy 108.076621 -279.940072) (xy 108.050318 -279.898476)
			(xy 108.031027 -279.8532) (xy 108.01925 -279.805416) (xy 108.01529 -279.756362) (xy 107.686348 -279.756362)
			(xy 107.685853 -279.780969) (xy 107.677958 -279.829546) (xy 107.662374 -279.876227) (xy 107.639503 -279.919804)
			(xy 107.609938 -279.959148) (xy 107.574445 -279.99324) (xy 107.533942 -280.021196) (xy 107.48948 -280.042294)
			(xy 107.442209 -280.055986) (xy 107.393354 -280.061918) (xy 107.344179 -280.059937) (xy 107.29596 -280.050093)
			(xy 107.249944 -280.032641) (xy 107.207323 -280.008034) (xy 107.169202 -279.976909) (xy 107.136567 -279.940072)
			(xy 107.110264 -279.898476) (xy 107.090973 -279.8532) (xy 107.079196 -279.805416) (xy 107.075236 -279.756362)
			(xy 106.746294 -279.756362) (xy 106.745799 -279.780969) (xy 106.737904 -279.829546) (xy 106.72232 -279.876227)
			(xy 106.699449 -279.919804) (xy 106.669884 -279.959148) (xy 106.634391 -279.99324) (xy 106.593888 -280.021196)
			(xy 106.549426 -280.042294) (xy 106.502155 -280.055986) (xy 106.4533 -280.061918) (xy 106.404125 -280.059937)
			(xy 106.355906 -280.050093) (xy 106.30989 -280.032641) (xy 106.267269 -280.008034) (xy 106.229148 -279.976909)
			(xy 106.196513 -279.940072) (xy 106.17021 -279.898476) (xy 106.150919 -279.8532) (xy 106.139142 -279.805416)
			(xy 106.135182 -279.756362) (xy 105.80624 -279.756362) (xy 105.805745 -279.780969) (xy 105.79785 -279.829546)
			(xy 105.782266 -279.876227) (xy 105.759395 -279.919804) (xy 105.72983 -279.959148) (xy 105.694337 -279.99324)
			(xy 105.653834 -280.021196) (xy 105.609372 -280.042294) (xy 105.562101 -280.055986) (xy 105.513246 -280.061918)
			(xy 105.464071 -280.059937) (xy 105.415852 -280.050093) (xy 105.369836 -280.032641) (xy 105.327215 -280.008034)
			(xy 105.289094 -279.976909) (xy 105.256459 -279.940072) (xy 105.230156 -279.898476) (xy 105.210865 -279.8532)
			(xy 105.199088 -279.805416) (xy 105.195128 -279.756362) (xy 104.86644 -279.756362) (xy 104.865945 -279.780969)
			(xy 104.85805 -279.829546) (xy 104.842466 -279.876227) (xy 104.819595 -279.919804) (xy 104.79003 -279.959148)
			(xy 104.754537 -279.99324) (xy 104.714034 -280.021196) (xy 104.669572 -280.042294) (xy 104.622301 -280.055986)
			(xy 104.573446 -280.061918) (xy 104.524271 -280.059937) (xy 104.476052 -280.050093) (xy 104.430036 -280.032641)
			(xy 104.387415 -280.008034) (xy 104.349294 -279.976909) (xy 104.316659 -279.940072) (xy 104.290356 -279.898476)
			(xy 104.271065 -279.8532) (xy 104.259288 -279.805416) (xy 104.255328 -279.756362) (xy 103.926386 -279.756362)
			(xy 103.925891 -279.780969) (xy 103.917996 -279.829546) (xy 103.902412 -279.876227) (xy 103.879541 -279.919804)
			(xy 103.849976 -279.959148) (xy 103.814483 -279.99324) (xy 103.77398 -280.021196) (xy 103.729518 -280.042294)
			(xy 103.682247 -280.055986) (xy 103.633392 -280.061918) (xy 103.584217 -280.059937) (xy 103.535998 -280.050093)
			(xy 103.489982 -280.032641) (xy 103.447361 -280.008034) (xy 103.40924 -279.976909) (xy 103.376605 -279.940072)
			(xy 103.350302 -279.898476) (xy 103.331011 -279.8532) (xy 103.319234 -279.805416) (xy 103.315274 -279.756362)
			(xy 102.986332 -279.756362) (xy 102.985837 -279.780969) (xy 102.977942 -279.829546) (xy 102.962358 -279.876227)
			(xy 102.939487 -279.919804) (xy 102.909922 -279.959148) (xy 102.874429 -279.99324) (xy 102.833926 -280.021196)
			(xy 102.789464 -280.042294) (xy 102.742193 -280.055986) (xy 102.693338 -280.061918) (xy 102.644163 -280.059937)
			(xy 102.595944 -280.050093) (xy 102.549928 -280.032641) (xy 102.507307 -280.008034) (xy 102.469186 -279.976909)
			(xy 102.436551 -279.940072) (xy 102.410248 -279.898476) (xy 102.390957 -279.8532) (xy 102.37918 -279.805416)
			(xy 102.37522 -279.756362) (xy 102.046278 -279.756362) (xy 102.045783 -279.780969) (xy 102.037888 -279.829546)
			(xy 102.022304 -279.876227) (xy 101.999433 -279.919804) (xy 101.969868 -279.959148) (xy 101.934375 -279.99324)
			(xy 101.893872 -280.021196) (xy 101.84941 -280.042294) (xy 101.802139 -280.055986) (xy 101.753284 -280.061918)
			(xy 101.704109 -280.059937) (xy 101.65589 -280.050093) (xy 101.609874 -280.032641) (xy 101.567253 -280.008034)
			(xy 101.529132 -279.976909) (xy 101.496497 -279.940072) (xy 101.470194 -279.898476) (xy 101.450903 -279.8532)
			(xy 101.439126 -279.805416) (xy 101.435166 -279.756362) (xy 101.106478 -279.756362) (xy 101.105983 -279.780969)
			(xy 101.098088 -279.829546) (xy 101.082504 -279.876227) (xy 101.059633 -279.919804) (xy 101.030068 -279.959148)
			(xy 100.994575 -279.99324) (xy 100.954072 -280.021196) (xy 100.90961 -280.042294) (xy 100.862339 -280.055986)
			(xy 100.813484 -280.061918) (xy 100.764309 -280.059937) (xy 100.71609 -280.050093) (xy 100.670074 -280.032641)
			(xy 100.627453 -280.008034) (xy 100.589332 -279.976909) (xy 100.556697 -279.940072) (xy 100.530394 -279.898476)
			(xy 100.511103 -279.8532) (xy 100.499326 -279.805416) (xy 100.495366 -279.756362) (xy 100.166424 -279.756362)
			(xy 100.165929 -279.780969) (xy 100.158034 -279.829546) (xy 100.14245 -279.876227) (xy 100.119579 -279.919804)
			(xy 100.090014 -279.959148) (xy 100.054521 -279.99324) (xy 100.014018 -280.021196) (xy 99.969556 -280.042294)
			(xy 99.922285 -280.055986) (xy 99.87343 -280.061918) (xy 99.824255 -280.059937) (xy 99.776036 -280.050093)
			(xy 99.73002 -280.032641) (xy 99.687399 -280.008034) (xy 99.649278 -279.976909) (xy 99.616643 -279.940072)
			(xy 99.59034 -279.898476) (xy 99.571049 -279.8532) (xy 99.559272 -279.805416) (xy 99.555312 -279.756362)
			(xy 99.22637 -279.756362) (xy 99.225875 -279.780969) (xy 99.21798 -279.829546) (xy 99.202396 -279.876227)
			(xy 99.179525 -279.919804) (xy 99.14996 -279.959148) (xy 99.114467 -279.99324) (xy 99.073964 -280.021196)
			(xy 99.029502 -280.042294) (xy 98.982231 -280.055986) (xy 98.933376 -280.061918) (xy 98.884201 -280.059937)
			(xy 98.835982 -280.050093) (xy 98.789966 -280.032641) (xy 98.747345 -280.008034) (xy 98.709224 -279.976909)
			(xy 98.676589 -279.940072) (xy 98.650286 -279.898476) (xy 98.630995 -279.8532) (xy 98.619218 -279.805416)
			(xy 98.615258 -279.756362) (xy 98.286316 -279.756362) (xy 98.285821 -279.780969) (xy 98.277926 -279.829546)
			(xy 98.262342 -279.876227) (xy 98.239471 -279.919804) (xy 98.209906 -279.959148) (xy 98.174413 -279.99324)
			(xy 98.13391 -280.021196) (xy 98.089448 -280.042294) (xy 98.042177 -280.055986) (xy 97.993322 -280.061918)
			(xy 97.944147 -280.059937) (xy 97.895928 -280.050093) (xy 97.849912 -280.032641) (xy 97.807291 -280.008034)
			(xy 97.76917 -279.976909) (xy 97.736535 -279.940072) (xy 97.710232 -279.898476) (xy 97.690941 -279.8532)
			(xy 97.679164 -279.805416) (xy 97.675204 -279.756362) (xy 97.346262 -279.756362) (xy 97.345767 -279.780969)
			(xy 97.337872 -279.829546) (xy 97.322288 -279.876227) (xy 97.299417 -279.919804) (xy 97.269852 -279.959148)
			(xy 97.234359 -279.99324) (xy 97.193856 -280.021196) (xy 97.149394 -280.042294) (xy 97.102123 -280.055986)
			(xy 97.053268 -280.061918) (xy 97.004093 -280.059937) (xy 96.955874 -280.050093) (xy 96.909858 -280.032641)
			(xy 96.867237 -280.008034) (xy 96.829116 -279.976909) (xy 96.796481 -279.940072) (xy 96.770178 -279.898476)
			(xy 96.750887 -279.8532) (xy 96.73911 -279.805416) (xy 96.73515 -279.756362) (xy 96.416876 -279.756362)
			(xy 96.416364 -279.781808) (xy 96.4082 -279.832042) (xy 96.392084 -279.880316) (xy 96.368433 -279.925379)
			(xy 96.33786 -279.966065) (xy 96.301156 -280.00132) (xy 96.259272 -280.03023) (xy 96.213293 -280.052047)
			(xy 96.164409 -280.066207) (xy 96.113888 -280.072341) (xy 96.063036 -280.070292) (xy 96.013172 -280.060112)
			(xy 95.965586 -280.042065) (xy 95.921512 -280.016619) (xy 95.88209 -279.984432) (xy 95.848342 -279.946338)
			(xy 95.821141 -279.903324) (xy 95.801193 -279.856504) (xy 95.789014 -279.80709) (xy 95.784919 -279.756362)
			(xy 95.466408 -279.756362) (xy 95.465913 -279.780969) (xy 95.458018 -279.829546) (xy 95.442434 -279.876227)
			(xy 95.419563 -279.919804) (xy 95.389998 -279.959148) (xy 95.354505 -279.99324) (xy 95.314002 -280.021196)
			(xy 95.26954 -280.042294) (xy 95.222269 -280.055986) (xy 95.173414 -280.061918) (xy 95.124239 -280.059937)
			(xy 95.07602 -280.050093) (xy 95.030004 -280.032641) (xy 94.987383 -280.008034) (xy 94.949262 -279.976909)
			(xy 94.916627 -279.940072) (xy 94.890324 -279.898476) (xy 94.871033 -279.8532) (xy 94.859256 -279.805416)
			(xy 94.855296 -279.756362) (xy 94.536768 -279.756362) (xy 94.536256 -279.781808) (xy 94.528092 -279.832042)
			(xy 94.511976 -279.880316) (xy 94.488325 -279.925379) (xy 94.457752 -279.966065) (xy 94.421048 -280.00132)
			(xy 94.379164 -280.03023) (xy 94.333185 -280.052047) (xy 94.284301 -280.066207) (xy 94.23378 -280.072341)
			(xy 94.182928 -280.070292) (xy 94.133064 -280.060112) (xy 94.085478 -280.042065) (xy 94.041404 -280.016619)
			(xy 94.001982 -279.984432) (xy 93.968234 -279.946338) (xy 93.941033 -279.903324) (xy 93.921085 -279.856504)
			(xy 93.908906 -279.80709) (xy 93.904811 -279.756362) (xy 93.5863 -279.756362) (xy 93.585837 -279.780213)
			(xy 93.578412 -279.827335) (xy 93.563754 -279.872731) (xy 93.542218 -279.915296) (xy 93.514328 -279.953996)
			(xy 93.480762 -279.987891) (xy 93.442335 -280.016157) (xy 93.399981 -280.038107) (xy 93.354731 -280.053206)
			(xy 93.331284 -280.057606) (xy 93.322648 -280.05913) (xy 93.294708 -280.07945) (xy 93.289839 -280.083206)
			(xy 93.281892 -280.092586) (xy 93.27896 -280.097992) (xy 93.248226 -280.160476) (xy 93.24721 -280.163016)
			(xy 93.24363 -280.172385) (xy 93.243354 -280.192425) (xy 93.246702 -280.201878) (xy 93.246956 -280.20264)
			(xy 93.250004 -280.208482) (xy 93.294708 -280.285444) (xy 93.305179 -280.303923) (xy 93.323614 -280.342192)
			(xy 93.331538 -280.361898) (xy 93.331538 -280.362152) (xy 93.334231 -280.368354) (xy 93.34234 -280.379167)
			(xy 93.34754 -280.383488) (xy 93.352874 -280.387552) (xy 93.365066 -280.392886) (xy 93.45803 -280.405078)
			(xy 93.464894 -280.405743) (xy 93.47854 -280.403803) (xy 93.484954 -280.401268) (xy 93.490981 -280.398467)
			(xy 93.501401 -280.390223) (xy 93.505528 -280.385012) (xy 93.505782 -280.384758) (xy 93.520284 -280.365926)
			(xy 93.554138 -280.332566) (xy 93.59275 -280.304851) (xy 93.635189 -280.283452) (xy 93.68043 -280.268883)
			(xy 93.727382 -280.261498) (xy 93.751146 -280.26106) (xy 93.776401 -280.261585) (xy 93.826223 -280.269906)
			(xy 93.873995 -280.286312) (xy 93.918416 -280.310358) (xy 93.958273 -280.341386) (xy 93.992481 -280.37855)
			(xy 94.020105 -280.420838) (xy 94.040394 -280.467096) (xy 94.052792 -280.516061) (xy 94.05696 -280.566368)
			(xy 94.374711 -280.566368) (xy 94.378806 -280.51564) (xy 94.390985 -280.466226) (xy 94.410933 -280.419406)
			(xy 94.438134 -280.376392) (xy 94.471882 -280.338298) (xy 94.511304 -280.306111) (xy 94.555378 -280.280665)
			(xy 94.602964 -280.262618) (xy 94.652828 -280.252438) (xy 94.70368 -280.250389) (xy 94.754201 -280.256523)
			(xy 94.803085 -280.270683) (xy 94.849064 -280.2925) (xy 94.890948 -280.32141) (xy 94.927652 -280.356665)
			(xy 94.958225 -280.397351) (xy 94.981876 -280.442414) (xy 94.997992 -280.490688) (xy 95.006156 -280.540922)
			(xy 95.006668 -280.566368) (xy 95.314765 -280.566368) (xy 95.31886 -280.51564) (xy 95.331039 -280.466226)
			(xy 95.350987 -280.419406) (xy 95.378188 -280.376392) (xy 95.411936 -280.338298) (xy 95.451358 -280.306111)
			(xy 95.495432 -280.280665) (xy 95.543018 -280.262618) (xy 95.592882 -280.252438) (xy 95.643734 -280.250389)
			(xy 95.694255 -280.256523) (xy 95.743139 -280.270683) (xy 95.789118 -280.2925) (xy 95.831002 -280.32141)
			(xy 95.867706 -280.356665) (xy 95.898279 -280.397351) (xy 95.92193 -280.442414) (xy 95.938046 -280.490688)
			(xy 95.94621 -280.540922) (xy 95.946722 -280.566368) (xy 96.26525 -280.566368) (xy 96.26921 -280.517314)
			(xy 96.280987 -280.46953) (xy 96.300278 -280.424254) (xy 96.326581 -280.382658) (xy 96.359216 -280.345821)
			(xy 96.397337 -280.314696) (xy 96.439958 -280.290089) (xy 96.485974 -280.272637) (xy 96.534193 -280.262793)
			(xy 96.583368 -280.260812) (xy 96.632223 -280.266744) (xy 96.679494 -280.280436) (xy 96.723956 -280.301534)
			(xy 96.764459 -280.32949) (xy 96.799952 -280.363582) (xy 96.829517 -280.402926) (xy 96.852388 -280.446503)
			(xy 96.867972 -280.493184) (xy 96.875867 -280.541761) (xy 96.876362 -280.566368) (xy 97.205304 -280.566368)
			(xy 97.209264 -280.517314) (xy 97.221041 -280.46953) (xy 97.240332 -280.424254) (xy 97.266635 -280.382658)
			(xy 97.29927 -280.345821) (xy 97.337391 -280.314696) (xy 97.380012 -280.290089) (xy 97.426028 -280.272637)
			(xy 97.474247 -280.262793) (xy 97.523422 -280.260812) (xy 97.572277 -280.266744) (xy 97.619548 -280.280436)
			(xy 97.66401 -280.301534) (xy 97.704513 -280.32949) (xy 97.740006 -280.363582) (xy 97.769571 -280.402926)
			(xy 97.792442 -280.446503) (xy 97.808026 -280.493184) (xy 97.815921 -280.541761) (xy 97.816416 -280.566368)
			(xy 98.145358 -280.566368) (xy 98.149318 -280.517314) (xy 98.161095 -280.46953) (xy 98.180386 -280.424254)
			(xy 98.206689 -280.382658) (xy 98.239324 -280.345821) (xy 98.277445 -280.314696) (xy 98.320066 -280.290089)
			(xy 98.366082 -280.272637) (xy 98.414301 -280.262793) (xy 98.463476 -280.260812) (xy 98.512331 -280.266744)
			(xy 98.559602 -280.280436) (xy 98.604064 -280.301534) (xy 98.644567 -280.32949) (xy 98.68006 -280.363582)
			(xy 98.709625 -280.402926) (xy 98.732496 -280.446503) (xy 98.74808 -280.493184) (xy 98.755975 -280.541761)
			(xy 98.75647 -280.566368) (xy 99.085158 -280.566368) (xy 99.089118 -280.517314) (xy 99.100895 -280.46953)
			(xy 99.120186 -280.424254) (xy 99.146489 -280.382658) (xy 99.179124 -280.345821) (xy 99.217245 -280.314696)
			(xy 99.259866 -280.290089) (xy 99.305882 -280.272637) (xy 99.354101 -280.262793) (xy 99.403276 -280.260812)
			(xy 99.452131 -280.266744) (xy 99.499402 -280.280436) (xy 99.543864 -280.301534) (xy 99.584367 -280.32949)
			(xy 99.61986 -280.363582) (xy 99.649425 -280.402926) (xy 99.672296 -280.446503) (xy 99.68788 -280.493184)
			(xy 99.695775 -280.541761) (xy 99.69627 -280.566368) (xy 100.025212 -280.566368) (xy 100.029172 -280.517314)
			(xy 100.040949 -280.46953) (xy 100.06024 -280.424254) (xy 100.086543 -280.382658) (xy 100.119178 -280.345821)
			(xy 100.157299 -280.314696) (xy 100.19992 -280.290089) (xy 100.245936 -280.272637) (xy 100.294155 -280.262793)
			(xy 100.34333 -280.260812) (xy 100.392185 -280.266744) (xy 100.439456 -280.280436) (xy 100.483918 -280.301534)
			(xy 100.524421 -280.32949) (xy 100.559914 -280.363582) (xy 100.589479 -280.402926) (xy 100.61235 -280.446503)
			(xy 100.627934 -280.493184) (xy 100.635829 -280.541761) (xy 100.636324 -280.566368) (xy 100.965266 -280.566368)
			(xy 100.969226 -280.517314) (xy 100.981003 -280.46953) (xy 101.000294 -280.424254) (xy 101.026597 -280.382658)
			(xy 101.059232 -280.345821) (xy 101.097353 -280.314696) (xy 101.139974 -280.290089) (xy 101.18599 -280.272637)
			(xy 101.234209 -280.262793) (xy 101.283384 -280.260812) (xy 101.332239 -280.266744) (xy 101.37951 -280.280436)
			(xy 101.423972 -280.301534) (xy 101.464475 -280.32949) (xy 101.499968 -280.363582) (xy 101.529533 -280.402926)
			(xy 101.552404 -280.446503) (xy 101.567988 -280.493184) (xy 101.575883 -280.541761) (xy 101.576378 -280.566368)
			(xy 101.90532 -280.566368) (xy 101.90928 -280.517314) (xy 101.921057 -280.46953) (xy 101.940348 -280.424254)
			(xy 101.966651 -280.382658) (xy 101.999286 -280.345821) (xy 102.037407 -280.314696) (xy 102.080028 -280.290089)
			(xy 102.126044 -280.272637) (xy 102.174263 -280.262793) (xy 102.223438 -280.260812) (xy 102.272293 -280.266744)
			(xy 102.319564 -280.280436) (xy 102.364026 -280.301534) (xy 102.404529 -280.32949) (xy 102.440022 -280.363582)
			(xy 102.469587 -280.402926) (xy 102.492458 -280.446503) (xy 102.508042 -280.493184) (xy 102.515937 -280.541761)
			(xy 102.516432 -280.566368) (xy 102.845374 -280.566368) (xy 102.849334 -280.517314) (xy 102.861111 -280.46953)
			(xy 102.880402 -280.424254) (xy 102.906705 -280.382658) (xy 102.93934 -280.345821) (xy 102.977461 -280.314696)
			(xy 103.020082 -280.290089) (xy 103.066098 -280.272637) (xy 103.114317 -280.262793) (xy 103.163492 -280.260812)
			(xy 103.212347 -280.266744) (xy 103.259618 -280.280436) (xy 103.30408 -280.301534) (xy 103.344583 -280.32949)
			(xy 103.380076 -280.363582) (xy 103.409641 -280.402926) (xy 103.432512 -280.446503) (xy 103.448096 -280.493184)
			(xy 103.455991 -280.541761) (xy 103.456486 -280.566368) (xy 103.785174 -280.566368) (xy 103.789134 -280.517314)
			(xy 103.800911 -280.46953) (xy 103.820202 -280.424254) (xy 103.846505 -280.382658) (xy 103.87914 -280.345821)
			(xy 103.917261 -280.314696) (xy 103.959882 -280.290089) (xy 104.005898 -280.272637) (xy 104.054117 -280.262793)
			(xy 104.103292 -280.260812) (xy 104.152147 -280.266744) (xy 104.199418 -280.280436) (xy 104.24388 -280.301534)
			(xy 104.284383 -280.32949) (xy 104.319876 -280.363582) (xy 104.349441 -280.402926) (xy 104.372312 -280.446503)
			(xy 104.387896 -280.493184) (xy 104.395791 -280.541761) (xy 104.396286 -280.566368) (xy 104.725228 -280.566368)
			(xy 104.729188 -280.517314) (xy 104.740965 -280.46953) (xy 104.760256 -280.424254) (xy 104.786559 -280.382658)
			(xy 104.819194 -280.345821) (xy 104.857315 -280.314696) (xy 104.899936 -280.290089) (xy 104.945952 -280.272637)
			(xy 104.994171 -280.262793) (xy 105.043346 -280.260812) (xy 105.092201 -280.266744) (xy 105.139472 -280.280436)
			(xy 105.183934 -280.301534) (xy 105.224437 -280.32949) (xy 105.25993 -280.363582) (xy 105.289495 -280.402926)
			(xy 105.312366 -280.446503) (xy 105.32795 -280.493184) (xy 105.335845 -280.541761) (xy 105.33634 -280.566368)
			(xy 105.665282 -280.566368) (xy 105.669242 -280.517314) (xy 105.681019 -280.46953) (xy 105.70031 -280.424254)
			(xy 105.726613 -280.382658) (xy 105.759248 -280.345821) (xy 105.797369 -280.314696) (xy 105.83999 -280.290089)
			(xy 105.886006 -280.272637) (xy 105.934225 -280.262793) (xy 105.9834 -280.260812) (xy 106.032255 -280.266744)
			(xy 106.079526 -280.280436) (xy 106.123988 -280.301534) (xy 106.164491 -280.32949) (xy 106.199984 -280.363582)
			(xy 106.229549 -280.402926) (xy 106.25242 -280.446503) (xy 106.268004 -280.493184) (xy 106.275899 -280.541761)
			(xy 106.276394 -280.566368) (xy 106.605336 -280.566368) (xy 106.609296 -280.517314) (xy 106.621073 -280.46953)
			(xy 106.640364 -280.424254) (xy 106.666667 -280.382658) (xy 106.699302 -280.345821) (xy 106.737423 -280.314696)
			(xy 106.780044 -280.290089) (xy 106.82606 -280.272637) (xy 106.874279 -280.262793) (xy 106.923454 -280.260812)
			(xy 106.972309 -280.266744) (xy 107.01958 -280.280436) (xy 107.064042 -280.301534) (xy 107.104545 -280.32949)
			(xy 107.140038 -280.363582) (xy 107.169603 -280.402926) (xy 107.192474 -280.446503) (xy 107.208058 -280.493184)
			(xy 107.215953 -280.541761) (xy 107.216448 -280.566368) (xy 107.545136 -280.566368) (xy 107.549096 -280.517314)
			(xy 107.560873 -280.46953) (xy 107.580164 -280.424254) (xy 107.606467 -280.382658) (xy 107.639102 -280.345821)
			(xy 107.677223 -280.314696) (xy 107.719844 -280.290089) (xy 107.76586 -280.272637) (xy 107.814079 -280.262793)
			(xy 107.863254 -280.260812) (xy 107.912109 -280.266744) (xy 107.95938 -280.280436) (xy 108.003842 -280.301534)
			(xy 108.044345 -280.32949) (xy 108.079838 -280.363582) (xy 108.109403 -280.402926) (xy 108.132274 -280.446503)
			(xy 108.147858 -280.493184) (xy 108.155753 -280.541761) (xy 108.156248 -280.566368) (xy 110.365298 -280.566368)
			(xy 110.369258 -280.517314) (xy 110.381035 -280.46953) (xy 110.400326 -280.424254) (xy 110.426629 -280.382658)
			(xy 110.459264 -280.345821) (xy 110.497385 -280.314696) (xy 110.540006 -280.290089) (xy 110.586022 -280.272637)
			(xy 110.634241 -280.262793) (xy 110.683416 -280.260812) (xy 110.732271 -280.266744) (xy 110.779542 -280.280436)
			(xy 110.824004 -280.301534) (xy 110.864507 -280.32949) (xy 110.9 -280.363582) (xy 110.929565 -280.402926)
			(xy 110.952436 -280.446503) (xy 110.96802 -280.493184) (xy 110.975915 -280.541761) (xy 110.97641 -280.566368)
			(xy 113.178856 -280.566368) (xy 113.182816 -280.517314) (xy 113.194593 -280.46953) (xy 113.213884 -280.424254)
			(xy 113.240187 -280.382658) (xy 113.272822 -280.345821) (xy 113.310943 -280.314696) (xy 113.353564 -280.290089)
			(xy 113.39958 -280.272637) (xy 113.447799 -280.262793) (xy 113.496974 -280.260812) (xy 113.545829 -280.266744)
			(xy 113.5931 -280.280436) (xy 113.637562 -280.301534) (xy 113.678065 -280.32949) (xy 113.713558 -280.363582)
			(xy 113.743123 -280.402926) (xy 113.765994 -280.446503) (xy 113.781578 -280.493184) (xy 113.789473 -280.541761)
			(xy 113.789968 -280.566368) (xy 115.999018 -280.566368) (xy 116.002978 -280.517314) (xy 116.014755 -280.46953)
			(xy 116.034046 -280.424254) (xy 116.060349 -280.382658) (xy 116.092984 -280.345821) (xy 116.131105 -280.314696)
			(xy 116.173726 -280.290089) (xy 116.219742 -280.272637) (xy 116.267961 -280.262793) (xy 116.317136 -280.260812)
			(xy 116.365991 -280.266744) (xy 116.413262 -280.280436) (xy 116.457724 -280.301534) (xy 116.498227 -280.32949)
			(xy 116.53372 -280.363582) (xy 116.563285 -280.402926) (xy 116.586156 -280.446503) (xy 116.60174 -280.493184)
			(xy 116.609635 -280.541761) (xy 116.61013 -280.566368) (xy 116.938818 -280.566368) (xy 116.942778 -280.517314)
			(xy 116.954555 -280.46953) (xy 116.973846 -280.424254) (xy 117.000149 -280.382658) (xy 117.032784 -280.345821)
			(xy 117.070905 -280.314696) (xy 117.113526 -280.290089) (xy 117.159542 -280.272637) (xy 117.207761 -280.262793)
			(xy 117.256936 -280.260812) (xy 117.305791 -280.266744) (xy 117.353062 -280.280436) (xy 117.397524 -280.301534)
			(xy 117.438027 -280.32949) (xy 117.47352 -280.363582) (xy 117.503085 -280.402926) (xy 117.525956 -280.446503)
			(xy 117.54154 -280.493184) (xy 117.549435 -280.541761) (xy 117.54993 -280.566368) (xy 117.878872 -280.566368)
			(xy 117.882832 -280.517314) (xy 117.894609 -280.46953) (xy 117.9139 -280.424254) (xy 117.940203 -280.382658)
			(xy 117.972838 -280.345821) (xy 118.010959 -280.314696) (xy 118.05358 -280.290089) (xy 118.099596 -280.272637)
			(xy 118.147815 -280.262793) (xy 118.19699 -280.260812) (xy 118.245845 -280.266744) (xy 118.293116 -280.280436)
			(xy 118.337578 -280.301534) (xy 118.378081 -280.32949) (xy 118.413574 -280.363582) (xy 118.443139 -280.402926)
			(xy 118.46601 -280.446503) (xy 118.481594 -280.493184) (xy 118.489489 -280.541761) (xy 118.489984 -280.566368)
			(xy 118.818926 -280.566368) (xy 118.822886 -280.517314) (xy 118.834663 -280.46953) (xy 118.853954 -280.424254)
			(xy 118.880257 -280.382658) (xy 118.912892 -280.345821) (xy 118.951013 -280.314696) (xy 118.993634 -280.290089)
			(xy 119.03965 -280.272637) (xy 119.087869 -280.262793) (xy 119.137044 -280.260812) (xy 119.185899 -280.266744)
			(xy 119.23317 -280.280436) (xy 119.277632 -280.301534) (xy 119.318135 -280.32949) (xy 119.353628 -280.363582)
			(xy 119.383193 -280.402926) (xy 119.406064 -280.446503) (xy 119.421648 -280.493184) (xy 119.429543 -280.541761)
			(xy 119.430038 -280.566368) (xy 119.75898 -280.566368) (xy 119.76294 -280.517314) (xy 119.774717 -280.46953)
			(xy 119.794008 -280.424254) (xy 119.820311 -280.382658) (xy 119.852946 -280.345821) (xy 119.891067 -280.314696)
			(xy 119.933688 -280.290089) (xy 119.979704 -280.272637) (xy 120.027923 -280.262793) (xy 120.077098 -280.260812)
			(xy 120.125953 -280.266744) (xy 120.173224 -280.280436) (xy 120.217686 -280.301534) (xy 120.258189 -280.32949)
			(xy 120.293682 -280.363582) (xy 120.323247 -280.402926) (xy 120.346118 -280.446503) (xy 120.361702 -280.493184)
			(xy 120.369597 -280.541761) (xy 120.370092 -280.566368) (xy 120.699034 -280.566368) (xy 120.702994 -280.517314)
			(xy 120.714771 -280.46953) (xy 120.734062 -280.424254) (xy 120.760365 -280.382658) (xy 120.793 -280.345821)
			(xy 120.831121 -280.314696) (xy 120.873742 -280.290089) (xy 120.919758 -280.272637) (xy 120.967977 -280.262793)
			(xy 121.017152 -280.260812) (xy 121.066007 -280.266744) (xy 121.113278 -280.280436) (xy 121.15774 -280.301534)
			(xy 121.198243 -280.32949) (xy 121.233736 -280.363582) (xy 121.263301 -280.402926) (xy 121.286172 -280.446503)
			(xy 121.301756 -280.493184) (xy 121.309651 -280.541761) (xy 121.310146 -280.566368) (xy 121.638834 -280.566368)
			(xy 121.642794 -280.517314) (xy 121.654571 -280.46953) (xy 121.673862 -280.424254) (xy 121.700165 -280.382658)
			(xy 121.7328 -280.345821) (xy 121.770921 -280.314696) (xy 121.813542 -280.290089) (xy 121.859558 -280.272637)
			(xy 121.907777 -280.262793) (xy 121.956952 -280.260812) (xy 122.005807 -280.266744) (xy 122.053078 -280.280436)
			(xy 122.09754 -280.301534) (xy 122.138043 -280.32949) (xy 122.173536 -280.363582) (xy 122.203101 -280.402926)
			(xy 122.225972 -280.446503) (xy 122.241556 -280.493184) (xy 122.249451 -280.541761) (xy 122.249946 -280.566368)
			(xy 122.578888 -280.566368) (xy 122.582848 -280.517314) (xy 122.594625 -280.46953) (xy 122.613916 -280.424254)
			(xy 122.640219 -280.382658) (xy 122.672854 -280.345821) (xy 122.710975 -280.314696) (xy 122.753596 -280.290089)
			(xy 122.799612 -280.272637) (xy 122.847831 -280.262793) (xy 122.897006 -280.260812) (xy 122.945861 -280.266744)
			(xy 122.993132 -280.280436) (xy 123.037594 -280.301534) (xy 123.078097 -280.32949) (xy 123.11359 -280.363582)
			(xy 123.143155 -280.402926) (xy 123.166026 -280.446503) (xy 123.18161 -280.493184) (xy 123.189505 -280.541761)
			(xy 123.19 -280.566368) (xy 123.518942 -280.566368) (xy 123.522902 -280.517314) (xy 123.534679 -280.46953)
			(xy 123.55397 -280.424254) (xy 123.580273 -280.382658) (xy 123.612908 -280.345821) (xy 123.651029 -280.314696)
			(xy 123.69365 -280.290089) (xy 123.739666 -280.272637) (xy 123.787885 -280.262793) (xy 123.83706 -280.260812)
			(xy 123.885915 -280.266744) (xy 123.933186 -280.280436) (xy 123.977648 -280.301534) (xy 124.018151 -280.32949)
			(xy 124.053644 -280.363582) (xy 124.083209 -280.402926) (xy 124.10608 -280.446503) (xy 124.121664 -280.493184)
			(xy 124.129559 -280.541761) (xy 124.130054 -280.566368) (xy 124.458996 -280.566368) (xy 124.462956 -280.517314)
			(xy 124.474733 -280.46953) (xy 124.494024 -280.424254) (xy 124.520327 -280.382658) (xy 124.552962 -280.345821)
			(xy 124.591083 -280.314696) (xy 124.633704 -280.290089) (xy 124.67972 -280.272637) (xy 124.727939 -280.262793)
			(xy 124.777114 -280.260812) (xy 124.825969 -280.266744) (xy 124.87324 -280.280436) (xy 124.917702 -280.301534)
			(xy 124.958205 -280.32949) (xy 124.993698 -280.363582) (xy 125.023263 -280.402926) (xy 125.046134 -280.446503)
			(xy 125.061718 -280.493184) (xy 125.069613 -280.541761) (xy 125.070108 -280.566368) (xy 125.069613 -280.590975)
			(xy 125.061718 -280.639552) (xy 125.046134 -280.686233) (xy 125.023263 -280.72981) (xy 124.993698 -280.769154)
			(xy 124.958205 -280.803246) (xy 124.917702 -280.831202) (xy 124.87324 -280.8523) (xy 124.825969 -280.865992)
			(xy 124.777114 -280.871924) (xy 124.727939 -280.869943) (xy 124.67972 -280.860099) (xy 124.633704 -280.842647)
			(xy 124.591083 -280.81804) (xy 124.552962 -280.786915) (xy 124.520327 -280.750078) (xy 124.494024 -280.708482)
			(xy 124.474733 -280.663206) (xy 124.462956 -280.615422) (xy 124.458996 -280.566368) (xy 124.130054 -280.566368)
			(xy 124.129559 -280.590975) (xy 124.121664 -280.639552) (xy 124.10608 -280.686233) (xy 124.083209 -280.72981)
			(xy 124.053644 -280.769154) (xy 124.018151 -280.803246) (xy 123.977648 -280.831202) (xy 123.933186 -280.8523)
			(xy 123.885915 -280.865992) (xy 123.83706 -280.871924) (xy 123.787885 -280.869943) (xy 123.739666 -280.860099)
			(xy 123.69365 -280.842647) (xy 123.651029 -280.81804) (xy 123.612908 -280.786915) (xy 123.580273 -280.750078)
			(xy 123.55397 -280.708482) (xy 123.534679 -280.663206) (xy 123.522902 -280.615422) (xy 123.518942 -280.566368)
			(xy 123.19 -280.566368) (xy 123.189505 -280.590975) (xy 123.18161 -280.639552) (xy 123.166026 -280.686233)
			(xy 123.143155 -280.72981) (xy 123.11359 -280.769154) (xy 123.078097 -280.803246) (xy 123.037594 -280.831202)
			(xy 122.993132 -280.8523) (xy 122.945861 -280.865992) (xy 122.897006 -280.871924) (xy 122.847831 -280.869943)
			(xy 122.799612 -280.860099) (xy 122.753596 -280.842647) (xy 122.710975 -280.81804) (xy 122.672854 -280.786915)
			(xy 122.640219 -280.750078) (xy 122.613916 -280.708482) (xy 122.594625 -280.663206) (xy 122.582848 -280.615422)
			(xy 122.578888 -280.566368) (xy 122.249946 -280.566368) (xy 122.249451 -280.590975) (xy 122.241556 -280.639552)
			(xy 122.225972 -280.686233) (xy 122.203101 -280.72981) (xy 122.173536 -280.769154) (xy 122.138043 -280.803246)
			(xy 122.09754 -280.831202) (xy 122.053078 -280.8523) (xy 122.005807 -280.865992) (xy 121.956952 -280.871924)
			(xy 121.907777 -280.869943) (xy 121.859558 -280.860099) (xy 121.813542 -280.842647) (xy 121.770921 -280.81804)
			(xy 121.7328 -280.786915) (xy 121.700165 -280.750078) (xy 121.673862 -280.708482) (xy 121.654571 -280.663206)
			(xy 121.642794 -280.615422) (xy 121.638834 -280.566368) (xy 121.310146 -280.566368) (xy 121.309651 -280.590975)
			(xy 121.301756 -280.639552) (xy 121.286172 -280.686233) (xy 121.263301 -280.72981) (xy 121.233736 -280.769154)
			(xy 121.198243 -280.803246) (xy 121.15774 -280.831202) (xy 121.113278 -280.8523) (xy 121.066007 -280.865992)
			(xy 121.017152 -280.871924) (xy 120.967977 -280.869943) (xy 120.919758 -280.860099) (xy 120.873742 -280.842647)
			(xy 120.831121 -280.81804) (xy 120.793 -280.786915) (xy 120.760365 -280.750078) (xy 120.734062 -280.708482)
			(xy 120.714771 -280.663206) (xy 120.702994 -280.615422) (xy 120.699034 -280.566368) (xy 120.370092 -280.566368)
			(xy 120.369597 -280.590975) (xy 120.361702 -280.639552) (xy 120.346118 -280.686233) (xy 120.323247 -280.72981)
			(xy 120.293682 -280.769154) (xy 120.258189 -280.803246) (xy 120.217686 -280.831202) (xy 120.173224 -280.8523)
			(xy 120.125953 -280.865992) (xy 120.077098 -280.871924) (xy 120.027923 -280.869943) (xy 119.979704 -280.860099)
			(xy 119.933688 -280.842647) (xy 119.891067 -280.81804) (xy 119.852946 -280.786915) (xy 119.820311 -280.750078)
			(xy 119.794008 -280.708482) (xy 119.774717 -280.663206) (xy 119.76294 -280.615422) (xy 119.75898 -280.566368)
			(xy 119.430038 -280.566368) (xy 119.429543 -280.590975) (xy 119.421648 -280.639552) (xy 119.406064 -280.686233)
			(xy 119.383193 -280.72981) (xy 119.353628 -280.769154) (xy 119.318135 -280.803246) (xy 119.277632 -280.831202)
			(xy 119.23317 -280.8523) (xy 119.185899 -280.865992) (xy 119.137044 -280.871924) (xy 119.087869 -280.869943)
			(xy 119.03965 -280.860099) (xy 118.993634 -280.842647) (xy 118.951013 -280.81804) (xy 118.912892 -280.786915)
			(xy 118.880257 -280.750078) (xy 118.853954 -280.708482) (xy 118.834663 -280.663206) (xy 118.822886 -280.615422)
			(xy 118.818926 -280.566368) (xy 118.489984 -280.566368) (xy 118.489489 -280.590975) (xy 118.481594 -280.639552)
			(xy 118.46601 -280.686233) (xy 118.443139 -280.72981) (xy 118.413574 -280.769154) (xy 118.378081 -280.803246)
			(xy 118.337578 -280.831202) (xy 118.293116 -280.8523) (xy 118.245845 -280.865992) (xy 118.19699 -280.871924)
			(xy 118.147815 -280.869943) (xy 118.099596 -280.860099) (xy 118.05358 -280.842647) (xy 118.010959 -280.81804)
			(xy 117.972838 -280.786915) (xy 117.940203 -280.750078) (xy 117.9139 -280.708482) (xy 117.894609 -280.663206)
			(xy 117.882832 -280.615422) (xy 117.878872 -280.566368) (xy 117.54993 -280.566368) (xy 117.549435 -280.590975)
			(xy 117.54154 -280.639552) (xy 117.525956 -280.686233) (xy 117.503085 -280.72981) (xy 117.47352 -280.769154)
			(xy 117.438027 -280.803246) (xy 117.397524 -280.831202) (xy 117.353062 -280.8523) (xy 117.305791 -280.865992)
			(xy 117.256936 -280.871924) (xy 117.207761 -280.869943) (xy 117.159542 -280.860099) (xy 117.113526 -280.842647)
			(xy 117.070905 -280.81804) (xy 117.032784 -280.786915) (xy 117.000149 -280.750078) (xy 116.973846 -280.708482)
			(xy 116.954555 -280.663206) (xy 116.942778 -280.615422) (xy 116.938818 -280.566368) (xy 116.61013 -280.566368)
			(xy 116.609635 -280.590975) (xy 116.60174 -280.639552) (xy 116.586156 -280.686233) (xy 116.563285 -280.72981)
			(xy 116.53372 -280.769154) (xy 116.498227 -280.803246) (xy 116.457724 -280.831202) (xy 116.413262 -280.8523)
			(xy 116.365991 -280.865992) (xy 116.317136 -280.871924) (xy 116.267961 -280.869943) (xy 116.219742 -280.860099)
			(xy 116.173726 -280.842647) (xy 116.131105 -280.81804) (xy 116.092984 -280.786915) (xy 116.060349 -280.750078)
			(xy 116.034046 -280.708482) (xy 116.014755 -280.663206) (xy 116.002978 -280.615422) (xy 115.999018 -280.566368)
			(xy 113.789968 -280.566368) (xy 113.789473 -280.590975) (xy 113.781578 -280.639552) (xy 113.765994 -280.686233)
			(xy 113.743123 -280.72981) (xy 113.713558 -280.769154) (xy 113.678065 -280.803246) (xy 113.637562 -280.831202)
			(xy 113.5931 -280.8523) (xy 113.545829 -280.865992) (xy 113.496974 -280.871924) (xy 113.447799 -280.869943)
			(xy 113.39958 -280.860099) (xy 113.353564 -280.842647) (xy 113.310943 -280.81804) (xy 113.272822 -280.786915)
			(xy 113.240187 -280.750078) (xy 113.213884 -280.708482) (xy 113.194593 -280.663206) (xy 113.182816 -280.615422)
			(xy 113.178856 -280.566368) (xy 110.97641 -280.566368) (xy 110.975915 -280.590975) (xy 110.96802 -280.639552)
			(xy 110.952436 -280.686233) (xy 110.929565 -280.72981) (xy 110.9 -280.769154) (xy 110.864507 -280.803246)
			(xy 110.824004 -280.831202) (xy 110.779542 -280.8523) (xy 110.732271 -280.865992) (xy 110.683416 -280.871924)
			(xy 110.634241 -280.869943) (xy 110.586022 -280.860099) (xy 110.540006 -280.842647) (xy 110.497385 -280.81804)
			(xy 110.459264 -280.786915) (xy 110.426629 -280.750078) (xy 110.400326 -280.708482) (xy 110.381035 -280.663206)
			(xy 110.369258 -280.615422) (xy 110.365298 -280.566368) (xy 108.156248 -280.566368) (xy 108.155753 -280.590975)
			(xy 108.147858 -280.639552) (xy 108.132274 -280.686233) (xy 108.109403 -280.72981) (xy 108.079838 -280.769154)
			(xy 108.044345 -280.803246) (xy 108.003842 -280.831202) (xy 107.95938 -280.8523) (xy 107.912109 -280.865992)
			(xy 107.863254 -280.871924) (xy 107.814079 -280.869943) (xy 107.76586 -280.860099) (xy 107.719844 -280.842647)
			(xy 107.677223 -280.81804) (xy 107.639102 -280.786915) (xy 107.606467 -280.750078) (xy 107.580164 -280.708482)
			(xy 107.560873 -280.663206) (xy 107.549096 -280.615422) (xy 107.545136 -280.566368) (xy 107.216448 -280.566368)
			(xy 107.215953 -280.590975) (xy 107.208058 -280.639552) (xy 107.192474 -280.686233) (xy 107.169603 -280.72981)
			(xy 107.140038 -280.769154) (xy 107.104545 -280.803246) (xy 107.064042 -280.831202) (xy 107.01958 -280.8523)
			(xy 106.972309 -280.865992) (xy 106.923454 -280.871924) (xy 106.874279 -280.869943) (xy 106.82606 -280.860099)
			(xy 106.780044 -280.842647) (xy 106.737423 -280.81804) (xy 106.699302 -280.786915) (xy 106.666667 -280.750078)
			(xy 106.640364 -280.708482) (xy 106.621073 -280.663206) (xy 106.609296 -280.615422) (xy 106.605336 -280.566368)
			(xy 106.276394 -280.566368) (xy 106.275899 -280.590975) (xy 106.268004 -280.639552) (xy 106.25242 -280.686233)
			(xy 106.229549 -280.72981) (xy 106.199984 -280.769154) (xy 106.164491 -280.803246) (xy 106.123988 -280.831202)
			(xy 106.079526 -280.8523) (xy 106.032255 -280.865992) (xy 105.9834 -280.871924) (xy 105.934225 -280.869943)
			(xy 105.886006 -280.860099) (xy 105.83999 -280.842647) (xy 105.797369 -280.81804) (xy 105.759248 -280.786915)
			(xy 105.726613 -280.750078) (xy 105.70031 -280.708482) (xy 105.681019 -280.663206) (xy 105.669242 -280.615422)
			(xy 105.665282 -280.566368) (xy 105.33634 -280.566368) (xy 105.335845 -280.590975) (xy 105.32795 -280.639552)
			(xy 105.312366 -280.686233) (xy 105.289495 -280.72981) (xy 105.25993 -280.769154) (xy 105.224437 -280.803246)
			(xy 105.183934 -280.831202) (xy 105.139472 -280.8523) (xy 105.092201 -280.865992) (xy 105.043346 -280.871924)
			(xy 104.994171 -280.869943) (xy 104.945952 -280.860099) (xy 104.899936 -280.842647) (xy 104.857315 -280.81804)
			(xy 104.819194 -280.786915) (xy 104.786559 -280.750078) (xy 104.760256 -280.708482) (xy 104.740965 -280.663206)
			(xy 104.729188 -280.615422) (xy 104.725228 -280.566368) (xy 104.396286 -280.566368) (xy 104.395791 -280.590975)
			(xy 104.387896 -280.639552) (xy 104.372312 -280.686233) (xy 104.349441 -280.72981) (xy 104.319876 -280.769154)
			(xy 104.284383 -280.803246) (xy 104.24388 -280.831202) (xy 104.199418 -280.8523) (xy 104.152147 -280.865992)
			(xy 104.103292 -280.871924) (xy 104.054117 -280.869943) (xy 104.005898 -280.860099) (xy 103.959882 -280.842647)
			(xy 103.917261 -280.81804) (xy 103.87914 -280.786915) (xy 103.846505 -280.750078) (xy 103.820202 -280.708482)
			(xy 103.800911 -280.663206) (xy 103.789134 -280.615422) (xy 103.785174 -280.566368) (xy 103.456486 -280.566368)
			(xy 103.455991 -280.590975) (xy 103.448096 -280.639552) (xy 103.432512 -280.686233) (xy 103.409641 -280.72981)
			(xy 103.380076 -280.769154) (xy 103.344583 -280.803246) (xy 103.30408 -280.831202) (xy 103.259618 -280.8523)
			(xy 103.212347 -280.865992) (xy 103.163492 -280.871924) (xy 103.114317 -280.869943) (xy 103.066098 -280.860099)
			(xy 103.020082 -280.842647) (xy 102.977461 -280.81804) (xy 102.93934 -280.786915) (xy 102.906705 -280.750078)
			(xy 102.880402 -280.708482) (xy 102.861111 -280.663206) (xy 102.849334 -280.615422) (xy 102.845374 -280.566368)
			(xy 102.516432 -280.566368) (xy 102.515937 -280.590975) (xy 102.508042 -280.639552) (xy 102.492458 -280.686233)
			(xy 102.469587 -280.72981) (xy 102.440022 -280.769154) (xy 102.404529 -280.803246) (xy 102.364026 -280.831202)
			(xy 102.319564 -280.8523) (xy 102.272293 -280.865992) (xy 102.223438 -280.871924) (xy 102.174263 -280.869943)
			(xy 102.126044 -280.860099) (xy 102.080028 -280.842647) (xy 102.037407 -280.81804) (xy 101.999286 -280.786915)
			(xy 101.966651 -280.750078) (xy 101.940348 -280.708482) (xy 101.921057 -280.663206) (xy 101.90928 -280.615422)
			(xy 101.90532 -280.566368) (xy 101.576378 -280.566368) (xy 101.575883 -280.590975) (xy 101.567988 -280.639552)
			(xy 101.552404 -280.686233) (xy 101.529533 -280.72981) (xy 101.499968 -280.769154) (xy 101.464475 -280.803246)
			(xy 101.423972 -280.831202) (xy 101.37951 -280.8523) (xy 101.332239 -280.865992) (xy 101.283384 -280.871924)
			(xy 101.234209 -280.869943) (xy 101.18599 -280.860099) (xy 101.139974 -280.842647) (xy 101.097353 -280.81804)
			(xy 101.059232 -280.786915) (xy 101.026597 -280.750078) (xy 101.000294 -280.708482) (xy 100.981003 -280.663206)
			(xy 100.969226 -280.615422) (xy 100.965266 -280.566368) (xy 100.636324 -280.566368) (xy 100.635829 -280.590975)
			(xy 100.627934 -280.639552) (xy 100.61235 -280.686233) (xy 100.589479 -280.72981) (xy 100.559914 -280.769154)
			(xy 100.524421 -280.803246) (xy 100.483918 -280.831202) (xy 100.439456 -280.8523) (xy 100.392185 -280.865992)
			(xy 100.34333 -280.871924) (xy 100.294155 -280.869943) (xy 100.245936 -280.860099) (xy 100.19992 -280.842647)
			(xy 100.157299 -280.81804) (xy 100.119178 -280.786915) (xy 100.086543 -280.750078) (xy 100.06024 -280.708482)
			(xy 100.040949 -280.663206) (xy 100.029172 -280.615422) (xy 100.025212 -280.566368) (xy 99.69627 -280.566368)
			(xy 99.695775 -280.590975) (xy 99.68788 -280.639552) (xy 99.672296 -280.686233) (xy 99.649425 -280.72981)
			(xy 99.61986 -280.769154) (xy 99.584367 -280.803246) (xy 99.543864 -280.831202) (xy 99.499402 -280.8523)
			(xy 99.452131 -280.865992) (xy 99.403276 -280.871924) (xy 99.354101 -280.869943) (xy 99.305882 -280.860099)
			(xy 99.259866 -280.842647) (xy 99.217245 -280.81804) (xy 99.179124 -280.786915) (xy 99.146489 -280.750078)
			(xy 99.120186 -280.708482) (xy 99.100895 -280.663206) (xy 99.089118 -280.615422) (xy 99.085158 -280.566368)
			(xy 98.75647 -280.566368) (xy 98.755975 -280.590975) (xy 98.74808 -280.639552) (xy 98.732496 -280.686233)
			(xy 98.709625 -280.72981) (xy 98.68006 -280.769154) (xy 98.644567 -280.803246) (xy 98.604064 -280.831202)
			(xy 98.559602 -280.8523) (xy 98.512331 -280.865992) (xy 98.463476 -280.871924) (xy 98.414301 -280.869943)
			(xy 98.366082 -280.860099) (xy 98.320066 -280.842647) (xy 98.277445 -280.81804) (xy 98.239324 -280.786915)
			(xy 98.206689 -280.750078) (xy 98.180386 -280.708482) (xy 98.161095 -280.663206) (xy 98.149318 -280.615422)
			(xy 98.145358 -280.566368) (xy 97.816416 -280.566368) (xy 97.815921 -280.590975) (xy 97.808026 -280.639552)
			(xy 97.792442 -280.686233) (xy 97.769571 -280.72981) (xy 97.740006 -280.769154) (xy 97.704513 -280.803246)
			(xy 97.66401 -280.831202) (xy 97.619548 -280.8523) (xy 97.572277 -280.865992) (xy 97.523422 -280.871924)
			(xy 97.474247 -280.869943) (xy 97.426028 -280.860099) (xy 97.380012 -280.842647) (xy 97.337391 -280.81804)
			(xy 97.29927 -280.786915) (xy 97.266635 -280.750078) (xy 97.240332 -280.708482) (xy 97.221041 -280.663206)
			(xy 97.209264 -280.615422) (xy 97.205304 -280.566368) (xy 96.876362 -280.566368) (xy 96.875867 -280.590975)
			(xy 96.867972 -280.639552) (xy 96.852388 -280.686233) (xy 96.829517 -280.72981) (xy 96.799952 -280.769154)
			(xy 96.764459 -280.803246) (xy 96.723956 -280.831202) (xy 96.679494 -280.8523) (xy 96.632223 -280.865992)
			(xy 96.583368 -280.871924) (xy 96.534193 -280.869943) (xy 96.485974 -280.860099) (xy 96.439958 -280.842647)
			(xy 96.397337 -280.81804) (xy 96.359216 -280.786915) (xy 96.326581 -280.750078) (xy 96.300278 -280.708482)
			(xy 96.280987 -280.663206) (xy 96.26921 -280.615422) (xy 96.26525 -280.566368) (xy 95.946722 -280.566368)
			(xy 95.94621 -280.591814) (xy 95.938046 -280.642048) (xy 95.92193 -280.690322) (xy 95.898279 -280.735385)
			(xy 95.867706 -280.776071) (xy 95.831002 -280.811326) (xy 95.789118 -280.840236) (xy 95.743139 -280.862053)
			(xy 95.694255 -280.876213) (xy 95.643734 -280.882347) (xy 95.592882 -280.880298) (xy 95.543018 -280.870118)
			(xy 95.495432 -280.852071) (xy 95.451358 -280.826625) (xy 95.411936 -280.794438) (xy 95.378188 -280.756344)
			(xy 95.350987 -280.71333) (xy 95.331039 -280.66651) (xy 95.31886 -280.617096) (xy 95.314765 -280.566368)
			(xy 95.006668 -280.566368) (xy 95.006156 -280.591814) (xy 94.997992 -280.642048) (xy 94.981876 -280.690322)
			(xy 94.958225 -280.735385) (xy 94.927652 -280.776071) (xy 94.890948 -280.811326) (xy 94.849064 -280.840236)
			(xy 94.803085 -280.862053) (xy 94.754201 -280.876213) (xy 94.70368 -280.882347) (xy 94.652828 -280.880298)
			(xy 94.602964 -280.870118) (xy 94.555378 -280.852071) (xy 94.511304 -280.826625) (xy 94.471882 -280.794438)
			(xy 94.438134 -280.756344) (xy 94.410933 -280.71333) (xy 94.390985 -280.66651) (xy 94.378806 -280.617096)
			(xy 94.374711 -280.566368) (xy 94.05696 -280.566368) (xy 94.056963 -280.5664) (xy 94.052792 -280.616739)
			(xy 94.040394 -280.665704) (xy 94.020105 -280.711962) (xy 93.992481 -280.75425) (xy 93.958273 -280.791414)
			(xy 93.918416 -280.822442) (xy 93.873995 -280.846488) (xy 93.826223 -280.862894) (xy 93.776401 -280.871215)
			(xy 93.751146 -280.871676) (xy 93.727381 -280.871225) (xy 93.680424 -280.863861) (xy 93.635178 -280.849304)
			(xy 93.592737 -280.827905) (xy 93.554128 -280.800184) (xy 93.520286 -280.76681) (xy 93.505782 -280.747978)
			(xy 93.505782 -280.747724) (xy 93.505528 -280.747724) (xy 93.50137 -280.742547) (xy 93.490952 -280.734319)
			(xy 93.484954 -280.731468) (xy 93.478545 -280.728924) (xy 93.464896 -280.727005) (xy 93.45803 -280.727658)
			(xy 93.372178 -280.739088) (xy 93.365417 -280.740161) (xy 93.352791 -280.745434) (xy 93.347286 -280.749502)
			(xy 93.341952 -280.753566) (xy 93.334078 -280.764234) (xy 93.331538 -280.770838) (xy 93.315989 -280.80851)
			(xy 93.275568 -280.879275) (xy 93.25102 -280.911808) (xy 93.25102 -280.912062) (xy 93.246987 -280.917466)
			(xy 93.241587 -280.929817) (xy 93.240352 -280.936446) (xy 93.238574 -280.949654) (xy 93.276928 -281.042364)
			(xy 93.279684 -281.048526) (xy 93.287927 -281.059211) (xy 93.293184 -281.063446) (xy 93.298518 -281.06751)
			(xy 93.31071 -281.072336) (xy 93.317822 -281.073352) (xy 93.342182 -281.076816) (xy 93.389436 -281.090518)
			(xy 93.433883 -281.111619) (xy 93.474371 -281.139572) (xy 93.509854 -281.173655) (xy 93.539413 -281.212987)
			(xy 93.562285 -281.256548) (xy 93.577876 -281.303213) (xy 93.585784 -281.351774) (xy 93.5863 -281.376374)
			(xy 93.904811 -281.376374) (xy 93.908906 -281.325646) (xy 93.921085 -281.276232) (xy 93.941033 -281.229412)
			(xy 93.968234 -281.186398) (xy 94.001982 -281.148304) (xy 94.041404 -281.116117) (xy 94.085478 -281.090671)
			(xy 94.133064 -281.072624) (xy 94.182928 -281.062444) (xy 94.23378 -281.060395) (xy 94.284301 -281.066529)
			(xy 94.333185 -281.080689) (xy 94.379164 -281.102506) (xy 94.421048 -281.131416) (xy 94.457752 -281.166671)
			(xy 94.488325 -281.207357) (xy 94.511976 -281.25242) (xy 94.528092 -281.300694) (xy 94.536256 -281.350928)
			(xy 94.536768 -281.376374) (xy 94.855296 -281.376374) (xy 94.859256 -281.32732) (xy 94.871033 -281.279536)
			(xy 94.890324 -281.23426) (xy 94.916627 -281.192664) (xy 94.949262 -281.155827) (xy 94.987383 -281.124702)
			(xy 95.030004 -281.100095) (xy 95.07602 -281.082643) (xy 95.124239 -281.072799) (xy 95.173414 -281.070818)
			(xy 95.222269 -281.07675) (xy 95.26954 -281.090442) (xy 95.314002 -281.11154) (xy 95.354505 -281.139496)
			(xy 95.389998 -281.173588) (xy 95.419563 -281.212932) (xy 95.442434 -281.256509) (xy 95.458018 -281.30319)
			(xy 95.465913 -281.351767) (xy 95.466408 -281.376374) (xy 95.784919 -281.376374) (xy 95.789014 -281.325646)
			(xy 95.801193 -281.276232) (xy 95.821141 -281.229412) (xy 95.848342 -281.186398) (xy 95.88209 -281.148304)
			(xy 95.921512 -281.116117) (xy 95.965586 -281.090671) (xy 96.013172 -281.072624) (xy 96.063036 -281.062444)
			(xy 96.113888 -281.060395) (xy 96.164409 -281.066529) (xy 96.213293 -281.080689) (xy 96.259272 -281.102506)
			(xy 96.301156 -281.131416) (xy 96.33786 -281.166671) (xy 96.368433 -281.207357) (xy 96.392084 -281.25242)
			(xy 96.4082 -281.300694) (xy 96.416364 -281.350928) (xy 96.416876 -281.376374) (xy 96.73515 -281.376374)
			(xy 96.73911 -281.32732) (xy 96.750887 -281.279536) (xy 96.770178 -281.23426) (xy 96.796481 -281.192664)
			(xy 96.829116 -281.155827) (xy 96.867237 -281.124702) (xy 96.909858 -281.100095) (xy 96.955874 -281.082643)
			(xy 97.004093 -281.072799) (xy 97.053268 -281.070818) (xy 97.102123 -281.07675) (xy 97.149394 -281.090442)
			(xy 97.193856 -281.11154) (xy 97.234359 -281.139496) (xy 97.269852 -281.173588) (xy 97.299417 -281.212932)
			(xy 97.322288 -281.256509) (xy 97.337872 -281.30319) (xy 97.345767 -281.351767) (xy 97.346262 -281.376374)
			(xy 97.346261 -281.3764) (xy 97.674859 -281.3764) (xy 97.679035 -281.32601) (xy 97.691448 -281.276995)
			(xy 97.711759 -281.230691) (xy 97.739414 -281.188362) (xy 97.77366 -281.151162) (xy 97.813561 -281.120107)
			(xy 97.85803 -281.096042) (xy 97.905853 -281.079626) (xy 97.955727 -281.071304) (xy 97.981008 -281.070812)
			(xy 98.921062 -281.070812) (xy 98.946341 -281.071354) (xy 98.996209 -281.07967) (xy 99.044029 -281.096081)
			(xy 99.088494 -281.12014) (xy 99.128393 -281.15119) (xy 99.162637 -281.188384) (xy 99.190291 -281.230707)
			(xy 99.210601 -281.277006) (xy 99.223013 -281.326016) (xy 99.227187 -281.376374) (xy 99.555312 -281.376374)
			(xy 99.559272 -281.32732) (xy 99.571049 -281.279536) (xy 99.59034 -281.23426) (xy 99.616643 -281.192664)
			(xy 99.649278 -281.155827) (xy 99.687399 -281.124702) (xy 99.73002 -281.100095) (xy 99.776036 -281.082643)
			(xy 99.824255 -281.072799) (xy 99.87343 -281.070818) (xy 99.922285 -281.07675) (xy 99.969556 -281.090442)
			(xy 100.014018 -281.11154) (xy 100.054521 -281.139496) (xy 100.090014 -281.173588) (xy 100.119579 -281.212932)
			(xy 100.14245 -281.256509) (xy 100.158034 -281.30319) (xy 100.165929 -281.351767) (xy 100.166424 -281.376374)
			(xy 100.166423 -281.3764) (xy 100.495088 -281.3764) (xy 100.499263 -281.326019) (xy 100.511672 -281.277012)
			(xy 100.531978 -281.230715) (xy 100.559627 -281.188392) (xy 100.593865 -281.151197) (xy 100.633757 -281.120144)
			(xy 100.678216 -281.09608) (xy 100.72603 -281.079662) (xy 100.775893 -281.071336) (xy 100.80117 -281.070812)
			(xy 101.741224 -281.070812) (xy 101.766497 -281.071388) (xy 101.816353 -281.079711) (xy 101.864159 -281.096126)
			(xy 101.908611 -281.120186) (xy 101.948498 -281.151233) (xy 101.98273 -281.188422) (xy 102.010375 -281.230738)
			(xy 102.030678 -281.277027) (xy 102.043086 -281.326027) (xy 102.047258 -281.376374) (xy 102.37522 -281.376374)
			(xy 102.37918 -281.32732) (xy 102.390957 -281.279536) (xy 102.410248 -281.23426) (xy 102.436551 -281.192664)
			(xy 102.469186 -281.155827) (xy 102.507307 -281.124702) (xy 102.549928 -281.100095) (xy 102.595944 -281.082643)
			(xy 102.644163 -281.072799) (xy 102.693338 -281.070818) (xy 102.742193 -281.07675) (xy 102.789464 -281.090442)
			(xy 102.833926 -281.11154) (xy 102.874429 -281.139496) (xy 102.909922 -281.173588) (xy 102.939487 -281.212932)
			(xy 102.962358 -281.256509) (xy 102.977942 -281.30319) (xy 102.985837 -281.351767) (xy 102.986332 -281.376374)
			(xy 105.195128 -281.376374) (xy 105.199088 -281.32732) (xy 105.210865 -281.279536) (xy 105.230156 -281.23426)
			(xy 105.256459 -281.192664) (xy 105.289094 -281.155827) (xy 105.327215 -281.124702) (xy 105.369836 -281.100095)
			(xy 105.415852 -281.082643) (xy 105.464071 -281.072799) (xy 105.513246 -281.070818) (xy 105.562101 -281.07675)
			(xy 105.609372 -281.090442) (xy 105.653834 -281.11154) (xy 105.694337 -281.139496) (xy 105.72983 -281.173588)
			(xy 105.759395 -281.212932) (xy 105.782266 -281.256509) (xy 105.79785 -281.30319) (xy 105.805745 -281.351767)
			(xy 105.80624 -281.376374) (xy 108.01529 -281.376374) (xy 108.01925 -281.32732) (xy 108.031027 -281.279536)
			(xy 108.050318 -281.23426) (xy 108.076621 -281.192664) (xy 108.109256 -281.155827) (xy 108.147377 -281.124702)
			(xy 108.189998 -281.100095) (xy 108.236014 -281.082643) (xy 108.284233 -281.072799) (xy 108.333408 -281.070818)
			(xy 108.382263 -281.07675) (xy 108.429534 -281.090442) (xy 108.473996 -281.11154) (xy 108.514499 -281.139496)
			(xy 108.549992 -281.173588) (xy 108.579557 -281.212932) (xy 108.602428 -281.256509) (xy 108.618012 -281.30319)
			(xy 108.625907 -281.351767) (xy 108.626402 -281.376374) (xy 108.955344 -281.376374) (xy 108.959304 -281.32732)
			(xy 108.971081 -281.279536) (xy 108.990372 -281.23426) (xy 109.016675 -281.192664) (xy 109.04931 -281.155827)
			(xy 109.087431 -281.124702) (xy 109.130052 -281.100095) (xy 109.176068 -281.082643) (xy 109.224287 -281.072799)
			(xy 109.273462 -281.070818) (xy 109.322317 -281.07675) (xy 109.369588 -281.090442) (xy 109.41405 -281.11154)
			(xy 109.454553 -281.139496) (xy 109.490046 -281.173588) (xy 109.519611 -281.212932) (xy 109.542482 -281.256509)
			(xy 109.558066 -281.30319) (xy 109.565961 -281.351767) (xy 109.566456 -281.376374) (xy 109.895144 -281.376374)
			(xy 109.899104 -281.32732) (xy 109.910881 -281.279536) (xy 109.930172 -281.23426) (xy 109.956475 -281.192664)
			(xy 109.98911 -281.155827) (xy 110.027231 -281.124702) (xy 110.069852 -281.100095) (xy 110.115868 -281.082643)
			(xy 110.164087 -281.072799) (xy 110.213262 -281.070818) (xy 110.262117 -281.07675) (xy 110.309388 -281.090442)
			(xy 110.35385 -281.11154) (xy 110.394353 -281.139496) (xy 110.429846 -281.173588) (xy 110.459411 -281.212932)
			(xy 110.482282 -281.256509) (xy 110.497866 -281.30319) (xy 110.505761 -281.351767) (xy 110.506256 -281.376374)
			(xy 113.64901 -281.376374) (xy 113.65297 -281.32732) (xy 113.664747 -281.279536) (xy 113.684038 -281.23426)
			(xy 113.710341 -281.192664) (xy 113.742976 -281.155827) (xy 113.781097 -281.124702) (xy 113.823718 -281.100095)
			(xy 113.869734 -281.082643) (xy 113.917953 -281.072799) (xy 113.967128 -281.070818) (xy 114.015983 -281.07675)
			(xy 114.063254 -281.090442) (xy 114.107716 -281.11154) (xy 114.148219 -281.139496) (xy 114.183712 -281.173588)
			(xy 114.213277 -281.212932) (xy 114.236148 -281.256509) (xy 114.251732 -281.30319) (xy 114.259627 -281.351767)
			(xy 114.260122 -281.376374) (xy 114.58881 -281.376374) (xy 114.59277 -281.32732) (xy 114.604547 -281.279536)
			(xy 114.623838 -281.23426) (xy 114.650141 -281.192664) (xy 114.682776 -281.155827) (xy 114.720897 -281.124702)
			(xy 114.763518 -281.100095) (xy 114.809534 -281.082643) (xy 114.857753 -281.072799) (xy 114.906928 -281.070818)
			(xy 114.955783 -281.07675) (xy 115.003054 -281.090442) (xy 115.047516 -281.11154) (xy 115.088019 -281.139496)
			(xy 115.123512 -281.173588) (xy 115.153077 -281.212932) (xy 115.175948 -281.256509) (xy 115.191532 -281.30319)
			(xy 115.199427 -281.351767) (xy 115.199922 -281.376374) (xy 115.528864 -281.376374) (xy 115.532824 -281.32732)
			(xy 115.544601 -281.279536) (xy 115.563892 -281.23426) (xy 115.590195 -281.192664) (xy 115.62283 -281.155827)
			(xy 115.660951 -281.124702) (xy 115.703572 -281.100095) (xy 115.749588 -281.082643) (xy 115.797807 -281.072799)
			(xy 115.846982 -281.070818) (xy 115.895837 -281.07675) (xy 115.943108 -281.090442) (xy 115.98757 -281.11154)
			(xy 116.028073 -281.139496) (xy 116.063566 -281.173588) (xy 116.093131 -281.212932) (xy 116.116002 -281.256509)
			(xy 116.131586 -281.30319) (xy 116.139481 -281.351767) (xy 116.139976 -281.376374) (xy 118.349026 -281.376374)
			(xy 118.352986 -281.32732) (xy 118.364763 -281.279536) (xy 118.384054 -281.23426) (xy 118.410357 -281.192664)
			(xy 118.442992 -281.155827) (xy 118.481113 -281.124702) (xy 118.523734 -281.100095) (xy 118.56975 -281.082643)
			(xy 118.617969 -281.072799) (xy 118.667144 -281.070818) (xy 118.715999 -281.07675) (xy 118.76327 -281.090442)
			(xy 118.807732 -281.11154) (xy 118.848235 -281.139496) (xy 118.883728 -281.173588) (xy 118.913293 -281.212932)
			(xy 118.936164 -281.256509) (xy 118.951748 -281.30319) (xy 118.959643 -281.351767) (xy 118.960138 -281.376374)
			(xy 121.168934 -281.376374) (xy 121.172894 -281.32732) (xy 121.184671 -281.279536) (xy 121.203962 -281.23426)
			(xy 121.230265 -281.192664) (xy 121.2629 -281.155827) (xy 121.301021 -281.124702) (xy 121.343642 -281.100095)
			(xy 121.389658 -281.082643) (xy 121.437877 -281.072799) (xy 121.487052 -281.070818) (xy 121.535907 -281.07675)
			(xy 121.583178 -281.090442) (xy 121.62764 -281.11154) (xy 121.668143 -281.139496) (xy 121.703636 -281.173588)
			(xy 121.733201 -281.212932) (xy 121.756072 -281.256509) (xy 121.771656 -281.30319) (xy 121.779551 -281.351767)
			(xy 121.780046 -281.376374) (xy 121.780045 -281.3764) (xy 122.108688 -281.3764) (xy 122.112863 -281.326017)
			(xy 122.125274 -281.277007) (xy 122.145582 -281.230709) (xy 122.173233 -281.188385) (xy 122.207473 -281.151189)
			(xy 122.247369 -281.120136) (xy 122.291831 -281.096074) (xy 122.339648 -281.079657) (xy 122.389514 -281.071335)
			(xy 122.414792 -281.070812) (xy 123.354846 -281.070812) (xy 123.380118 -281.071389) (xy 123.429971 -281.079715)
			(xy 123.477774 -281.096133) (xy 123.522223 -281.120193) (xy 123.562106 -281.151241) (xy 123.596336 -281.18843)
			(xy 123.623978 -281.230745) (xy 123.64428 -281.277032) (xy 123.656686 -281.326029) (xy 123.660858 -281.376374)
			(xy 123.988842 -281.376374) (xy 123.992802 -281.32732) (xy 124.004579 -281.279536) (xy 124.02387 -281.23426)
			(xy 124.050173 -281.192664) (xy 124.082808 -281.155827) (xy 124.120929 -281.124702) (xy 124.16355 -281.100095)
			(xy 124.209566 -281.082643) (xy 124.257785 -281.072799) (xy 124.30696 -281.070818) (xy 124.355815 -281.07675)
			(xy 124.403086 -281.090442) (xy 124.447548 -281.11154) (xy 124.488051 -281.139496) (xy 124.523544 -281.173588)
			(xy 124.553109 -281.212932) (xy 124.57598 -281.256509) (xy 124.591564 -281.30319) (xy 124.599459 -281.351767)
			(xy 124.599954 -281.376374) (xy 124.599459 -281.400981) (xy 124.591564 -281.449558) (xy 124.57598 -281.496239)
			(xy 124.553109 -281.539816) (xy 124.523544 -281.57916) (xy 124.488051 -281.613252) (xy 124.447548 -281.641208)
			(xy 124.403086 -281.662306) (xy 124.355815 -281.675998) (xy 124.30696 -281.68193) (xy 124.257785 -281.679949)
			(xy 124.209566 -281.670105) (xy 124.16355 -281.652653) (xy 124.120929 -281.628046) (xy 124.082808 -281.596921)
			(xy 124.050173 -281.560084) (xy 124.02387 -281.518488) (xy 124.004579 -281.473212) (xy 123.992802 -281.425428)
			(xy 123.988842 -281.376374) (xy 123.660858 -281.376374) (xy 123.66086 -281.3764) (xy 123.656686 -281.426771)
			(xy 123.64428 -281.475768) (xy 123.623978 -281.522055) (xy 123.596336 -281.56437) (xy 123.562106 -281.601559)
			(xy 123.522223 -281.632607) (xy 123.477774 -281.656667) (xy 123.429971 -281.673085) (xy 123.380118 -281.681411)
			(xy 123.354846 -281.681936) (xy 122.414792 -281.681936) (xy 122.389514 -281.681465) (xy 122.339648 -281.673143)
			(xy 122.291831 -281.656726) (xy 122.247369 -281.632664) (xy 122.207473 -281.601611) (xy 122.173233 -281.564415)
			(xy 122.145582 -281.522091) (xy 122.125274 -281.475793) (xy 122.112863 -281.426783) (xy 122.108688 -281.3764)
			(xy 121.780045 -281.3764) (xy 121.779551 -281.400981) (xy 121.771656 -281.449558) (xy 121.756072 -281.496239)
			(xy 121.733201 -281.539816) (xy 121.703636 -281.57916) (xy 121.668143 -281.613252) (xy 121.62764 -281.641208)
			(xy 121.583178 -281.662306) (xy 121.535907 -281.675998) (xy 121.487052 -281.68193) (xy 121.437877 -281.679949)
			(xy 121.389658 -281.670105) (xy 121.343642 -281.652653) (xy 121.301021 -281.628046) (xy 121.2629 -281.596921)
			(xy 121.230265 -281.560084) (xy 121.203962 -281.518488) (xy 121.184671 -281.473212) (xy 121.172894 -281.425428)
			(xy 121.168934 -281.376374) (xy 118.960138 -281.376374) (xy 118.959643 -281.400981) (xy 118.951748 -281.449558)
			(xy 118.936164 -281.496239) (xy 118.913293 -281.539816) (xy 118.883728 -281.57916) (xy 118.848235 -281.613252)
			(xy 118.807732 -281.641208) (xy 118.76327 -281.662306) (xy 118.715999 -281.675998) (xy 118.667144 -281.68193)
			(xy 118.617969 -281.679949) (xy 118.56975 -281.670105) (xy 118.523734 -281.652653) (xy 118.481113 -281.628046)
			(xy 118.442992 -281.596921) (xy 118.410357 -281.560084) (xy 118.384054 -281.518488) (xy 118.364763 -281.473212)
			(xy 118.352986 -281.425428) (xy 118.349026 -281.376374) (xy 116.139976 -281.376374) (xy 116.139481 -281.400981)
			(xy 116.131586 -281.449558) (xy 116.116002 -281.496239) (xy 116.093131 -281.539816) (xy 116.063566 -281.57916)
			(xy 116.028073 -281.613252) (xy 115.98757 -281.641208) (xy 115.943108 -281.662306) (xy 115.895837 -281.675998)
			(xy 115.846982 -281.68193) (xy 115.797807 -281.679949) (xy 115.749588 -281.670105) (xy 115.703572 -281.652653)
			(xy 115.660951 -281.628046) (xy 115.62283 -281.596921) (xy 115.590195 -281.560084) (xy 115.563892 -281.518488)
			(xy 115.544601 -281.473212) (xy 115.532824 -281.425428) (xy 115.528864 -281.376374) (xy 115.199922 -281.376374)
			(xy 115.199427 -281.400981) (xy 115.191532 -281.449558) (xy 115.175948 -281.496239) (xy 115.153077 -281.539816)
			(xy 115.123512 -281.57916) (xy 115.088019 -281.613252) (xy 115.047516 -281.641208) (xy 115.003054 -281.662306)
			(xy 114.955783 -281.675998) (xy 114.906928 -281.68193) (xy 114.857753 -281.679949) (xy 114.809534 -281.670105)
			(xy 114.763518 -281.652653) (xy 114.720897 -281.628046) (xy 114.682776 -281.596921) (xy 114.650141 -281.560084)
			(xy 114.623838 -281.518488) (xy 114.604547 -281.473212) (xy 114.59277 -281.425428) (xy 114.58881 -281.376374)
			(xy 114.260122 -281.376374) (xy 114.259627 -281.400981) (xy 114.251732 -281.449558) (xy 114.236148 -281.496239)
			(xy 114.213277 -281.539816) (xy 114.183712 -281.57916) (xy 114.148219 -281.613252) (xy 114.107716 -281.641208)
			(xy 114.063254 -281.662306) (xy 114.015983 -281.675998) (xy 113.967128 -281.68193) (xy 113.917953 -281.679949)
			(xy 113.869734 -281.670105) (xy 113.823718 -281.652653) (xy 113.781097 -281.628046) (xy 113.742976 -281.596921)
			(xy 113.710341 -281.560084) (xy 113.684038 -281.518488) (xy 113.664747 -281.473212) (xy 113.65297 -281.425428)
			(xy 113.64901 -281.376374) (xy 110.506256 -281.376374) (xy 110.505761 -281.400981) (xy 110.497866 -281.449558)
			(xy 110.482282 -281.496239) (xy 110.459411 -281.539816) (xy 110.429846 -281.57916) (xy 110.394353 -281.613252)
			(xy 110.35385 -281.641208) (xy 110.309388 -281.662306) (xy 110.262117 -281.675998) (xy 110.213262 -281.68193)
			(xy 110.164087 -281.679949) (xy 110.115868 -281.670105) (xy 110.069852 -281.652653) (xy 110.027231 -281.628046)
			(xy 109.98911 -281.596921) (xy 109.956475 -281.560084) (xy 109.930172 -281.518488) (xy 109.910881 -281.473212)
			(xy 109.899104 -281.425428) (xy 109.895144 -281.376374) (xy 109.566456 -281.376374) (xy 109.565961 -281.400981)
			(xy 109.558066 -281.449558) (xy 109.542482 -281.496239) (xy 109.519611 -281.539816) (xy 109.490046 -281.57916)
			(xy 109.454553 -281.613252) (xy 109.41405 -281.641208) (xy 109.369588 -281.662306) (xy 109.322317 -281.675998)
			(xy 109.273462 -281.68193) (xy 109.224287 -281.679949) (xy 109.176068 -281.670105) (xy 109.130052 -281.652653)
			(xy 109.087431 -281.628046) (xy 109.04931 -281.596921) (xy 109.016675 -281.560084) (xy 108.990372 -281.518488)
			(xy 108.971081 -281.473212) (xy 108.959304 -281.425428) (xy 108.955344 -281.376374) (xy 108.626402 -281.376374)
			(xy 108.625907 -281.400981) (xy 108.618012 -281.449558) (xy 108.602428 -281.496239) (xy 108.579557 -281.539816)
			(xy 108.549992 -281.57916) (xy 108.514499 -281.613252) (xy 108.473996 -281.641208) (xy 108.429534 -281.662306)
			(xy 108.382263 -281.675998) (xy 108.333408 -281.68193) (xy 108.284233 -281.679949) (xy 108.236014 -281.670105)
			(xy 108.189998 -281.652653) (xy 108.147377 -281.628046) (xy 108.109256 -281.596921) (xy 108.076621 -281.560084)
			(xy 108.050318 -281.518488) (xy 108.031027 -281.473212) (xy 108.01925 -281.425428) (xy 108.01529 -281.376374)
			(xy 105.80624 -281.376374) (xy 105.805745 -281.400981) (xy 105.79785 -281.449558) (xy 105.782266 -281.496239)
			(xy 105.759395 -281.539816) (xy 105.72983 -281.57916) (xy 105.694337 -281.613252) (xy 105.653834 -281.641208)
			(xy 105.609372 -281.662306) (xy 105.562101 -281.675998) (xy 105.513246 -281.68193) (xy 105.464071 -281.679949)
			(xy 105.415852 -281.670105) (xy 105.369836 -281.652653) (xy 105.327215 -281.628046) (xy 105.289094 -281.596921)
			(xy 105.256459 -281.560084) (xy 105.230156 -281.518488) (xy 105.210865 -281.473212) (xy 105.199088 -281.425428)
			(xy 105.195128 -281.376374) (xy 102.986332 -281.376374) (xy 102.985837 -281.400981) (xy 102.977942 -281.449558)
			(xy 102.962358 -281.496239) (xy 102.939487 -281.539816) (xy 102.909922 -281.57916) (xy 102.874429 -281.613252)
			(xy 102.833926 -281.641208) (xy 102.789464 -281.662306) (xy 102.742193 -281.675998) (xy 102.693338 -281.68193)
			(xy 102.644163 -281.679949) (xy 102.595944 -281.670105) (xy 102.549928 -281.652653) (xy 102.507307 -281.628046)
			(xy 102.469186 -281.596921) (xy 102.436551 -281.560084) (xy 102.410248 -281.518488) (xy 102.390957 -281.473212)
			(xy 102.37918 -281.425428) (xy 102.37522 -281.376374) (xy 102.047258 -281.376374) (xy 102.04726 -281.3764)
			(xy 102.043086 -281.426773) (xy 102.030678 -281.475773) (xy 102.010375 -281.522062) (xy 101.98273 -281.564378)
			(xy 101.948498 -281.601567) (xy 101.908611 -281.632614) (xy 101.864159 -281.656674) (xy 101.816353 -281.673089)
			(xy 101.766497 -281.681412) (xy 101.741224 -281.681936) (xy 100.80117 -281.681936) (xy 100.775893 -281.681464)
			(xy 100.72603 -281.673138) (xy 100.678216 -281.65672) (xy 100.633757 -281.632656) (xy 100.593865 -281.601603)
			(xy 100.559627 -281.564408) (xy 100.531978 -281.522085) (xy 100.511672 -281.475788) (xy 100.499263 -281.426781)
			(xy 100.495088 -281.3764) (xy 100.166423 -281.3764) (xy 100.165929 -281.400981) (xy 100.158034 -281.449558)
			(xy 100.14245 -281.496239) (xy 100.119579 -281.539816) (xy 100.090014 -281.57916) (xy 100.054521 -281.613252)
			(xy 100.014018 -281.641208) (xy 99.969556 -281.662306) (xy 99.922285 -281.675998) (xy 99.87343 -281.68193)
			(xy 99.824255 -281.679949) (xy 99.776036 -281.670105) (xy 99.73002 -281.652653) (xy 99.687399 -281.628046)
			(xy 99.649278 -281.596921) (xy 99.616643 -281.560084) (xy 99.59034 -281.518488) (xy 99.571049 -281.473212)
			(xy 99.559272 -281.425428) (xy 99.555312 -281.376374) (xy 99.227187 -281.376374) (xy 99.227189 -281.3764)
			(xy 99.223013 -281.426784) (xy 99.210601 -281.475794) (xy 99.190291 -281.522093) (xy 99.162637 -281.564416)
			(xy 99.128393 -281.60161) (xy 99.088494 -281.63266) (xy 99.044029 -281.656719) (xy 98.996209 -281.67313)
			(xy 98.946341 -281.681446) (xy 98.921062 -281.681936) (xy 97.981008 -281.681936) (xy 97.955727 -281.681496)
			(xy 97.905853 -281.673174) (xy 97.85803 -281.656758) (xy 97.813561 -281.632693) (xy 97.77366 -281.601638)
			(xy 97.739414 -281.564438) (xy 97.711759 -281.522109) (xy 97.691448 -281.475805) (xy 97.679035 -281.42679)
			(xy 97.674859 -281.3764) (xy 97.346261 -281.3764) (xy 97.345767 -281.400981) (xy 97.337872 -281.449558)
			(xy 97.322288 -281.496239) (xy 97.299417 -281.539816) (xy 97.269852 -281.57916) (xy 97.234359 -281.613252)
			(xy 97.193856 -281.641208) (xy 97.149394 -281.662306) (xy 97.102123 -281.675998) (xy 97.053268 -281.68193)
			(xy 97.004093 -281.679949) (xy 96.955874 -281.670105) (xy 96.909858 -281.652653) (xy 96.867237 -281.628046)
			(xy 96.829116 -281.596921) (xy 96.796481 -281.560084) (xy 96.770178 -281.518488) (xy 96.750887 -281.473212)
			(xy 96.73911 -281.425428) (xy 96.73515 -281.376374) (xy 96.416876 -281.376374) (xy 96.416364 -281.40182)
			(xy 96.4082 -281.452054) (xy 96.392084 -281.500328) (xy 96.368433 -281.545391) (xy 96.33786 -281.586077)
			(xy 96.301156 -281.621332) (xy 96.259272 -281.650242) (xy 96.213293 -281.672059) (xy 96.164409 -281.686219)
			(xy 96.113888 -281.692353) (xy 96.063036 -281.690304) (xy 96.013172 -281.680124) (xy 95.965586 -281.662077)
			(xy 95.921512 -281.636631) (xy 95.88209 -281.604444) (xy 95.848342 -281.56635) (xy 95.821141 -281.523336)
			(xy 95.801193 -281.476516) (xy 95.789014 -281.427102) (xy 95.784919 -281.376374) (xy 95.466408 -281.376374)
			(xy 95.465913 -281.400981) (xy 95.458018 -281.449558) (xy 95.442434 -281.496239) (xy 95.419563 -281.539816)
			(xy 95.389998 -281.57916) (xy 95.354505 -281.613252) (xy 95.314002 -281.641208) (xy 95.26954 -281.662306)
			(xy 95.222269 -281.675998) (xy 95.173414 -281.68193) (xy 95.124239 -281.679949) (xy 95.07602 -281.670105)
			(xy 95.030004 -281.652653) (xy 94.987383 -281.628046) (xy 94.949262 -281.596921) (xy 94.916627 -281.560084)
			(xy 94.890324 -281.518488) (xy 94.871033 -281.473212) (xy 94.859256 -281.425428) (xy 94.855296 -281.376374)
			(xy 94.536768 -281.376374) (xy 94.536256 -281.40182) (xy 94.528092 -281.452054) (xy 94.511976 -281.500328)
			(xy 94.488325 -281.545391) (xy 94.457752 -281.586077) (xy 94.421048 -281.621332) (xy 94.379164 -281.650242)
			(xy 94.333185 -281.672059) (xy 94.284301 -281.686219) (xy 94.23378 -281.692353) (xy 94.182928 -281.690304)
			(xy 94.133064 -281.680124) (xy 94.085478 -281.662077) (xy 94.041404 -281.636631) (xy 94.001982 -281.604444)
			(xy 93.968234 -281.56635) (xy 93.941033 -281.523336) (xy 93.921085 -281.476516) (xy 93.908906 -281.427102)
			(xy 93.904811 -281.376374) (xy 93.5863 -281.376374) (xy 93.585836 -281.400225) (xy 93.57841 -281.447345)
			(xy 93.563751 -281.492739) (xy 93.542214 -281.535303) (xy 93.514324 -281.574002) (xy 93.480757 -281.607895)
			(xy 93.442331 -281.63616) (xy 93.399978 -281.658108) (xy 93.354728 -281.673207) (xy 93.331284 -281.677618)
			(xy 93.322648 -281.679142) (xy 93.294708 -281.699462) (xy 93.289834 -281.703214) (xy 93.281872 -281.712586)
			(xy 93.27896 -281.718004) (xy 93.248226 -281.780488) (xy 93.24721 -281.783028) (xy 93.243633 -281.792397)
			(xy 93.24336 -281.812435) (xy 93.246702 -281.82189) (xy 93.246956 -281.822652) (xy 93.250004 -281.828494)
			(xy 93.294708 -281.905456) (xy 93.305178 -281.923936) (xy 93.323613 -281.962204) (xy 93.331538 -281.98191)
			(xy 93.331538 -281.982164) (xy 93.334232 -281.988365) (xy 93.342343 -281.999176) (xy 93.34754 -282.0035)
			(xy 93.352874 -282.007564) (xy 93.365066 -282.012898) (xy 93.45803 -282.02509) (xy 93.464894 -282.025755)
			(xy 93.478541 -282.023815) (xy 93.484954 -282.02128) (xy 93.490982 -282.018479) (xy 93.501403 -282.010237)
			(xy 93.505528 -282.005024) (xy 93.505782 -282.00477) (xy 93.520284 -281.985938) (xy 93.554137 -281.952576)
			(xy 93.592749 -281.92486) (xy 93.635188 -281.90346) (xy 93.680429 -281.888891) (xy 93.727382 -281.881505)
			(xy 93.751146 -281.881072) (xy 93.7764 -281.881597) (xy 93.82622 -281.889917) (xy 93.87399 -281.906323)
			(xy 93.918409 -281.930368) (xy 93.958265 -281.961395) (xy 93.992471 -281.998558) (xy 94.020095 -282.040844)
			(xy 94.040382 -282.0871) (xy 94.05278 -282.136063) (xy 94.056949 -282.18638) (xy 94.374711 -282.18638)
			(xy 94.378806 -282.135652) (xy 94.390985 -282.086238) (xy 94.410933 -282.039418) (xy 94.438134 -281.996404)
			(xy 94.471882 -281.95831) (xy 94.511304 -281.926123) (xy 94.555378 -281.900677) (xy 94.602964 -281.88263)
			(xy 94.652828 -281.87245) (xy 94.70368 -281.870401) (xy 94.754201 -281.876535) (xy 94.803085 -281.890695)
			(xy 94.849064 -281.912512) (xy 94.890948 -281.941422) (xy 94.927652 -281.976677) (xy 94.958225 -282.017363)
			(xy 94.981876 -282.062426) (xy 94.997992 -282.1107) (xy 95.006156 -282.160934) (xy 95.006668 -282.18638)
			(xy 95.314765 -282.18638) (xy 95.31886 -282.135652) (xy 95.331039 -282.086238) (xy 95.350987 -282.039418)
			(xy 95.378188 -281.996404) (xy 95.411936 -281.95831) (xy 95.451358 -281.926123) (xy 95.495432 -281.900677)
			(xy 95.543018 -281.88263) (xy 95.592882 -281.87245) (xy 95.643734 -281.870401) (xy 95.694255 -281.876535)
			(xy 95.743139 -281.890695) (xy 95.789118 -281.912512) (xy 95.831002 -281.941422) (xy 95.867706 -281.976677)
			(xy 95.898279 -282.017363) (xy 95.92193 -282.062426) (xy 95.938046 -282.1107) (xy 95.94621 -282.160934)
			(xy 95.946722 -282.18638) (xy 96.26525 -282.18638) (xy 96.26921 -282.137326) (xy 96.280987 -282.089542)
			(xy 96.300278 -282.044266) (xy 96.326581 -282.00267) (xy 96.359216 -281.965833) (xy 96.397337 -281.934708)
			(xy 96.439958 -281.910101) (xy 96.485974 -281.892649) (xy 96.534193 -281.882805) (xy 96.583368 -281.880824)
			(xy 96.632223 -281.886756) (xy 96.679494 -281.900448) (xy 96.723956 -281.921546) (xy 96.764459 -281.949502)
			(xy 96.799952 -281.983594) (xy 96.829517 -282.022938) (xy 96.852388 -282.066515) (xy 96.867972 -282.113196)
			(xy 96.875867 -282.161773) (xy 96.876362 -282.18638) (xy 97.205304 -282.18638) (xy 97.209264 -282.137326)
			(xy 97.221041 -282.089542) (xy 97.240332 -282.044266) (xy 97.266635 -282.00267) (xy 97.29927 -281.965833)
			(xy 97.337391 -281.934708) (xy 97.380012 -281.910101) (xy 97.426028 -281.892649) (xy 97.474247 -281.882805)
			(xy 97.523422 -281.880824) (xy 97.572277 -281.886756) (xy 97.619548 -281.900448) (xy 97.66401 -281.921546)
			(xy 97.704513 -281.949502) (xy 97.740006 -281.983594) (xy 97.769571 -282.022938) (xy 97.792442 -282.066515)
			(xy 97.808026 -282.113196) (xy 97.815921 -282.161773) (xy 97.816416 -282.18638) (xy 98.145358 -282.18638)
			(xy 98.149318 -282.137326) (xy 98.161095 -282.089542) (xy 98.180386 -282.044266) (xy 98.206689 -282.00267)
			(xy 98.239324 -281.965833) (xy 98.277445 -281.934708) (xy 98.320066 -281.910101) (xy 98.366082 -281.892649)
			(xy 98.414301 -281.882805) (xy 98.463476 -281.880824) (xy 98.512331 -281.886756) (xy 98.559602 -281.900448)
			(xy 98.604064 -281.921546) (xy 98.644567 -281.949502) (xy 98.68006 -281.983594) (xy 98.709625 -282.022938)
			(xy 98.732496 -282.066515) (xy 98.74808 -282.113196) (xy 98.755975 -282.161773) (xy 98.75647 -282.18638)
			(xy 99.085158 -282.18638) (xy 99.089118 -282.137326) (xy 99.100895 -282.089542) (xy 99.120186 -282.044266)
			(xy 99.146489 -282.00267) (xy 99.179124 -281.965833) (xy 99.217245 -281.934708) (xy 99.259866 -281.910101)
			(xy 99.305882 -281.892649) (xy 99.354101 -281.882805) (xy 99.403276 -281.880824) (xy 99.452131 -281.886756)
			(xy 99.499402 -281.900448) (xy 99.543864 -281.921546) (xy 99.584367 -281.949502) (xy 99.61986 -281.983594)
			(xy 99.649425 -282.022938) (xy 99.672296 -282.066515) (xy 99.68788 -282.113196) (xy 99.695775 -282.161773)
			(xy 99.69627 -282.18638) (xy 100.025212 -282.18638) (xy 100.029172 -282.137326) (xy 100.040949 -282.089542)
			(xy 100.06024 -282.044266) (xy 100.086543 -282.00267) (xy 100.119178 -281.965833) (xy 100.157299 -281.934708)
			(xy 100.19992 -281.910101) (xy 100.245936 -281.892649) (xy 100.294155 -281.882805) (xy 100.34333 -281.880824)
			(xy 100.392185 -281.886756) (xy 100.439456 -281.900448) (xy 100.483918 -281.921546) (xy 100.524421 -281.949502)
			(xy 100.559914 -281.983594) (xy 100.589479 -282.022938) (xy 100.61235 -282.066515) (xy 100.627934 -282.113196)
			(xy 100.635829 -282.161773) (xy 100.636324 -282.18638) (xy 100.965266 -282.18638) (xy 100.969226 -282.137326)
			(xy 100.981003 -282.089542) (xy 101.000294 -282.044266) (xy 101.026597 -282.00267) (xy 101.059232 -281.965833)
			(xy 101.097353 -281.934708) (xy 101.139974 -281.910101) (xy 101.18599 -281.892649) (xy 101.234209 -281.882805)
			(xy 101.283384 -281.880824) (xy 101.332239 -281.886756) (xy 101.37951 -281.900448) (xy 101.423972 -281.921546)
			(xy 101.464475 -281.949502) (xy 101.499968 -281.983594) (xy 101.529533 -282.022938) (xy 101.552404 -282.066515)
			(xy 101.567988 -282.113196) (xy 101.575883 -282.161773) (xy 101.576378 -282.18638) (xy 101.90532 -282.18638)
			(xy 101.90928 -282.137326) (xy 101.921057 -282.089542) (xy 101.940348 -282.044266) (xy 101.966651 -282.00267)
			(xy 101.999286 -281.965833) (xy 102.037407 -281.934708) (xy 102.080028 -281.910101) (xy 102.126044 -281.892649)
			(xy 102.174263 -281.882805) (xy 102.223438 -281.880824) (xy 102.272293 -281.886756) (xy 102.319564 -281.900448)
			(xy 102.364026 -281.921546) (xy 102.404529 -281.949502) (xy 102.440022 -281.983594) (xy 102.469587 -282.022938)
			(xy 102.492458 -282.066515) (xy 102.508042 -282.113196) (xy 102.515937 -282.161773) (xy 102.516432 -282.18638)
			(xy 102.845374 -282.18638) (xy 102.849334 -282.137326) (xy 102.861111 -282.089542) (xy 102.880402 -282.044266)
			(xy 102.906705 -282.00267) (xy 102.93934 -281.965833) (xy 102.977461 -281.934708) (xy 103.020082 -281.910101)
			(xy 103.066098 -281.892649) (xy 103.114317 -281.882805) (xy 103.163492 -281.880824) (xy 103.212347 -281.886756)
			(xy 103.259618 -281.900448) (xy 103.30408 -281.921546) (xy 103.344583 -281.949502) (xy 103.380076 -281.983594)
			(xy 103.409641 -282.022938) (xy 103.432512 -282.066515) (xy 103.448096 -282.113196) (xy 103.455991 -282.161773)
			(xy 103.456486 -282.18638) (xy 103.785174 -282.18638) (xy 103.789134 -282.137326) (xy 103.800911 -282.089542)
			(xy 103.820202 -282.044266) (xy 103.846505 -282.00267) (xy 103.87914 -281.965833) (xy 103.917261 -281.934708)
			(xy 103.959882 -281.910101) (xy 104.005898 -281.892649) (xy 104.054117 -281.882805) (xy 104.103292 -281.880824)
			(xy 104.152147 -281.886756) (xy 104.199418 -281.900448) (xy 104.24388 -281.921546) (xy 104.284383 -281.949502)
			(xy 104.319876 -281.983594) (xy 104.349441 -282.022938) (xy 104.372312 -282.066515) (xy 104.387896 -282.113196)
			(xy 104.395791 -282.161773) (xy 104.396286 -282.18638) (xy 104.725228 -282.18638) (xy 104.729188 -282.137326)
			(xy 104.740965 -282.089542) (xy 104.760256 -282.044266) (xy 104.786559 -282.00267) (xy 104.819194 -281.965833)
			(xy 104.857315 -281.934708) (xy 104.899936 -281.910101) (xy 104.945952 -281.892649) (xy 104.994171 -281.882805)
			(xy 105.043346 -281.880824) (xy 105.092201 -281.886756) (xy 105.139472 -281.900448) (xy 105.183934 -281.921546)
			(xy 105.224437 -281.949502) (xy 105.25993 -281.983594) (xy 105.289495 -282.022938) (xy 105.312366 -282.066515)
			(xy 105.32795 -282.113196) (xy 105.335845 -282.161773) (xy 105.33634 -282.18638) (xy 105.665282 -282.18638)
			(xy 105.669242 -282.137326) (xy 105.681019 -282.089542) (xy 105.70031 -282.044266) (xy 105.726613 -282.00267)
			(xy 105.759248 -281.965833) (xy 105.797369 -281.934708) (xy 105.83999 -281.910101) (xy 105.886006 -281.892649)
			(xy 105.934225 -281.882805) (xy 105.9834 -281.880824) (xy 106.032255 -281.886756) (xy 106.079526 -281.900448)
			(xy 106.123988 -281.921546) (xy 106.164491 -281.949502) (xy 106.199984 -281.983594) (xy 106.229549 -282.022938)
			(xy 106.25242 -282.066515) (xy 106.268004 -282.113196) (xy 106.275899 -282.161773) (xy 106.276394 -282.18638)
			(xy 106.605336 -282.18638) (xy 106.609296 -282.137326) (xy 106.621073 -282.089542) (xy 106.640364 -282.044266)
			(xy 106.666667 -282.00267) (xy 106.699302 -281.965833) (xy 106.737423 -281.934708) (xy 106.780044 -281.910101)
			(xy 106.82606 -281.892649) (xy 106.874279 -281.882805) (xy 106.923454 -281.880824) (xy 106.972309 -281.886756)
			(xy 107.01958 -281.900448) (xy 107.064042 -281.921546) (xy 107.104545 -281.949502) (xy 107.140038 -281.983594)
			(xy 107.169603 -282.022938) (xy 107.192474 -282.066515) (xy 107.208058 -282.113196) (xy 107.215953 -282.161773)
			(xy 107.216448 -282.18638) (xy 107.545136 -282.18638) (xy 107.549096 -282.137326) (xy 107.560873 -282.089542)
			(xy 107.580164 -282.044266) (xy 107.606467 -282.00267) (xy 107.639102 -281.965833) (xy 107.677223 -281.934708)
			(xy 107.719844 -281.910101) (xy 107.76586 -281.892649) (xy 107.814079 -281.882805) (xy 107.863254 -281.880824)
			(xy 107.912109 -281.886756) (xy 107.95938 -281.900448) (xy 108.003842 -281.921546) (xy 108.044345 -281.949502)
			(xy 108.079838 -281.983594) (xy 108.109403 -282.022938) (xy 108.132274 -282.066515) (xy 108.147858 -282.113196)
			(xy 108.155753 -282.161773) (xy 108.156248 -282.18638) (xy 108.156248 -282.1864) (xy 108.485149 -282.1864)
			(xy 108.48932 -282.136059) (xy 108.50172 -282.087092) (xy 108.522011 -282.040833) (xy 108.549639 -281.998544)
			(xy 108.58385 -281.96138) (xy 108.623712 -281.930354) (xy 108.668137 -281.906312) (xy 108.715913 -281.889909)
			(xy 108.765737 -281.881594) (xy 108.790994 -281.881072) (xy 109.731048 -281.881072) (xy 109.756299 -281.881637)
			(xy 109.806111 -281.889957) (xy 109.853875 -281.906361) (xy 109.898288 -281.930402) (xy 109.938139 -281.961425)
			(xy 109.97234 -281.998583) (xy 109.99996 -282.040863) (xy 110.020245 -282.087113) (xy 110.032641 -282.13607)
			(xy 110.036809 -282.18638) (xy 110.365298 -282.18638) (xy 110.369258 -282.137326) (xy 110.381035 -282.089542)
			(xy 110.400326 -282.044266) (xy 110.426629 -282.00267) (xy 110.459264 -281.965833) (xy 110.497385 -281.934708)
			(xy 110.540006 -281.910101) (xy 110.586022 -281.892649) (xy 110.634241 -281.882805) (xy 110.683416 -281.880824)
			(xy 110.732271 -281.886756) (xy 110.779542 -281.900448) (xy 110.824004 -281.921546) (xy 110.864507 -281.949502)
			(xy 110.9 -281.983594) (xy 110.929565 -282.022938) (xy 110.952436 -282.066515) (xy 110.96802 -282.113196)
			(xy 110.975915 -282.161773) (xy 110.97641 -282.18638) (xy 113.178856 -282.18638) (xy 113.182816 -282.137326)
			(xy 113.194593 -282.089542) (xy 113.213884 -282.044266) (xy 113.240187 -282.00267) (xy 113.272822 -281.965833)
			(xy 113.310943 -281.934708) (xy 113.353564 -281.910101) (xy 113.39958 -281.892649) (xy 113.447799 -281.882805)
			(xy 113.496974 -281.880824) (xy 113.545829 -281.886756) (xy 113.5931 -281.900448) (xy 113.637562 -281.921546)
			(xy 113.678065 -281.949502) (xy 113.713558 -281.983594) (xy 113.743123 -282.022938) (xy 113.765994 -282.066515)
			(xy 113.781578 -282.113196) (xy 113.789473 -282.161773) (xy 113.789968 -282.18638) (xy 113.789968 -282.1864)
			(xy 114.11882 -282.1864) (xy 114.122992 -282.136052) (xy 114.135394 -282.087078) (xy 114.155689 -282.040813)
			(xy 114.183321 -281.99852) (xy 114.217539 -281.961352) (xy 114.257407 -281.930323) (xy 114.301839 -281.906279)
			(xy 114.349622 -281.889877) (xy 114.399454 -281.881564) (xy 114.424714 -281.881072) (xy 115.364768 -281.881072)
			(xy 115.390026 -281.881602) (xy 115.439853 -281.889912) (xy 115.487633 -281.90631) (xy 115.532062 -281.93035)
			(xy 115.571927 -281.961375) (xy 115.606142 -281.998539) (xy 115.633773 -282.040827) (xy 115.654067 -282.087088)
			(xy 115.666468 -282.136057) (xy 115.670638 -282.18638) (xy 115.999018 -282.18638) (xy 116.002978 -282.137326)
			(xy 116.014755 -282.089542) (xy 116.034046 -282.044266) (xy 116.060349 -282.00267) (xy 116.092984 -281.965833)
			(xy 116.131105 -281.934708) (xy 116.173726 -281.910101) (xy 116.219742 -281.892649) (xy 116.267961 -281.882805)
			(xy 116.317136 -281.880824) (xy 116.365991 -281.886756) (xy 116.413262 -281.900448) (xy 116.457724 -281.921546)
			(xy 116.498227 -281.949502) (xy 116.53372 -281.983594) (xy 116.563285 -282.022938) (xy 116.586156 -282.066515)
			(xy 116.60174 -282.113196) (xy 116.609635 -282.161773) (xy 116.61013 -282.18638) (xy 116.938818 -282.18638)
			(xy 116.942778 -282.137326) (xy 116.954555 -282.089542) (xy 116.973846 -282.044266) (xy 117.000149 -282.00267)
			(xy 117.032784 -281.965833) (xy 117.070905 -281.934708) (xy 117.113526 -281.910101) (xy 117.159542 -281.892649)
			(xy 117.207761 -281.882805) (xy 117.256936 -281.880824) (xy 117.305791 -281.886756) (xy 117.353062 -281.900448)
			(xy 117.397524 -281.921546) (xy 117.438027 -281.949502) (xy 117.47352 -281.983594) (xy 117.503085 -282.022938)
			(xy 117.525956 -282.066515) (xy 117.54154 -282.113196) (xy 117.549435 -282.161773) (xy 117.54993 -282.18638)
			(xy 117.878872 -282.18638) (xy 117.882832 -282.137326) (xy 117.894609 -282.089542) (xy 117.9139 -282.044266)
			(xy 117.940203 -282.00267) (xy 117.972838 -281.965833) (xy 118.010959 -281.934708) (xy 118.05358 -281.910101)
			(xy 118.099596 -281.892649) (xy 118.147815 -281.882805) (xy 118.19699 -281.880824) (xy 118.245845 -281.886756)
			(xy 118.293116 -281.900448) (xy 118.337578 -281.921546) (xy 118.378081 -281.949502) (xy 118.413574 -281.983594)
			(xy 118.443139 -282.022938) (xy 118.46601 -282.066515) (xy 118.481594 -282.113196) (xy 118.489489 -282.161773)
			(xy 118.489984 -282.18638) (xy 118.818926 -282.18638) (xy 118.822886 -282.137326) (xy 118.834663 -282.089542)
			(xy 118.853954 -282.044266) (xy 118.880257 -282.00267) (xy 118.912892 -281.965833) (xy 118.951013 -281.934708)
			(xy 118.993634 -281.910101) (xy 119.03965 -281.892649) (xy 119.087869 -281.882805) (xy 119.137044 -281.880824)
			(xy 119.185899 -281.886756) (xy 119.23317 -281.900448) (xy 119.277632 -281.921546) (xy 119.318135 -281.949502)
			(xy 119.353628 -281.983594) (xy 119.383193 -282.022938) (xy 119.406064 -282.066515) (xy 119.421648 -282.113196)
			(xy 119.429543 -282.161773) (xy 119.430038 -282.18638) (xy 119.75898 -282.18638) (xy 119.76294 -282.137326)
			(xy 119.774717 -282.089542) (xy 119.794008 -282.044266) (xy 119.820311 -282.00267) (xy 119.852946 -281.965833)
			(xy 119.891067 -281.934708) (xy 119.933688 -281.910101) (xy 119.979704 -281.892649) (xy 120.027923 -281.882805)
			(xy 120.077098 -281.880824) (xy 120.125953 -281.886756) (xy 120.173224 -281.900448) (xy 120.217686 -281.921546)
			(xy 120.258189 -281.949502) (xy 120.293682 -281.983594) (xy 120.323247 -282.022938) (xy 120.346118 -282.066515)
			(xy 120.361702 -282.113196) (xy 120.369597 -282.161773) (xy 120.370092 -282.18638) (xy 120.699034 -282.18638)
			(xy 120.702994 -282.137326) (xy 120.714771 -282.089542) (xy 120.734062 -282.044266) (xy 120.760365 -282.00267)
			(xy 120.793 -281.965833) (xy 120.831121 -281.934708) (xy 120.873742 -281.910101) (xy 120.919758 -281.892649)
			(xy 120.967977 -281.882805) (xy 121.017152 -281.880824) (xy 121.066007 -281.886756) (xy 121.113278 -281.900448)
			(xy 121.15774 -281.921546) (xy 121.198243 -281.949502) (xy 121.233736 -281.983594) (xy 121.263301 -282.022938)
			(xy 121.286172 -282.066515) (xy 121.301756 -282.113196) (xy 121.309651 -282.161773) (xy 121.310146 -282.18638)
			(xy 121.638834 -282.18638) (xy 121.642794 -282.137326) (xy 121.654571 -282.089542) (xy 121.673862 -282.044266)
			(xy 121.700165 -282.00267) (xy 121.7328 -281.965833) (xy 121.770921 -281.934708) (xy 121.813542 -281.910101)
			(xy 121.859558 -281.892649) (xy 121.907777 -281.882805) (xy 121.956952 -281.880824) (xy 122.005807 -281.886756)
			(xy 122.053078 -281.900448) (xy 122.09754 -281.921546) (xy 122.138043 -281.949502) (xy 122.173536 -281.983594)
			(xy 122.203101 -282.022938) (xy 122.225972 -282.066515) (xy 122.241556 -282.113196) (xy 122.249451 -282.161773)
			(xy 122.249946 -282.18638) (xy 122.578888 -282.18638) (xy 122.582848 -282.137326) (xy 122.594625 -282.089542)
			(xy 122.613916 -282.044266) (xy 122.640219 -282.00267) (xy 122.672854 -281.965833) (xy 122.710975 -281.934708)
			(xy 122.753596 -281.910101) (xy 122.799612 -281.892649) (xy 122.847831 -281.882805) (xy 122.897006 -281.880824)
			(xy 122.945861 -281.886756) (xy 122.993132 -281.900448) (xy 123.037594 -281.921546) (xy 123.078097 -281.949502)
			(xy 123.11359 -281.983594) (xy 123.143155 -282.022938) (xy 123.166026 -282.066515) (xy 123.18161 -282.113196)
			(xy 123.189505 -282.161773) (xy 123.19 -282.18638) (xy 123.518942 -282.18638) (xy 123.522902 -282.137326)
			(xy 123.534679 -282.089542) (xy 123.55397 -282.044266) (xy 123.580273 -282.00267) (xy 123.612908 -281.965833)
			(xy 123.651029 -281.934708) (xy 123.69365 -281.910101) (xy 123.739666 -281.892649) (xy 123.787885 -281.882805)
			(xy 123.83706 -281.880824) (xy 123.885915 -281.886756) (xy 123.933186 -281.900448) (xy 123.977648 -281.921546)
			(xy 124.018151 -281.949502) (xy 124.053644 -281.983594) (xy 124.083209 -282.022938) (xy 124.10608 -282.066515)
			(xy 124.121664 -282.113196) (xy 124.129559 -282.161773) (xy 124.130054 -282.18638) (xy 124.458996 -282.18638)
			(xy 124.462956 -282.137326) (xy 124.474733 -282.089542) (xy 124.494024 -282.044266) (xy 124.520327 -282.00267)
			(xy 124.552962 -281.965833) (xy 124.591083 -281.934708) (xy 124.633704 -281.910101) (xy 124.67972 -281.892649)
			(xy 124.727939 -281.882805) (xy 124.777114 -281.880824) (xy 124.825969 -281.886756) (xy 124.87324 -281.900448)
			(xy 124.917702 -281.921546) (xy 124.958205 -281.949502) (xy 124.993698 -281.983594) (xy 125.023263 -282.022938)
			(xy 125.046134 -282.066515) (xy 125.061718 -282.113196) (xy 125.069613 -282.161773) (xy 125.070108 -282.18638)
			(xy 125.39905 -282.18638) (xy 125.40301 -282.137326) (xy 125.414787 -282.089542) (xy 125.434078 -282.044266)
			(xy 125.460381 -282.00267) (xy 125.493016 -281.965833) (xy 125.531137 -281.934708) (xy 125.573758 -281.910101)
			(xy 125.619774 -281.892649) (xy 125.667993 -281.882805) (xy 125.717168 -281.880824) (xy 125.766023 -281.886756)
			(xy 125.813294 -281.900448) (xy 125.857756 -281.921546) (xy 125.898259 -281.949502) (xy 125.933752 -281.983594)
			(xy 125.963317 -282.022938) (xy 125.986188 -282.066515) (xy 126.001772 -282.113196) (xy 126.009667 -282.161773)
			(xy 126.010162 -282.18638) (xy 126.009667 -282.210987) (xy 126.001772 -282.259564) (xy 125.986188 -282.306245)
			(xy 125.963317 -282.349822) (xy 125.933752 -282.389166) (xy 125.898259 -282.423258) (xy 125.857756 -282.451214)
			(xy 125.813294 -282.472312) (xy 125.766023 -282.486004) (xy 125.717168 -282.491936) (xy 125.667993 -282.489955)
			(xy 125.619774 -282.480111) (xy 125.573758 -282.462659) (xy 125.531137 -282.438052) (xy 125.493016 -282.406927)
			(xy 125.460381 -282.37009) (xy 125.434078 -282.328494) (xy 125.414787 -282.283218) (xy 125.40301 -282.235434)
			(xy 125.39905 -282.18638) (xy 125.070108 -282.18638) (xy 125.069613 -282.210987) (xy 125.061718 -282.259564)
			(xy 125.046134 -282.306245) (xy 125.023263 -282.349822) (xy 124.993698 -282.389166) (xy 124.958205 -282.423258)
			(xy 124.917702 -282.451214) (xy 124.87324 -282.472312) (xy 124.825969 -282.486004) (xy 124.777114 -282.491936)
			(xy 124.727939 -282.489955) (xy 124.67972 -282.480111) (xy 124.633704 -282.462659) (xy 124.591083 -282.438052)
			(xy 124.552962 -282.406927) (xy 124.520327 -282.37009) (xy 124.494024 -282.328494) (xy 124.474733 -282.283218)
			(xy 124.462956 -282.235434) (xy 124.458996 -282.18638) (xy 124.130054 -282.18638) (xy 124.129559 -282.210987)
			(xy 124.121664 -282.259564) (xy 124.10608 -282.306245) (xy 124.083209 -282.349822) (xy 124.053644 -282.389166)
			(xy 124.018151 -282.423258) (xy 123.977648 -282.451214) (xy 123.933186 -282.472312) (xy 123.885915 -282.486004)
			(xy 123.83706 -282.491936) (xy 123.787885 -282.489955) (xy 123.739666 -282.480111) (xy 123.69365 -282.462659)
			(xy 123.651029 -282.438052) (xy 123.612908 -282.406927) (xy 123.580273 -282.37009) (xy 123.55397 -282.328494)
			(xy 123.534679 -282.283218) (xy 123.522902 -282.235434) (xy 123.518942 -282.18638) (xy 123.19 -282.18638)
			(xy 123.189505 -282.210987) (xy 123.18161 -282.259564) (xy 123.166026 -282.306245) (xy 123.143155 -282.349822)
			(xy 123.11359 -282.389166) (xy 123.078097 -282.423258) (xy 123.037594 -282.451214) (xy 122.993132 -282.472312)
			(xy 122.945861 -282.486004) (xy 122.897006 -282.491936) (xy 122.847831 -282.489955) (xy 122.799612 -282.480111)
			(xy 122.753596 -282.462659) (xy 122.710975 -282.438052) (xy 122.672854 -282.406927) (xy 122.640219 -282.37009)
			(xy 122.613916 -282.328494) (xy 122.594625 -282.283218) (xy 122.582848 -282.235434) (xy 122.578888 -282.18638)
			(xy 122.249946 -282.18638) (xy 122.249451 -282.210987) (xy 122.241556 -282.259564) (xy 122.225972 -282.306245)
			(xy 122.203101 -282.349822) (xy 122.173536 -282.389166) (xy 122.138043 -282.423258) (xy 122.09754 -282.451214)
			(xy 122.053078 -282.472312) (xy 122.005807 -282.486004) (xy 121.956952 -282.491936) (xy 121.907777 -282.489955)
			(xy 121.859558 -282.480111) (xy 121.813542 -282.462659) (xy 121.770921 -282.438052) (xy 121.7328 -282.406927)
			(xy 121.700165 -282.37009) (xy 121.673862 -282.328494) (xy 121.654571 -282.283218) (xy 121.642794 -282.235434)
			(xy 121.638834 -282.18638) (xy 121.310146 -282.18638) (xy 121.309651 -282.210987) (xy 121.301756 -282.259564)
			(xy 121.286172 -282.306245) (xy 121.263301 -282.349822) (xy 121.233736 -282.389166) (xy 121.198243 -282.423258)
			(xy 121.15774 -282.451214) (xy 121.113278 -282.472312) (xy 121.066007 -282.486004) (xy 121.017152 -282.491936)
			(xy 120.967977 -282.489955) (xy 120.919758 -282.480111) (xy 120.873742 -282.462659) (xy 120.831121 -282.438052)
			(xy 120.793 -282.406927) (xy 120.760365 -282.37009) (xy 120.734062 -282.328494) (xy 120.714771 -282.283218)
			(xy 120.702994 -282.235434) (xy 120.699034 -282.18638) (xy 120.370092 -282.18638) (xy 120.369597 -282.210987)
			(xy 120.361702 -282.259564) (xy 120.346118 -282.306245) (xy 120.323247 -282.349822) (xy 120.293682 -282.389166)
			(xy 120.258189 -282.423258) (xy 120.217686 -282.451214) (xy 120.173224 -282.472312) (xy 120.125953 -282.486004)
			(xy 120.077098 -282.491936) (xy 120.027923 -282.489955) (xy 119.979704 -282.480111) (xy 119.933688 -282.462659)
			(xy 119.891067 -282.438052) (xy 119.852946 -282.406927) (xy 119.820311 -282.37009) (xy 119.794008 -282.328494)
			(xy 119.774717 -282.283218) (xy 119.76294 -282.235434) (xy 119.75898 -282.18638) (xy 119.430038 -282.18638)
			(xy 119.429543 -282.210987) (xy 119.421648 -282.259564) (xy 119.406064 -282.306245) (xy 119.383193 -282.349822)
			(xy 119.353628 -282.389166) (xy 119.318135 -282.423258) (xy 119.277632 -282.451214) (xy 119.23317 -282.472312)
			(xy 119.185899 -282.486004) (xy 119.137044 -282.491936) (xy 119.087869 -282.489955) (xy 119.03965 -282.480111)
			(xy 118.993634 -282.462659) (xy 118.951013 -282.438052) (xy 118.912892 -282.406927) (xy 118.880257 -282.37009)
			(xy 118.853954 -282.328494) (xy 118.834663 -282.283218) (xy 118.822886 -282.235434) (xy 118.818926 -282.18638)
			(xy 118.489984 -282.18638) (xy 118.489489 -282.210987) (xy 118.481594 -282.259564) (xy 118.46601 -282.306245)
			(xy 118.443139 -282.349822) (xy 118.413574 -282.389166) (xy 118.378081 -282.423258) (xy 118.337578 -282.451214)
			(xy 118.293116 -282.472312) (xy 118.245845 -282.486004) (xy 118.19699 -282.491936) (xy 118.147815 -282.489955)
			(xy 118.099596 -282.480111) (xy 118.05358 -282.462659) (xy 118.010959 -282.438052) (xy 117.972838 -282.406927)
			(xy 117.940203 -282.37009) (xy 117.9139 -282.328494) (xy 117.894609 -282.283218) (xy 117.882832 -282.235434)
			(xy 117.878872 -282.18638) (xy 117.54993 -282.18638) (xy 117.549435 -282.210987) (xy 117.54154 -282.259564)
			(xy 117.525956 -282.306245) (xy 117.503085 -282.349822) (xy 117.47352 -282.389166) (xy 117.438027 -282.423258)
			(xy 117.397524 -282.451214) (xy 117.353062 -282.472312) (xy 117.305791 -282.486004) (xy 117.256936 -282.491936)
			(xy 117.207761 -282.489955) (xy 117.159542 -282.480111) (xy 117.113526 -282.462659) (xy 117.070905 -282.438052)
			(xy 117.032784 -282.406927) (xy 117.000149 -282.37009) (xy 116.973846 -282.328494) (xy 116.954555 -282.283218)
			(xy 116.942778 -282.235434) (xy 116.938818 -282.18638) (xy 116.61013 -282.18638) (xy 116.609635 -282.210987)
			(xy 116.60174 -282.259564) (xy 116.586156 -282.306245) (xy 116.563285 -282.349822) (xy 116.53372 -282.389166)
			(xy 116.498227 -282.423258) (xy 116.457724 -282.451214) (xy 116.413262 -282.472312) (xy 116.365991 -282.486004)
			(xy 116.317136 -282.491936) (xy 116.267961 -282.489955) (xy 116.219742 -282.480111) (xy 116.173726 -282.462659)
			(xy 116.131105 -282.438052) (xy 116.092984 -282.406927) (xy 116.060349 -282.37009) (xy 116.034046 -282.328494)
			(xy 116.014755 -282.283218) (xy 116.002978 -282.235434) (xy 115.999018 -282.18638) (xy 115.670638 -282.18638)
			(xy 115.67064 -282.1864) (xy 115.666468 -282.236743) (xy 115.654067 -282.285712) (xy 115.633773 -282.331973)
			(xy 115.606142 -282.374261) (xy 115.571927 -282.411425) (xy 115.532062 -282.44245) (xy 115.487633 -282.46649)
			(xy 115.439853 -282.482888) (xy 115.390026 -282.491198) (xy 115.364768 -282.491688) (xy 114.424714 -282.491688)
			(xy 114.399454 -282.491236) (xy 114.349622 -282.482923) (xy 114.301839 -282.466521) (xy 114.257407 -282.442477)
			(xy 114.217539 -282.411448) (xy 114.183321 -282.37428) (xy 114.155689 -282.331987) (xy 114.135394 -282.285722)
			(xy 114.122992 -282.236748) (xy 114.11882 -282.1864) (xy 113.789968 -282.1864) (xy 113.789473 -282.210987)
			(xy 113.781578 -282.259564) (xy 113.765994 -282.306245) (xy 113.743123 -282.349822) (xy 113.713558 -282.389166)
			(xy 113.678065 -282.423258) (xy 113.637562 -282.451214) (xy 113.5931 -282.472312) (xy 113.545829 -282.486004)
			(xy 113.496974 -282.491936) (xy 113.447799 -282.489955) (xy 113.39958 -282.480111) (xy 113.353564 -282.462659)
			(xy 113.310943 -282.438052) (xy 113.272822 -282.406927) (xy 113.240187 -282.37009) (xy 113.213884 -282.328494)
			(xy 113.194593 -282.283218) (xy 113.182816 -282.235434) (xy 113.178856 -282.18638) (xy 110.97641 -282.18638)
			(xy 110.975915 -282.210987) (xy 110.96802 -282.259564) (xy 110.952436 -282.306245) (xy 110.929565 -282.349822)
			(xy 110.9 -282.389166) (xy 110.864507 -282.423258) (xy 110.824004 -282.451214) (xy 110.779542 -282.472312)
			(xy 110.732271 -282.486004) (xy 110.683416 -282.491936) (xy 110.634241 -282.489955) (xy 110.586022 -282.480111)
			(xy 110.540006 -282.462659) (xy 110.497385 -282.438052) (xy 110.459264 -282.406927) (xy 110.426629 -282.37009)
			(xy 110.400326 -282.328494) (xy 110.381035 -282.283218) (xy 110.369258 -282.235434) (xy 110.365298 -282.18638)
			(xy 110.036809 -282.18638) (xy 110.036811 -282.1864) (xy 110.032641 -282.23673) (xy 110.020245 -282.285687)
			(xy 109.99996 -282.331937) (xy 109.97234 -282.374217) (xy 109.938139 -282.411375) (xy 109.898288 -282.442398)
			(xy 109.853875 -282.466439) (xy 109.806111 -282.482843) (xy 109.756299 -282.491163) (xy 109.731048 -282.491688)
			(xy 108.790994 -282.491688) (xy 108.765737 -282.491206) (xy 108.715913 -282.482891) (xy 108.668137 -282.466488)
			(xy 108.623712 -282.442446) (xy 108.58385 -282.41142) (xy 108.549639 -282.374256) (xy 108.522011 -282.331967)
			(xy 108.50172 -282.285708) (xy 108.48932 -282.236741) (xy 108.485149 -282.1864) (xy 108.156248 -282.1864)
			(xy 108.155753 -282.210987) (xy 108.147858 -282.259564) (xy 108.132274 -282.306245) (xy 108.109403 -282.349822)
			(xy 108.079838 -282.389166) (xy 108.044345 -282.423258) (xy 108.003842 -282.451214) (xy 107.95938 -282.472312)
			(xy 107.912109 -282.486004) (xy 107.863254 -282.491936) (xy 107.814079 -282.489955) (xy 107.76586 -282.480111)
			(xy 107.719844 -282.462659) (xy 107.677223 -282.438052) (xy 107.639102 -282.406927) (xy 107.606467 -282.37009)
			(xy 107.580164 -282.328494) (xy 107.560873 -282.283218) (xy 107.549096 -282.235434) (xy 107.545136 -282.18638)
			(xy 107.216448 -282.18638) (xy 107.215953 -282.210987) (xy 107.208058 -282.259564) (xy 107.192474 -282.306245)
			(xy 107.169603 -282.349822) (xy 107.140038 -282.389166) (xy 107.104545 -282.423258) (xy 107.064042 -282.451214)
			(xy 107.01958 -282.472312) (xy 106.972309 -282.486004) (xy 106.923454 -282.491936) (xy 106.874279 -282.489955)
			(xy 106.82606 -282.480111) (xy 106.780044 -282.462659) (xy 106.737423 -282.438052) (xy 106.699302 -282.406927)
			(xy 106.666667 -282.37009) (xy 106.640364 -282.328494) (xy 106.621073 -282.283218) (xy 106.609296 -282.235434)
			(xy 106.605336 -282.18638) (xy 106.276394 -282.18638) (xy 106.275899 -282.210987) (xy 106.268004 -282.259564)
			(xy 106.25242 -282.306245) (xy 106.229549 -282.349822) (xy 106.199984 -282.389166) (xy 106.164491 -282.423258)
			(xy 106.123988 -282.451214) (xy 106.079526 -282.472312) (xy 106.032255 -282.486004) (xy 105.9834 -282.491936)
			(xy 105.934225 -282.489955) (xy 105.886006 -282.480111) (xy 105.83999 -282.462659) (xy 105.797369 -282.438052)
			(xy 105.759248 -282.406927) (xy 105.726613 -282.37009) (xy 105.70031 -282.328494) (xy 105.681019 -282.283218)
			(xy 105.669242 -282.235434) (xy 105.665282 -282.18638) (xy 105.33634 -282.18638) (xy 105.335845 -282.210987)
			(xy 105.32795 -282.259564) (xy 105.312366 -282.306245) (xy 105.289495 -282.349822) (xy 105.25993 -282.389166)
			(xy 105.224437 -282.423258) (xy 105.183934 -282.451214) (xy 105.139472 -282.472312) (xy 105.092201 -282.486004)
			(xy 105.043346 -282.491936) (xy 104.994171 -282.489955) (xy 104.945952 -282.480111) (xy 104.899936 -282.462659)
			(xy 104.857315 -282.438052) (xy 104.819194 -282.406927) (xy 104.786559 -282.37009) (xy 104.760256 -282.328494)
			(xy 104.740965 -282.283218) (xy 104.729188 -282.235434) (xy 104.725228 -282.18638) (xy 104.396286 -282.18638)
			(xy 104.395791 -282.210987) (xy 104.387896 -282.259564) (xy 104.372312 -282.306245) (xy 104.349441 -282.349822)
			(xy 104.319876 -282.389166) (xy 104.284383 -282.423258) (xy 104.24388 -282.451214) (xy 104.199418 -282.472312)
			(xy 104.152147 -282.486004) (xy 104.103292 -282.491936) (xy 104.054117 -282.489955) (xy 104.005898 -282.480111)
			(xy 103.959882 -282.462659) (xy 103.917261 -282.438052) (xy 103.87914 -282.406927) (xy 103.846505 -282.37009)
			(xy 103.820202 -282.328494) (xy 103.800911 -282.283218) (xy 103.789134 -282.235434) (xy 103.785174 -282.18638)
			(xy 103.456486 -282.18638) (xy 103.455991 -282.210987) (xy 103.448096 -282.259564) (xy 103.432512 -282.306245)
			(xy 103.409641 -282.349822) (xy 103.380076 -282.389166) (xy 103.344583 -282.423258) (xy 103.30408 -282.451214)
			(xy 103.259618 -282.472312) (xy 103.212347 -282.486004) (xy 103.163492 -282.491936) (xy 103.114317 -282.489955)
			(xy 103.066098 -282.480111) (xy 103.020082 -282.462659) (xy 102.977461 -282.438052) (xy 102.93934 -282.406927)
			(xy 102.906705 -282.37009) (xy 102.880402 -282.328494) (xy 102.861111 -282.283218) (xy 102.849334 -282.235434)
			(xy 102.845374 -282.18638) (xy 102.516432 -282.18638) (xy 102.515937 -282.210987) (xy 102.508042 -282.259564)
			(xy 102.492458 -282.306245) (xy 102.469587 -282.349822) (xy 102.440022 -282.389166) (xy 102.404529 -282.423258)
			(xy 102.364026 -282.451214) (xy 102.319564 -282.472312) (xy 102.272293 -282.486004) (xy 102.223438 -282.491936)
			(xy 102.174263 -282.489955) (xy 102.126044 -282.480111) (xy 102.080028 -282.462659) (xy 102.037407 -282.438052)
			(xy 101.999286 -282.406927) (xy 101.966651 -282.37009) (xy 101.940348 -282.328494) (xy 101.921057 -282.283218)
			(xy 101.90928 -282.235434) (xy 101.90532 -282.18638) (xy 101.576378 -282.18638) (xy 101.575883 -282.210987)
			(xy 101.567988 -282.259564) (xy 101.552404 -282.306245) (xy 101.529533 -282.349822) (xy 101.499968 -282.389166)
			(xy 101.464475 -282.423258) (xy 101.423972 -282.451214) (xy 101.37951 -282.472312) (xy 101.332239 -282.486004)
			(xy 101.283384 -282.491936) (xy 101.234209 -282.489955) (xy 101.18599 -282.480111) (xy 101.139974 -282.462659)
			(xy 101.097353 -282.438052) (xy 101.059232 -282.406927) (xy 101.026597 -282.37009) (xy 101.000294 -282.328494)
			(xy 100.981003 -282.283218) (xy 100.969226 -282.235434) (xy 100.965266 -282.18638) (xy 100.636324 -282.18638)
			(xy 100.635829 -282.210987) (xy 100.627934 -282.259564) (xy 100.61235 -282.306245) (xy 100.589479 -282.349822)
			(xy 100.559914 -282.389166) (xy 100.524421 -282.423258) (xy 100.483918 -282.451214) (xy 100.439456 -282.472312)
			(xy 100.392185 -282.486004) (xy 100.34333 -282.491936) (xy 100.294155 -282.489955) (xy 100.245936 -282.480111)
			(xy 100.19992 -282.462659) (xy 100.157299 -282.438052) (xy 100.119178 -282.406927) (xy 100.086543 -282.37009)
			(xy 100.06024 -282.328494) (xy 100.040949 -282.283218) (xy 100.029172 -282.235434) (xy 100.025212 -282.18638)
			(xy 99.69627 -282.18638) (xy 99.695775 -282.210987) (xy 99.68788 -282.259564) (xy 99.672296 -282.306245)
			(xy 99.649425 -282.349822) (xy 99.61986 -282.389166) (xy 99.584367 -282.423258) (xy 99.543864 -282.451214)
			(xy 99.499402 -282.472312) (xy 99.452131 -282.486004) (xy 99.403276 -282.491936) (xy 99.354101 -282.489955)
			(xy 99.305882 -282.480111) (xy 99.259866 -282.462659) (xy 99.217245 -282.438052) (xy 99.179124 -282.406927)
			(xy 99.146489 -282.37009) (xy 99.120186 -282.328494) (xy 99.100895 -282.283218) (xy 99.089118 -282.235434)
			(xy 99.085158 -282.18638) (xy 98.75647 -282.18638) (xy 98.755975 -282.210987) (xy 98.74808 -282.259564)
			(xy 98.732496 -282.306245) (xy 98.709625 -282.349822) (xy 98.68006 -282.389166) (xy 98.644567 -282.423258)
			(xy 98.604064 -282.451214) (xy 98.559602 -282.472312) (xy 98.512331 -282.486004) (xy 98.463476 -282.491936)
			(xy 98.414301 -282.489955) (xy 98.366082 -282.480111) (xy 98.320066 -282.462659) (xy 98.277445 -282.438052)
			(xy 98.239324 -282.406927) (xy 98.206689 -282.37009) (xy 98.180386 -282.328494) (xy 98.161095 -282.283218)
			(xy 98.149318 -282.235434) (xy 98.145358 -282.18638) (xy 97.816416 -282.18638) (xy 97.815921 -282.210987)
			(xy 97.808026 -282.259564) (xy 97.792442 -282.306245) (xy 97.769571 -282.349822) (xy 97.740006 -282.389166)
			(xy 97.704513 -282.423258) (xy 97.66401 -282.451214) (xy 97.619548 -282.472312) (xy 97.572277 -282.486004)
			(xy 97.523422 -282.491936) (xy 97.474247 -282.489955) (xy 97.426028 -282.480111) (xy 97.380012 -282.462659)
			(xy 97.337391 -282.438052) (xy 97.29927 -282.406927) (xy 97.266635 -282.37009) (xy 97.240332 -282.328494)
			(xy 97.221041 -282.283218) (xy 97.209264 -282.235434) (xy 97.205304 -282.18638) (xy 96.876362 -282.18638)
			(xy 96.875867 -282.210987) (xy 96.867972 -282.259564) (xy 96.852388 -282.306245) (xy 96.829517 -282.349822)
			(xy 96.799952 -282.389166) (xy 96.764459 -282.423258) (xy 96.723956 -282.451214) (xy 96.679494 -282.472312)
			(xy 96.632223 -282.486004) (xy 96.583368 -282.491936) (xy 96.534193 -282.489955) (xy 96.485974 -282.480111)
			(xy 96.439958 -282.462659) (xy 96.397337 -282.438052) (xy 96.359216 -282.406927) (xy 96.326581 -282.37009)
			(xy 96.300278 -282.328494) (xy 96.280987 -282.283218) (xy 96.26921 -282.235434) (xy 96.26525 -282.18638)
			(xy 95.946722 -282.18638) (xy 95.94621 -282.211826) (xy 95.938046 -282.26206) (xy 95.92193 -282.310334)
			(xy 95.898279 -282.355397) (xy 95.867706 -282.396083) (xy 95.831002 -282.431338) (xy 95.789118 -282.460248)
			(xy 95.743139 -282.482065) (xy 95.694255 -282.496225) (xy 95.643734 -282.502359) (xy 95.592882 -282.50031)
			(xy 95.543018 -282.49013) (xy 95.495432 -282.472083) (xy 95.451358 -282.446637) (xy 95.411936 -282.41445)
			(xy 95.378188 -282.376356) (xy 95.350987 -282.333342) (xy 95.331039 -282.286522) (xy 95.31886 -282.237108)
			(xy 95.314765 -282.18638) (xy 95.006668 -282.18638) (xy 95.006156 -282.211826) (xy 94.997992 -282.26206)
			(xy 94.981876 -282.310334) (xy 94.958225 -282.355397) (xy 94.927652 -282.396083) (xy 94.890948 -282.431338)
			(xy 94.849064 -282.460248) (xy 94.803085 -282.482065) (xy 94.754201 -282.496225) (xy 94.70368 -282.502359)
			(xy 94.652828 -282.50031) (xy 94.602964 -282.49013) (xy 94.555378 -282.472083) (xy 94.511304 -282.446637)
			(xy 94.471882 -282.41445) (xy 94.438134 -282.376356) (xy 94.410933 -282.333342) (xy 94.390985 -282.286522)
			(xy 94.378806 -282.237108) (xy 94.374711 -282.18638) (xy 94.056949 -282.18638) (xy 94.056951 -282.1864)
			(xy 94.05278 -282.236737) (xy 94.040382 -282.2857) (xy 94.020095 -282.331956) (xy 93.992471 -282.374242)
			(xy 93.958265 -282.411405) (xy 93.918409 -282.442432) (xy 93.87399 -282.466477) (xy 93.82622 -282.482883)
			(xy 93.7764 -282.491203) (xy 93.751146 -282.491688) (xy 93.727381 -282.491237) (xy 93.680424 -282.483873)
			(xy 93.635177 -282.469316) (xy 93.592736 -282.447919) (xy 93.554126 -282.420198) (xy 93.520282 -282.386825)
			(xy 93.505782 -282.36799) (xy 93.505782 -282.367736) (xy 93.505528 -282.367736) (xy 93.50137 -282.362558)
			(xy 93.490953 -282.354328) (xy 93.484954 -282.35148) (xy 93.478545 -282.348935) (xy 93.464896 -282.347016)
			(xy 93.45803 -282.34767) (xy 93.372178 -282.3591) (xy 93.365417 -282.360174) (xy 93.352792 -282.365448)
			(xy 93.347286 -282.369514) (xy 93.341952 -282.373578) (xy 93.334078 -282.384246) (xy 93.331538 -282.39085)
			(xy 93.315988 -282.428522) (xy 93.275566 -282.499286) (xy 93.25102 -282.53182) (xy 93.25102 -282.532074)
			(xy 93.246988 -282.537479) (xy 93.241591 -282.54983) (xy 93.240352 -282.556458) (xy 93.238574 -282.569666)
			(xy 93.276928 -282.662376) (xy 93.279686 -282.668537) (xy 93.28793 -282.67922) (xy 93.293184 -282.683458)
			(xy 93.298518 -282.687522) (xy 93.31071 -282.692348) (xy 93.317822 -282.693364) (xy 93.342182 -282.696829)
			(xy 93.389435 -282.710531) (xy 93.43388 -282.731632) (xy 93.474367 -282.759585) (xy 93.509849 -282.793669)
			(xy 93.539407 -282.833) (xy 93.562277 -282.876561) (xy 93.577866 -282.923226) (xy 93.585773 -282.971786)
			(xy 93.5863 -282.996386) (xy 93.904811 -282.996386) (xy 93.908906 -282.945658) (xy 93.921085 -282.896244)
			(xy 93.941033 -282.849424) (xy 93.968234 -282.80641) (xy 94.001982 -282.768316) (xy 94.041404 -282.736129)
			(xy 94.085478 -282.710683) (xy 94.133064 -282.692636) (xy 94.182928 -282.682456) (xy 94.23378 -282.680407)
			(xy 94.284301 -282.686541) (xy 94.333185 -282.700701) (xy 94.379164 -282.722518) (xy 94.421048 -282.751428)
			(xy 94.457752 -282.786683) (xy 94.488325 -282.827369) (xy 94.511976 -282.872432) (xy 94.528092 -282.920706)
			(xy 94.536256 -282.97094) (xy 94.536768 -282.996386) (xy 94.855296 -282.996386) (xy 94.859256 -282.947332)
			(xy 94.871033 -282.899548) (xy 94.890324 -282.854272) (xy 94.916627 -282.812676) (xy 94.949262 -282.775839)
			(xy 94.987383 -282.744714) (xy 95.030004 -282.720107) (xy 95.07602 -282.702655) (xy 95.124239 -282.692811)
			(xy 95.173414 -282.69083) (xy 95.222269 -282.696762) (xy 95.26954 -282.710454) (xy 95.314002 -282.731552)
			(xy 95.354505 -282.759508) (xy 95.389998 -282.7936) (xy 95.419563 -282.832944) (xy 95.442434 -282.876521)
			(xy 95.458018 -282.923202) (xy 95.465913 -282.971779) (xy 95.466408 -282.996386) (xy 95.784919 -282.996386)
			(xy 95.789014 -282.945658) (xy 95.801193 -282.896244) (xy 95.821141 -282.849424) (xy 95.848342 -282.80641)
			(xy 95.88209 -282.768316) (xy 95.921512 -282.736129) (xy 95.965586 -282.710683) (xy 96.013172 -282.692636)
			(xy 96.063036 -282.682456) (xy 96.113888 -282.680407) (xy 96.164409 -282.686541) (xy 96.213293 -282.700701)
			(xy 96.259272 -282.722518) (xy 96.301156 -282.751428) (xy 96.33786 -282.786683) (xy 96.368433 -282.827369)
			(xy 96.392084 -282.872432) (xy 96.4082 -282.920706) (xy 96.416364 -282.97094) (xy 96.416876 -282.996386)
			(xy 96.73515 -282.996386) (xy 96.73911 -282.947332) (xy 96.750887 -282.899548) (xy 96.770178 -282.854272)
			(xy 96.796481 -282.812676) (xy 96.829116 -282.775839) (xy 96.867237 -282.744714) (xy 96.909858 -282.720107)
			(xy 96.955874 -282.702655) (xy 97.004093 -282.692811) (xy 97.053268 -282.69083) (xy 97.102123 -282.696762)
			(xy 97.149394 -282.710454) (xy 97.193856 -282.731552) (xy 97.234359 -282.759508) (xy 97.269852 -282.7936)
			(xy 97.299417 -282.832944) (xy 97.322288 -282.876521) (xy 97.337872 -282.923202) (xy 97.345767 -282.971779)
			(xy 97.346262 -282.996386) (xy 97.346262 -282.9964) (xy 97.674871 -282.9964) (xy 97.679047 -282.946012)
			(xy 97.691459 -282.896999) (xy 97.711769 -282.850697) (xy 97.739424 -282.808369) (xy 97.773668 -282.771171)
			(xy 97.813568 -282.740117) (xy 97.858035 -282.716053) (xy 97.905856 -282.699637) (xy 97.955728 -282.691316)
			(xy 97.981008 -282.690824) (xy 98.921062 -282.690824) (xy 98.946342 -282.691342) (xy 98.996212 -282.699658)
			(xy 99.044033 -282.71607) (xy 99.088501 -282.74013) (xy 99.128401 -282.771181) (xy 99.162646 -282.808377)
			(xy 99.190302 -282.850702) (xy 99.210613 -282.897002) (xy 99.223025 -282.946014) (xy 99.2272 -282.996386)
			(xy 99.555312 -282.996386) (xy 99.559272 -282.947332) (xy 99.571049 -282.899548) (xy 99.59034 -282.854272)
			(xy 99.616643 -282.812676) (xy 99.649278 -282.775839) (xy 99.687399 -282.744714) (xy 99.73002 -282.720107)
			(xy 99.776036 -282.702655) (xy 99.824255 -282.692811) (xy 99.87343 -282.69083) (xy 99.922285 -282.696762)
			(xy 99.969556 -282.710454) (xy 100.014018 -282.731552) (xy 100.054521 -282.759508) (xy 100.090014 -282.7936)
			(xy 100.119579 -282.832944) (xy 100.14245 -282.876521) (xy 100.158034 -282.923202) (xy 100.165929 -282.971779)
			(xy 100.166424 -282.996386) (xy 100.166424 -282.9964) (xy 100.4951 -282.9964) (xy 100.499275 -282.946021)
			(xy 100.511684 -282.897016) (xy 100.531989 -282.850721) (xy 100.559637 -282.8084) (xy 100.593873 -282.771206)
			(xy 100.633764 -282.740154) (xy 100.678221 -282.716091) (xy 100.726032 -282.699673) (xy 100.775894 -282.691348)
			(xy 100.80117 -282.690824) (xy 101.741224 -282.690824) (xy 101.766498 -282.691376) (xy 101.816356 -282.699699)
			(xy 101.864164 -282.716115) (xy 101.908618 -282.740176) (xy 101.948506 -282.771224) (xy 101.98274 -282.808415)
			(xy 102.010385 -282.850733) (xy 102.030689 -282.897024) (xy 102.043098 -282.946025) (xy 102.047271 -282.996386)
			(xy 102.37522 -282.996386) (xy 102.37918 -282.947332) (xy 102.390957 -282.899548) (xy 102.410248 -282.854272)
			(xy 102.436551 -282.812676) (xy 102.469186 -282.775839) (xy 102.507307 -282.744714) (xy 102.549928 -282.720107)
			(xy 102.595944 -282.702655) (xy 102.644163 -282.692811) (xy 102.693338 -282.69083) (xy 102.742193 -282.696762)
			(xy 102.789464 -282.710454) (xy 102.833926 -282.731552) (xy 102.874429 -282.759508) (xy 102.909922 -282.7936)
			(xy 102.939487 -282.832944) (xy 102.962358 -282.876521) (xy 102.977942 -282.923202) (xy 102.985837 -282.971779)
			(xy 102.986332 -282.996386) (xy 102.986332 -282.9964) (xy 103.315 -282.9964) (xy 103.319175 -282.94602)
			(xy 103.331584 -282.897014) (xy 103.35189 -282.850719) (xy 103.379539 -282.808397) (xy 103.413776 -282.771203)
			(xy 103.453668 -282.740151) (xy 103.498126 -282.716089) (xy 103.545939 -282.699672) (xy 103.595802 -282.691348)
			(xy 103.621078 -282.690824) (xy 104.561132 -282.690824) (xy 104.586405 -282.691376) (xy 104.636262 -282.699701)
			(xy 104.684069 -282.716117) (xy 104.728522 -282.740178) (xy 104.768409 -282.771227) (xy 104.802642 -282.808418)
			(xy 104.830287 -282.850735) (xy 104.85059 -282.897025) (xy 104.862998 -282.946026) (xy 104.867171 -282.996386)
			(xy 105.195128 -282.996386) (xy 105.199088 -282.947332) (xy 105.210865 -282.899548) (xy 105.230156 -282.854272)
			(xy 105.256459 -282.812676) (xy 105.289094 -282.775839) (xy 105.327215 -282.744714) (xy 105.369836 -282.720107)
			(xy 105.415852 -282.702655) (xy 105.464071 -282.692811) (xy 105.513246 -282.69083) (xy 105.562101 -282.696762)
			(xy 105.609372 -282.710454) (xy 105.653834 -282.731552) (xy 105.694337 -282.759508) (xy 105.72983 -282.7936)
			(xy 105.759395 -282.832944) (xy 105.782266 -282.876521) (xy 105.79785 -282.923202) (xy 105.805745 -282.971779)
			(xy 105.80624 -282.996386) (xy 105.80624 -282.9964) (xy 106.1349 -282.9964) (xy 106.139075 -282.946019)
			(xy 106.151485 -282.897012) (xy 106.171791 -282.850717) (xy 106.199441 -282.808394) (xy 106.233679 -282.7712)
			(xy 106.273572 -282.740149) (xy 106.318032 -282.716086) (xy 106.365846 -282.69967) (xy 106.415709 -282.691347)
			(xy 106.440986 -282.690824) (xy 107.38104 -282.690824) (xy 107.406313 -282.691377) (xy 107.456169 -282.699702)
			(xy 107.503975 -282.71612) (xy 107.548426 -282.740181) (xy 107.588312 -282.77123) (xy 107.622544 -282.80842)
			(xy 107.650188 -282.850737) (xy 107.67049 -282.897027) (xy 107.682898 -282.946026) (xy 107.687071 -282.996386)
			(xy 108.01529 -282.996386) (xy 108.01925 -282.947332) (xy 108.031027 -282.899548) (xy 108.050318 -282.854272)
			(xy 108.076621 -282.812676) (xy 108.109256 -282.775839) (xy 108.147377 -282.744714) (xy 108.189998 -282.720107)
			(xy 108.236014 -282.702655) (xy 108.284233 -282.692811) (xy 108.333408 -282.69083) (xy 108.382263 -282.696762)
			(xy 108.429534 -282.710454) (xy 108.473996 -282.731552) (xy 108.514499 -282.759508) (xy 108.549992 -282.7936)
			(xy 108.579557 -282.832944) (xy 108.602428 -282.876521) (xy 108.618012 -282.923202) (xy 108.625907 -282.971779)
			(xy 108.626402 -282.996386) (xy 115.528864 -282.996386) (xy 115.532824 -282.947332) (xy 115.544601 -282.899548)
			(xy 115.563892 -282.854272) (xy 115.590195 -282.812676) (xy 115.62283 -282.775839) (xy 115.660951 -282.744714)
			(xy 115.703572 -282.720107) (xy 115.749588 -282.702655) (xy 115.797807 -282.692811) (xy 115.846982 -282.69083)
			(xy 115.895837 -282.696762) (xy 115.943108 -282.710454) (xy 115.98757 -282.731552) (xy 116.028073 -282.759508)
			(xy 116.063566 -282.7936) (xy 116.093131 -282.832944) (xy 116.116002 -282.876521) (xy 116.131586 -282.923202)
			(xy 116.139481 -282.971779) (xy 116.139976 -282.996386) (xy 116.139976 -282.9964) (xy 116.468571 -282.9964)
			(xy 116.472747 -282.946011) (xy 116.48516 -282.896996) (xy 116.505471 -282.850693) (xy 116.533127 -282.808365)
			(xy 116.567373 -282.771166) (xy 116.607275 -282.740112) (xy 116.651744 -282.716049) (xy 116.699568 -282.699634)
			(xy 116.749441 -282.691315) (xy 116.774722 -282.690824) (xy 117.714776 -282.690824) (xy 117.740055 -282.691343)
			(xy 117.789924 -282.699661) (xy 117.837743 -282.716074) (xy 117.882208 -282.740135) (xy 117.922107 -282.771186)
			(xy 117.95635 -282.808381) (xy 117.984004 -282.850706) (xy 118.004313 -282.897005) (xy 118.016725 -282.946015)
			(xy 118.0209 -282.996386) (xy 118.349026 -282.996386) (xy 118.352986 -282.947332) (xy 118.364763 -282.899548)
			(xy 118.384054 -282.854272) (xy 118.410357 -282.812676) (xy 118.442992 -282.775839) (xy 118.481113 -282.744714)
			(xy 118.523734 -282.720107) (xy 118.56975 -282.702655) (xy 118.617969 -282.692811) (xy 118.667144 -282.69083)
			(xy 118.715999 -282.696762) (xy 118.76327 -282.710454) (xy 118.807732 -282.731552) (xy 118.848235 -282.759508)
			(xy 118.883728 -282.7936) (xy 118.913293 -282.832944) (xy 118.936164 -282.876521) (xy 118.951748 -282.923202)
			(xy 118.959643 -282.971779) (xy 118.960138 -282.996386) (xy 118.960138 -282.9964) (xy 119.288471 -282.9964)
			(xy 119.292647 -282.94601) (xy 119.30506 -282.896994) (xy 119.325373 -282.850691) (xy 119.353029 -282.808362)
			(xy 119.387276 -282.771163) (xy 119.427179 -282.740109) (xy 119.47165 -282.716047) (xy 119.519474 -282.699633)
			(xy 119.569348 -282.691315) (xy 119.59463 -282.690824) (xy 120.534684 -282.690824) (xy 120.559962 -282.691344)
			(xy 120.60983 -282.699663) (xy 120.657648 -282.716077) (xy 120.702113 -282.740137) (xy 120.74201 -282.771189)
			(xy 120.776252 -282.808384) (xy 120.803905 -282.850708) (xy 120.824214 -282.897006) (xy 120.836625 -282.946016)
			(xy 120.8408 -282.996386) (xy 121.168934 -282.996386) (xy 121.172894 -282.947332) (xy 121.184671 -282.899548)
			(xy 121.203962 -282.854272) (xy 121.230265 -282.812676) (xy 121.2629 -282.775839) (xy 121.301021 -282.744714)
			(xy 121.343642 -282.720107) (xy 121.389658 -282.702655) (xy 121.437877 -282.692811) (xy 121.487052 -282.69083)
			(xy 121.535907 -282.696762) (xy 121.583178 -282.710454) (xy 121.62764 -282.731552) (xy 121.668143 -282.759508)
			(xy 121.703636 -282.7936) (xy 121.733201 -282.832944) (xy 121.756072 -282.876521) (xy 121.771656 -282.923202)
			(xy 121.779551 -282.971779) (xy 121.780046 -282.996386) (xy 121.780046 -282.9964) (xy 122.1087 -282.9964)
			(xy 122.112875 -282.946019) (xy 122.125285 -282.897011) (xy 122.145592 -282.850715) (xy 122.173242 -282.808392)
			(xy 122.207481 -282.771198) (xy 122.247375 -282.740147) (xy 122.291836 -282.716085) (xy 122.33965 -282.699669)
			(xy 122.389515 -282.691347) (xy 122.414792 -282.690824) (xy 123.354846 -282.690824) (xy 123.380119 -282.691377)
			(xy 123.429974 -282.699704) (xy 123.477779 -282.716122) (xy 123.52223 -282.740183) (xy 123.562114 -282.771232)
			(xy 123.596345 -282.808422) (xy 123.623989 -282.850739) (xy 123.644291 -282.897028) (xy 123.656698 -282.946027)
			(xy 123.660871 -282.996386) (xy 123.988842 -282.996386) (xy 123.992802 -282.947332) (xy 124.004579 -282.899548)
			(xy 124.02387 -282.854272) (xy 124.050173 -282.812676) (xy 124.082808 -282.775839) (xy 124.120929 -282.744714)
			(xy 124.16355 -282.720107) (xy 124.209566 -282.702655) (xy 124.257785 -282.692811) (xy 124.30696 -282.69083)
			(xy 124.355815 -282.696762) (xy 124.403086 -282.710454) (xy 124.447548 -282.731552) (xy 124.488051 -282.759508)
			(xy 124.523544 -282.7936) (xy 124.553109 -282.832944) (xy 124.57598 -282.876521) (xy 124.591564 -282.923202)
			(xy 124.599459 -282.971779) (xy 124.599954 -282.996386) (xy 124.599954 -282.9964) (xy 124.928601 -282.9964)
			(xy 124.932775 -282.946018) (xy 124.945186 -282.89701) (xy 124.965494 -282.850713) (xy 124.993144 -282.80839)
			(xy 125.027384 -282.771195) (xy 125.067279 -282.740144) (xy 125.111741 -282.716082) (xy 125.159557 -282.699667)
			(xy 125.209423 -282.691346) (xy 125.2347 -282.690824) (xy 126.174754 -282.690824) (xy 126.200034 -282.691341)
			(xy 126.249906 -282.699657) (xy 126.297728 -282.716068) (xy 126.342197 -282.740127) (xy 126.382098 -282.771178)
			(xy 126.416344 -282.808374) (xy 126.444 -282.850699) (xy 126.464312 -282.897) (xy 126.476725 -282.946013)
			(xy 126.480901 -282.9964) (xy 126.476725 -283.046787) (xy 126.464312 -283.0958) (xy 126.444 -283.142101)
			(xy 126.416344 -283.184426) (xy 126.382098 -283.221622) (xy 126.342197 -283.252673) (xy 126.297728 -283.276732)
			(xy 126.249906 -283.293143) (xy 126.200034 -283.301459) (xy 126.174754 -283.301948) (xy 125.2347 -283.301948)
			(xy 125.209423 -283.301454) (xy 125.159557 -283.293133) (xy 125.111741 -283.276718) (xy 125.067279 -283.252656)
			(xy 125.027384 -283.221605) (xy 124.993144 -283.18441) (xy 124.965494 -283.142087) (xy 124.945186 -283.09579)
			(xy 124.932775 -283.046782) (xy 124.928601 -282.9964) (xy 124.599954 -282.9964) (xy 124.599459 -283.020993)
			(xy 124.591564 -283.06957) (xy 124.57598 -283.116251) (xy 124.553109 -283.159828) (xy 124.523544 -283.199172)
			(xy 124.488051 -283.233264) (xy 124.447548 -283.26122) (xy 124.403086 -283.282318) (xy 124.355815 -283.29601)
			(xy 124.30696 -283.301942) (xy 124.257785 -283.299961) (xy 124.209566 -283.290117) (xy 124.16355 -283.272665)
			(xy 124.120929 -283.248058) (xy 124.082808 -283.216933) (xy 124.050173 -283.180096) (xy 124.02387 -283.1385)
			(xy 124.004579 -283.093224) (xy 123.992802 -283.04544) (xy 123.988842 -282.996386) (xy 123.660871 -282.996386)
			(xy 123.660872 -282.9964) (xy 123.656698 -283.046773) (xy 123.644291 -283.095772) (xy 123.623989 -283.142061)
			(xy 123.596345 -283.184378) (xy 123.562114 -283.221568) (xy 123.52223 -283.252617) (xy 123.477779 -283.276678)
			(xy 123.429974 -283.293096) (xy 123.380119 -283.301423) (xy 123.354846 -283.301948) (xy 122.414792 -283.301948)
			(xy 122.389515 -283.301453) (xy 122.33965 -283.293131) (xy 122.291836 -283.276715) (xy 122.247375 -283.252653)
			(xy 122.207481 -283.221602) (xy 122.173242 -283.184408) (xy 122.145592 -283.142085) (xy 122.125285 -283.095789)
			(xy 122.112875 -283.046781) (xy 122.1087 -282.9964) (xy 121.780046 -282.9964) (xy 121.779551 -283.020993)
			(xy 121.771656 -283.06957) (xy 121.756072 -283.116251) (xy 121.733201 -283.159828) (xy 121.703636 -283.199172)
			(xy 121.668143 -283.233264) (xy 121.62764 -283.26122) (xy 121.583178 -283.282318) (xy 121.535907 -283.29601)
			(xy 121.487052 -283.301942) (xy 121.437877 -283.299961) (xy 121.389658 -283.290117) (xy 121.343642 -283.272665)
			(xy 121.301021 -283.248058) (xy 121.2629 -283.216933) (xy 121.230265 -283.180096) (xy 121.203962 -283.1385)
			(xy 121.184671 -283.093224) (xy 121.172894 -283.04544) (xy 121.168934 -282.996386) (xy 120.8408 -282.996386)
			(xy 120.840801 -282.9964) (xy 120.836625 -283.046784) (xy 120.824214 -283.095794) (xy 120.803905 -283.142092)
			(xy 120.776252 -283.184416) (xy 120.74201 -283.221611) (xy 120.702113 -283.252663) (xy 120.657648 -283.276723)
			(xy 120.60983 -283.293137) (xy 120.559962 -283.301456) (xy 120.534684 -283.301948) (xy 119.59463 -283.301948)
			(xy 119.569348 -283.301485) (xy 119.519474 -283.293167) (xy 119.47165 -283.276753) (xy 119.427179 -283.252691)
			(xy 119.387276 -283.221637) (xy 119.353029 -283.184438) (xy 119.325373 -283.142109) (xy 119.30506 -283.095806)
			(xy 119.292647 -283.04679) (xy 119.288471 -282.9964) (xy 118.960138 -282.9964) (xy 118.959643 -283.020993)
			(xy 118.951748 -283.06957) (xy 118.936164 -283.116251) (xy 118.913293 -283.159828) (xy 118.883728 -283.199172)
			(xy 118.848235 -283.233264) (xy 118.807732 -283.26122) (xy 118.76327 -283.282318) (xy 118.715999 -283.29601)
			(xy 118.667144 -283.301942) (xy 118.617969 -283.299961) (xy 118.56975 -283.290117) (xy 118.523734 -283.272665)
			(xy 118.481113 -283.248058) (xy 118.442992 -283.216933) (xy 118.410357 -283.180096) (xy 118.384054 -283.1385)
			(xy 118.364763 -283.093224) (xy 118.352986 -283.04544) (xy 118.349026 -282.996386) (xy 118.0209 -282.996386)
			(xy 118.020901 -282.9964) (xy 118.016725 -283.046785) (xy 118.004313 -283.095795) (xy 117.984004 -283.142094)
			(xy 117.95635 -283.184419) (xy 117.922107 -283.221614) (xy 117.882208 -283.252665) (xy 117.837743 -283.276726)
			(xy 117.789924 -283.293139) (xy 117.740055 -283.301457) (xy 117.714776 -283.301948) (xy 116.774722 -283.301948)
			(xy 116.749441 -283.301485) (xy 116.699568 -283.293166) (xy 116.651744 -283.276751) (xy 116.607275 -283.252688)
			(xy 116.567373 -283.221634) (xy 116.533127 -283.184435) (xy 116.505471 -283.142107) (xy 116.48516 -283.095804)
			(xy 116.472747 -283.046789) (xy 116.468571 -282.9964) (xy 116.139976 -282.9964) (xy 116.139481 -283.020993)
			(xy 116.131586 -283.06957) (xy 116.116002 -283.116251) (xy 116.093131 -283.159828) (xy 116.063566 -283.199172)
			(xy 116.028073 -283.233264) (xy 115.98757 -283.26122) (xy 115.943108 -283.282318) (xy 115.895837 -283.29601)
			(xy 115.846982 -283.301942) (xy 115.797807 -283.299961) (xy 115.749588 -283.290117) (xy 115.703572 -283.272665)
			(xy 115.660951 -283.248058) (xy 115.62283 -283.216933) (xy 115.590195 -283.180096) (xy 115.563892 -283.1385)
			(xy 115.544601 -283.093224) (xy 115.532824 -283.04544) (xy 115.528864 -282.996386) (xy 108.626402 -282.996386)
			(xy 108.625907 -283.020993) (xy 108.618012 -283.06957) (xy 108.602428 -283.116251) (xy 108.579557 -283.159828)
			(xy 108.549992 -283.199172) (xy 108.514499 -283.233264) (xy 108.473996 -283.26122) (xy 108.429534 -283.282318)
			(xy 108.382263 -283.29601) (xy 108.333408 -283.301942) (xy 108.284233 -283.299961) (xy 108.236014 -283.290117)
			(xy 108.189998 -283.272665) (xy 108.147377 -283.248058) (xy 108.109256 -283.216933) (xy 108.076621 -283.180096)
			(xy 108.050318 -283.1385) (xy 108.031027 -283.093224) (xy 108.01925 -283.04544) (xy 108.01529 -282.996386)
			(xy 107.687071 -282.996386) (xy 107.687072 -282.9964) (xy 107.682898 -283.046774) (xy 107.67049 -283.095773)
			(xy 107.650188 -283.142063) (xy 107.622544 -283.18438) (xy 107.588312 -283.22157) (xy 107.548426 -283.252619)
			(xy 107.503975 -283.27668) (xy 107.456169 -283.293098) (xy 107.406313 -283.301423) (xy 107.38104 -283.301948)
			(xy 106.440986 -283.301948) (xy 106.415709 -283.301453) (xy 106.365846 -283.29313) (xy 106.318032 -283.276714)
			(xy 106.273572 -283.252651) (xy 106.233679 -283.2216) (xy 106.199441 -283.184406) (xy 106.171791 -283.142083)
			(xy 106.151485 -283.095788) (xy 106.139075 -283.046781) (xy 106.1349 -282.9964) (xy 105.80624 -282.9964)
			(xy 105.805745 -283.020993) (xy 105.79785 -283.06957) (xy 105.782266 -283.116251) (xy 105.759395 -283.159828)
			(xy 105.72983 -283.199172) (xy 105.694337 -283.233264) (xy 105.653834 -283.26122) (xy 105.609372 -283.282318)
			(xy 105.562101 -283.29601) (xy 105.513246 -283.301942) (xy 105.464071 -283.299961) (xy 105.415852 -283.290117)
			(xy 105.369836 -283.272665) (xy 105.327215 -283.248058) (xy 105.289094 -283.216933) (xy 105.256459 -283.180096)
			(xy 105.230156 -283.1385) (xy 105.210865 -283.093224) (xy 105.199088 -283.04544) (xy 105.195128 -282.996386)
			(xy 104.867171 -282.996386) (xy 104.867172 -282.9964) (xy 104.862998 -283.046774) (xy 104.85059 -283.095775)
			(xy 104.830287 -283.142065) (xy 104.802642 -283.184382) (xy 104.768409 -283.221573) (xy 104.728522 -283.252622)
			(xy 104.684069 -283.276683) (xy 104.636262 -283.293099) (xy 104.586405 -283.301424) (xy 104.561132 -283.301948)
			(xy 103.621078 -283.301948) (xy 103.595802 -283.301452) (xy 103.545939 -283.293128) (xy 103.498126 -283.276711)
			(xy 103.453668 -283.252649) (xy 103.413776 -283.221597) (xy 103.379539 -283.184403) (xy 103.35189 -283.142081)
			(xy 103.331584 -283.095786) (xy 103.319175 -283.04678) (xy 103.315 -282.9964) (xy 102.986332 -282.9964)
			(xy 102.985837 -283.020993) (xy 102.977942 -283.06957) (xy 102.962358 -283.116251) (xy 102.939487 -283.159828)
			(xy 102.909922 -283.199172) (xy 102.874429 -283.233264) (xy 102.833926 -283.26122) (xy 102.789464 -283.282318)
			(xy 102.742193 -283.29601) (xy 102.693338 -283.301942) (xy 102.644163 -283.299961) (xy 102.595944 -283.290117)
			(xy 102.549928 -283.272665) (xy 102.507307 -283.248058) (xy 102.469186 -283.216933) (xy 102.436551 -283.180096)
			(xy 102.410248 -283.1385) (xy 102.390957 -283.093224) (xy 102.37918 -283.04544) (xy 102.37522 -282.996386)
			(xy 102.047271 -282.996386) (xy 102.047272 -282.9964) (xy 102.043098 -283.046775) (xy 102.030689 -283.095776)
			(xy 102.010385 -283.142067) (xy 101.98274 -283.184385) (xy 101.948506 -283.221576) (xy 101.908618 -283.252624)
			(xy 101.864164 -283.276685) (xy 101.816356 -283.293101) (xy 101.766498 -283.301424) (xy 101.741224 -283.301948)
			(xy 100.80117 -283.301948) (xy 100.775894 -283.301452) (xy 100.726032 -283.293127) (xy 100.678221 -283.276709)
			(xy 100.633764 -283.252646) (xy 100.593873 -283.221594) (xy 100.559637 -283.1844) (xy 100.531989 -283.142079)
			(xy 100.511684 -283.095784) (xy 100.499275 -283.046779) (xy 100.4951 -282.9964) (xy 100.166424 -282.9964)
			(xy 100.165929 -283.020993) (xy 100.158034 -283.06957) (xy 100.14245 -283.116251) (xy 100.119579 -283.159828)
			(xy 100.090014 -283.199172) (xy 100.054521 -283.233264) (xy 100.014018 -283.26122) (xy 99.969556 -283.282318)
			(xy 99.922285 -283.29601) (xy 99.87343 -283.301942) (xy 99.824255 -283.299961) (xy 99.776036 -283.290117)
			(xy 99.73002 -283.272665) (xy 99.687399 -283.248058) (xy 99.649278 -283.216933) (xy 99.616643 -283.180096)
			(xy 99.59034 -283.1385) (xy 99.571049 -283.093224) (xy 99.559272 -283.04544) (xy 99.555312 -282.996386)
			(xy 99.2272 -282.996386) (xy 99.227201 -282.9964) (xy 99.223025 -283.046786) (xy 99.210613 -283.095798)
			(xy 99.190302 -283.142098) (xy 99.162646 -283.184423) (xy 99.128401 -283.221619) (xy 99.088501 -283.25267)
			(xy 99.044033 -283.27673) (xy 98.996212 -283.293142) (xy 98.946342 -283.301458) (xy 98.921062 -283.301948)
			(xy 97.981008 -283.301948) (xy 97.955728 -283.301484) (xy 97.905856 -283.293163) (xy 97.858035 -283.276747)
			(xy 97.813568 -283.252683) (xy 97.773668 -283.221629) (xy 97.739424 -283.184431) (xy 97.711769 -283.142103)
			(xy 97.691459 -283.095801) (xy 97.679047 -283.046788) (xy 97.674871 -282.9964) (xy 97.346262 -282.9964)
			(xy 97.345767 -283.020993) (xy 97.337872 -283.06957) (xy 97.322288 -283.116251) (xy 97.299417 -283.159828)
			(xy 97.269852 -283.199172) (xy 97.234359 -283.233264) (xy 97.193856 -283.26122) (xy 97.149394 -283.282318)
			(xy 97.102123 -283.29601) (xy 97.053268 -283.301942) (xy 97.004093 -283.299961) (xy 96.955874 -283.290117)
			(xy 96.909858 -283.272665) (xy 96.867237 -283.248058) (xy 96.829116 -283.216933) (xy 96.796481 -283.180096)
			(xy 96.770178 -283.1385) (xy 96.750887 -283.093224) (xy 96.73911 -283.04544) (xy 96.73515 -282.996386)
			(xy 96.416876 -282.996386) (xy 96.416364 -283.021832) (xy 96.4082 -283.072066) (xy 96.392084 -283.12034)
			(xy 96.368433 -283.165403) (xy 96.33786 -283.206089) (xy 96.301156 -283.241344) (xy 96.259272 -283.270254)
			(xy 96.213293 -283.292071) (xy 96.164409 -283.306231) (xy 96.113888 -283.312365) (xy 96.063036 -283.310316)
			(xy 96.013172 -283.300136) (xy 95.965586 -283.282089) (xy 95.921512 -283.256643) (xy 95.88209 -283.224456)
			(xy 95.848342 -283.186362) (xy 95.821141 -283.143348) (xy 95.801193 -283.096528) (xy 95.789014 -283.047114)
			(xy 95.784919 -282.996386) (xy 95.466408 -282.996386) (xy 95.465913 -283.020993) (xy 95.458018 -283.06957)
			(xy 95.442434 -283.116251) (xy 95.419563 -283.159828) (xy 95.389998 -283.199172) (xy 95.354505 -283.233264)
			(xy 95.314002 -283.26122) (xy 95.26954 -283.282318) (xy 95.222269 -283.29601) (xy 95.173414 -283.301942)
			(xy 95.124239 -283.299961) (xy 95.07602 -283.290117) (xy 95.030004 -283.272665) (xy 94.987383 -283.248058)
			(xy 94.949262 -283.216933) (xy 94.916627 -283.180096) (xy 94.890324 -283.1385) (xy 94.871033 -283.093224)
			(xy 94.859256 -283.04544) (xy 94.855296 -282.996386) (xy 94.536768 -282.996386) (xy 94.536256 -283.021832)
			(xy 94.528092 -283.072066) (xy 94.511976 -283.12034) (xy 94.488325 -283.165403) (xy 94.457752 -283.206089)
			(xy 94.421048 -283.241344) (xy 94.379164 -283.270254) (xy 94.333185 -283.292071) (xy 94.284301 -283.306231)
			(xy 94.23378 -283.312365) (xy 94.182928 -283.310316) (xy 94.133064 -283.300136) (xy 94.085478 -283.282089)
			(xy 94.041404 -283.256643) (xy 94.001982 -283.224456) (xy 93.968234 -283.186362) (xy 93.941033 -283.143348)
			(xy 93.921085 -283.096528) (xy 93.908906 -283.047114) (xy 93.904811 -282.996386) (xy 93.5863 -282.996386)
			(xy 93.585835 -283.020236) (xy 93.578408 -283.067355) (xy 93.563747 -283.112748) (xy 93.54221 -283.15531)
			(xy 93.514319 -283.194007) (xy 93.480753 -283.227899) (xy 93.442326 -283.256162) (xy 93.399974 -283.27811)
			(xy 93.354726 -283.293208) (xy 93.331284 -283.29763) (xy 93.322648 -283.299154) (xy 93.294708 -283.319474)
			(xy 93.289834 -283.323227) (xy 93.281875 -283.3326) (xy 93.27896 -283.338016) (xy 93.248226 -283.4005)
			(xy 93.24721 -283.40304) (xy 93.243635 -283.412409) (xy 93.243367 -283.432445) (xy 93.246702 -283.441902)
			(xy 93.246956 -283.442664) (xy 93.250004 -283.448506) (xy 93.294708 -283.525468) (xy 93.305178 -283.543948)
			(xy 93.323612 -283.582217) (xy 93.331538 -283.601922) (xy 93.331538 -283.602176) (xy 93.334233 -283.608376)
			(xy 93.342346 -283.619185) (xy 93.34754 -283.623512) (xy 93.352874 -283.627576) (xy 93.365066 -283.63291)
			(xy 93.45803 -283.645102) (xy 93.464894 -283.645767) (xy 93.478541 -283.643828) (xy 93.484954 -283.641292)
			(xy 93.490982 -283.638492) (xy 93.501405 -283.63025) (xy 93.505528 -283.625036) (xy 93.505782 -283.624782)
			(xy 93.520287 -283.605954) (xy 93.554144 -283.572602) (xy 93.592757 -283.544894) (xy 93.635195 -283.5235)
			(xy 93.680435 -283.508936) (xy 93.727383 -283.501553) (xy 93.751146 -283.501084) (xy 93.776399 -283.501609)
			(xy 93.826217 -283.509929) (xy 93.873985 -283.526334) (xy 93.918402 -283.550378) (xy 93.958257 -283.581403)
			(xy 93.992462 -283.618565) (xy 94.020084 -283.66085) (xy 94.040371 -283.707103) (xy 94.052769 -283.756065)
			(xy 94.056938 -283.806392) (xy 94.374711 -283.806392) (xy 94.378806 -283.755664) (xy 94.390985 -283.70625)
			(xy 94.410933 -283.65943) (xy 94.438134 -283.616416) (xy 94.471882 -283.578322) (xy 94.511304 -283.546135)
			(xy 94.555378 -283.520689) (xy 94.602964 -283.502642) (xy 94.652828 -283.492462) (xy 94.70368 -283.490413)
			(xy 94.754201 -283.496547) (xy 94.803085 -283.510707) (xy 94.849064 -283.532524) (xy 94.890948 -283.561434)
			(xy 94.927652 -283.596689) (xy 94.958225 -283.637375) (xy 94.981876 -283.682438) (xy 94.997992 -283.730712)
			(xy 95.006156 -283.780946) (xy 95.006668 -283.806392) (xy 95.314765 -283.806392) (xy 95.31886 -283.755664)
			(xy 95.331039 -283.70625) (xy 95.350987 -283.65943) (xy 95.378188 -283.616416) (xy 95.411936 -283.578322)
			(xy 95.451358 -283.546135) (xy 95.495432 -283.520689) (xy 95.543018 -283.502642) (xy 95.592882 -283.492462)
			(xy 95.643734 -283.490413) (xy 95.694255 -283.496547) (xy 95.743139 -283.510707) (xy 95.789118 -283.532524)
			(xy 95.831002 -283.561434) (xy 95.867706 -283.596689) (xy 95.898279 -283.637375) (xy 95.92193 -283.682438)
			(xy 95.938046 -283.730712) (xy 95.94621 -283.780946) (xy 95.946722 -283.806392) (xy 96.26525 -283.806392)
			(xy 96.26921 -283.757338) (xy 96.280987 -283.709554) (xy 96.300278 -283.664278) (xy 96.326581 -283.622682)
			(xy 96.359216 -283.585845) (xy 96.397337 -283.55472) (xy 96.439958 -283.530113) (xy 96.485974 -283.512661)
			(xy 96.534193 -283.502817) (xy 96.583368 -283.500836) (xy 96.632223 -283.506768) (xy 96.679494 -283.52046)
			(xy 96.723956 -283.541558) (xy 96.764459 -283.569514) (xy 96.799952 -283.603606) (xy 96.829517 -283.64295)
			(xy 96.852388 -283.686527) (xy 96.867972 -283.733208) (xy 96.875867 -283.781785) (xy 96.876362 -283.806392)
			(xy 99.085158 -283.806392) (xy 99.089118 -283.757338) (xy 99.100895 -283.709554) (xy 99.120186 -283.664278)
			(xy 99.146489 -283.622682) (xy 99.179124 -283.585845) (xy 99.217245 -283.55472) (xy 99.259866 -283.530113)
			(xy 99.305882 -283.512661) (xy 99.354101 -283.502817) (xy 99.403276 -283.500836) (xy 99.452131 -283.506768)
			(xy 99.499402 -283.52046) (xy 99.543864 -283.541558) (xy 99.584367 -283.569514) (xy 99.61986 -283.603606)
			(xy 99.649425 -283.64295) (xy 99.672296 -283.686527) (xy 99.68788 -283.733208) (xy 99.695775 -283.781785)
			(xy 99.69627 -283.806392) (xy 101.90532 -283.806392) (xy 101.90928 -283.757338) (xy 101.921057 -283.709554)
			(xy 101.940348 -283.664278) (xy 101.966651 -283.622682) (xy 101.999286 -283.585845) (xy 102.037407 -283.55472)
			(xy 102.080028 -283.530113) (xy 102.126044 -283.512661) (xy 102.174263 -283.502817) (xy 102.223438 -283.500836)
			(xy 102.272293 -283.506768) (xy 102.319564 -283.52046) (xy 102.364026 -283.541558) (xy 102.404529 -283.569514)
			(xy 102.440022 -283.603606) (xy 102.469587 -283.64295) (xy 102.492458 -283.686527) (xy 102.508042 -283.733208)
			(xy 102.515937 -283.781785) (xy 102.516432 -283.806392) (xy 104.725228 -283.806392) (xy 104.729188 -283.757338)
			(xy 104.740965 -283.709554) (xy 104.760256 -283.664278) (xy 104.786559 -283.622682) (xy 104.819194 -283.585845)
			(xy 104.857315 -283.55472) (xy 104.899936 -283.530113) (xy 104.945952 -283.512661) (xy 104.994171 -283.502817)
			(xy 105.043346 -283.500836) (xy 105.092201 -283.506768) (xy 105.139472 -283.52046) (xy 105.183934 -283.541558)
			(xy 105.224437 -283.569514) (xy 105.25993 -283.603606) (xy 105.289495 -283.64295) (xy 105.312366 -283.686527)
			(xy 105.32795 -283.733208) (xy 105.335845 -283.781785) (xy 105.33634 -283.806392) (xy 107.545136 -283.806392)
			(xy 107.549096 -283.757338) (xy 107.560873 -283.709554) (xy 107.580164 -283.664278) (xy 107.606467 -283.622682)
			(xy 107.639102 -283.585845) (xy 107.677223 -283.55472) (xy 107.719844 -283.530113) (xy 107.76586 -283.512661)
			(xy 107.814079 -283.502817) (xy 107.863254 -283.500836) (xy 107.912109 -283.506768) (xy 107.95938 -283.52046)
			(xy 108.003842 -283.541558) (xy 108.044345 -283.569514) (xy 108.079838 -283.603606) (xy 108.109403 -283.64295)
			(xy 108.132274 -283.686527) (xy 108.147858 -283.733208) (xy 108.155753 -283.781785) (xy 108.156248 -283.806392)
			(xy 108.156248 -283.8064) (xy 108.485161 -283.8064) (xy 108.489332 -283.756061) (xy 108.501732 -283.707095)
			(xy 108.522022 -283.660838) (xy 108.549649 -283.618552) (xy 108.583859 -283.581389) (xy 108.623719 -283.550364)
			(xy 108.668142 -283.526323) (xy 108.715916 -283.509921) (xy 108.765738 -283.501606) (xy 108.790994 -283.501084)
			(xy 109.731048 -283.501084) (xy 109.7563 -283.501625) (xy 109.806114 -283.509945) (xy 109.85388 -283.52635)
			(xy 109.898295 -283.550392) (xy 109.938147 -283.581416) (xy 109.97235 -283.618576) (xy 109.999971 -283.660858)
			(xy 110.020256 -283.707109) (xy 110.032653 -283.756068) (xy 110.036822 -283.806392) (xy 110.365298 -283.806392)
			(xy 110.369258 -283.757338) (xy 110.381035 -283.709554) (xy 110.400326 -283.664278) (xy 110.426629 -283.622682)
			(xy 110.459264 -283.585845) (xy 110.497385 -283.55472) (xy 110.540006 -283.530113) (xy 110.586022 -283.512661)
			(xy 110.634241 -283.502817) (xy 110.683416 -283.500836) (xy 110.732271 -283.506768) (xy 110.779542 -283.52046)
			(xy 110.824004 -283.541558) (xy 110.864507 -283.569514) (xy 110.9 -283.603606) (xy 110.929565 -283.64295)
			(xy 110.952436 -283.686527) (xy 110.96802 -283.733208) (xy 110.975915 -283.781785) (xy 110.97641 -283.806392)
			(xy 113.178856 -283.806392) (xy 113.182816 -283.757338) (xy 113.194593 -283.709554) (xy 113.213884 -283.664278)
			(xy 113.240187 -283.622682) (xy 113.272822 -283.585845) (xy 113.310943 -283.55472) (xy 113.353564 -283.530113)
			(xy 113.39958 -283.512661) (xy 113.447799 -283.502817) (xy 113.496974 -283.500836) (xy 113.545829 -283.506768)
			(xy 113.5931 -283.52046) (xy 113.637562 -283.541558) (xy 113.678065 -283.569514) (xy 113.713558 -283.603606)
			(xy 113.743123 -283.64295) (xy 113.765994 -283.686527) (xy 113.781578 -283.733208) (xy 113.789473 -283.781785)
			(xy 113.789968 -283.806392) (xy 113.789968 -283.8064) (xy 114.118832 -283.8064) (xy 114.123004 -283.756054)
			(xy 114.135406 -283.707082) (xy 114.155699 -283.660819) (xy 114.183331 -283.618527) (xy 114.217547 -283.581361)
			(xy 114.257413 -283.550333) (xy 114.301844 -283.52629) (xy 114.349625 -283.509889) (xy 114.399455 -283.501576)
			(xy 114.424714 -283.501084) (xy 115.364768 -283.501084) (xy 115.390027 -283.50159) (xy 115.439856 -283.5099)
			(xy 115.487638 -283.526299) (xy 115.532068 -283.55034) (xy 115.571936 -283.581366) (xy 115.606152 -283.618531)
			(xy 115.633784 -283.660822) (xy 115.654078 -283.707084) (xy 115.66648 -283.756055) (xy 115.670651 -283.806392)
			(xy 115.999018 -283.806392) (xy 116.002978 -283.757338) (xy 116.014755 -283.709554) (xy 116.034046 -283.664278)
			(xy 116.060349 -283.622682) (xy 116.092984 -283.585845) (xy 116.131105 -283.55472) (xy 116.173726 -283.530113)
			(xy 116.219742 -283.512661) (xy 116.267961 -283.502817) (xy 116.317136 -283.500836) (xy 116.365991 -283.506768)
			(xy 116.413262 -283.52046) (xy 116.457724 -283.541558) (xy 116.498227 -283.569514) (xy 116.53372 -283.603606)
			(xy 116.563285 -283.64295) (xy 116.586156 -283.686527) (xy 116.60174 -283.733208) (xy 116.609635 -283.781785)
			(xy 116.61013 -283.806392) (xy 118.818926 -283.806392) (xy 118.822886 -283.757338) (xy 118.834663 -283.709554)
			(xy 118.853954 -283.664278) (xy 118.880257 -283.622682) (xy 118.912892 -283.585845) (xy 118.951013 -283.55472)
			(xy 118.993634 -283.530113) (xy 119.03965 -283.512661) (xy 119.087869 -283.502817) (xy 119.137044 -283.500836)
			(xy 119.185899 -283.506768) (xy 119.23317 -283.52046) (xy 119.277632 -283.541558) (xy 119.318135 -283.569514)
			(xy 119.353628 -283.603606) (xy 119.383193 -283.64295) (xy 119.406064 -283.686527) (xy 119.421648 -283.733208)
			(xy 119.429543 -283.781785) (xy 119.430038 -283.806392) (xy 121.638834 -283.806392) (xy 121.642794 -283.757338)
			(xy 121.654571 -283.709554) (xy 121.673862 -283.664278) (xy 121.700165 -283.622682) (xy 121.7328 -283.585845)
			(xy 121.770921 -283.55472) (xy 121.813542 -283.530113) (xy 121.859558 -283.512661) (xy 121.907777 -283.502817)
			(xy 121.956952 -283.500836) (xy 122.005807 -283.506768) (xy 122.053078 -283.52046) (xy 122.09754 -283.541558)
			(xy 122.138043 -283.569514) (xy 122.173536 -283.603606) (xy 122.203101 -283.64295) (xy 122.225972 -283.686527)
			(xy 122.241556 -283.733208) (xy 122.249451 -283.781785) (xy 122.249946 -283.806392) (xy 124.458996 -283.806392)
			(xy 124.462956 -283.757338) (xy 124.474733 -283.709554) (xy 124.494024 -283.664278) (xy 124.520327 -283.622682)
			(xy 124.552962 -283.585845) (xy 124.591083 -283.55472) (xy 124.633704 -283.530113) (xy 124.67972 -283.512661)
			(xy 124.727939 -283.502817) (xy 124.777114 -283.500836) (xy 124.825969 -283.506768) (xy 124.87324 -283.52046)
			(xy 124.917702 -283.541558) (xy 124.958205 -283.569514) (xy 124.993698 -283.603606) (xy 125.023263 -283.64295)
			(xy 125.046134 -283.686527) (xy 125.061718 -283.733208) (xy 125.069613 -283.781785) (xy 125.070108 -283.806392)
			(xy 125.069613 -283.830999) (xy 125.061718 -283.879576) (xy 125.046134 -283.926257) (xy 125.023263 -283.969834)
			(xy 124.993698 -284.009178) (xy 124.958205 -284.04327) (xy 124.917702 -284.071226) (xy 124.87324 -284.092324)
			(xy 124.825969 -284.106016) (xy 124.777114 -284.111948) (xy 124.727939 -284.109967) (xy 124.67972 -284.100123)
			(xy 124.633704 -284.082671) (xy 124.591083 -284.058064) (xy 124.552962 -284.026939) (xy 124.520327 -283.990102)
			(xy 124.494024 -283.948506) (xy 124.474733 -283.90323) (xy 124.462956 -283.855446) (xy 124.458996 -283.806392)
			(xy 122.249946 -283.806392) (xy 122.249451 -283.830999) (xy 122.241556 -283.879576) (xy 122.225972 -283.926257)
			(xy 122.203101 -283.969834) (xy 122.173536 -284.009178) (xy 122.138043 -284.04327) (xy 122.09754 -284.071226)
			(xy 122.053078 -284.092324) (xy 122.005807 -284.106016) (xy 121.956952 -284.111948) (xy 121.907777 -284.109967)
			(xy 121.859558 -284.100123) (xy 121.813542 -284.082671) (xy 121.770921 -284.058064) (xy 121.7328 -284.026939)
			(xy 121.700165 -283.990102) (xy 121.673862 -283.948506) (xy 121.654571 -283.90323) (xy 121.642794 -283.855446)
			(xy 121.638834 -283.806392) (xy 119.430038 -283.806392) (xy 119.429543 -283.830999) (xy 119.421648 -283.879576)
			(xy 119.406064 -283.926257) (xy 119.383193 -283.969834) (xy 119.353628 -284.009178) (xy 119.318135 -284.04327)
			(xy 119.277632 -284.071226) (xy 119.23317 -284.092324) (xy 119.185899 -284.106016) (xy 119.137044 -284.111948)
			(xy 119.087869 -284.109967) (xy 119.03965 -284.100123) (xy 118.993634 -284.082671) (xy 118.951013 -284.058064)
			(xy 118.912892 -284.026939) (xy 118.880257 -283.990102) (xy 118.853954 -283.948506) (xy 118.834663 -283.90323)
			(xy 118.822886 -283.855446) (xy 118.818926 -283.806392) (xy 116.61013 -283.806392) (xy 116.609635 -283.830999)
			(xy 116.60174 -283.879576) (xy 116.586156 -283.926257) (xy 116.563285 -283.969834) (xy 116.53372 -284.009178)
			(xy 116.498227 -284.04327) (xy 116.457724 -284.071226) (xy 116.413262 -284.092324) (xy 116.365991 -284.106016)
			(xy 116.317136 -284.111948) (xy 116.267961 -284.109967) (xy 116.219742 -284.100123) (xy 116.173726 -284.082671)
			(xy 116.131105 -284.058064) (xy 116.092984 -284.026939) (xy 116.060349 -283.990102) (xy 116.034046 -283.948506)
			(xy 116.014755 -283.90323) (xy 116.002978 -283.855446) (xy 115.999018 -283.806392) (xy 115.670651 -283.806392)
			(xy 115.670652 -283.8064) (xy 115.66648 -283.856745) (xy 115.654078 -283.905716) (xy 115.633784 -283.951978)
			(xy 115.606152 -283.994269) (xy 115.571936 -284.031434) (xy 115.532068 -284.06246) (xy 115.487638 -284.086501)
			(xy 115.439856 -284.1029) (xy 115.390027 -284.11121) (xy 115.364768 -284.1117) (xy 114.424714 -284.1117)
			(xy 114.399455 -284.111224) (xy 114.349625 -284.102911) (xy 114.301844 -284.08651) (xy 114.257413 -284.062467)
			(xy 114.217547 -284.031439) (xy 114.183331 -283.994273) (xy 114.155699 -283.951981) (xy 114.135406 -283.905718)
			(xy 114.123004 -283.856746) (xy 114.118832 -283.8064) (xy 113.789968 -283.8064) (xy 113.789473 -283.830999)
			(xy 113.781578 -283.879576) (xy 113.765994 -283.926257) (xy 113.743123 -283.969834) (xy 113.713558 -284.009178)
			(xy 113.678065 -284.04327) (xy 113.637562 -284.071226) (xy 113.5931 -284.092324) (xy 113.545829 -284.106016)
			(xy 113.496974 -284.111948) (xy 113.447799 -284.109967) (xy 113.39958 -284.100123) (xy 113.353564 -284.082671)
			(xy 113.310943 -284.058064) (xy 113.272822 -284.026939) (xy 113.240187 -283.990102) (xy 113.213884 -283.948506)
			(xy 113.194593 -283.90323) (xy 113.182816 -283.855446) (xy 113.178856 -283.806392) (xy 110.97641 -283.806392)
			(xy 110.975915 -283.830999) (xy 110.96802 -283.879576) (xy 110.952436 -283.926257) (xy 110.929565 -283.969834)
			(xy 110.9 -284.009178) (xy 110.864507 -284.04327) (xy 110.824004 -284.071226) (xy 110.779542 -284.092324)
			(xy 110.732271 -284.106016) (xy 110.683416 -284.111948) (xy 110.634241 -284.109967) (xy 110.586022 -284.100123)
			(xy 110.540006 -284.082671) (xy 110.497385 -284.058064) (xy 110.459264 -284.026939) (xy 110.426629 -283.990102)
			(xy 110.400326 -283.948506) (xy 110.381035 -283.90323) (xy 110.369258 -283.855446) (xy 110.365298 -283.806392)
			(xy 110.036822 -283.806392) (xy 110.036823 -283.8064) (xy 110.032653 -283.856732) (xy 110.020256 -283.905691)
			(xy 109.999971 -283.951942) (xy 109.97235 -283.994224) (xy 109.938147 -284.031384) (xy 109.898295 -284.062408)
			(xy 109.85388 -284.08645) (xy 109.806114 -284.102855) (xy 109.7563 -284.111175) (xy 109.731048 -284.1117)
			(xy 108.790994 -284.1117) (xy 108.765738 -284.111194) (xy 108.715916 -284.102879) (xy 108.668142 -284.086477)
			(xy 108.623719 -284.062436) (xy 108.583859 -284.031411) (xy 108.549649 -283.994248) (xy 108.522022 -283.951962)
			(xy 108.501732 -283.905705) (xy 108.489332 -283.856739) (xy 108.485161 -283.8064) (xy 108.156248 -283.8064)
			(xy 108.155753 -283.830999) (xy 108.147858 -283.879576) (xy 108.132274 -283.926257) (xy 108.109403 -283.969834)
			(xy 108.079838 -284.009178) (xy 108.044345 -284.04327) (xy 108.003842 -284.071226) (xy 107.95938 -284.092324)
			(xy 107.912109 -284.106016) (xy 107.863254 -284.111948) (xy 107.814079 -284.109967) (xy 107.76586 -284.100123)
			(xy 107.719844 -284.082671) (xy 107.677223 -284.058064) (xy 107.639102 -284.026939) (xy 107.606467 -283.990102)
			(xy 107.580164 -283.948506) (xy 107.560873 -283.90323) (xy 107.549096 -283.855446) (xy 107.545136 -283.806392)
			(xy 105.33634 -283.806392) (xy 105.335845 -283.830999) (xy 105.32795 -283.879576) (xy 105.312366 -283.926257)
			(xy 105.289495 -283.969834) (xy 105.25993 -284.009178) (xy 105.224437 -284.04327) (xy 105.183934 -284.071226)
			(xy 105.139472 -284.092324) (xy 105.092201 -284.106016) (xy 105.043346 -284.111948) (xy 104.994171 -284.109967)
			(xy 104.945952 -284.100123) (xy 104.899936 -284.082671) (xy 104.857315 -284.058064) (xy 104.819194 -284.026939)
			(xy 104.786559 -283.990102) (xy 104.760256 -283.948506) (xy 104.740965 -283.90323) (xy 104.729188 -283.855446)
			(xy 104.725228 -283.806392) (xy 102.516432 -283.806392) (xy 102.515937 -283.830999) (xy 102.508042 -283.879576)
			(xy 102.492458 -283.926257) (xy 102.469587 -283.969834) (xy 102.440022 -284.009178) (xy 102.404529 -284.04327)
			(xy 102.364026 -284.071226) (xy 102.319564 -284.092324) (xy 102.272293 -284.106016) (xy 102.223438 -284.111948)
			(xy 102.174263 -284.109967) (xy 102.126044 -284.100123) (xy 102.080028 -284.082671) (xy 102.037407 -284.058064)
			(xy 101.999286 -284.026939) (xy 101.966651 -283.990102) (xy 101.940348 -283.948506) (xy 101.921057 -283.90323)
			(xy 101.90928 -283.855446) (xy 101.90532 -283.806392) (xy 99.69627 -283.806392) (xy 99.695775 -283.830999)
			(xy 99.68788 -283.879576) (xy 99.672296 -283.926257) (xy 99.649425 -283.969834) (xy 99.61986 -284.009178)
			(xy 99.584367 -284.04327) (xy 99.543864 -284.071226) (xy 99.499402 -284.092324) (xy 99.452131 -284.106016)
			(xy 99.403276 -284.111948) (xy 99.354101 -284.109967) (xy 99.305882 -284.100123) (xy 99.259866 -284.082671)
			(xy 99.217245 -284.058064) (xy 99.179124 -284.026939) (xy 99.146489 -283.990102) (xy 99.120186 -283.948506)
			(xy 99.100895 -283.90323) (xy 99.089118 -283.855446) (xy 99.085158 -283.806392) (xy 96.876362 -283.806392)
			(xy 96.875867 -283.830999) (xy 96.867972 -283.879576) (xy 96.852388 -283.926257) (xy 96.829517 -283.969834)
			(xy 96.799952 -284.009178) (xy 96.764459 -284.04327) (xy 96.723956 -284.071226) (xy 96.679494 -284.092324)
			(xy 96.632223 -284.106016) (xy 96.583368 -284.111948) (xy 96.534193 -284.109967) (xy 96.485974 -284.100123)
			(xy 96.439958 -284.082671) (xy 96.397337 -284.058064) (xy 96.359216 -284.026939) (xy 96.326581 -283.990102)
			(xy 96.300278 -283.948506) (xy 96.280987 -283.90323) (xy 96.26921 -283.855446) (xy 96.26525 -283.806392)
			(xy 95.946722 -283.806392) (xy 95.94621 -283.831838) (xy 95.938046 -283.882072) (xy 95.92193 -283.930346)
			(xy 95.898279 -283.975409) (xy 95.867706 -284.016095) (xy 95.831002 -284.05135) (xy 95.789118 -284.08026)
			(xy 95.743139 -284.102077) (xy 95.694255 -284.116237) (xy 95.643734 -284.122371) (xy 95.592882 -284.120322)
			(xy 95.543018 -284.110142) (xy 95.495432 -284.092095) (xy 95.451358 -284.066649) (xy 95.411936 -284.034462)
			(xy 95.378188 -283.996368) (xy 95.350987 -283.953354) (xy 95.331039 -283.906534) (xy 95.31886 -283.85712)
			(xy 95.314765 -283.806392) (xy 95.006668 -283.806392) (xy 95.006156 -283.831838) (xy 94.997992 -283.882072)
			(xy 94.981876 -283.930346) (xy 94.958225 -283.975409) (xy 94.927652 -284.016095) (xy 94.890948 -284.05135)
			(xy 94.849064 -284.08026) (xy 94.803085 -284.102077) (xy 94.754201 -284.116237) (xy 94.70368 -284.122371)
			(xy 94.652828 -284.120322) (xy 94.602964 -284.110142) (xy 94.555378 -284.092095) (xy 94.511304 -284.066649)
			(xy 94.471882 -284.034462) (xy 94.438134 -283.996368) (xy 94.410933 -283.953354) (xy 94.390985 -283.906534)
			(xy 94.378806 -283.85712) (xy 94.374711 -283.806392) (xy 94.056938 -283.806392) (xy 94.056939 -283.8064)
			(xy 94.052769 -283.856735) (xy 94.040371 -283.905697) (xy 94.020084 -283.95195) (xy 93.992462 -283.994235)
			(xy 93.958257 -284.031397) (xy 93.918402 -284.062422) (xy 93.873985 -284.086466) (xy 93.826217 -284.102871)
			(xy 93.776399 -284.111191) (xy 93.751146 -284.1117) (xy 93.727381 -284.11125) (xy 93.680424 -284.103886)
			(xy 93.635177 -284.089329) (xy 93.592734 -284.067932) (xy 93.554124 -284.040212) (xy 93.520279 -284.006839)
			(xy 93.505782 -283.988002) (xy 93.505782 -283.987748) (xy 93.505528 -283.987748) (xy 93.501371 -283.982569)
			(xy 93.490955 -283.974337) (xy 93.484954 -283.971492) (xy 93.478545 -283.968947) (xy 93.464895 -283.967027)
			(xy 93.45803 -283.967682) (xy 93.372178 -283.979112) (xy 93.365418 -283.980186) (xy 93.352793 -283.985461)
			(xy 93.347286 -283.989526) (xy 93.341952 -283.99359) (xy 93.334078 -284.004258) (xy 93.331538 -284.010862)
			(xy 93.315988 -284.048533) (xy 93.275564 -284.119297) (xy 93.25102 -284.151832) (xy 93.25102 -284.152086)
			(xy 93.24699 -284.157491) (xy 93.241595 -284.169842) (xy 93.240352 -284.17647) (xy 93.238574 -284.189678)
			(xy 93.276928 -284.282388) (xy 93.279687 -284.288548) (xy 93.287932 -284.299229) (xy 93.293184 -284.30347)
			(xy 93.298518 -284.307534) (xy 93.31071 -284.31236) (xy 93.317822 -284.313376) (xy 93.342181 -284.316841)
			(xy 93.389434 -284.330543) (xy 93.433878 -284.351644) (xy 93.474364 -284.379598) (xy 93.509845 -284.413682)
			(xy 93.539401 -284.453013) (xy 93.562269 -284.496574) (xy 93.577857 -284.543239) (xy 93.585762 -284.591799)
			(xy 93.5863 -284.616398) (xy 93.904811 -284.616398) (xy 93.908906 -284.56567) (xy 93.921085 -284.516256)
			(xy 93.941033 -284.469436) (xy 93.968234 -284.426422) (xy 94.001982 -284.388328) (xy 94.041404 -284.356141)
			(xy 94.085478 -284.330695) (xy 94.133064 -284.312648) (xy 94.182928 -284.302468) (xy 94.23378 -284.300419)
			(xy 94.284301 -284.306553) (xy 94.333185 -284.320713) (xy 94.379164 -284.34253) (xy 94.421048 -284.37144)
			(xy 94.457752 -284.406695) (xy 94.488325 -284.447381) (xy 94.511976 -284.492444) (xy 94.528092 -284.540718)
			(xy 94.536256 -284.590952) (xy 94.536768 -284.616398) (xy 94.855296 -284.616398) (xy 94.859256 -284.567344)
			(xy 94.871033 -284.51956) (xy 94.890324 -284.474284) (xy 94.916627 -284.432688) (xy 94.949262 -284.395851)
			(xy 94.987383 -284.364726) (xy 95.030004 -284.340119) (xy 95.07602 -284.322667) (xy 95.124239 -284.312823)
			(xy 95.173414 -284.310842) (xy 95.222269 -284.316774) (xy 95.26954 -284.330466) (xy 95.314002 -284.351564)
			(xy 95.354505 -284.37952) (xy 95.389998 -284.413612) (xy 95.419563 -284.452956) (xy 95.442434 -284.496533)
			(xy 95.458018 -284.543214) (xy 95.465913 -284.591791) (xy 95.466408 -284.616398) (xy 95.784919 -284.616398)
			(xy 95.789014 -284.56567) (xy 95.801193 -284.516256) (xy 95.821141 -284.469436) (xy 95.848342 -284.426422)
			(xy 95.88209 -284.388328) (xy 95.921512 -284.356141) (xy 95.965586 -284.330695) (xy 96.013172 -284.312648)
			(xy 96.063036 -284.302468) (xy 96.113888 -284.300419) (xy 96.164409 -284.306553) (xy 96.213293 -284.320713)
			(xy 96.259272 -284.34253) (xy 96.301156 -284.37144) (xy 96.33786 -284.406695) (xy 96.368433 -284.447381)
			(xy 96.392084 -284.492444) (xy 96.4082 -284.540718) (xy 96.416364 -284.590952) (xy 96.416876 -284.616398)
			(xy 96.73515 -284.616398) (xy 96.73911 -284.567344) (xy 96.750887 -284.51956) (xy 96.770178 -284.474284)
			(xy 96.796481 -284.432688) (xy 96.829116 -284.395851) (xy 96.867237 -284.364726) (xy 96.909858 -284.340119)
			(xy 96.955874 -284.322667) (xy 97.004093 -284.312823) (xy 97.053268 -284.310842) (xy 97.102123 -284.316774)
			(xy 97.149394 -284.330466) (xy 97.193856 -284.351564) (xy 97.234359 -284.37952) (xy 97.269852 -284.413612)
			(xy 97.299417 -284.452956) (xy 97.322288 -284.496533) (xy 97.337872 -284.543214) (xy 97.345767 -284.591791)
			(xy 97.346262 -284.616398) (xy 97.346262 -284.6164) (xy 97.674883 -284.6164) (xy 97.679059 -284.566014)
			(xy 97.69147 -284.517003) (xy 97.71178 -284.470702) (xy 97.739433 -284.428377) (xy 97.773676 -284.39118)
			(xy 97.813574 -284.360127) (xy 97.85804 -284.336064) (xy 97.905859 -284.319649) (xy 97.955729 -284.311328)
			(xy 97.981008 -284.310836) (xy 98.921062 -284.310836) (xy 98.946343 -284.31133) (xy 98.996215 -284.319647)
			(xy 99.044038 -284.336059) (xy 99.088508 -284.36012) (xy 99.12841 -284.391172) (xy 99.162656 -284.428369)
			(xy 99.190312 -284.470696) (xy 99.210624 -284.516998) (xy 99.223037 -284.566012) (xy 99.227213 -284.616398)
			(xy 99.555312 -284.616398) (xy 99.559272 -284.567344) (xy 99.571049 -284.51956) (xy 99.59034 -284.474284)
			(xy 99.616643 -284.432688) (xy 99.649278 -284.395851) (xy 99.687399 -284.364726) (xy 99.73002 -284.340119)
			(xy 99.776036 -284.322667) (xy 99.824255 -284.312823) (xy 99.87343 -284.310842) (xy 99.922285 -284.316774)
			(xy 99.969556 -284.330466) (xy 100.014018 -284.351564) (xy 100.054521 -284.37952) (xy 100.090014 -284.413612)
			(xy 100.119579 -284.452956) (xy 100.14245 -284.496533) (xy 100.158034 -284.543214) (xy 100.165929 -284.591791)
			(xy 100.166424 -284.616398) (xy 100.166424 -284.6164) (xy 100.495112 -284.6164) (xy 100.499287 -284.566023)
			(xy 100.511695 -284.51702) (xy 100.532 -284.470727) (xy 100.559646 -284.428407) (xy 100.593881 -284.391215)
			(xy 100.63377 -284.360164) (xy 100.678226 -284.336102) (xy 100.726035 -284.319685) (xy 100.775895 -284.31136)
			(xy 100.80117 -284.310836) (xy 101.741224 -284.310836) (xy 101.766499 -284.311364) (xy 101.816359 -284.319688)
			(xy 101.864169 -284.336104) (xy 101.908625 -284.360165) (xy 101.948514 -284.391216) (xy 101.982749 -284.428408)
			(xy 102.010396 -284.470727) (xy 102.030701 -284.51702) (xy 102.043109 -284.566023) (xy 102.047284 -284.616398)
			(xy 102.37522 -284.616398) (xy 102.37918 -284.567344) (xy 102.390957 -284.51956) (xy 102.410248 -284.474284)
			(xy 102.436551 -284.432688) (xy 102.469186 -284.395851) (xy 102.507307 -284.364726) (xy 102.549928 -284.340119)
			(xy 102.595944 -284.322667) (xy 102.644163 -284.312823) (xy 102.693338 -284.310842) (xy 102.742193 -284.316774)
			(xy 102.789464 -284.330466) (xy 102.833926 -284.351564) (xy 102.874429 -284.37952) (xy 102.909922 -284.413612)
			(xy 102.939487 -284.452956) (xy 102.962358 -284.496533) (xy 102.977942 -284.543214) (xy 102.985837 -284.591791)
			(xy 102.986332 -284.616398) (xy 102.986332 -284.6164) (xy 103.315012 -284.6164) (xy 103.319187 -284.566022)
			(xy 103.331596 -284.517018) (xy 103.351901 -284.470725) (xy 103.379548 -284.428404) (xy 103.413784 -284.391212)
			(xy 103.453674 -284.360161) (xy 103.498131 -284.3361) (xy 103.545942 -284.319683) (xy 103.595803 -284.31136)
			(xy 103.621078 -284.310836) (xy 104.561132 -284.310836) (xy 104.586406 -284.311364) (xy 104.636265 -284.319689)
			(xy 104.684074 -284.336106) (xy 104.728529 -284.360168) (xy 104.768417 -284.391218) (xy 104.802651 -284.42841)
			(xy 104.830297 -284.470729) (xy 104.850601 -284.517021) (xy 104.863009 -284.566024) (xy 104.867184 -284.616398)
			(xy 105.195128 -284.616398) (xy 105.199088 -284.567344) (xy 105.210865 -284.51956) (xy 105.230156 -284.474284)
			(xy 105.256459 -284.432688) (xy 105.289094 -284.395851) (xy 105.327215 -284.364726) (xy 105.369836 -284.340119)
			(xy 105.415852 -284.322667) (xy 105.464071 -284.312823) (xy 105.513246 -284.310842) (xy 105.562101 -284.316774)
			(xy 105.609372 -284.330466) (xy 105.653834 -284.351564) (xy 105.694337 -284.37952) (xy 105.72983 -284.413612)
			(xy 105.759395 -284.452956) (xy 105.782266 -284.496533) (xy 105.79785 -284.543214) (xy 105.805745 -284.591791)
			(xy 105.80624 -284.616398) (xy 105.80624 -284.6164) (xy 106.134912 -284.6164) (xy 106.139087 -284.566021)
			(xy 106.151496 -284.517016) (xy 106.171802 -284.470722) (xy 106.19945 -284.428402) (xy 106.233687 -284.391209)
			(xy 106.273579 -284.360159) (xy 106.318037 -284.336097) (xy 106.365849 -284.319682) (xy 106.41571 -284.311359)
			(xy 106.440986 -284.310836) (xy 107.38104 -284.310836) (xy 107.406314 -284.311365) (xy 107.456172 -284.319691)
			(xy 107.503979 -284.336109) (xy 107.548433 -284.360171) (xy 107.58832 -284.391221) (xy 107.622553 -284.428413)
			(xy 107.650198 -284.470731) (xy 107.670502 -284.517023) (xy 107.68291 -284.566024) (xy 107.687084 -284.616398)
			(xy 108.01529 -284.616398) (xy 108.01925 -284.567344) (xy 108.031027 -284.51956) (xy 108.050318 -284.474284)
			(xy 108.076621 -284.432688) (xy 108.109256 -284.395851) (xy 108.147377 -284.364726) (xy 108.189998 -284.340119)
			(xy 108.236014 -284.322667) (xy 108.284233 -284.312823) (xy 108.333408 -284.310842) (xy 108.382263 -284.316774)
			(xy 108.429534 -284.330466) (xy 108.473996 -284.351564) (xy 108.514499 -284.37952) (xy 108.549992 -284.413612)
			(xy 108.579557 -284.452956) (xy 108.602428 -284.496533) (xy 108.618012 -284.543214) (xy 108.625907 -284.591791)
			(xy 108.626402 -284.616398) (xy 108.955344 -284.616398) (xy 108.959304 -284.567344) (xy 108.971081 -284.51956)
			(xy 108.990372 -284.474284) (xy 109.016675 -284.432688) (xy 109.04931 -284.395851) (xy 109.087431 -284.364726)
			(xy 109.130052 -284.340119) (xy 109.176068 -284.322667) (xy 109.224287 -284.312823) (xy 109.273462 -284.310842)
			(xy 109.322317 -284.316774) (xy 109.369588 -284.330466) (xy 109.41405 -284.351564) (xy 109.454553 -284.37952)
			(xy 109.490046 -284.413612) (xy 109.519611 -284.452956) (xy 109.542482 -284.496533) (xy 109.558066 -284.543214)
			(xy 109.565961 -284.591791) (xy 109.566456 -284.616398) (xy 109.895144 -284.616398) (xy 109.899104 -284.567344)
			(xy 109.910881 -284.51956) (xy 109.930172 -284.474284) (xy 109.956475 -284.432688) (xy 109.98911 -284.395851)
			(xy 110.027231 -284.364726) (xy 110.069852 -284.340119) (xy 110.115868 -284.322667) (xy 110.164087 -284.312823)
			(xy 110.213262 -284.310842) (xy 110.262117 -284.316774) (xy 110.309388 -284.330466) (xy 110.35385 -284.351564)
			(xy 110.394353 -284.37952) (xy 110.429846 -284.413612) (xy 110.459411 -284.452956) (xy 110.482282 -284.496533)
			(xy 110.497866 -284.543214) (xy 110.505761 -284.591791) (xy 110.506256 -284.616398) (xy 113.64901 -284.616398)
			(xy 113.65297 -284.567344) (xy 113.664747 -284.51956) (xy 113.684038 -284.474284) (xy 113.710341 -284.432688)
			(xy 113.742976 -284.395851) (xy 113.781097 -284.364726) (xy 113.823718 -284.340119) (xy 113.869734 -284.322667)
			(xy 113.917953 -284.312823) (xy 113.967128 -284.310842) (xy 114.015983 -284.316774) (xy 114.063254 -284.330466)
			(xy 114.107716 -284.351564) (xy 114.148219 -284.37952) (xy 114.183712 -284.413612) (xy 114.213277 -284.452956)
			(xy 114.236148 -284.496533) (xy 114.251732 -284.543214) (xy 114.259627 -284.591791) (xy 114.260122 -284.616398)
			(xy 114.58881 -284.616398) (xy 114.59277 -284.567344) (xy 114.604547 -284.51956) (xy 114.623838 -284.474284)
			(xy 114.650141 -284.432688) (xy 114.682776 -284.395851) (xy 114.720897 -284.364726) (xy 114.763518 -284.340119)
			(xy 114.809534 -284.322667) (xy 114.857753 -284.312823) (xy 114.906928 -284.310842) (xy 114.955783 -284.316774)
			(xy 115.003054 -284.330466) (xy 115.047516 -284.351564) (xy 115.088019 -284.37952) (xy 115.123512 -284.413612)
			(xy 115.153077 -284.452956) (xy 115.175948 -284.496533) (xy 115.191532 -284.543214) (xy 115.199427 -284.591791)
			(xy 115.199922 -284.616398) (xy 115.528864 -284.616398) (xy 115.532824 -284.567344) (xy 115.544601 -284.51956)
			(xy 115.563892 -284.474284) (xy 115.590195 -284.432688) (xy 115.62283 -284.395851) (xy 115.660951 -284.364726)
			(xy 115.703572 -284.340119) (xy 115.749588 -284.322667) (xy 115.797807 -284.312823) (xy 115.846982 -284.310842)
			(xy 115.895837 -284.316774) (xy 115.943108 -284.330466) (xy 115.98757 -284.351564) (xy 116.028073 -284.37952)
			(xy 116.063566 -284.413612) (xy 116.093131 -284.452956) (xy 116.116002 -284.496533) (xy 116.131586 -284.543214)
			(xy 116.139481 -284.591791) (xy 116.139976 -284.616398) (xy 116.139976 -284.6164) (xy 116.468583 -284.6164)
			(xy 116.472759 -284.566013) (xy 116.485171 -284.517) (xy 116.505482 -284.470699) (xy 116.533137 -284.428372)
			(xy 116.567381 -284.391175) (xy 116.607282 -284.360122) (xy 116.651749 -284.33606) (xy 116.699571 -284.319646)
			(xy 116.749442 -284.311327) (xy 116.774722 -284.310836) (xy 117.714776 -284.310836) (xy 117.740056 -284.311331)
			(xy 117.789927 -284.319649) (xy 117.837748 -284.336063) (xy 117.882215 -284.360125) (xy 117.922115 -284.391177)
			(xy 117.95636 -284.428374) (xy 117.984014 -284.4707) (xy 118.004325 -284.517001) (xy 118.016737 -284.566013)
			(xy 118.020913 -284.616398) (xy 118.349026 -284.616398) (xy 118.352986 -284.567344) (xy 118.364763 -284.51956)
			(xy 118.384054 -284.474284) (xy 118.410357 -284.432688) (xy 118.442992 -284.395851) (xy 118.481113 -284.364726)
			(xy 118.523734 -284.340119) (xy 118.56975 -284.322667) (xy 118.617969 -284.312823) (xy 118.667144 -284.310842)
			(xy 118.715999 -284.316774) (xy 118.76327 -284.330466) (xy 118.807732 -284.351564) (xy 118.848235 -284.37952)
			(xy 118.883728 -284.413612) (xy 118.913293 -284.452956) (xy 118.936164 -284.496533) (xy 118.951748 -284.543214)
			(xy 118.959643 -284.591791) (xy 118.960138 -284.616398) (xy 118.960138 -284.6164) (xy 119.288483 -284.6164)
			(xy 119.292659 -284.566012) (xy 119.305072 -284.516998) (xy 119.325383 -284.470696) (xy 119.353039 -284.428369)
			(xy 119.387285 -284.391172) (xy 119.427186 -284.360119) (xy 119.471655 -284.336058) (xy 119.519477 -284.319644)
			(xy 119.569349 -284.311327) (xy 119.59463 -284.310836) (xy 120.534684 -284.310836) (xy 120.559963 -284.311332)
			(xy 120.609833 -284.319651) (xy 120.657653 -284.336066) (xy 120.702119 -284.360127) (xy 120.742018 -284.39118)
			(xy 120.776262 -284.428376) (xy 120.803915 -284.470702) (xy 120.824225 -284.517002) (xy 120.836637 -284.566014)
			(xy 120.840813 -284.616398) (xy 121.168934 -284.616398) (xy 121.172894 -284.567344) (xy 121.184671 -284.51956)
			(xy 121.203962 -284.474284) (xy 121.230265 -284.432688) (xy 121.2629 -284.395851) (xy 121.301021 -284.364726)
			(xy 121.343642 -284.340119) (xy 121.389658 -284.322667) (xy 121.437877 -284.312823) (xy 121.487052 -284.310842)
			(xy 121.535907 -284.316774) (xy 121.583178 -284.330466) (xy 121.62764 -284.351564) (xy 121.668143 -284.37952)
			(xy 121.703636 -284.413612) (xy 121.733201 -284.452956) (xy 121.756072 -284.496533) (xy 121.771656 -284.543214)
			(xy 121.779551 -284.591791) (xy 121.780046 -284.616398) (xy 121.780046 -284.6164) (xy 122.108712 -284.6164)
			(xy 122.112887 -284.56602) (xy 122.125297 -284.517015) (xy 122.145603 -284.470721) (xy 122.173252 -284.4284)
			(xy 122.207489 -284.391207) (xy 122.247382 -284.360157) (xy 122.291841 -284.336096) (xy 122.339653 -284.31968)
			(xy 122.389516 -284.311359) (xy 122.414792 -284.310836) (xy 123.354846 -284.310836) (xy 123.38012 -284.311366)
			(xy 123.429977 -284.319692) (xy 123.477783 -284.336111) (xy 123.522236 -284.360173) (xy 123.562123 -284.391223)
			(xy 123.596355 -284.428415) (xy 123.623999 -284.470733) (xy 123.644302 -284.517024) (xy 123.65671 -284.566025)
			(xy 123.660884 -284.616398) (xy 123.988842 -284.616398) (xy 123.992802 -284.567344) (xy 124.004579 -284.51956)
			(xy 124.02387 -284.474284) (xy 124.050173 -284.432688) (xy 124.082808 -284.395851) (xy 124.120929 -284.364726)
			(xy 124.16355 -284.340119) (xy 124.209566 -284.322667) (xy 124.257785 -284.312823) (xy 124.30696 -284.310842)
			(xy 124.355815 -284.316774) (xy 124.403086 -284.330466) (xy 124.447548 -284.351564) (xy 124.488051 -284.37952)
			(xy 124.523544 -284.413612) (xy 124.553109 -284.452956) (xy 124.57598 -284.496533) (xy 124.591564 -284.543214)
			(xy 124.599459 -284.591791) (xy 124.599954 -284.616398) (xy 124.599954 -284.6164) (xy 124.928613 -284.6164)
			(xy 124.932787 -284.56602) (xy 124.945197 -284.517014) (xy 124.965504 -284.470718) (xy 124.993154 -284.428397)
			(xy 125.027393 -284.391204) (xy 125.067286 -284.360154) (xy 125.111746 -284.336093) (xy 125.15956 -284.319679)
			(xy 125.209423 -284.311358) (xy 125.2347 -284.310836) (xy 126.174754 -284.310836) (xy 126.200035 -284.311329)
			(xy 126.249909 -284.319645) (xy 126.297733 -284.336057) (xy 126.342203 -284.360117) (xy 126.382107 -284.391169)
			(xy 126.416354 -284.428366) (xy 126.444011 -284.470694) (xy 126.464323 -284.516996) (xy 126.476737 -284.566011)
			(xy 126.480913 -284.6164) (xy 126.476737 -284.666789) (xy 126.464323 -284.715804) (xy 126.444011 -284.762106)
			(xy 126.416354 -284.804434) (xy 126.382107 -284.841631) (xy 126.342203 -284.872683) (xy 126.297733 -284.896743)
			(xy 126.249909 -284.913155) (xy 126.200035 -284.921471) (xy 126.174754 -284.92196) (xy 125.2347 -284.92196)
			(xy 125.209423 -284.921442) (xy 125.15956 -284.913121) (xy 125.111746 -284.896707) (xy 125.067286 -284.872646)
			(xy 125.027393 -284.841596) (xy 124.993154 -284.804403) (xy 124.965504 -284.762082) (xy 124.945197 -284.715786)
			(xy 124.932787 -284.66678) (xy 124.928613 -284.6164) (xy 124.599954 -284.6164) (xy 124.599459 -284.641005)
			(xy 124.591564 -284.689582) (xy 124.57598 -284.736263) (xy 124.553109 -284.77984) (xy 124.523544 -284.819184)
			(xy 124.488051 -284.853276) (xy 124.447548 -284.881232) (xy 124.403086 -284.90233) (xy 124.355815 -284.916022)
			(xy 124.30696 -284.921954) (xy 124.257785 -284.919973) (xy 124.209566 -284.910129) (xy 124.16355 -284.892677)
			(xy 124.120929 -284.86807) (xy 124.082808 -284.836945) (xy 124.050173 -284.800108) (xy 124.02387 -284.758512)
			(xy 124.004579 -284.713236) (xy 123.992802 -284.665452) (xy 123.988842 -284.616398) (xy 123.660884 -284.616398)
			(xy 123.660884 -284.6164) (xy 123.65671 -284.666775) (xy 123.644302 -284.715776) (xy 123.623999 -284.762067)
			(xy 123.596355 -284.804385) (xy 123.562123 -284.841577) (xy 123.522236 -284.872627) (xy 123.477783 -284.896689)
			(xy 123.429977 -284.913108) (xy 123.38012 -284.921434) (xy 123.354846 -284.92196) (xy 122.414792 -284.92196)
			(xy 122.389516 -284.921441) (xy 122.339653 -284.91312) (xy 122.291841 -284.896704) (xy 122.247382 -284.872643)
			(xy 122.207489 -284.841593) (xy 122.173252 -284.8044) (xy 122.145603 -284.762079) (xy 122.125297 -284.715785)
			(xy 122.112887 -284.66678) (xy 122.108712 -284.6164) (xy 121.780046 -284.6164) (xy 121.779551 -284.641005)
			(xy 121.771656 -284.689582) (xy 121.756072 -284.736263) (xy 121.733201 -284.77984) (xy 121.703636 -284.819184)
			(xy 121.668143 -284.853276) (xy 121.62764 -284.881232) (xy 121.583178 -284.90233) (xy 121.535907 -284.916022)
			(xy 121.487052 -284.921954) (xy 121.437877 -284.919973) (xy 121.389658 -284.910129) (xy 121.343642 -284.892677)
			(xy 121.301021 -284.86807) (xy 121.2629 -284.836945) (xy 121.230265 -284.800108) (xy 121.203962 -284.758512)
			(xy 121.184671 -284.713236) (xy 121.172894 -284.665452) (xy 121.168934 -284.616398) (xy 120.840813 -284.616398)
			(xy 120.840813 -284.6164) (xy 120.836637 -284.666786) (xy 120.824225 -284.715798) (xy 120.803915 -284.762098)
			(xy 120.776262 -284.804424) (xy 120.742018 -284.84162) (xy 120.702119 -284.872673) (xy 120.657653 -284.896734)
			(xy 120.609833 -284.913149) (xy 120.559963 -284.921468) (xy 120.534684 -284.92196) (xy 119.59463 -284.92196)
			(xy 119.569349 -284.921473) (xy 119.519477 -284.913156) (xy 119.471655 -284.896742) (xy 119.427186 -284.872681)
			(xy 119.387285 -284.841628) (xy 119.353039 -284.804431) (xy 119.325383 -284.762104) (xy 119.305072 -284.715802)
			(xy 119.292659 -284.666788) (xy 119.288483 -284.6164) (xy 118.960138 -284.6164) (xy 118.959643 -284.641005)
			(xy 118.951748 -284.689582) (xy 118.936164 -284.736263) (xy 118.913293 -284.77984) (xy 118.883728 -284.819184)
			(xy 118.848235 -284.853276) (xy 118.807732 -284.881232) (xy 118.76327 -284.90233) (xy 118.715999 -284.916022)
			(xy 118.667144 -284.921954) (xy 118.617969 -284.919973) (xy 118.56975 -284.910129) (xy 118.523734 -284.892677)
			(xy 118.481113 -284.86807) (xy 118.442992 -284.836945) (xy 118.410357 -284.800108) (xy 118.384054 -284.758512)
			(xy 118.364763 -284.713236) (xy 118.352986 -284.665452) (xy 118.349026 -284.616398) (xy 118.020913 -284.616398)
			(xy 118.020913 -284.6164) (xy 118.016737 -284.666787) (xy 118.004325 -284.715799) (xy 117.984014 -284.7621)
			(xy 117.95636 -284.804426) (xy 117.922115 -284.841623) (xy 117.882215 -284.872675) (xy 117.837748 -284.896737)
			(xy 117.789927 -284.913151) (xy 117.740056 -284.921469) (xy 117.714776 -284.92196) (xy 116.774722 -284.92196)
			(xy 116.749442 -284.921473) (xy 116.699571 -284.913154) (xy 116.651749 -284.89674) (xy 116.607282 -284.872678)
			(xy 116.567381 -284.841625) (xy 116.533137 -284.804428) (xy 116.505482 -284.762101) (xy 116.485171 -284.7158)
			(xy 116.472759 -284.666787) (xy 116.468583 -284.6164) (xy 116.139976 -284.6164) (xy 116.139481 -284.641005)
			(xy 116.131586 -284.689582) (xy 116.116002 -284.736263) (xy 116.093131 -284.77984) (xy 116.063566 -284.819184)
			(xy 116.028073 -284.853276) (xy 115.98757 -284.881232) (xy 115.943108 -284.90233) (xy 115.895837 -284.916022)
			(xy 115.846982 -284.921954) (xy 115.797807 -284.919973) (xy 115.749588 -284.910129) (xy 115.703572 -284.892677)
			(xy 115.660951 -284.86807) (xy 115.62283 -284.836945) (xy 115.590195 -284.800108) (xy 115.563892 -284.758512)
			(xy 115.544601 -284.713236) (xy 115.532824 -284.665452) (xy 115.528864 -284.616398) (xy 115.199922 -284.616398)
			(xy 115.199427 -284.641005) (xy 115.191532 -284.689582) (xy 115.175948 -284.736263) (xy 115.153077 -284.77984)
			(xy 115.123512 -284.819184) (xy 115.088019 -284.853276) (xy 115.047516 -284.881232) (xy 115.003054 -284.90233)
			(xy 114.955783 -284.916022) (xy 114.906928 -284.921954) (xy 114.857753 -284.919973) (xy 114.809534 -284.910129)
			(xy 114.763518 -284.892677) (xy 114.720897 -284.86807) (xy 114.682776 -284.836945) (xy 114.650141 -284.800108)
			(xy 114.623838 -284.758512) (xy 114.604547 -284.713236) (xy 114.59277 -284.665452) (xy 114.58881 -284.616398)
			(xy 114.260122 -284.616398) (xy 114.259627 -284.641005) (xy 114.251732 -284.689582) (xy 114.236148 -284.736263)
			(xy 114.213277 -284.77984) (xy 114.183712 -284.819184) (xy 114.148219 -284.853276) (xy 114.107716 -284.881232)
			(xy 114.063254 -284.90233) (xy 114.015983 -284.916022) (xy 113.967128 -284.921954) (xy 113.917953 -284.919973)
			(xy 113.869734 -284.910129) (xy 113.823718 -284.892677) (xy 113.781097 -284.86807) (xy 113.742976 -284.836945)
			(xy 113.710341 -284.800108) (xy 113.684038 -284.758512) (xy 113.664747 -284.713236) (xy 113.65297 -284.665452)
			(xy 113.64901 -284.616398) (xy 110.506256 -284.616398) (xy 110.505761 -284.641005) (xy 110.497866 -284.689582)
			(xy 110.482282 -284.736263) (xy 110.459411 -284.77984) (xy 110.429846 -284.819184) (xy 110.394353 -284.853276)
			(xy 110.35385 -284.881232) (xy 110.309388 -284.90233) (xy 110.262117 -284.916022) (xy 110.213262 -284.921954)
			(xy 110.164087 -284.919973) (xy 110.115868 -284.910129) (xy 110.069852 -284.892677) (xy 110.027231 -284.86807)
			(xy 109.98911 -284.836945) (xy 109.956475 -284.800108) (xy 109.930172 -284.758512) (xy 109.910881 -284.713236)
			(xy 109.899104 -284.665452) (xy 109.895144 -284.616398) (xy 109.566456 -284.616398) (xy 109.565961 -284.641005)
			(xy 109.558066 -284.689582) (xy 109.542482 -284.736263) (xy 109.519611 -284.77984) (xy 109.490046 -284.819184)
			(xy 109.454553 -284.853276) (xy 109.41405 -284.881232) (xy 109.369588 -284.90233) (xy 109.322317 -284.916022)
			(xy 109.273462 -284.921954) (xy 109.224287 -284.919973) (xy 109.176068 -284.910129) (xy 109.130052 -284.892677)
			(xy 109.087431 -284.86807) (xy 109.04931 -284.836945) (xy 109.016675 -284.800108) (xy 108.990372 -284.758512)
			(xy 108.971081 -284.713236) (xy 108.959304 -284.665452) (xy 108.955344 -284.616398) (xy 108.626402 -284.616398)
			(xy 108.625907 -284.641005) (xy 108.618012 -284.689582) (xy 108.602428 -284.736263) (xy 108.579557 -284.77984)
			(xy 108.549992 -284.819184) (xy 108.514499 -284.853276) (xy 108.473996 -284.881232) (xy 108.429534 -284.90233)
			(xy 108.382263 -284.916022) (xy 108.333408 -284.921954) (xy 108.284233 -284.919973) (xy 108.236014 -284.910129)
			(xy 108.189998 -284.892677) (xy 108.147377 -284.86807) (xy 108.109256 -284.836945) (xy 108.076621 -284.800108)
			(xy 108.050318 -284.758512) (xy 108.031027 -284.713236) (xy 108.01925 -284.665452) (xy 108.01529 -284.616398)
			(xy 107.687084 -284.616398) (xy 107.687084 -284.6164) (xy 107.68291 -284.666776) (xy 107.670502 -284.715777)
			(xy 107.650198 -284.762069) (xy 107.622553 -284.804387) (xy 107.58832 -284.841579) (xy 107.548433 -284.872629)
			(xy 107.503979 -284.896691) (xy 107.456172 -284.913109) (xy 107.406314 -284.921435) (xy 107.38104 -284.92196)
			(xy 106.440986 -284.92196) (xy 106.41571 -284.921441) (xy 106.365849 -284.913118) (xy 106.318037 -284.896703)
			(xy 106.273579 -284.872641) (xy 106.233687 -284.841591) (xy 106.19945 -284.804398) (xy 106.171802 -284.762078)
			(xy 106.151496 -284.715784) (xy 106.139087 -284.666779) (xy 106.134912 -284.6164) (xy 105.80624 -284.6164)
			(xy 105.805745 -284.641005) (xy 105.79785 -284.689582) (xy 105.782266 -284.736263) (xy 105.759395 -284.77984)
			(xy 105.72983 -284.819184) (xy 105.694337 -284.853276) (xy 105.653834 -284.881232) (xy 105.609372 -284.90233)
			(xy 105.562101 -284.916022) (xy 105.513246 -284.921954) (xy 105.464071 -284.919973) (xy 105.415852 -284.910129)
			(xy 105.369836 -284.892677) (xy 105.327215 -284.86807) (xy 105.289094 -284.836945) (xy 105.256459 -284.800108)
			(xy 105.230156 -284.758512) (xy 105.210865 -284.713236) (xy 105.199088 -284.665452) (xy 105.195128 -284.616398)
			(xy 104.867184 -284.616398) (xy 104.867184 -284.6164) (xy 104.863009 -284.666776) (xy 104.850601 -284.715779)
			(xy 104.830297 -284.762071) (xy 104.802651 -284.80439) (xy 104.768417 -284.841582) (xy 104.728529 -284.872632)
			(xy 104.684074 -284.896694) (xy 104.636265 -284.913111) (xy 104.586406 -284.921436) (xy 104.561132 -284.92196)
			(xy 103.621078 -284.92196) (xy 103.595803 -284.92144) (xy 103.545942 -284.913117) (xy 103.498131 -284.8967)
			(xy 103.453674 -284.872639) (xy 103.413784 -284.841588) (xy 103.379548 -284.804396) (xy 103.351901 -284.762075)
			(xy 103.331596 -284.715782) (xy 103.319187 -284.666778) (xy 103.315012 -284.6164) (xy 102.986332 -284.6164)
			(xy 102.985837 -284.641005) (xy 102.977942 -284.689582) (xy 102.962358 -284.736263) (xy 102.939487 -284.77984)
			(xy 102.909922 -284.819184) (xy 102.874429 -284.853276) (xy 102.833926 -284.881232) (xy 102.789464 -284.90233)
			(xy 102.742193 -284.916022) (xy 102.693338 -284.921954) (xy 102.644163 -284.919973) (xy 102.595944 -284.910129)
			(xy 102.549928 -284.892677) (xy 102.507307 -284.86807) (xy 102.469186 -284.836945) (xy 102.436551 -284.800108)
			(xy 102.410248 -284.758512) (xy 102.390957 -284.713236) (xy 102.37918 -284.665452) (xy 102.37522 -284.616398)
			(xy 102.047284 -284.616398) (xy 102.047284 -284.6164) (xy 102.043109 -284.666777) (xy 102.030701 -284.71578)
			(xy 102.010396 -284.762073) (xy 101.982749 -284.804392) (xy 101.948514 -284.841584) (xy 101.908625 -284.872635)
			(xy 101.864169 -284.896696) (xy 101.816359 -284.913112) (xy 101.766499 -284.921436) (xy 101.741224 -284.92196)
			(xy 100.80117 -284.92196) (xy 100.775895 -284.92144) (xy 100.726035 -284.913115) (xy 100.678226 -284.896698)
			(xy 100.63377 -284.872636) (xy 100.593881 -284.841585) (xy 100.559646 -284.804393) (xy 100.532 -284.762073)
			(xy 100.511695 -284.71578) (xy 100.499287 -284.666777) (xy 100.495112 -284.6164) (xy 100.166424 -284.6164)
			(xy 100.165929 -284.641005) (xy 100.158034 -284.689582) (xy 100.14245 -284.736263) (xy 100.119579 -284.77984)
			(xy 100.090014 -284.819184) (xy 100.054521 -284.853276) (xy 100.014018 -284.881232) (xy 99.969556 -284.90233)
			(xy 99.922285 -284.916022) (xy 99.87343 -284.921954) (xy 99.824255 -284.919973) (xy 99.776036 -284.910129)
			(xy 99.73002 -284.892677) (xy 99.687399 -284.86807) (xy 99.649278 -284.836945) (xy 99.616643 -284.800108)
			(xy 99.59034 -284.758512) (xy 99.571049 -284.713236) (xy 99.559272 -284.665452) (xy 99.555312 -284.616398)
			(xy 99.227213 -284.616398) (xy 99.227213 -284.6164) (xy 99.223037 -284.666788) (xy 99.210624 -284.715802)
			(xy 99.190312 -284.762104) (xy 99.162656 -284.804431) (xy 99.12841 -284.841628) (xy 99.088508 -284.87268)
			(xy 99.044038 -284.896741) (xy 98.996215 -284.913153) (xy 98.946343 -284.92147) (xy 98.921062 -284.92196)
			(xy 97.981008 -284.92196) (xy 97.955729 -284.921472) (xy 97.905859 -284.913151) (xy 97.85804 -284.896736)
			(xy 97.813574 -284.872673) (xy 97.773676 -284.84162) (xy 97.739433 -284.804423) (xy 97.71178 -284.762098)
			(xy 97.69147 -284.715797) (xy 97.679059 -284.666786) (xy 97.674883 -284.6164) (xy 97.346262 -284.6164)
			(xy 97.345767 -284.641005) (xy 97.337872 -284.689582) (xy 97.322288 -284.736263) (xy 97.299417 -284.77984)
			(xy 97.269852 -284.819184) (xy 97.234359 -284.853276) (xy 97.193856 -284.881232) (xy 97.149394 -284.90233)
			(xy 97.102123 -284.916022) (xy 97.053268 -284.921954) (xy 97.004093 -284.919973) (xy 96.955874 -284.910129)
			(xy 96.909858 -284.892677) (xy 96.867237 -284.86807) (xy 96.829116 -284.836945) (xy 96.796481 -284.800108)
			(xy 96.770178 -284.758512) (xy 96.750887 -284.713236) (xy 96.73911 -284.665452) (xy 96.73515 -284.616398)
			(xy 96.416876 -284.616398) (xy 96.416364 -284.641844) (xy 96.4082 -284.692078) (xy 96.392084 -284.740352)
			(xy 96.368433 -284.785415) (xy 96.33786 -284.826101) (xy 96.301156 -284.861356) (xy 96.259272 -284.890266)
			(xy 96.213293 -284.912083) (xy 96.164409 -284.926243) (xy 96.113888 -284.932377) (xy 96.063036 -284.930328)
			(xy 96.013172 -284.920148) (xy 95.965586 -284.902101) (xy 95.921512 -284.876655) (xy 95.88209 -284.844468)
			(xy 95.848342 -284.806374) (xy 95.821141 -284.76336) (xy 95.801193 -284.71654) (xy 95.789014 -284.667126)
			(xy 95.784919 -284.616398) (xy 95.466408 -284.616398) (xy 95.465913 -284.641005) (xy 95.458018 -284.689582)
			(xy 95.442434 -284.736263) (xy 95.419563 -284.77984) (xy 95.389998 -284.819184) (xy 95.354505 -284.853276)
			(xy 95.314002 -284.881232) (xy 95.26954 -284.90233) (xy 95.222269 -284.916022) (xy 95.173414 -284.921954)
			(xy 95.124239 -284.919973) (xy 95.07602 -284.910129) (xy 95.030004 -284.892677) (xy 94.987383 -284.86807)
			(xy 94.949262 -284.836945) (xy 94.916627 -284.800108) (xy 94.890324 -284.758512) (xy 94.871033 -284.713236)
			(xy 94.859256 -284.665452) (xy 94.855296 -284.616398) (xy 94.536768 -284.616398) (xy 94.536256 -284.641844)
			(xy 94.528092 -284.692078) (xy 94.511976 -284.740352) (xy 94.488325 -284.785415) (xy 94.457752 -284.826101)
			(xy 94.421048 -284.861356) (xy 94.379164 -284.890266) (xy 94.333185 -284.912083) (xy 94.284301 -284.926243)
			(xy 94.23378 -284.932377) (xy 94.182928 -284.930328) (xy 94.133064 -284.920148) (xy 94.085478 -284.902101)
			(xy 94.041404 -284.876655) (xy 94.001982 -284.844468) (xy 93.968234 -284.806374) (xy 93.941033 -284.76336)
			(xy 93.921085 -284.71654) (xy 93.908906 -284.667126) (xy 93.904811 -284.616398) (xy 93.5863 -284.616398)
			(xy 93.585834 -284.640248) (xy 93.578405 -284.687366) (xy 93.563744 -284.732756) (xy 93.542206 -284.775317)
			(xy 93.514315 -284.814012) (xy 93.480748 -284.847903) (xy 93.442322 -284.876165) (xy 93.399971 -284.898111)
			(xy 93.354723 -284.913208) (xy 93.331284 -284.917642) (xy 93.322648 -284.919166) (xy 93.294708 -284.939486)
			(xy 93.289835 -284.943239) (xy 93.281878 -284.952613) (xy 93.27896 -284.958028) (xy 93.248226 -285.020512)
			(xy 93.24721 -285.023052) (xy 93.243637 -285.032421) (xy 93.243374 -285.052456) (xy 93.246702 -285.061914)
			(xy 93.246956 -285.062676) (xy 93.250004 -285.068518) (xy 93.294708 -285.14548) (xy 93.305178 -285.16396)
			(xy 93.323611 -285.202229) (xy 93.331538 -285.221934) (xy 93.331538 -285.222188) (xy 93.334234 -285.228387)
			(xy 93.342348 -285.239194) (xy 93.34754 -285.243524) (xy 93.352874 -285.247588) (xy 93.365066 -285.252922)
			(xy 93.45803 -285.265114) (xy 93.464894 -285.265778) (xy 93.478541 -285.26384) (xy 93.484954 -285.261304)
			(xy 93.490983 -285.258504) (xy 93.501407 -285.250264) (xy 93.505528 -285.245048) (xy 93.505782 -285.244794)
			(xy 93.520286 -285.225966) (xy 93.554143 -285.192612) (xy 93.592756 -285.164903) (xy 93.635194 -285.143508)
			(xy 93.680434 -285.128943) (xy 93.727383 -285.12156) (xy 93.751146 -285.121096) (xy 93.776398 -285.121621)
			(xy 93.826214 -285.129941) (xy 93.87398 -285.146345) (xy 93.918396 -285.170388) (xy 93.958249 -285.201412)
			(xy 93.992452 -285.238572) (xy 94.020074 -285.280855) (xy 94.04036 -285.327107) (xy 94.052757 -285.376067)
			(xy 94.056927 -285.4264) (xy 94.056927 -285.426404) (xy 94.374711 -285.426404) (xy 94.378806 -285.375676)
			(xy 94.390985 -285.326262) (xy 94.410933 -285.279442) (xy 94.438134 -285.236428) (xy 94.471882 -285.198334)
			(xy 94.511304 -285.166147) (xy 94.555378 -285.140701) (xy 94.602964 -285.122654) (xy 94.652828 -285.112474)
			(xy 94.70368 -285.110425) (xy 94.754201 -285.116559) (xy 94.803085 -285.130719) (xy 94.849064 -285.152536)
			(xy 94.890948 -285.181446) (xy 94.927652 -285.216701) (xy 94.958225 -285.257387) (xy 94.981876 -285.30245)
			(xy 94.997992 -285.350724) (xy 95.006156 -285.400958) (xy 95.006668 -285.426404) (xy 95.314765 -285.426404)
			(xy 95.31886 -285.375676) (xy 95.331039 -285.326262) (xy 95.350987 -285.279442) (xy 95.378188 -285.236428)
			(xy 95.411936 -285.198334) (xy 95.451358 -285.166147) (xy 95.495432 -285.140701) (xy 95.543018 -285.122654)
			(xy 95.592882 -285.112474) (xy 95.643734 -285.110425) (xy 95.694255 -285.116559) (xy 95.743139 -285.130719)
			(xy 95.789118 -285.152536) (xy 95.831002 -285.181446) (xy 95.867706 -285.216701) (xy 95.898279 -285.257387)
			(xy 95.92193 -285.30245) (xy 95.938046 -285.350724) (xy 95.94621 -285.400958) (xy 95.946722 -285.426404)
			(xy 96.26525 -285.426404) (xy 96.26921 -285.37735) (xy 96.280987 -285.329566) (xy 96.300278 -285.28429)
			(xy 96.326581 -285.242694) (xy 96.359216 -285.205857) (xy 96.397337 -285.174732) (xy 96.439958 -285.150125)
			(xy 96.485974 -285.132673) (xy 96.534193 -285.122829) (xy 96.583368 -285.120848) (xy 96.632223 -285.12678)
			(xy 96.679494 -285.140472) (xy 96.723956 -285.16157) (xy 96.764459 -285.189526) (xy 96.799952 -285.223618)
			(xy 96.829517 -285.262962) (xy 96.852388 -285.306539) (xy 96.867972 -285.35322) (xy 96.875867 -285.401797)
			(xy 96.876362 -285.426404) (xy 96.875867 -285.451011) (xy 96.867972 -285.499588) (xy 96.852388 -285.546269)
			(xy 96.829517 -285.589846) (xy 96.799952 -285.62919) (xy 96.764459 -285.663282) (xy 96.723956 -285.691238)
			(xy 96.679494 -285.712336) (xy 96.632223 -285.726028) (xy 96.583368 -285.73196) (xy 96.534193 -285.729979)
			(xy 96.485974 -285.720135) (xy 96.439958 -285.702683) (xy 96.397337 -285.678076) (xy 96.359216 -285.646951)
			(xy 96.326581 -285.610114) (xy 96.300278 -285.568518) (xy 96.280987 -285.523242) (xy 96.26921 -285.475458)
			(xy 96.26525 -285.426404) (xy 95.946722 -285.426404) (xy 95.94621 -285.45185) (xy 95.938046 -285.502084)
			(xy 95.92193 -285.550358) (xy 95.898279 -285.595421) (xy 95.867706 -285.636107) (xy 95.831002 -285.671362)
			(xy 95.789118 -285.700272) (xy 95.743139 -285.722089) (xy 95.694255 -285.736249) (xy 95.643734 -285.742383)
			(xy 95.592882 -285.740334) (xy 95.543018 -285.730154) (xy 95.495432 -285.712107) (xy 95.451358 -285.686661)
			(xy 95.411936 -285.654474) (xy 95.378188 -285.61638) (xy 95.350987 -285.573366) (xy 95.331039 -285.526546)
			(xy 95.31886 -285.477132) (xy 95.314765 -285.426404) (xy 95.006668 -285.426404) (xy 95.006156 -285.45185)
			(xy 94.997992 -285.502084) (xy 94.981876 -285.550358) (xy 94.958225 -285.595421) (xy 94.927652 -285.636107)
			(xy 94.890948 -285.671362) (xy 94.849064 -285.700272) (xy 94.803085 -285.722089) (xy 94.754201 -285.736249)
			(xy 94.70368 -285.742383) (xy 94.652828 -285.740334) (xy 94.602964 -285.730154) (xy 94.555378 -285.712107)
			(xy 94.511304 -285.686661) (xy 94.471882 -285.654474) (xy 94.438134 -285.61638) (xy 94.410933 -285.573366)
			(xy 94.390985 -285.526546) (xy 94.378806 -285.477132) (xy 94.374711 -285.426404) (xy 94.056927 -285.426404)
			(xy 94.052757 -285.476733) (xy 94.04036 -285.525693) (xy 94.020074 -285.571945) (xy 93.992452 -285.614228)
			(xy 93.958249 -285.651388) (xy 93.918396 -285.682412) (xy 93.87398 -285.706455) (xy 93.826214 -285.722859)
			(xy 93.776398 -285.731179) (xy 93.751146 -285.731712) (xy 93.72738 -285.731262) (xy 93.680423 -285.723898)
			(xy 93.635176 -285.709342) (xy 93.592733 -285.687945) (xy 93.554122 -285.660225) (xy 93.520276 -285.626854)
			(xy 93.505782 -285.608014) (xy 93.505782 -285.60776) (xy 93.505528 -285.60776) (xy 93.501372 -285.60258)
			(xy 93.490956 -285.594347) (xy 93.484954 -285.591504) (xy 93.478545 -285.588958) (xy 93.464895 -285.587038)
			(xy 93.45803 -285.587694) (xy 93.372178 -285.599124) (xy 93.365418 -285.600198) (xy 93.352794 -285.605474)
			(xy 93.347286 -285.609538) (xy 93.341952 -285.613602) (xy 93.334078 -285.62427) (xy 93.331538 -285.630874)
			(xy 93.315987 -285.668545) (xy 93.275562 -285.739307) (xy 93.25102 -285.771844) (xy 93.25102 -285.772098)
			(xy 93.246981 -285.7775) (xy 93.241565 -285.789848) (xy 93.240352 -285.796482) (xy 93.238574 -285.80969)
			(xy 93.276928 -285.9024) (xy 93.279688 -285.90856) (xy 93.287935 -285.919238) (xy 93.293184 -285.923482)
			(xy 93.298518 -285.927546) (xy 93.31071 -285.932372) (xy 93.317822 -285.933388) (xy 93.342181 -285.936853)
			(xy 93.389433 -285.950555) (xy 93.433876 -285.971657) (xy 93.474361 -285.999611) (xy 93.50984 -286.033695)
			(xy 93.539395 -286.073026) (xy 93.562262 -286.116587) (xy 93.577848 -286.163252) (xy 93.585751 -286.211811)
			(xy 93.5863 -286.23641) (xy 93.904811 -286.23641) (xy 93.908906 -286.185682) (xy 93.921085 -286.136268)
			(xy 93.941033 -286.089448) (xy 93.968234 -286.046434) (xy 94.001982 -286.00834) (xy 94.041404 -285.976153)
			(xy 94.085478 -285.950707) (xy 94.133064 -285.93266) (xy 94.182928 -285.92248) (xy 94.23378 -285.920431)
			(xy 94.284301 -285.926565) (xy 94.333185 -285.940725) (xy 94.379164 -285.962542) (xy 94.421048 -285.991452)
			(xy 94.457752 -286.026707) (xy 94.488325 -286.067393) (xy 94.511976 -286.112456) (xy 94.528092 -286.16073)
			(xy 94.536256 -286.210964) (xy 94.536768 -286.23641) (xy 94.855296 -286.23641) (xy 94.859256 -286.187356)
			(xy 94.871033 -286.139572) (xy 94.890324 -286.094296) (xy 94.916627 -286.0527) (xy 94.949262 -286.015863)
			(xy 94.987383 -285.984738) (xy 95.030004 -285.960131) (xy 95.07602 -285.942679) (xy 95.124239 -285.932835)
			(xy 95.173414 -285.930854) (xy 95.222269 -285.936786) (xy 95.26954 -285.950478) (xy 95.314002 -285.971576)
			(xy 95.354505 -285.999532) (xy 95.389998 -286.033624) (xy 95.419563 -286.072968) (xy 95.442434 -286.116545)
			(xy 95.458018 -286.163226) (xy 95.465913 -286.211803) (xy 95.466408 -286.23641) (xy 95.784919 -286.23641)
			(xy 95.789014 -286.185682) (xy 95.801193 -286.136268) (xy 95.821141 -286.089448) (xy 95.848342 -286.046434)
			(xy 95.88209 -286.00834) (xy 95.921512 -285.976153) (xy 95.965586 -285.950707) (xy 96.013172 -285.93266)
			(xy 96.063036 -285.92248) (xy 96.113888 -285.920431) (xy 96.164409 -285.926565) (xy 96.213293 -285.940725)
			(xy 96.259272 -285.962542) (xy 96.301156 -285.991452) (xy 96.33786 -286.026707) (xy 96.368433 -286.067393)
			(xy 96.392084 -286.112456) (xy 96.4082 -286.16073) (xy 96.416364 -286.210964) (xy 96.416876 -286.23641)
			(xy 96.416364 -286.261856) (xy 96.4082 -286.31209) (xy 96.392084 -286.360364) (xy 96.368433 -286.405427)
			(xy 96.33786 -286.446113) (xy 96.301156 -286.481368) (xy 96.259272 -286.510278) (xy 96.213293 -286.532095)
			(xy 96.164409 -286.546255) (xy 96.113888 -286.552389) (xy 96.063036 -286.55034) (xy 96.013172 -286.54016)
			(xy 95.965586 -286.522113) (xy 95.921512 -286.496667) (xy 95.88209 -286.46448) (xy 95.848342 -286.426386)
			(xy 95.821141 -286.383372) (xy 95.801193 -286.336552) (xy 95.789014 -286.287138) (xy 95.784919 -286.23641)
			(xy 95.466408 -286.23641) (xy 95.465913 -286.261017) (xy 95.458018 -286.309594) (xy 95.442434 -286.356275)
			(xy 95.419563 -286.399852) (xy 95.389998 -286.439196) (xy 95.354505 -286.473288) (xy 95.314002 -286.501244)
			(xy 95.26954 -286.522342) (xy 95.222269 -286.536034) (xy 95.173414 -286.541966) (xy 95.124239 -286.539985)
			(xy 95.07602 -286.530141) (xy 95.030004 -286.512689) (xy 94.987383 -286.488082) (xy 94.949262 -286.456957)
			(xy 94.916627 -286.42012) (xy 94.890324 -286.378524) (xy 94.871033 -286.333248) (xy 94.859256 -286.285464)
			(xy 94.855296 -286.23641) (xy 94.536768 -286.23641) (xy 94.536256 -286.261856) (xy 94.528092 -286.31209)
			(xy 94.511976 -286.360364) (xy 94.488325 -286.405427) (xy 94.457752 -286.446113) (xy 94.421048 -286.481368)
			(xy 94.379164 -286.510278) (xy 94.333185 -286.532095) (xy 94.284301 -286.546255) (xy 94.23378 -286.552389)
			(xy 94.182928 -286.55034) (xy 94.133064 -286.54016) (xy 94.085478 -286.522113) (xy 94.041404 -286.496667)
			(xy 94.001982 -286.46448) (xy 93.968234 -286.426386) (xy 93.941033 -286.383372) (xy 93.921085 -286.336552)
			(xy 93.908906 -286.287138) (xy 93.904811 -286.23641) (xy 93.5863 -286.23641) (xy 93.585833 -286.260259)
			(xy 93.578403 -286.307376) (xy 93.56374 -286.352765) (xy 93.542201 -286.395324) (xy 93.51431 -286.434018)
			(xy 93.480744 -286.467907) (xy 93.442318 -286.496167) (xy 93.399968 -286.518112) (xy 93.354721 -286.533209)
			(xy 93.331284 -286.537654) (xy 93.322648 -286.539178) (xy 93.294708 -286.559498) (xy 93.289795 -286.563287)
			(xy 93.281823 -286.57279) (xy 93.27896 -286.578294) (xy 93.247464 -286.642556) (xy 93.243174 -286.653957)
			(xy 93.244632 -286.678234) (xy 93.250258 -286.689038) (xy 93.294708 -286.765238) (xy 93.305179 -286.783717)
			(xy 93.323615 -286.821986) (xy 93.331538 -286.841692) (xy 93.331538 -286.841946) (xy 93.33423 -286.848148)
			(xy 93.342339 -286.858962) (xy 93.34754 -286.863282) (xy 93.352874 -286.867346) (xy 93.365066 -286.87268)
			(xy 93.45803 -286.884872) (xy 93.464894 -286.885537) (xy 93.47854 -286.883597) (xy 93.484954 -286.881062)
			(xy 93.490981 -286.87826) (xy 93.5014 -286.870016) (xy 93.505528 -286.864806) (xy 93.505782 -286.864552)
			(xy 93.520284 -286.84572) (xy 93.554138 -286.812361) (xy 93.592751 -286.784647) (xy 93.63519 -286.763248)
			(xy 93.680431 -286.74868) (xy 93.727382 -286.741295) (xy 93.751146 -286.740854) (xy 93.776402 -286.741379)
			(xy 93.826224 -286.7497) (xy 93.873997 -286.766107) (xy 93.918419 -286.790153) (xy 93.958277 -286.821181)
			(xy 93.992486 -286.858347) (xy 94.020111 -286.900635) (xy 94.040399 -286.946894) (xy 94.052798 -286.99586)
			(xy 94.056966 -287.046162) (xy 94.374711 -287.046162) (xy 94.378806 -286.995434) (xy 94.390985 -286.94602)
			(xy 94.410933 -286.8992) (xy 94.438134 -286.856186) (xy 94.471882 -286.818092) (xy 94.511304 -286.785905)
			(xy 94.555378 -286.760459) (xy 94.602964 -286.742412) (xy 94.652828 -286.732232) (xy 94.70368 -286.730183)
			(xy 94.754201 -286.736317) (xy 94.803085 -286.750477) (xy 94.849064 -286.772294) (xy 94.890948 -286.801204)
			(xy 94.927652 -286.836459) (xy 94.958225 -286.877145) (xy 94.981876 -286.922208) (xy 94.997992 -286.970482)
			(xy 95.006156 -287.020716) (xy 95.006668 -287.046162) (xy 95.314765 -287.046162) (xy 95.31886 -286.995434)
			(xy 95.331039 -286.94602) (xy 95.350987 -286.8992) (xy 95.378188 -286.856186) (xy 95.411936 -286.818092)
			(xy 95.451358 -286.785905) (xy 95.495432 -286.760459) (xy 95.543018 -286.742412) (xy 95.592882 -286.732232)
			(xy 95.643734 -286.730183) (xy 95.694255 -286.736317) (xy 95.743139 -286.750477) (xy 95.789118 -286.772294)
			(xy 95.831002 -286.801204) (xy 95.867706 -286.836459) (xy 95.898279 -286.877145) (xy 95.92193 -286.922208)
			(xy 95.938046 -286.970482) (xy 95.94621 -287.020716) (xy 95.946722 -287.046162) (xy 96.26525 -287.046162)
			(xy 96.26921 -286.997108) (xy 96.280987 -286.949324) (xy 96.300278 -286.904048) (xy 96.326581 -286.862452)
			(xy 96.359216 -286.825615) (xy 96.397337 -286.79449) (xy 96.439958 -286.769883) (xy 96.485974 -286.752431)
			(xy 96.534193 -286.742587) (xy 96.583368 -286.740606) (xy 96.632223 -286.746538) (xy 96.679494 -286.76023)
			(xy 96.723956 -286.781328) (xy 96.764459 -286.809284) (xy 96.799952 -286.843376) (xy 96.829517 -286.88272)
			(xy 96.852388 -286.926297) (xy 96.867972 -286.972978) (xy 96.875867 -287.021555) (xy 96.876362 -287.046162)
			(xy 96.875867 -287.070769) (xy 96.867972 -287.119346) (xy 96.852388 -287.166027) (xy 96.829517 -287.209604)
			(xy 96.799952 -287.248948) (xy 96.764459 -287.28304) (xy 96.723956 -287.310996) (xy 96.679494 -287.332094)
			(xy 96.632223 -287.345786) (xy 96.583368 -287.351718) (xy 96.534193 -287.349737) (xy 96.485974 -287.339893)
			(xy 96.439958 -287.322441) (xy 96.397337 -287.297834) (xy 96.359216 -287.266709) (xy 96.326581 -287.229872)
			(xy 96.300278 -287.188276) (xy 96.280987 -287.143) (xy 96.26921 -287.095216) (xy 96.26525 -287.046162)
			(xy 95.946722 -287.046162) (xy 95.94621 -287.071608) (xy 95.938046 -287.121842) (xy 95.92193 -287.170116)
			(xy 95.898279 -287.215179) (xy 95.867706 -287.255865) (xy 95.831002 -287.29112) (xy 95.789118 -287.32003)
			(xy 95.743139 -287.341847) (xy 95.694255 -287.356007) (xy 95.643734 -287.362141) (xy 95.592882 -287.360092)
			(xy 95.543018 -287.349912) (xy 95.495432 -287.331865) (xy 95.451358 -287.306419) (xy 95.411936 -287.274232)
			(xy 95.378188 -287.236138) (xy 95.350987 -287.193124) (xy 95.331039 -287.146304) (xy 95.31886 -287.09689)
			(xy 95.314765 -287.046162) (xy 95.006668 -287.046162) (xy 95.006156 -287.071608) (xy 94.997992 -287.121842)
			(xy 94.981876 -287.170116) (xy 94.958225 -287.215179) (xy 94.927652 -287.255865) (xy 94.890948 -287.29112)
			(xy 94.849064 -287.32003) (xy 94.803085 -287.341847) (xy 94.754201 -287.356007) (xy 94.70368 -287.362141)
			(xy 94.652828 -287.360092) (xy 94.602964 -287.349912) (xy 94.555378 -287.331865) (xy 94.511304 -287.306419)
			(xy 94.471882 -287.274232) (xy 94.438134 -287.236138) (xy 94.410933 -287.193124) (xy 94.390985 -287.146304)
			(xy 94.378806 -287.09689) (xy 94.374711 -287.046162) (xy 94.056966 -287.046162) (xy 94.056969 -287.0462)
			(xy 94.052798 -287.09654) (xy 94.040399 -287.145506) (xy 94.020111 -287.191765) (xy 93.992486 -287.234053)
			(xy 93.958277 -287.271219) (xy 93.918419 -287.302247) (xy 93.873997 -287.326293) (xy 93.826224 -287.3427)
			(xy 93.776402 -287.351021) (xy 93.751146 -287.35147) (xy 93.727381 -287.351019) (xy 93.680425 -287.343655)
			(xy 93.635179 -287.329097) (xy 93.592738 -287.307699) (xy 93.554129 -287.279977) (xy 93.520287 -287.246603)
			(xy 93.505782 -287.227772) (xy 93.505782 -287.227518) (xy 93.505528 -287.227518) (xy 93.501369 -287.222341)
			(xy 93.490951 -287.214114) (xy 93.484954 -287.211262) (xy 93.478545 -287.208718) (xy 93.464896 -287.2068)
			(xy 93.45803 -287.207452) (xy 93.372178 -287.218882) (xy 93.365419 -287.219958) (xy 93.352798 -287.225239)
			(xy 93.347286 -287.229296) (xy 93.341952 -287.23336) (xy 93.334078 -287.244028) (xy 93.331538 -287.250632)
			(xy 93.315969 -287.288333) (xy 93.275414 -287.359102) (xy 93.250766 -287.391602) (xy 93.250766 -287.39211)
			(xy 93.250258 -287.392364) (xy 93.246449 -287.397692) (xy 93.241418 -287.409779) (xy 93.240352 -287.41624)
			(xy 93.239336 -287.422844) (xy 93.24086 -287.436052) (xy 93.260164 -287.48228) (xy 93.260164 -287.482788)
			(xy 93.276928 -287.522412) (xy 93.279749 -287.528481) (xy 93.287989 -287.53902) (xy 93.293184 -287.54324)
			(xy 93.298518 -287.547304) (xy 93.310456 -287.55213) (xy 93.317568 -287.553146) (xy 93.341952 -287.556608)
			(xy 93.389253 -287.570313) (xy 93.433744 -287.591426) (xy 93.474273 -287.6194) (xy 93.509792 -287.653513)
			(xy 93.53938 -287.69288) (xy 93.562272 -287.736482) (xy 93.577875 -287.783192) (xy 93.585785 -287.831799)
			(xy 93.5863 -287.856422) (xy 93.904811 -287.856422) (xy 93.908906 -287.805694) (xy 93.921085 -287.75628)
			(xy 93.941033 -287.70946) (xy 93.968234 -287.666446) (xy 94.001982 -287.628352) (xy 94.041404 -287.596165)
			(xy 94.085478 -287.570719) (xy 94.133064 -287.552672) (xy 94.182928 -287.542492) (xy 94.23378 -287.540443)
			(xy 94.284301 -287.546577) (xy 94.333185 -287.560737) (xy 94.379164 -287.582554) (xy 94.421048 -287.611464)
			(xy 94.457752 -287.646719) (xy 94.488325 -287.687405) (xy 94.511976 -287.732468) (xy 94.528092 -287.780742)
			(xy 94.536256 -287.830976) (xy 94.536768 -287.856422) (xy 94.855296 -287.856422) (xy 94.859256 -287.807368)
			(xy 94.871033 -287.759584) (xy 94.890324 -287.714308) (xy 94.916627 -287.672712) (xy 94.949262 -287.635875)
			(xy 94.987383 -287.60475) (xy 95.030004 -287.580143) (xy 95.07602 -287.562691) (xy 95.124239 -287.552847)
			(xy 95.173414 -287.550866) (xy 95.222269 -287.556798) (xy 95.26954 -287.57049) (xy 95.314002 -287.591588)
			(xy 95.354505 -287.619544) (xy 95.389998 -287.653636) (xy 95.419563 -287.69298) (xy 95.442434 -287.736557)
			(xy 95.458018 -287.783238) (xy 95.465913 -287.831815) (xy 95.466408 -287.856422) (xy 95.465913 -287.881029)
			(xy 95.458018 -287.929606) (xy 95.442434 -287.976287) (xy 95.419563 -288.019864) (xy 95.389998 -288.059208)
			(xy 95.354505 -288.0933) (xy 95.314002 -288.121256) (xy 95.26954 -288.142354) (xy 95.222269 -288.156046)
			(xy 95.173414 -288.161978) (xy 95.124239 -288.159997) (xy 95.07602 -288.150153) (xy 95.030004 -288.132701)
			(xy 94.987383 -288.108094) (xy 94.949262 -288.076969) (xy 94.916627 -288.040132) (xy 94.890324 -287.998536)
			(xy 94.871033 -287.95326) (xy 94.859256 -287.905476) (xy 94.855296 -287.856422) (xy 94.536768 -287.856422)
			(xy 94.536256 -287.881868) (xy 94.528092 -287.932102) (xy 94.511976 -287.980376) (xy 94.488325 -288.025439)
			(xy 94.457752 -288.066125) (xy 94.421048 -288.10138) (xy 94.379164 -288.13029) (xy 94.333185 -288.152107)
			(xy 94.284301 -288.166267) (xy 94.23378 -288.172401) (xy 94.182928 -288.170352) (xy 94.133064 -288.160172)
			(xy 94.085478 -288.142125) (xy 94.041404 -288.116679) (xy 94.001982 -288.084492) (xy 93.968234 -288.046398)
			(xy 93.941033 -288.003384) (xy 93.921085 -287.956564) (xy 93.908906 -287.90715) (xy 93.904811 -287.856422)
			(xy 93.5863 -287.856422) (xy 93.585832 -287.880271) (xy 93.5784 -287.927386) (xy 93.563737 -287.972773)
			(xy 93.542197 -288.01533) (xy 93.514305 -288.054023) (xy 93.480739 -288.087911) (xy 93.442314 -288.11617)
			(xy 93.399964 -288.138114) (xy 93.354719 -288.153209) (xy 93.331284 -288.157666) (xy 93.322648 -288.15919)
			(xy 93.294708 -288.17951) (xy 93.289796 -288.1833) (xy 93.281826 -288.192804) (xy 93.27896 -288.198306)
			(xy 93.247464 -288.262568) (xy 93.243177 -288.273968) (xy 93.24464 -288.298243) (xy 93.250258 -288.30905)
			(xy 93.294708 -288.38525) (xy 93.305179 -288.403729) (xy 93.323614 -288.441998) (xy 93.331538 -288.461704)
			(xy 93.331538 -288.461958) (xy 93.334231 -288.468159) (xy 93.342342 -288.478971) (xy 93.34754 -288.483294)
			(xy 93.352874 -288.487358) (xy 93.365066 -288.492692) (xy 93.45803 -288.504884) (xy 93.464894 -288.505549)
			(xy 93.478541 -288.503609) (xy 93.484954 -288.501074) (xy 93.490982 -288.498273) (xy 93.501402 -288.49003)
			(xy 93.505528 -288.484818) (xy 93.505782 -288.484564) (xy 93.520284 -288.465732) (xy 93.554137 -288.432371)
			(xy 93.59275 -288.404656) (xy 93.635188 -288.383256) (xy 93.68043 -288.368687) (xy 93.727382 -288.361302)
			(xy 93.751146 -288.360866) (xy 93.776401 -288.361391) (xy 93.826221 -288.369712) (xy 93.873992 -288.386118)
			(xy 93.918412 -288.410163) (xy 93.958269 -288.44119) (xy 93.992476 -288.478354) (xy 94.0201 -288.520641)
			(xy 94.040388 -288.566898) (xy 94.052786 -288.615862) (xy 94.056955 -288.666174) (xy 94.374711 -288.666174)
			(xy 94.378806 -288.615446) (xy 94.390985 -288.566032) (xy 94.410933 -288.519212) (xy 94.438134 -288.476198)
			(xy 94.471882 -288.438104) (xy 94.511304 -288.405917) (xy 94.555378 -288.380471) (xy 94.602964 -288.362424)
			(xy 94.652828 -288.352244) (xy 94.70368 -288.350195) (xy 94.754201 -288.356329) (xy 94.803085 -288.370489)
			(xy 94.849064 -288.392306) (xy 94.890948 -288.421216) (xy 94.927652 -288.456471) (xy 94.958225 -288.497157)
			(xy 94.981876 -288.54222) (xy 94.997992 -288.590494) (xy 95.006156 -288.640728) (xy 95.006668 -288.666174)
			(xy 95.314765 -288.666174) (xy 95.31886 -288.615446) (xy 95.331039 -288.566032) (xy 95.350987 -288.519212)
			(xy 95.378188 -288.476198) (xy 95.411936 -288.438104) (xy 95.451358 -288.405917) (xy 95.495432 -288.380471)
			(xy 95.543018 -288.362424) (xy 95.592882 -288.352244) (xy 95.643734 -288.350195) (xy 95.694255 -288.356329)
			(xy 95.743139 -288.370489) (xy 95.789118 -288.392306) (xy 95.831002 -288.421216) (xy 95.867706 -288.456471)
			(xy 95.898279 -288.497157) (xy 95.92193 -288.54222) (xy 95.938046 -288.590494) (xy 95.94621 -288.640728)
			(xy 95.946722 -288.666174) (xy 95.94621 -288.69162) (xy 95.938046 -288.741854) (xy 95.92193 -288.790128)
			(xy 95.898279 -288.835191) (xy 95.867706 -288.875877) (xy 95.831002 -288.911132) (xy 95.789118 -288.940042)
			(xy 95.743139 -288.961859) (xy 95.694255 -288.976019) (xy 95.643734 -288.982153) (xy 95.592882 -288.980104)
			(xy 95.543018 -288.969924) (xy 95.495432 -288.951877) (xy 95.451358 -288.926431) (xy 95.411936 -288.894244)
			(xy 95.378188 -288.85615) (xy 95.350987 -288.813136) (xy 95.331039 -288.766316) (xy 95.31886 -288.716902)
			(xy 95.314765 -288.666174) (xy 95.006668 -288.666174) (xy 95.006156 -288.69162) (xy 94.997992 -288.741854)
			(xy 94.981876 -288.790128) (xy 94.958225 -288.835191) (xy 94.927652 -288.875877) (xy 94.890948 -288.911132)
			(xy 94.849064 -288.940042) (xy 94.803085 -288.961859) (xy 94.754201 -288.976019) (xy 94.70368 -288.982153)
			(xy 94.652828 -288.980104) (xy 94.602964 -288.969924) (xy 94.555378 -288.951877) (xy 94.511304 -288.926431)
			(xy 94.471882 -288.894244) (xy 94.438134 -288.85615) (xy 94.410933 -288.813136) (xy 94.390985 -288.766316)
			(xy 94.378806 -288.716902) (xy 94.374711 -288.666174) (xy 94.056955 -288.666174) (xy 94.056957 -288.6662)
			(xy 94.052786 -288.716538) (xy 94.040388 -288.765502) (xy 94.0201 -288.811759) (xy 93.992476 -288.854046)
			(xy 93.958269 -288.89121) (xy 93.918412 -288.922237) (xy 93.873992 -288.946282) (xy 93.826221 -288.962688)
			(xy 93.776401 -288.971009) (xy 93.751146 -288.971482) (xy 93.727381 -288.971031) (xy 93.680424 -288.963667)
			(xy 93.635178 -288.94911) (xy 93.592736 -288.927712) (xy 93.554127 -288.899991) (xy 93.520284 -288.866617)
			(xy 93.505782 -288.847784) (xy 93.505782 -288.84753) (xy 93.505528 -288.84753) (xy 93.50137 -288.842352)
			(xy 93.490952 -288.834123) (xy 93.484954 -288.831274) (xy 93.478545 -288.82873) (xy 93.464896 -288.826811)
			(xy 93.45803 -288.827464) (xy 93.372178 -288.838894) (xy 93.365417 -288.839967) (xy 93.352792 -288.845241)
			(xy 93.347286 -288.849308) (xy 93.341952 -288.853372) (xy 93.334078 -288.86404) (xy 93.331538 -288.870644)
			(xy 93.315989 -288.908316) (xy 93.275567 -288.979081) (xy 93.25102 -289.011614) (xy 93.25102 -289.011868)
			(xy 93.246988 -289.017273) (xy 93.241589 -289.029623) (xy 93.240352 -289.036252) (xy 93.238574 -289.04946)
			(xy 93.276928 -289.14217) (xy 93.279685 -289.148332) (xy 93.287928 -289.159015) (xy 93.293184 -289.163252)
			(xy 93.298518 -289.167316) (xy 93.31071 -289.172142) (xy 93.317822 -289.173158) (xy 93.342182 -289.176623)
			(xy 93.389436 -289.190325) (xy 93.433881 -289.211425) (xy 93.474369 -289.239379) (xy 93.509851 -289.273462)
			(xy 93.53941 -289.312793) (xy 93.56228 -289.356355) (xy 93.577871 -289.40302) (xy 93.585778 -289.45158)
			(xy 93.5863 -289.47618) (xy 93.904811 -289.47618) (xy 93.908906 -289.425452) (xy 93.921085 -289.376038)
			(xy 93.941033 -289.329218) (xy 93.968234 -289.286204) (xy 94.001982 -289.24811) (xy 94.041404 -289.215923)
			(xy 94.085478 -289.190477) (xy 94.133064 -289.17243) (xy 94.182928 -289.16225) (xy 94.23378 -289.160201)
			(xy 94.284301 -289.166335) (xy 94.333185 -289.180495) (xy 94.379164 -289.202312) (xy 94.421048 -289.231222)
			(xy 94.457752 -289.266477) (xy 94.488325 -289.307163) (xy 94.511976 -289.352226) (xy 94.528092 -289.4005)
			(xy 94.536256 -289.450734) (xy 94.536768 -289.47618) (xy 94.855296 -289.47618) (xy 94.859256 -289.427126)
			(xy 94.871033 -289.379342) (xy 94.890324 -289.334066) (xy 94.916627 -289.29247) (xy 94.949262 -289.255633)
			(xy 94.987383 -289.224508) (xy 95.030004 -289.199901) (xy 95.07602 -289.182449) (xy 95.124239 -289.172605)
			(xy 95.173414 -289.170624) (xy 95.222269 -289.176556) (xy 95.26954 -289.190248) (xy 95.314002 -289.211346)
			(xy 95.354505 -289.239302) (xy 95.389998 -289.273394) (xy 95.419563 -289.312738) (xy 95.442434 -289.356315)
			(xy 95.458018 -289.402996) (xy 95.465913 -289.451573) (xy 95.466408 -289.47618) (xy 95.465913 -289.500787)
			(xy 95.458018 -289.549364) (xy 95.442434 -289.596045) (xy 95.419563 -289.639622) (xy 95.389998 -289.678966)
			(xy 95.354505 -289.713058) (xy 95.314002 -289.741014) (xy 95.26954 -289.762112) (xy 95.222269 -289.775804)
			(xy 95.173414 -289.781736) (xy 95.124239 -289.779755) (xy 95.07602 -289.769911) (xy 95.030004 -289.752459)
			(xy 94.987383 -289.727852) (xy 94.949262 -289.696727) (xy 94.916627 -289.65989) (xy 94.890324 -289.618294)
			(xy 94.871033 -289.573018) (xy 94.859256 -289.525234) (xy 94.855296 -289.47618) (xy 94.536768 -289.47618)
			(xy 94.536256 -289.501626) (xy 94.528092 -289.55186) (xy 94.511976 -289.600134) (xy 94.488325 -289.645197)
			(xy 94.457752 -289.685883) (xy 94.421048 -289.721138) (xy 94.379164 -289.750048) (xy 94.333185 -289.771865)
			(xy 94.284301 -289.786025) (xy 94.23378 -289.792159) (xy 94.182928 -289.79011) (xy 94.133064 -289.77993)
			(xy 94.085478 -289.761883) (xy 94.041404 -289.736437) (xy 94.001982 -289.70425) (xy 93.968234 -289.666156)
			(xy 93.941033 -289.623142) (xy 93.921085 -289.576322) (xy 93.908906 -289.526908) (xy 93.904811 -289.47618)
			(xy 93.5863 -289.47618) (xy 93.585835 -289.500031) (xy 93.578409 -289.54715) (xy 93.563749 -289.592543)
			(xy 93.542212 -289.635106) (xy 93.514321 -289.673804) (xy 93.480755 -289.707697) (xy 93.442328 -289.735961)
			(xy 93.399976 -289.757909) (xy 93.354727 -289.773007) (xy 93.331284 -289.777424) (xy 93.322648 -289.778948)
			(xy 93.294708 -289.799268) (xy 93.289834 -289.80302) (xy 93.281874 -289.812393) (xy 93.27896 -289.81781)
			(xy 93.248226 -289.880294) (xy 93.24721 -289.882834) (xy 93.243634 -289.892203) (xy 93.243364 -289.91224)
			(xy 93.246702 -289.921696) (xy 93.246956 -289.922458) (xy 93.250004 -289.9283) (xy 93.294708 -290.005262)
			(xy 93.305178 -290.023742) (xy 93.323612 -290.06201) (xy 93.331538 -290.081716) (xy 93.331538 -290.08197)
			(xy 93.334232 -290.08817) (xy 93.342344 -290.09898) (xy 93.34754 -290.103306) (xy 93.352874 -290.10737)
			(xy 93.365066 -290.112704) (xy 93.45803 -290.124896) (xy 93.464894 -290.125561) (xy 93.478541 -290.123622)
			(xy 93.484954 -290.121086) (xy 93.490982 -290.118285) (xy 93.501404 -290.110043) (xy 93.505528 -290.10483)
			(xy 93.505782 -290.104576) (xy 93.520284 -290.085743) (xy 93.554137 -290.052381) (xy 93.592748 -290.024665)
			(xy 93.635187 -290.003264) (xy 93.680429 -289.988695) (xy 93.727381 -289.981309) (xy 93.751146 -289.980878)
			(xy 93.7764 -289.981403) (xy 93.826218 -289.989723) (xy 93.873988 -290.006129) (xy 93.918406 -290.030173)
			(xy 93.958261 -290.061199) (xy 93.992467 -290.098361) (xy 94.02009 -290.140647) (xy 94.040377 -290.186901)
			(xy 94.052774 -290.235864) (xy 94.056944 -290.286186) (xy 94.374711 -290.286186) (xy 94.378806 -290.235458)
			(xy 94.390985 -290.186044) (xy 94.410933 -290.139224) (xy 94.438134 -290.09621) (xy 94.471882 -290.058116)
			(xy 94.511304 -290.025929) (xy 94.555378 -290.000483) (xy 94.602964 -289.982436) (xy 94.652828 -289.972256)
			(xy 94.70368 -289.970207) (xy 94.754201 -289.976341) (xy 94.803085 -289.990501) (xy 94.849064 -290.012318)
			(xy 94.890948 -290.041228) (xy 94.927652 -290.076483) (xy 94.958225 -290.117169) (xy 94.981876 -290.162232)
			(xy 94.997992 -290.210506) (xy 95.006156 -290.26074) (xy 95.006668 -290.286186) (xy 95.006156 -290.311632)
			(xy 94.997992 -290.361866) (xy 94.981876 -290.41014) (xy 94.958225 -290.455203) (xy 94.927652 -290.495889)
			(xy 94.890948 -290.531144) (xy 94.849064 -290.560054) (xy 94.803085 -290.581871) (xy 94.754201 -290.596031)
			(xy 94.70368 -290.602165) (xy 94.652828 -290.600116) (xy 94.602964 -290.589936) (xy 94.555378 -290.571889)
			(xy 94.511304 -290.546443) (xy 94.471882 -290.514256) (xy 94.438134 -290.476162) (xy 94.410933 -290.433148)
			(xy 94.390985 -290.386328) (xy 94.378806 -290.336914) (xy 94.374711 -290.286186) (xy 94.056944 -290.286186)
			(xy 94.056945 -290.2862) (xy 94.052774 -290.336536) (xy 94.040377 -290.385499) (xy 94.02009 -290.431753)
			(xy 93.992467 -290.474039) (xy 93.958261 -290.511201) (xy 93.918406 -290.542227) (xy 93.873988 -290.566271)
			(xy 93.826218 -290.582677) (xy 93.7764 -290.590997) (xy 93.751146 -290.591494) (xy 93.727381 -290.591044)
			(xy 93.680424 -290.58368) (xy 93.635177 -290.569123) (xy 93.592735 -290.547725) (xy 93.554125 -290.520005)
			(xy 93.520281 -290.486632) (xy 93.505782 -290.467796) (xy 93.505782 -290.467542) (xy 93.505528 -290.467542)
			(xy 93.501371 -290.462363) (xy 93.490954 -290.454133) (xy 93.484954 -290.451286) (xy 93.478545 -290.448741)
			(xy 93.464896 -290.446822) (xy 93.45803 -290.447476) (xy 93.372178 -290.458906) (xy 93.365418 -290.45998)
			(xy 93.352792 -290.465254) (xy 93.347286 -290.46932) (xy 93.341952 -290.473384) (xy 93.334078 -290.484052)
			(xy 93.331538 -290.490656) (xy 93.315988 -290.528327) (xy 93.275565 -290.599091) (xy 93.25102 -290.631626)
			(xy 93.25102 -290.63188) (xy 93.246989 -290.637285) (xy 93.241593 -290.649636) (xy 93.240352 -290.656264)
			(xy 93.238574 -290.669472) (xy 93.276928 -290.762182) (xy 93.279686 -290.768343) (xy 93.287931 -290.779024)
			(xy 93.293184 -290.783264) (xy 93.298518 -290.787328) (xy 93.31071 -290.792154) (xy 93.317822 -290.79317)
			(xy 93.342181 -290.796635) (xy 93.389434 -290.810337) (xy 93.433879 -290.831438) (xy 93.474366 -290.859392)
			(xy 93.509847 -290.893475) (xy 93.539404 -290.932806) (xy 93.562273 -290.976368) (xy 93.577862 -291.023032)
			(xy 93.585767 -291.071592) (xy 93.5863 -291.096192) (xy 93.904811 -291.096192) (xy 93.908906 -291.045464)
			(xy 93.921085 -290.99605) (xy 93.941033 -290.94923) (xy 93.968234 -290.906216) (xy 94.001982 -290.868122)
			(xy 94.041404 -290.835935) (xy 94.085478 -290.810489) (xy 94.133064 -290.792442) (xy 94.182928 -290.782262)
			(xy 94.23378 -290.780213) (xy 94.284301 -290.786347) (xy 94.333185 -290.800507) (xy 94.379164 -290.822324)
			(xy 94.421048 -290.851234) (xy 94.457752 -290.886489) (xy 94.488325 -290.927175) (xy 94.511976 -290.972238)
			(xy 94.528092 -291.020512) (xy 94.536256 -291.070746) (xy 94.536768 -291.096192) (xy 94.855296 -291.096192)
			(xy 94.859256 -291.047138) (xy 94.871033 -290.999354) (xy 94.890324 -290.954078) (xy 94.916627 -290.912482)
			(xy 94.949262 -290.875645) (xy 94.987383 -290.84452) (xy 95.030004 -290.819913) (xy 95.07602 -290.802461)
			(xy 95.124239 -290.792617) (xy 95.173414 -290.790636) (xy 95.222269 -290.796568) (xy 95.26954 -290.81026)
			(xy 95.314002 -290.831358) (xy 95.354505 -290.859314) (xy 95.389998 -290.893406) (xy 95.419563 -290.93275)
			(xy 95.442434 -290.976327) (xy 95.458018 -291.023008) (xy 95.465913 -291.071585) (xy 95.466408 -291.096192)
			(xy 95.465913 -291.120799) (xy 95.458018 -291.169376) (xy 95.442434 -291.216057) (xy 95.419563 -291.259634)
			(xy 95.389998 -291.298978) (xy 95.354505 -291.33307) (xy 95.314002 -291.361026) (xy 95.26954 -291.382124)
			(xy 95.222269 -291.395816) (xy 95.173414 -291.401748) (xy 95.124239 -291.399767) (xy 95.07602 -291.389923)
			(xy 95.030004 -291.372471) (xy 94.987383 -291.347864) (xy 94.949262 -291.316739) (xy 94.916627 -291.279902)
			(xy 94.890324 -291.238306) (xy 94.871033 -291.19303) (xy 94.859256 -291.145246) (xy 94.855296 -291.096192)
			(xy 94.536768 -291.096192) (xy 94.536256 -291.121638) (xy 94.528092 -291.171872) (xy 94.511976 -291.220146)
			(xy 94.488325 -291.265209) (xy 94.457752 -291.305895) (xy 94.421048 -291.34115) (xy 94.379164 -291.37006)
			(xy 94.333185 -291.391877) (xy 94.284301 -291.406037) (xy 94.23378 -291.412171) (xy 94.182928 -291.410122)
			(xy 94.133064 -291.399942) (xy 94.085478 -291.381895) (xy 94.041404 -291.356449) (xy 94.001982 -291.324262)
			(xy 93.968234 -291.286168) (xy 93.941033 -291.243154) (xy 93.921085 -291.196334) (xy 93.908906 -291.14692)
			(xy 93.904811 -291.096192) (xy 93.5863 -291.096192) (xy 93.585834 -291.120042) (xy 93.578406 -291.167161)
			(xy 93.563745 -291.212552) (xy 93.542208 -291.255113) (xy 93.514317 -291.29381) (xy 93.48075 -291.327701)
			(xy 93.442324 -291.355963) (xy 93.399973 -291.37791) (xy 93.354725 -291.393008) (xy 93.331284 -291.397436)
			(xy 93.322648 -291.39896) (xy 93.294708 -291.41928) (xy 93.289835 -291.423033) (xy 93.281876 -291.432406)
			(xy 93.27896 -291.437822) (xy 93.248226 -291.500306) (xy 93.24721 -291.502846) (xy 93.243636 -291.512215)
			(xy 93.24337 -291.532251) (xy 93.246702 -291.541708) (xy 93.246956 -291.54247) (xy 93.250004 -291.548312)
			(xy 93.294708 -291.625274) (xy 93.303136 -291.640097) (xy 93.318388 -291.670597) (xy 93.325188 -291.686234)
			(xy 93.32341 -291.688012) (xy 93.334332 -291.718238) (xy 93.341118 -291.737547) (xy 93.352176 -291.776958)
			(xy 93.35643 -291.796978) (xy 93.358405 -291.80524) (xy 93.366972 -291.819896) (xy 93.373194 -291.82568)
			(xy 93.378782 -291.830252) (xy 93.387838 -291.837323) (xy 93.410029 -291.843194) (xy 93.432555 -291.838783)
			(xy 93.442028 -291.832284) (xy 93.44533 -291.829744) (xy 93.451183 -291.825007) (xy 93.460084 -291.81287)
			(xy 93.462856 -291.805868) (xy 93.471029 -291.783732) (xy 93.493213 -291.742086) (xy 93.521538 -291.704348)
			(xy 93.55533 -291.671415) (xy 93.593784 -291.644071) (xy 93.635987 -291.622966) (xy 93.680933 -291.608603)
			(xy 93.727553 -291.601323) (xy 93.751146 -291.60089) (xy 93.776399 -291.601415) (xy 93.826215 -291.609735)
			(xy 93.873983 -291.62614) (xy 93.918399 -291.650183) (xy 93.958253 -291.681208) (xy 93.992457 -291.718369)
			(xy 94.020079 -291.760652) (xy 94.040365 -291.806905) (xy 94.052763 -291.855866) (xy 94.056933 -291.906198)
			(xy 94.374711 -291.906198) (xy 94.378806 -291.85547) (xy 94.390985 -291.806056) (xy 94.410933 -291.759236)
			(xy 94.438134 -291.716222) (xy 94.471882 -291.678128) (xy 94.511304 -291.645941) (xy 94.555378 -291.620495)
			(xy 94.602964 -291.602448) (xy 94.652828 -291.592268) (xy 94.70368 -291.590219) (xy 94.754201 -291.596353)
			(xy 94.803085 -291.610513) (xy 94.849064 -291.63233) (xy 94.890948 -291.66124) (xy 94.927652 -291.696495)
			(xy 94.958225 -291.737181) (xy 94.981876 -291.782244) (xy 94.997992 -291.830518) (xy 95.006156 -291.880752)
			(xy 95.006668 -291.906198) (xy 95.314765 -291.906198) (xy 95.31886 -291.85547) (xy 95.331039 -291.806056)
			(xy 95.350987 -291.759236) (xy 95.378188 -291.716222) (xy 95.411936 -291.678128) (xy 95.451358 -291.645941)
			(xy 95.495432 -291.620495) (xy 95.543018 -291.602448) (xy 95.592882 -291.592268) (xy 95.643734 -291.590219)
			(xy 95.694255 -291.596353) (xy 95.743139 -291.610513) (xy 95.789118 -291.63233) (xy 95.831002 -291.66124)
			(xy 95.867706 -291.696495) (xy 95.898279 -291.737181) (xy 95.92193 -291.782244) (xy 95.938046 -291.830518)
			(xy 95.94621 -291.880752) (xy 95.946722 -291.906198) (xy 95.94621 -291.931644) (xy 95.938046 -291.981878)
			(xy 95.92193 -292.030152) (xy 95.898279 -292.075215) (xy 95.867706 -292.115901) (xy 95.831002 -292.151156)
			(xy 95.789118 -292.180066) (xy 95.743139 -292.201883) (xy 95.694255 -292.216043) (xy 95.643734 -292.222177)
			(xy 95.592882 -292.220128) (xy 95.543018 -292.209948) (xy 95.495432 -292.191901) (xy 95.451358 -292.166455)
			(xy 95.411936 -292.134268) (xy 95.378188 -292.096174) (xy 95.350987 -292.05316) (xy 95.331039 -292.00634)
			(xy 95.31886 -291.956926) (xy 95.314765 -291.906198) (xy 95.006668 -291.906198) (xy 95.006156 -291.931644)
			(xy 94.997992 -291.981878) (xy 94.981876 -292.030152) (xy 94.958225 -292.075215) (xy 94.927652 -292.115901)
			(xy 94.890948 -292.151156) (xy 94.849064 -292.180066) (xy 94.803085 -292.201883) (xy 94.754201 -292.216043)
			(xy 94.70368 -292.222177) (xy 94.652828 -292.220128) (xy 94.602964 -292.209948) (xy 94.555378 -292.191901)
			(xy 94.511304 -292.166455) (xy 94.471882 -292.134268) (xy 94.438134 -292.096174) (xy 94.410933 -292.05316)
			(xy 94.390985 -292.00634) (xy 94.378806 -291.956926) (xy 94.374711 -291.906198) (xy 94.056933 -291.906198)
			(xy 94.056933 -291.9062) (xy 94.052763 -291.956534) (xy 94.040365 -292.005495) (xy 94.020079 -292.051748)
			(xy 93.992457 -292.094031) (xy 93.958253 -292.131192) (xy 93.918399 -292.162217) (xy 93.873983 -292.18626)
			(xy 93.826215 -292.202665) (xy 93.776399 -292.210985) (xy 93.751146 -292.211506) (xy 93.727275 -292.211047)
			(xy 93.680114 -292.203618) (xy 93.634686 -292.188934) (xy 93.5921 -292.167353) (xy 93.553394 -292.139402)
			(xy 93.519515 -292.105764) (xy 93.50502 -292.086792) (xy 93.499363 -292.079702) (xy 93.484222 -292.069738)
			(xy 93.466558 -292.065676) (xy 93.457522 -292.066472) (xy 93.35516 -292.07968) (xy 93.33357 -292.096698)
			(xy 93.32849 -292.109652) (xy 93.316069 -292.139941) (xy 93.285122 -292.197631) (xy 93.24762 -292.251292)
			(xy 93.204079 -292.300181) (xy 93.1799 -292.32225) (xy 93.172286 -292.329818) (xy 93.163503 -292.349378)
			(xy 93.162882 -292.360096) (xy 93.162882 -292.366446) (xy 93.163378 -292.376449) (xy 93.171045 -292.394928)
			(xy 93.185195 -292.409071) (xy 93.203679 -292.416728) (xy 93.213682 -292.417246) (xy 93.218508 -292.417246)
			(xy 93.223334 -292.416484) (xy 93.237607 -292.413886) (xy 93.266485 -292.411083) (xy 93.280992 -292.410896)
			(xy 93.30625 -292.411388) (xy 93.356077 -292.419701) (xy 93.403856 -292.436103) (xy 93.448283 -292.460145)
			(xy 93.488148 -292.491172) (xy 93.522361 -292.528337) (xy 93.549991 -292.570626) (xy 93.570283 -292.616887)
			(xy 93.582684 -292.665857) (xy 93.586856 -292.7162) (xy 93.586856 -292.716204) (xy 93.904811 -292.716204)
			(xy 93.908906 -292.665476) (xy 93.921085 -292.616062) (xy 93.941033 -292.569242) (xy 93.968234 -292.526228)
			(xy 94.001982 -292.488134) (xy 94.041404 -292.455947) (xy 94.085478 -292.430501) (xy 94.133064 -292.412454)
			(xy 94.182928 -292.402274) (xy 94.23378 -292.400225) (xy 94.284301 -292.406359) (xy 94.333185 -292.420519)
			(xy 94.379164 -292.442336) (xy 94.421048 -292.471246) (xy 94.457752 -292.506501) (xy 94.488325 -292.547187)
			(xy 94.511976 -292.59225) (xy 94.528092 -292.640524) (xy 94.536256 -292.690758) (xy 94.536768 -292.716204)
			(xy 94.855296 -292.716204) (xy 94.859256 -292.66715) (xy 94.871033 -292.619366) (xy 94.890324 -292.57409)
			(xy 94.916627 -292.532494) (xy 94.949262 -292.495657) (xy 94.987383 -292.464532) (xy 95.030004 -292.439925)
			(xy 95.07602 -292.422473) (xy 95.124239 -292.412629) (xy 95.173414 -292.410648) (xy 95.222269 -292.41658)
			(xy 95.26954 -292.430272) (xy 95.314002 -292.45137) (xy 95.354505 -292.479326) (xy 95.389998 -292.513418)
			(xy 95.419563 -292.552762) (xy 95.442434 -292.596339) (xy 95.458018 -292.64302) (xy 95.465913 -292.691597)
			(xy 95.466408 -292.716204) (xy 95.465913 -292.740811) (xy 95.458018 -292.789388) (xy 95.442434 -292.836069)
			(xy 95.419563 -292.879646) (xy 95.389998 -292.91899) (xy 95.354505 -292.953082) (xy 95.314002 -292.981038)
			(xy 95.26954 -293.002136) (xy 95.222269 -293.015828) (xy 95.173414 -293.02176) (xy 95.124239 -293.019779)
			(xy 95.07602 -293.009935) (xy 95.030004 -292.992483) (xy 94.987383 -292.967876) (xy 94.949262 -292.936751)
			(xy 94.916627 -292.899914) (xy 94.890324 -292.858318) (xy 94.871033 -292.813042) (xy 94.859256 -292.765258)
			(xy 94.855296 -292.716204) (xy 94.536768 -292.716204) (xy 94.536256 -292.74165) (xy 94.528092 -292.791884)
			(xy 94.511976 -292.840158) (xy 94.488325 -292.885221) (xy 94.457752 -292.925907) (xy 94.421048 -292.961162)
			(xy 94.379164 -292.990072) (xy 94.333185 -293.011889) (xy 94.284301 -293.026049) (xy 94.23378 -293.032183)
			(xy 94.182928 -293.030134) (xy 94.133064 -293.019954) (xy 94.085478 -293.001907) (xy 94.041404 -292.976461)
			(xy 94.001982 -292.944274) (xy 93.968234 -292.90618) (xy 93.941033 -292.863166) (xy 93.921085 -292.816346)
			(xy 93.908906 -292.766932) (xy 93.904811 -292.716204) (xy 93.586856 -292.716204) (xy 93.582684 -292.766543)
			(xy 93.570283 -292.815513) (xy 93.549991 -292.861774) (xy 93.522361 -292.904063) (xy 93.488148 -292.941228)
			(xy 93.448283 -292.972255) (xy 93.403856 -292.996297) (xy 93.356077 -293.012699) (xy 93.30625 -293.021012)
			(xy 93.280992 -293.021512) (xy 93.280484 -293.021512) (xy 93.253421 -293.020903) (xy 93.200148 -293.011315)
			(xy 93.174566 -293.002462) (xy 93.163898 -292.998398) (xy 93.141292 -293.000176) (xy 93.063822 -293.044626)
			(xy 93.054533 -293.050633) (xy 93.041764 -293.068667) (xy 93.039184 -293.079424) (xy 93.039184 -293.079678)
			(xy 93.029024 -293.12489) (xy 93.006672 -293.208202) (xy 92.996766 -293.241476) (xy 92.994087 -293.251097)
			(xy 92.995485 -293.270998) (xy 93.004326 -293.288883) (xy 93.011498 -293.295832) (xy 93.03086 -293.313375)
			(xy 93.063874 -293.353864) (xy 93.089512 -293.399384) (xy 93.107025 -293.448605) (xy 93.115902 -293.500088)
			(xy 93.1164 -293.52621) (xy 93.445342 -293.52621) (xy 93.449302 -293.477156) (xy 93.461079 -293.429372)
			(xy 93.48037 -293.384096) (xy 93.506673 -293.3425) (xy 93.539308 -293.305663) (xy 93.577429 -293.274538)
			(xy 93.62005 -293.249931) (xy 93.666066 -293.232479) (xy 93.714285 -293.222635) (xy 93.76346 -293.220654)
			(xy 93.812315 -293.226586) (xy 93.859586 -293.240278) (xy 93.904048 -293.261376) (xy 93.944551 -293.289332)
			(xy 93.980044 -293.323424) (xy 94.009609 -293.362768) (xy 94.03248 -293.406345) (xy 94.048064 -293.453026)
			(xy 94.055959 -293.501603) (xy 94.056454 -293.52621) (xy 94.385142 -293.52621) (xy 94.389102 -293.477156)
			(xy 94.400879 -293.429372) (xy 94.42017 -293.384096) (xy 94.446473 -293.3425) (xy 94.479108 -293.305663)
			(xy 94.517229 -293.274538) (xy 94.55985 -293.249931) (xy 94.605866 -293.232479) (xy 94.654085 -293.222635)
			(xy 94.70326 -293.220654) (xy 94.752115 -293.226586) (xy 94.799386 -293.240278) (xy 94.843848 -293.261376)
			(xy 94.884351 -293.289332) (xy 94.919844 -293.323424) (xy 94.949409 -293.362768) (xy 94.97228 -293.406345)
			(xy 94.987864 -293.453026) (xy 94.995759 -293.501603) (xy 94.996254 -293.52621) (xy 95.314765 -293.52621)
			(xy 95.31886 -293.475482) (xy 95.331039 -293.426068) (xy 95.350987 -293.379248) (xy 95.378188 -293.336234)
			(xy 95.411936 -293.29814) (xy 95.451358 -293.265953) (xy 95.495432 -293.240507) (xy 95.543018 -293.22246)
			(xy 95.592882 -293.21228) (xy 95.643734 -293.210231) (xy 95.694255 -293.216365) (xy 95.743139 -293.230525)
			(xy 95.789118 -293.252342) (xy 95.831002 -293.281252) (xy 95.867706 -293.316507) (xy 95.898279 -293.357193)
			(xy 95.92193 -293.402256) (xy 95.938046 -293.45053) (xy 95.94621 -293.500764) (xy 95.946722 -293.52621)
			(xy 95.94621 -293.551656) (xy 95.938046 -293.60189) (xy 95.92193 -293.650164) (xy 95.898279 -293.695227)
			(xy 95.867706 -293.735913) (xy 95.831002 -293.771168) (xy 95.789118 -293.800078) (xy 95.743139 -293.821895)
			(xy 95.694255 -293.836055) (xy 95.643734 -293.842189) (xy 95.592882 -293.84014) (xy 95.543018 -293.82996)
			(xy 95.495432 -293.811913) (xy 95.451358 -293.786467) (xy 95.411936 -293.75428) (xy 95.378188 -293.716186)
			(xy 95.350987 -293.673172) (xy 95.331039 -293.626352) (xy 95.31886 -293.576938) (xy 95.314765 -293.52621)
			(xy 94.996254 -293.52621) (xy 94.995759 -293.550817) (xy 94.987864 -293.599394) (xy 94.97228 -293.646075)
			(xy 94.949409 -293.689652) (xy 94.919844 -293.728996) (xy 94.884351 -293.763088) (xy 94.843848 -293.791044)
			(xy 94.799386 -293.812142) (xy 94.752115 -293.825834) (xy 94.70326 -293.831766) (xy 94.654085 -293.829785)
			(xy 94.605866 -293.819941) (xy 94.55985 -293.802489) (xy 94.517229 -293.777882) (xy 94.479108 -293.746757)
			(xy 94.446473 -293.70992) (xy 94.42017 -293.668324) (xy 94.400879 -293.623048) (xy 94.389102 -293.575264)
			(xy 94.385142 -293.52621) (xy 94.056454 -293.52621) (xy 94.055959 -293.550817) (xy 94.048064 -293.599394)
			(xy 94.03248 -293.646075) (xy 94.009609 -293.689652) (xy 93.980044 -293.728996) (xy 93.944551 -293.763088)
			(xy 93.904048 -293.791044) (xy 93.859586 -293.812142) (xy 93.812315 -293.825834) (xy 93.76346 -293.831766)
			(xy 93.714285 -293.829785) (xy 93.666066 -293.819941) (xy 93.62005 -293.802489) (xy 93.577429 -293.777882)
			(xy 93.539308 -293.746757) (xy 93.506673 -293.70992) (xy 93.48037 -293.668324) (xy 93.461079 -293.623048)
			(xy 93.449302 -293.575264) (xy 93.445342 -293.52621) (xy 93.1164 -293.52621) (xy 93.115929 -293.5502)
			(xy 93.108421 -293.597591) (xy 93.093593 -293.643223) (xy 93.071809 -293.685973) (xy 93.043605 -293.72479)
			(xy 93.009676 -293.758717) (xy 92.970858 -293.786918) (xy 92.928106 -293.8087) (xy 92.882473 -293.823525)
			(xy 92.835083 -293.83103) (xy 92.811092 -293.831518) (xy 92.786629 -293.831035) (xy 92.738329 -293.82324)
			(xy 92.691888 -293.807848) (xy 92.648492 -293.785255) (xy 92.609249 -293.756036) (xy 92.575163 -293.720939)
			(xy 92.547104 -293.68086) (xy 92.53601 -293.659052) (xy 92.530851 -293.649528) (xy 92.514266 -293.635626)
			(xy 92.493442 -293.629735) (xy 92.48267 -293.630858) (xy 92.435359 -293.637599) (xy 92.339911 -293.64245)
			(xy 92.244472 -293.637436) (xy 92.197174 -293.630604) (xy 92.1893 -293.630096) (xy 92.158058 -293.630096)
			(xy 92.148869 -293.653971) (xy 92.123692 -293.6985) (xy 92.091442 -293.738207) (xy 92.053023 -293.771981)
			(xy 92.00951 -293.798877) (xy 91.962122 -293.81814) (xy 91.912185 -293.829231) (xy 91.861098 -293.831841)
			(xy 91.81029 -293.825896) (xy 91.761186 -293.811562) (xy 91.715159 -293.789241) (xy 91.673498 -293.759557)
			(xy 91.63737 -293.723343) (xy 91.607787 -293.681611) (xy 91.59621 -293.658798) (xy 91.59169 -293.650353)
			(xy 91.57764 -293.637357) (xy 91.559807 -293.630408) (xy 91.550236 -293.630096) (xy 91.548966 -293.630096)
			(xy 91.50731 -293.635938) (xy 91.497353 -293.637528) (xy 91.479768 -293.647363) (xy 91.467306 -293.663195)
			(xy 91.46413 -293.672768) (xy 91.453742 -293.708135) (xy 91.424865 -293.775956) (xy 91.38722 -293.839331)
			(xy 91.364816 -293.868602) (xy 91.359545 -293.875942) (xy 91.354041 -293.893142) (xy 91.354812 -293.911185)
			(xy 91.357958 -293.919656) (xy 91.392248 -294.001952) (xy 91.396115 -294.010134) (xy 91.40851 -294.023304)
			(xy 91.424697 -294.031371) (xy 91.43365 -294.032686) (xy 91.433904 -294.032686) (xy 91.458539 -294.035838)
			(xy 91.506398 -294.049096) (xy 91.551481 -294.069926) (xy 91.592597 -294.097778) (xy 91.628663 -294.131917)
			(xy 91.658728 -294.171445) (xy 91.681998 -294.215317) (xy 91.69786 -294.262378) (xy 91.705896 -294.311385)
			(xy 91.706446 -294.336216) (xy 92.035134 -294.336216) (xy 92.039094 -294.287162) (xy 92.050871 -294.239378)
			(xy 92.070162 -294.194102) (xy 92.096465 -294.152506) (xy 92.1291 -294.115669) (xy 92.167221 -294.084544)
			(xy 92.209842 -294.059937) (xy 92.255858 -294.042485) (xy 92.304077 -294.032641) (xy 92.353252 -294.03066)
			(xy 92.402107 -294.036592) (xy 92.449378 -294.050284) (xy 92.49384 -294.071382) (xy 92.534343 -294.099338)
			(xy 92.569836 -294.13343) (xy 92.599401 -294.172774) (xy 92.622272 -294.216351) (xy 92.637856 -294.263032)
			(xy 92.645751 -294.311609) (xy 92.646246 -294.336216) (xy 92.975188 -294.336216) (xy 92.979148 -294.287162)
			(xy 92.990925 -294.239378) (xy 93.010216 -294.194102) (xy 93.036519 -294.152506) (xy 93.069154 -294.115669)
			(xy 93.107275 -294.084544) (xy 93.149896 -294.059937) (xy 93.195912 -294.042485) (xy 93.244131 -294.032641)
			(xy 93.293306 -294.03066) (xy 93.342161 -294.036592) (xy 93.389432 -294.050284) (xy 93.433894 -294.071382)
			(xy 93.474397 -294.099338) (xy 93.50989 -294.13343) (xy 93.539455 -294.172774) (xy 93.562326 -294.216351)
			(xy 93.57791 -294.263032) (xy 93.585805 -294.311609) (xy 93.5863 -294.336216) (xy 94.855296 -294.336216)
			(xy 94.859256 -294.287162) (xy 94.871033 -294.239378) (xy 94.890324 -294.194102) (xy 94.916627 -294.152506)
			(xy 94.949262 -294.115669) (xy 94.987383 -294.084544) (xy 95.030004 -294.059937) (xy 95.07602 -294.042485)
			(xy 95.124239 -294.032641) (xy 95.173414 -294.03066) (xy 95.222269 -294.036592) (xy 95.26954 -294.050284)
			(xy 95.314002 -294.071382) (xy 95.354505 -294.099338) (xy 95.389998 -294.13343) (xy 95.419563 -294.172774)
			(xy 95.442434 -294.216351) (xy 95.458018 -294.263032) (xy 95.465913 -294.311609) (xy 95.466408 -294.336216)
			(xy 95.465913 -294.360823) (xy 95.458018 -294.4094) (xy 95.442434 -294.456081) (xy 95.419563 -294.499658)
			(xy 95.389998 -294.539002) (xy 95.354505 -294.573094) (xy 95.314002 -294.60105) (xy 95.26954 -294.622148)
			(xy 95.222269 -294.63584) (xy 95.173414 -294.641772) (xy 95.124239 -294.639791) (xy 95.07602 -294.629947)
			(xy 95.030004 -294.612495) (xy 94.987383 -294.587888) (xy 94.949262 -294.556763) (xy 94.916627 -294.519926)
			(xy 94.890324 -294.47833) (xy 94.871033 -294.433054) (xy 94.859256 -294.38527) (xy 94.855296 -294.336216)
			(xy 93.5863 -294.336216) (xy 93.585805 -294.360823) (xy 93.57791 -294.4094) (xy 93.562326 -294.456081)
			(xy 93.539455 -294.499658) (xy 93.50989 -294.539002) (xy 93.474397 -294.573094) (xy 93.433894 -294.60105)
			(xy 93.389432 -294.622148) (xy 93.342161 -294.63584) (xy 93.293306 -294.641772) (xy 93.244131 -294.639791)
			(xy 93.195912 -294.629947) (xy 93.149896 -294.612495) (xy 93.107275 -294.587888) (xy 93.069154 -294.556763)
			(xy 93.036519 -294.519926) (xy 93.010216 -294.47833) (xy 92.990925 -294.433054) (xy 92.979148 -294.38527)
			(xy 92.975188 -294.336216) (xy 92.646246 -294.336216) (xy 92.645751 -294.360823) (xy 92.637856 -294.4094)
			(xy 92.622272 -294.456081) (xy 92.599401 -294.499658) (xy 92.569836 -294.539002) (xy 92.534343 -294.573094)
			(xy 92.49384 -294.60105) (xy 92.449378 -294.622148) (xy 92.402107 -294.63584) (xy 92.353252 -294.641772)
			(xy 92.304077 -294.639791) (xy 92.255858 -294.629947) (xy 92.209842 -294.612495) (xy 92.167221 -294.587888)
			(xy 92.1291 -294.556763) (xy 92.096465 -294.519926) (xy 92.070162 -294.47833) (xy 92.050871 -294.433054)
			(xy 92.039094 -294.38527) (xy 92.035134 -294.336216) (xy 91.706446 -294.336216) (xy 91.705924 -294.361471)
			(xy 91.697611 -294.411293) (xy 91.68121 -294.459067) (xy 91.657169 -294.50349) (xy 91.626145 -294.54335)
			(xy 91.588983 -294.57756) (xy 91.546697 -294.605186) (xy 91.500441 -294.625476) (xy 91.451476 -294.637876)
			(xy 91.401138 -294.642047) (xy 91.3508 -294.637876) (xy 91.301835 -294.625476) (xy 91.255579 -294.605186)
			(xy 91.213293 -294.57756) (xy 91.176131 -294.54335) (xy 91.145107 -294.50349) (xy 91.121066 -294.459067)
			(xy 91.104665 -294.411293) (xy 91.096352 -294.361471) (xy 91.09583 -294.336216) (xy 91.09583 -294.335708)
			(xy 91.096191 -294.314839) (xy 91.101917 -294.273495) (xy 91.113222 -294.233317) (xy 91.12123 -294.214042)
			(xy 91.126818 -294.201342) (xy 91.12377 -294.17391) (xy 91.060778 -294.092122) (xy 91.054997 -294.085244)
			(xy 91.039786 -294.075702) (xy 91.022225 -294.071953) (xy 91.01328 -294.072818) (xy 91.013026 -294.072818)
			(xy 90.992704 -294.075736) (xy 90.951767 -294.078916) (xy 90.931238 -294.079168) (xy 90.93073 -294.079168)
			(xy 90.910265 -294.078906) (xy 90.869456 -294.075725) (xy 90.849196 -294.072818) (xy 90.848688 -294.072818)
			(xy 90.835226 -294.070786) (xy 90.809826 -294.0812) (xy 90.738452 -294.17391) (xy 90.735404 -294.201342)
			(xy 90.740992 -294.214042) (xy 90.749017 -294.233311) (xy 90.760322 -294.273492) (xy 90.766048 -294.314838)
			(xy 90.766392 -294.335708) (xy 90.766392 -294.336216) (xy 90.76587 -294.361471) (xy 90.757557 -294.411293)
			(xy 90.741156 -294.459067) (xy 90.717115 -294.50349) (xy 90.686091 -294.54335) (xy 90.648929 -294.57756)
			(xy 90.606643 -294.605186) (xy 90.560387 -294.625476) (xy 90.511422 -294.637876) (xy 90.461084 -294.642047)
			(xy 90.410746 -294.637876) (xy 90.361781 -294.625476) (xy 90.315525 -294.605186) (xy 90.273239 -294.57756)
			(xy 90.236077 -294.54335) (xy 90.205053 -294.50349) (xy 90.181012 -294.459067) (xy 90.164611 -294.411293)
			(xy 90.156298 -294.361471) (xy 90.155776 -294.336216) (xy 90.156262 -294.31138) (xy 90.164299 -294.262364)
			(xy 90.180165 -294.215295) (xy 90.203441 -294.171415) (xy 90.233512 -294.131881) (xy 90.269587 -294.097736)
			(xy 90.310712 -294.069881) (xy 90.355804 -294.04905) (xy 90.403674 -294.035793) (xy 90.428318 -294.032686)
			(xy 90.442034 -294.031162) (xy 90.464132 -294.014652) (xy 90.509598 -293.906956) (xy 90.505788 -293.879778)
			(xy 90.497152 -293.868856) (xy 90.485468 -293.853362) (xy 90.478007 -293.844255) (xy 90.457086 -293.833518)
			(xy 90.445336 -293.832788) (xy 90.398527 -293.831595) (xy 90.305342 -293.822331) (xy 90.21326 -293.805299)
			(xy 90.167968 -293.793418) (xy 90.158691 -293.791344) (xy 90.139799 -293.793307) (xy 90.131138 -293.797228)
			(xy 90.109346 -293.80799) (xy 90.063203 -293.823244) (xy 90.015229 -293.831019) (xy 89.99093 -293.831518)
			(xy 89.966629 -293.831029) (xy 89.918649 -293.823278) (xy 89.872511 -293.807998) (xy 89.850722 -293.797228)
			(xy 89.842092 -293.793205) (xy 89.823165 -293.791255) (xy 89.813892 -293.793418) (xy 89.766082 -293.805847)
			(xy 89.668832 -293.823236) (xy 89.570426 -293.831971) (xy 89.52103 -293.832534) (xy 89.471633 -293.832004)
			(xy 89.373224 -293.823269) (xy 89.275975 -293.805865) (xy 89.228168 -293.793418) (xy 89.218891 -293.791344)
			(xy 89.199999 -293.793307) (xy 89.191338 -293.797228) (xy 89.169546 -293.80799) (xy 89.123403 -293.823244)
			(xy 89.075429 -293.831019) (xy 89.05113 -293.831518) (xy 89.026829 -293.831029) (xy 88.978849 -293.823278)
			(xy 88.932711 -293.807998) (xy 88.910922 -293.797228) (xy 88.902292 -293.793205) (xy 88.883365 -293.791255)
			(xy 88.874092 -293.793418) (xy 88.826282 -293.805847) (xy 88.729032 -293.823236) (xy 88.630626 -293.831971)
			(xy 88.58123 -293.832534) (xy 88.580976 -293.832534) (xy 88.531578 -293.832006) (xy 88.433169 -293.823275)
			(xy 88.335918 -293.805875) (xy 88.288114 -293.793418) (xy 88.278835 -293.791335) (xy 88.259936 -293.793283)
			(xy 88.251284 -293.797228) (xy 88.229491 -293.807986) (xy 88.183347 -293.823232) (xy 88.135374 -293.830998)
			(xy 88.111076 -293.831518) (xy 88.086774 -293.831033) (xy 88.038792 -293.823288) (xy 87.99265 -293.808015)
			(xy 87.970868 -293.797228) (xy 87.962238 -293.793196) (xy 87.943307 -293.791229) (xy 87.934038 -293.793418)
			(xy 87.886228 -293.805849) (xy 87.788978 -293.823242) (xy 87.690572 -293.831981) (xy 87.641176 -293.832534)
			(xy 87.640922 -293.832534) (xy 87.591525 -293.832003) (xy 87.493117 -293.823268) (xy 87.395867 -293.805863)
			(xy 87.34806 -293.793418) (xy 87.338783 -293.791345) (xy 87.319893 -293.793311) (xy 87.31123 -293.797228)
			(xy 87.289438 -293.807989) (xy 87.243294 -293.823242) (xy 87.195321 -293.831016) (xy 87.171022 -293.831518)
			(xy 87.146721 -293.831029) (xy 87.098742 -293.823276) (xy 87.052605 -293.807996) (xy 87.030814 -293.797228)
			(xy 87.022184 -293.793206) (xy 87.003258 -293.791259) (xy 86.993984 -293.793418) (xy 86.946174 -293.805851)
			(xy 86.848925 -293.823248) (xy 86.750519 -293.831991) (xy 86.701122 -293.832534) (xy 86.700868 -293.832534)
			(xy 86.65147 -293.832005) (xy 86.553062 -293.823274) (xy 86.455811 -293.805873) (xy 86.408006 -293.793418)
			(xy 86.398727 -293.791337) (xy 86.37983 -293.793287) (xy 86.371176 -293.797228) (xy 86.349383 -293.807985)
			(xy 86.303239 -293.82323) (xy 86.255266 -293.830995) (xy 86.230968 -293.831518) (xy 86.206666 -293.831032)
			(xy 86.158684 -293.823286) (xy 86.112543 -293.808012) (xy 86.09076 -293.797228) (xy 86.08213 -293.793198)
			(xy 86.0632 -293.791234) (xy 86.05393 -293.793418) (xy 86.00612 -293.805848) (xy 85.90887 -293.823241)
			(xy 85.810464 -293.831979) (xy 85.761068 -293.832534) (xy 85.760814 -293.832534) (xy 85.711416 -293.832007)
			(xy 85.613006 -293.82328) (xy 85.515754 -293.805883) (xy 85.467952 -293.793418) (xy 85.458675 -293.791347)
			(xy 85.439786 -293.793315) (xy 85.431122 -293.797228) (xy 85.40933 -293.807989) (xy 85.363186 -293.82324)
			(xy 85.315213 -293.831013) (xy 85.290914 -293.831518) (xy 85.266614 -293.831028) (xy 85.218635 -293.823274)
			(xy 85.172498 -293.807993) (xy 85.150706 -293.797228) (xy 85.142076 -293.793208) (xy 85.123151 -293.791263)
			(xy 85.113876 -293.793418) (xy 85.066066 -293.80585) (xy 84.968817 -293.823247) (xy 84.870411 -293.831989)
			(xy 84.821014 -293.832534) (xy 84.771616 -293.832007) (xy 84.673206 -293.82328) (xy 84.575954 -293.805883)
			(xy 84.528152 -293.793418) (xy 84.518875 -293.791347) (xy 84.499986 -293.793315) (xy 84.491322 -293.797228)
			(xy 84.46953 -293.807989) (xy 84.423386 -293.82324) (xy 84.375413 -293.831013) (xy 84.351114 -293.831518)
			(xy 84.326814 -293.831028) (xy 84.278835 -293.823274) (xy 84.232698 -293.807993) (xy 84.210906 -293.797228)
			(xy 84.202276 -293.793208) (xy 84.183351 -293.791263) (xy 84.174076 -293.793418) (xy 84.126266 -293.80585)
			(xy 84.029017 -293.823247) (xy 83.930611 -293.831989) (xy 83.881214 -293.832534) (xy 83.88096 -293.832534)
			(xy 83.86355 -293.832503) (xy 83.828746 -293.831489) (xy 83.811364 -293.830502) (xy 83.800442 -293.82974)
			(xy 83.780122 -293.83736) (xy 83.281266 -294.336216) (xy 83.575156 -294.336216) (xy 83.579116 -294.287162)
			(xy 83.590893 -294.239378) (xy 83.610184 -294.194102) (xy 83.636487 -294.152506) (xy 83.669122 -294.115669)
			(xy 83.707243 -294.084544) (xy 83.749864 -294.059937) (xy 83.79588 -294.042485) (xy 83.844099 -294.032641)
			(xy 83.893274 -294.03066) (xy 83.942129 -294.036592) (xy 83.9894 -294.050284) (xy 84.033862 -294.071382)
			(xy 84.074365 -294.099338) (xy 84.109858 -294.13343) (xy 84.139423 -294.172774) (xy 84.162294 -294.216351)
			(xy 84.177878 -294.263032) (xy 84.185773 -294.311609) (xy 84.186268 -294.336216) (xy 84.51521 -294.336216)
			(xy 84.51917 -294.287162) (xy 84.530947 -294.239378) (xy 84.550238 -294.194102) (xy 84.576541 -294.152506)
			(xy 84.609176 -294.115669) (xy 84.647297 -294.084544) (xy 84.689918 -294.059937) (xy 84.735934 -294.042485)
			(xy 84.784153 -294.032641) (xy 84.833328 -294.03066) (xy 84.882183 -294.036592) (xy 84.929454 -294.050284)
			(xy 84.973916 -294.071382) (xy 85.014419 -294.099338) (xy 85.049912 -294.13343) (xy 85.079477 -294.172774)
			(xy 85.102348 -294.216351) (xy 85.117932 -294.263032) (xy 85.125827 -294.311609) (xy 85.126322 -294.336216)
			(xy 85.455264 -294.336216) (xy 85.459224 -294.287162) (xy 85.471001 -294.239378) (xy 85.490292 -294.194102)
			(xy 85.516595 -294.152506) (xy 85.54923 -294.115669) (xy 85.587351 -294.084544) (xy 85.629972 -294.059937)
			(xy 85.675988 -294.042485) (xy 85.724207 -294.032641) (xy 85.773382 -294.03066) (xy 85.822237 -294.036592)
			(xy 85.869508 -294.050284) (xy 85.91397 -294.071382) (xy 85.954473 -294.099338) (xy 85.989966 -294.13343)
			(xy 86.019531 -294.172774) (xy 86.042402 -294.216351) (xy 86.057986 -294.263032) (xy 86.065881 -294.311609)
			(xy 86.066376 -294.336216) (xy 86.395318 -294.336216) (xy 86.399278 -294.287162) (xy 86.411055 -294.239378)
			(xy 86.430346 -294.194102) (xy 86.456649 -294.152506) (xy 86.489284 -294.115669) (xy 86.527405 -294.084544)
			(xy 86.570026 -294.059937) (xy 86.616042 -294.042485) (xy 86.664261 -294.032641) (xy 86.713436 -294.03066)
			(xy 86.762291 -294.036592) (xy 86.809562 -294.050284) (xy 86.854024 -294.071382) (xy 86.894527 -294.099338)
			(xy 86.93002 -294.13343) (xy 86.959585 -294.172774) (xy 86.982456 -294.216351) (xy 86.99804 -294.263032)
			(xy 87.005935 -294.311609) (xy 87.00643 -294.336216) (xy 87.335118 -294.336216) (xy 87.339078 -294.287162)
			(xy 87.350855 -294.239378) (xy 87.370146 -294.194102) (xy 87.396449 -294.152506) (xy 87.429084 -294.115669)
			(xy 87.467205 -294.084544) (xy 87.509826 -294.059937) (xy 87.555842 -294.042485) (xy 87.604061 -294.032641)
			(xy 87.653236 -294.03066) (xy 87.702091 -294.036592) (xy 87.749362 -294.050284) (xy 87.793824 -294.071382)
			(xy 87.834327 -294.099338) (xy 87.86982 -294.13343) (xy 87.899385 -294.172774) (xy 87.922256 -294.216351)
			(xy 87.93784 -294.263032) (xy 87.945735 -294.311609) (xy 87.94623 -294.336216) (xy 88.275172 -294.336216)
			(xy 88.279132 -294.287162) (xy 88.290909 -294.239378) (xy 88.3102 -294.194102) (xy 88.336503 -294.152506)
			(xy 88.369138 -294.115669) (xy 88.407259 -294.084544) (xy 88.44988 -294.059937) (xy 88.495896 -294.042485)
			(xy 88.544115 -294.032641) (xy 88.59329 -294.03066) (xy 88.642145 -294.036592) (xy 88.689416 -294.050284)
			(xy 88.733878 -294.071382) (xy 88.774381 -294.099338) (xy 88.809874 -294.13343) (xy 88.839439 -294.172774)
			(xy 88.86231 -294.216351) (xy 88.877894 -294.263032) (xy 88.885789 -294.311609) (xy 88.886284 -294.336216)
			(xy 89.215226 -294.336216) (xy 89.219186 -294.287162) (xy 89.230963 -294.239378) (xy 89.250254 -294.194102)
			(xy 89.276557 -294.152506) (xy 89.309192 -294.115669) (xy 89.347313 -294.084544) (xy 89.389934 -294.059937)
			(xy 89.43595 -294.042485) (xy 89.484169 -294.032641) (xy 89.533344 -294.03066) (xy 89.582199 -294.036592)
			(xy 89.62947 -294.050284) (xy 89.673932 -294.071382) (xy 89.714435 -294.099338) (xy 89.749928 -294.13343)
			(xy 89.779493 -294.172774) (xy 89.802364 -294.216351) (xy 89.817948 -294.263032) (xy 89.825843 -294.311609)
			(xy 89.826338 -294.336216) (xy 89.825843 -294.360823) (xy 89.817948 -294.4094) (xy 89.802364 -294.456081)
			(xy 89.779493 -294.499658) (xy 89.749928 -294.539002) (xy 89.714435 -294.573094) (xy 89.673932 -294.60105)
			(xy 89.62947 -294.622148) (xy 89.582199 -294.63584) (xy 89.533344 -294.641772) (xy 89.484169 -294.639791)
			(xy 89.43595 -294.629947) (xy 89.389934 -294.612495) (xy 89.347313 -294.587888) (xy 89.309192 -294.556763)
			(xy 89.276557 -294.519926) (xy 89.250254 -294.47833) (xy 89.230963 -294.433054) (xy 89.219186 -294.38527)
			(xy 89.215226 -294.336216) (xy 88.886284 -294.336216) (xy 88.885789 -294.360823) (xy 88.877894 -294.4094)
			(xy 88.86231 -294.456081) (xy 88.839439 -294.499658) (xy 88.809874 -294.539002) (xy 88.774381 -294.573094)
			(xy 88.733878 -294.60105) (xy 88.689416 -294.622148) (xy 88.642145 -294.63584) (xy 88.59329 -294.641772)
			(xy 88.544115 -294.639791) (xy 88.495896 -294.629947) (xy 88.44988 -294.612495) (xy 88.407259 -294.587888)
			(xy 88.369138 -294.556763) (xy 88.336503 -294.519926) (xy 88.3102 -294.47833) (xy 88.290909 -294.433054)
			(xy 88.279132 -294.38527) (xy 88.275172 -294.336216) (xy 87.94623 -294.336216) (xy 87.945735 -294.360823)
			(xy 87.93784 -294.4094) (xy 87.922256 -294.456081) (xy 87.899385 -294.499658) (xy 87.86982 -294.539002)
			(xy 87.834327 -294.573094) (xy 87.793824 -294.60105) (xy 87.749362 -294.622148) (xy 87.702091 -294.63584)
			(xy 87.653236 -294.641772) (xy 87.604061 -294.639791) (xy 87.555842 -294.629947) (xy 87.509826 -294.612495)
			(xy 87.467205 -294.587888) (xy 87.429084 -294.556763) (xy 87.396449 -294.519926) (xy 87.370146 -294.47833)
			(xy 87.350855 -294.433054) (xy 87.339078 -294.38527) (xy 87.335118 -294.336216) (xy 87.00643 -294.336216)
			(xy 87.005935 -294.360823) (xy 86.99804 -294.4094) (xy 86.982456 -294.456081) (xy 86.959585 -294.499658)
			(xy 86.93002 -294.539002) (xy 86.894527 -294.573094) (xy 86.854024 -294.60105) (xy 86.809562 -294.622148)
			(xy 86.762291 -294.63584) (xy 86.713436 -294.641772) (xy 86.664261 -294.639791) (xy 86.616042 -294.629947)
			(xy 86.570026 -294.612495) (xy 86.527405 -294.587888) (xy 86.489284 -294.556763) (xy 86.456649 -294.519926)
			(xy 86.430346 -294.47833) (xy 86.411055 -294.433054) (xy 86.399278 -294.38527) (xy 86.395318 -294.336216)
			(xy 86.066376 -294.336216) (xy 86.065881 -294.360823) (xy 86.057986 -294.4094) (xy 86.042402 -294.456081)
			(xy 86.019531 -294.499658) (xy 85.989966 -294.539002) (xy 85.954473 -294.573094) (xy 85.91397 -294.60105)
			(xy 85.869508 -294.622148) (xy 85.822237 -294.63584) (xy 85.773382 -294.641772) (xy 85.724207 -294.639791)
			(xy 85.675988 -294.629947) (xy 85.629972 -294.612495) (xy 85.587351 -294.587888) (xy 85.54923 -294.556763)
			(xy 85.516595 -294.519926) (xy 85.490292 -294.47833) (xy 85.471001 -294.433054) (xy 85.459224 -294.38527)
			(xy 85.455264 -294.336216) (xy 85.126322 -294.336216) (xy 85.125827 -294.360823) (xy 85.117932 -294.4094)
			(xy 85.102348 -294.456081) (xy 85.079477 -294.499658) (xy 85.049912 -294.539002) (xy 85.014419 -294.573094)
			(xy 84.973916 -294.60105) (xy 84.929454 -294.622148) (xy 84.882183 -294.63584) (xy 84.833328 -294.641772)
			(xy 84.784153 -294.639791) (xy 84.735934 -294.629947) (xy 84.689918 -294.612495) (xy 84.647297 -294.587888)
			(xy 84.609176 -294.556763) (xy 84.576541 -294.519926) (xy 84.550238 -294.47833) (xy 84.530947 -294.433054)
			(xy 84.51917 -294.38527) (xy 84.51521 -294.336216) (xy 84.186268 -294.336216) (xy 84.185773 -294.360823)
			(xy 84.177878 -294.4094) (xy 84.162294 -294.456081) (xy 84.139423 -294.499658) (xy 84.109858 -294.539002)
			(xy 84.074365 -294.573094) (xy 84.033862 -294.60105) (xy 83.9894 -294.622148) (xy 83.942129 -294.63584)
			(xy 83.893274 -294.641772) (xy 83.844099 -294.639791) (xy 83.79588 -294.629947) (xy 83.749864 -294.612495)
			(xy 83.707243 -294.587888) (xy 83.669122 -294.556763) (xy 83.636487 -294.519926) (xy 83.610184 -294.47833)
			(xy 83.590893 -294.433054) (xy 83.579116 -294.38527) (xy 83.575156 -294.336216) (xy 83.281266 -294.336216)
			(xy 83.255866 -294.361616) (xy 83.250527 -294.367319) (xy 83.243293 -294.381157) (xy 83.241642 -294.388794)
			(xy 83.237175 -294.411746) (xy 83.222192 -294.456037) (xy 83.200631 -294.497526) (xy 83.172996 -294.535242)
			(xy 83.139933 -294.568303) (xy 83.102216 -294.595937) (xy 83.060727 -294.617497) (xy 83.016435 -294.632478)
			(xy 82.993484 -294.636952) (xy 82.985864 -294.638222) (xy 82.971894 -294.645588) (xy 82.706972 -294.91051)
			(xy 82.704432 -294.948356) (xy 82.715608 -294.963342) (xy 82.729867 -294.983255) (xy 82.752527 -295.026669)
			(xy 82.767977 -295.073141) (xy 82.77582 -295.121482) (xy 82.776314 -295.145968) (xy 82.776314 -295.146222)
			(xy 83.105256 -295.146222) (xy 83.109216 -295.097168) (xy 83.120993 -295.049384) (xy 83.140284 -295.004108)
			(xy 83.166587 -294.962512) (xy 83.199222 -294.925675) (xy 83.237343 -294.89455) (xy 83.279964 -294.869943)
			(xy 83.32598 -294.852491) (xy 83.374199 -294.842647) (xy 83.423374 -294.840666) (xy 83.472229 -294.846598)
			(xy 83.5195 -294.86029) (xy 83.563962 -294.881388) (xy 83.604465 -294.909344) (xy 83.639958 -294.943436)
			(xy 83.669523 -294.98278) (xy 83.692394 -295.026357) (xy 83.707978 -295.073038) (xy 83.715873 -295.121615)
			(xy 83.716368 -295.146222) (xy 84.04531 -295.146222) (xy 84.04927 -295.097168) (xy 84.061047 -295.049384)
			(xy 84.080338 -295.004108) (xy 84.106641 -294.962512) (xy 84.139276 -294.925675) (xy 84.177397 -294.89455)
			(xy 84.220018 -294.869943) (xy 84.266034 -294.852491) (xy 84.314253 -294.842647) (xy 84.363428 -294.840666)
			(xy 84.412283 -294.846598) (xy 84.459554 -294.86029) (xy 84.504016 -294.881388) (xy 84.544519 -294.909344)
			(xy 84.580012 -294.943436) (xy 84.609577 -294.98278) (xy 84.632448 -295.026357) (xy 84.648032 -295.073038)
			(xy 84.655927 -295.121615) (xy 84.656422 -295.146222) (xy 84.98511 -295.146222) (xy 84.98907 -295.097168)
			(xy 85.000847 -295.049384) (xy 85.020138 -295.004108) (xy 85.046441 -294.962512) (xy 85.079076 -294.925675)
			(xy 85.117197 -294.89455) (xy 85.159818 -294.869943) (xy 85.205834 -294.852491) (xy 85.254053 -294.842647)
			(xy 85.303228 -294.840666) (xy 85.352083 -294.846598) (xy 85.399354 -294.86029) (xy 85.443816 -294.881388)
			(xy 85.484319 -294.909344) (xy 85.519812 -294.943436) (xy 85.549377 -294.98278) (xy 85.572248 -295.026357)
			(xy 85.587832 -295.073038) (xy 85.595727 -295.121615) (xy 85.596222 -295.146222) (xy 85.925164 -295.146222)
			(xy 85.929124 -295.097168) (xy 85.940901 -295.049384) (xy 85.960192 -295.004108) (xy 85.986495 -294.962512)
			(xy 86.01913 -294.925675) (xy 86.057251 -294.89455) (xy 86.099872 -294.869943) (xy 86.145888 -294.852491)
			(xy 86.194107 -294.842647) (xy 86.243282 -294.840666) (xy 86.292137 -294.846598) (xy 86.339408 -294.86029)
			(xy 86.38387 -294.881388) (xy 86.424373 -294.909344) (xy 86.459866 -294.943436) (xy 86.489431 -294.98278)
			(xy 86.512302 -295.026357) (xy 86.527886 -295.073038) (xy 86.535781 -295.121615) (xy 86.536276 -295.146222)
			(xy 86.865218 -295.146222) (xy 86.869178 -295.097168) (xy 86.880955 -295.049384) (xy 86.900246 -295.004108)
			(xy 86.926549 -294.962512) (xy 86.959184 -294.925675) (xy 86.997305 -294.89455) (xy 87.039926 -294.869943)
			(xy 87.085942 -294.852491) (xy 87.134161 -294.842647) (xy 87.183336 -294.840666) (xy 87.232191 -294.846598)
			(xy 87.279462 -294.86029) (xy 87.323924 -294.881388) (xy 87.364427 -294.909344) (xy 87.39992 -294.943436)
			(xy 87.429485 -294.98278) (xy 87.452356 -295.026357) (xy 87.46794 -295.073038) (xy 87.475835 -295.121615)
			(xy 87.47633 -295.146222) (xy 87.805272 -295.146222) (xy 87.809232 -295.097168) (xy 87.821009 -295.049384)
			(xy 87.8403 -295.004108) (xy 87.866603 -294.962512) (xy 87.899238 -294.925675) (xy 87.937359 -294.89455)
			(xy 87.97998 -294.869943) (xy 88.025996 -294.852491) (xy 88.074215 -294.842647) (xy 88.12339 -294.840666)
			(xy 88.172245 -294.846598) (xy 88.219516 -294.86029) (xy 88.263978 -294.881388) (xy 88.304481 -294.909344)
			(xy 88.339974 -294.943436) (xy 88.369539 -294.98278) (xy 88.39241 -295.026357) (xy 88.407994 -295.073038)
			(xy 88.415889 -295.121615) (xy 88.416384 -295.146222) (xy 88.745326 -295.146222) (xy 88.749286 -295.097168)
			(xy 88.761063 -295.049384) (xy 88.780354 -295.004108) (xy 88.806657 -294.962512) (xy 88.839292 -294.925675)
			(xy 88.877413 -294.89455) (xy 88.920034 -294.869943) (xy 88.96605 -294.852491) (xy 89.014269 -294.842647)
			(xy 89.063444 -294.840666) (xy 89.112299 -294.846598) (xy 89.15957 -294.86029) (xy 89.204032 -294.881388)
			(xy 89.244535 -294.909344) (xy 89.280028 -294.943436) (xy 89.309593 -294.98278) (xy 89.332464 -295.026357)
			(xy 89.348048 -295.073038) (xy 89.355943 -295.121615) (xy 89.356438 -295.146222) (xy 89.685126 -295.146222)
			(xy 89.689086 -295.097168) (xy 89.700863 -295.049384) (xy 89.720154 -295.004108) (xy 89.746457 -294.962512)
			(xy 89.779092 -294.925675) (xy 89.817213 -294.89455) (xy 89.859834 -294.869943) (xy 89.90585 -294.852491)
			(xy 89.954069 -294.842647) (xy 90.003244 -294.840666) (xy 90.052099 -294.846598) (xy 90.09937 -294.86029)
			(xy 90.143832 -294.881388) (xy 90.184335 -294.909344) (xy 90.219828 -294.943436) (xy 90.249393 -294.98278)
			(xy 90.272264 -295.026357) (xy 90.287848 -295.073038) (xy 90.295743 -295.121615) (xy 90.296238 -295.146222)
			(xy 90.62518 -295.146222) (xy 90.62914 -295.097168) (xy 90.640917 -295.049384) (xy 90.660208 -295.004108)
			(xy 90.686511 -294.962512) (xy 90.719146 -294.925675) (xy 90.757267 -294.89455) (xy 90.799888 -294.869943)
			(xy 90.845904 -294.852491) (xy 90.894123 -294.842647) (xy 90.943298 -294.840666) (xy 90.992153 -294.846598)
			(xy 91.039424 -294.86029) (xy 91.083886 -294.881388) (xy 91.124389 -294.909344) (xy 91.159882 -294.943436)
			(xy 91.189447 -294.98278) (xy 91.212318 -295.026357) (xy 91.227902 -295.073038) (xy 91.235797 -295.121615)
			(xy 91.236292 -295.146222) (xy 91.565234 -295.146222) (xy 91.569194 -295.097168) (xy 91.580971 -295.049384)
			(xy 91.600262 -295.004108) (xy 91.626565 -294.962512) (xy 91.6592 -294.925675) (xy 91.697321 -294.89455)
			(xy 91.739942 -294.869943) (xy 91.785958 -294.852491) (xy 91.834177 -294.842647) (xy 91.883352 -294.840666)
			(xy 91.932207 -294.846598) (xy 91.979478 -294.86029) (xy 92.02394 -294.881388) (xy 92.064443 -294.909344)
			(xy 92.099936 -294.943436) (xy 92.129501 -294.98278) (xy 92.152372 -295.026357) (xy 92.167956 -295.073038)
			(xy 92.175851 -295.121615) (xy 92.176346 -295.146222) (xy 92.505288 -295.146222) (xy 92.509248 -295.097168)
			(xy 92.521025 -295.049384) (xy 92.540316 -295.004108) (xy 92.566619 -294.962512) (xy 92.599254 -294.925675)
			(xy 92.637375 -294.89455) (xy 92.679996 -294.869943) (xy 92.726012 -294.852491) (xy 92.774231 -294.842647)
			(xy 92.823406 -294.840666) (xy 92.872261 -294.846598) (xy 92.919532 -294.86029) (xy 92.963994 -294.881388)
			(xy 93.004497 -294.909344) (xy 93.03999 -294.943436) (xy 93.069555 -294.98278) (xy 93.092426 -295.026357)
			(xy 93.10801 -295.073038) (xy 93.115905 -295.121615) (xy 93.1164 -295.146222) (xy 95.325196 -295.146222)
			(xy 95.329156 -295.097168) (xy 95.340933 -295.049384) (xy 95.360224 -295.004108) (xy 95.386527 -294.962512)
			(xy 95.419162 -294.925675) (xy 95.457283 -294.89455) (xy 95.499904 -294.869943) (xy 95.54592 -294.852491)
			(xy 95.594139 -294.842647) (xy 95.643314 -294.840666) (xy 95.692169 -294.846598) (xy 95.73944 -294.86029)
			(xy 95.783902 -294.881388) (xy 95.824405 -294.909344) (xy 95.859898 -294.943436) (xy 95.889463 -294.98278)
			(xy 95.912334 -295.026357) (xy 95.927918 -295.073038) (xy 95.935813 -295.121615) (xy 95.936308 -295.146222)
			(xy 95.935813 -295.170829) (xy 95.927918 -295.219406) (xy 95.912334 -295.266087) (xy 95.889463 -295.309664)
			(xy 95.859898 -295.349008) (xy 95.824405 -295.3831) (xy 95.783902 -295.411056) (xy 95.73944 -295.432154)
			(xy 95.692169 -295.445846) (xy 95.643314 -295.451778) (xy 95.594139 -295.449797) (xy 95.54592 -295.439953)
			(xy 95.499904 -295.422501) (xy 95.457283 -295.397894) (xy 95.419162 -295.366769) (xy 95.386527 -295.329932)
			(xy 95.360224 -295.288336) (xy 95.340933 -295.24306) (xy 95.329156 -295.195276) (xy 95.325196 -295.146222)
			(xy 93.1164 -295.146222) (xy 93.115905 -295.170829) (xy 93.10801 -295.219406) (xy 93.092426 -295.266087)
			(xy 93.069555 -295.309664) (xy 93.03999 -295.349008) (xy 93.004497 -295.3831) (xy 92.963994 -295.411056)
			(xy 92.919532 -295.432154) (xy 92.872261 -295.445846) (xy 92.823406 -295.451778) (xy 92.774231 -295.449797)
			(xy 92.726012 -295.439953) (xy 92.679996 -295.422501) (xy 92.637375 -295.397894) (xy 92.599254 -295.366769)
			(xy 92.566619 -295.329932) (xy 92.540316 -295.288336) (xy 92.521025 -295.24306) (xy 92.509248 -295.195276)
			(xy 92.505288 -295.146222) (xy 92.176346 -295.146222) (xy 92.175851 -295.170829) (xy 92.167956 -295.219406)
			(xy 92.152372 -295.266087) (xy 92.129501 -295.309664) (xy 92.099936 -295.349008) (xy 92.064443 -295.3831)
			(xy 92.02394 -295.411056) (xy 91.979478 -295.432154) (xy 91.932207 -295.445846) (xy 91.883352 -295.451778)
			(xy 91.834177 -295.449797) (xy 91.785958 -295.439953) (xy 91.739942 -295.422501) (xy 91.697321 -295.397894)
			(xy 91.6592 -295.366769) (xy 91.626565 -295.329932) (xy 91.600262 -295.288336) (xy 91.580971 -295.24306)
			(xy 91.569194 -295.195276) (xy 91.565234 -295.146222) (xy 91.236292 -295.146222) (xy 91.235797 -295.170829)
			(xy 91.227902 -295.219406) (xy 91.212318 -295.266087) (xy 91.189447 -295.309664) (xy 91.159882 -295.349008)
			(xy 91.124389 -295.3831) (xy 91.083886 -295.411056) (xy 91.039424 -295.432154) (xy 90.992153 -295.445846)
			(xy 90.943298 -295.451778) (xy 90.894123 -295.449797) (xy 90.845904 -295.439953) (xy 90.799888 -295.422501)
			(xy 90.757267 -295.397894) (xy 90.719146 -295.366769) (xy 90.686511 -295.329932) (xy 90.660208 -295.288336)
			(xy 90.640917 -295.24306) (xy 90.62914 -295.195276) (xy 90.62518 -295.146222) (xy 90.296238 -295.146222)
			(xy 90.295743 -295.170829) (xy 90.287848 -295.219406) (xy 90.272264 -295.266087) (xy 90.249393 -295.309664)
			(xy 90.219828 -295.349008) (xy 90.184335 -295.3831) (xy 90.143832 -295.411056) (xy 90.09937 -295.432154)
			(xy 90.052099 -295.445846) (xy 90.003244 -295.451778) (xy 89.954069 -295.449797) (xy 89.90585 -295.439953)
			(xy 89.859834 -295.422501) (xy 89.817213 -295.397894) (xy 89.779092 -295.366769) (xy 89.746457 -295.329932)
			(xy 89.720154 -295.288336) (xy 89.700863 -295.24306) (xy 89.689086 -295.195276) (xy 89.685126 -295.146222)
			(xy 89.356438 -295.146222) (xy 89.355943 -295.170829) (xy 89.348048 -295.219406) (xy 89.332464 -295.266087)
			(xy 89.309593 -295.309664) (xy 89.280028 -295.349008) (xy 89.244535 -295.3831) (xy 89.204032 -295.411056)
			(xy 89.15957 -295.432154) (xy 89.112299 -295.445846) (xy 89.063444 -295.451778) (xy 89.014269 -295.449797)
			(xy 88.96605 -295.439953) (xy 88.920034 -295.422501) (xy 88.877413 -295.397894) (xy 88.839292 -295.366769)
			(xy 88.806657 -295.329932) (xy 88.780354 -295.288336) (xy 88.761063 -295.24306) (xy 88.749286 -295.195276)
			(xy 88.745326 -295.146222) (xy 88.416384 -295.146222) (xy 88.415889 -295.170829) (xy 88.407994 -295.219406)
			(xy 88.39241 -295.266087) (xy 88.369539 -295.309664) (xy 88.339974 -295.349008) (xy 88.304481 -295.3831)
			(xy 88.263978 -295.411056) (xy 88.219516 -295.432154) (xy 88.172245 -295.445846) (xy 88.12339 -295.451778)
			(xy 88.074215 -295.449797) (xy 88.025996 -295.439953) (xy 87.97998 -295.422501) (xy 87.937359 -295.397894)
			(xy 87.899238 -295.366769) (xy 87.866603 -295.329932) (xy 87.8403 -295.288336) (xy 87.821009 -295.24306)
			(xy 87.809232 -295.195276) (xy 87.805272 -295.146222) (xy 87.47633 -295.146222) (xy 87.475835 -295.170829)
			(xy 87.46794 -295.219406) (xy 87.452356 -295.266087) (xy 87.429485 -295.309664) (xy 87.39992 -295.349008)
			(xy 87.364427 -295.3831) (xy 87.323924 -295.411056) (xy 87.279462 -295.432154) (xy 87.232191 -295.445846)
			(xy 87.183336 -295.451778) (xy 87.134161 -295.449797) (xy 87.085942 -295.439953) (xy 87.039926 -295.422501)
			(xy 86.997305 -295.397894) (xy 86.959184 -295.366769) (xy 86.926549 -295.329932) (xy 86.900246 -295.288336)
			(xy 86.880955 -295.24306) (xy 86.869178 -295.195276) (xy 86.865218 -295.146222) (xy 86.536276 -295.146222)
			(xy 86.535781 -295.170829) (xy 86.527886 -295.219406) (xy 86.512302 -295.266087) (xy 86.489431 -295.309664)
			(xy 86.459866 -295.349008) (xy 86.424373 -295.3831) (xy 86.38387 -295.411056) (xy 86.339408 -295.432154)
			(xy 86.292137 -295.445846) (xy 86.243282 -295.451778) (xy 86.194107 -295.449797) (xy 86.145888 -295.439953)
			(xy 86.099872 -295.422501) (xy 86.057251 -295.397894) (xy 86.01913 -295.366769) (xy 85.986495 -295.329932)
			(xy 85.960192 -295.288336) (xy 85.940901 -295.24306) (xy 85.929124 -295.195276) (xy 85.925164 -295.146222)
			(xy 85.596222 -295.146222) (xy 85.595727 -295.170829) (xy 85.587832 -295.219406) (xy 85.572248 -295.266087)
			(xy 85.549377 -295.309664) (xy 85.519812 -295.349008) (xy 85.484319 -295.3831) (xy 85.443816 -295.411056)
			(xy 85.399354 -295.432154) (xy 85.352083 -295.445846) (xy 85.303228 -295.451778) (xy 85.254053 -295.449797)
			(xy 85.205834 -295.439953) (xy 85.159818 -295.422501) (xy 85.117197 -295.397894) (xy 85.079076 -295.366769)
			(xy 85.046441 -295.329932) (xy 85.020138 -295.288336) (xy 85.000847 -295.24306) (xy 84.98907 -295.195276)
			(xy 84.98511 -295.146222) (xy 84.656422 -295.146222) (xy 84.655927 -295.170829) (xy 84.648032 -295.219406)
			(xy 84.632448 -295.266087) (xy 84.609577 -295.309664) (xy 84.580012 -295.349008) (xy 84.544519 -295.3831)
			(xy 84.504016 -295.411056) (xy 84.459554 -295.432154) (xy 84.412283 -295.445846) (xy 84.363428 -295.451778)
			(xy 84.314253 -295.449797) (xy 84.266034 -295.439953) (xy 84.220018 -295.422501) (xy 84.177397 -295.397894)
			(xy 84.139276 -295.366769) (xy 84.106641 -295.329932) (xy 84.080338 -295.288336) (xy 84.061047 -295.24306)
			(xy 84.04927 -295.195276) (xy 84.04531 -295.146222) (xy 83.716368 -295.146222) (xy 83.715873 -295.170829)
			(xy 83.707978 -295.219406) (xy 83.692394 -295.266087) (xy 83.669523 -295.309664) (xy 83.639958 -295.349008)
			(xy 83.604465 -295.3831) (xy 83.563962 -295.411056) (xy 83.5195 -295.432154) (xy 83.472229 -295.445846)
			(xy 83.423374 -295.451778) (xy 83.374199 -295.449797) (xy 83.32598 -295.439953) (xy 83.279964 -295.422501)
			(xy 83.237343 -295.397894) (xy 83.199222 -295.366769) (xy 83.166587 -295.329932) (xy 83.140284 -295.288336)
			(xy 83.120993 -295.24306) (xy 83.109216 -295.195276) (xy 83.105256 -295.146222) (xy 82.776314 -295.146222)
			(xy 82.775842 -295.170212) (xy 82.768333 -295.217602) (xy 82.753504 -295.263233) (xy 82.731719 -295.305983)
			(xy 82.703515 -295.344799) (xy 82.669587 -295.378726) (xy 82.63077 -295.406927) (xy 82.588018 -295.42871)
			(xy 82.542386 -295.443537) (xy 82.494996 -295.451043) (xy 82.471006 -295.45153) (xy 82.470752 -295.45153)
			(xy 82.446264 -295.451047) (xy 82.397917 -295.443224) (xy 82.351443 -295.427772) (xy 82.308037 -295.405088)
			(xy 82.288126 -295.390824) (xy 82.27314 -295.379648) (xy 82.235294 -295.382188) (xy 81.661254 -295.956228)
			(xy 82.635102 -295.956228) (xy 82.639062 -295.907174) (xy 82.650839 -295.85939) (xy 82.67013 -295.814114)
			(xy 82.696433 -295.772518) (xy 82.729068 -295.735681) (xy 82.767189 -295.704556) (xy 82.80981 -295.679949)
			(xy 82.855826 -295.662497) (xy 82.904045 -295.652653) (xy 82.95322 -295.650672) (xy 83.002075 -295.656604)
			(xy 83.049346 -295.670296) (xy 83.093808 -295.691394) (xy 83.134311 -295.71935) (xy 83.169804 -295.753442)
			(xy 83.199369 -295.792786) (xy 83.22224 -295.836363) (xy 83.237824 -295.883044) (xy 83.245719 -295.931621)
			(xy 83.246214 -295.956228) (xy 83.575156 -295.956228) (xy 83.579116 -295.907174) (xy 83.590893 -295.85939)
			(xy 83.610184 -295.814114) (xy 83.636487 -295.772518) (xy 83.669122 -295.735681) (xy 83.707243 -295.704556)
			(xy 83.749864 -295.679949) (xy 83.79588 -295.662497) (xy 83.844099 -295.652653) (xy 83.893274 -295.650672)
			(xy 83.942129 -295.656604) (xy 83.9894 -295.670296) (xy 84.033862 -295.691394) (xy 84.074365 -295.71935)
			(xy 84.109858 -295.753442) (xy 84.139423 -295.792786) (xy 84.162294 -295.836363) (xy 84.177878 -295.883044)
			(xy 84.185773 -295.931621) (xy 84.186268 -295.956228) (xy 84.51521 -295.956228) (xy 84.51917 -295.907174)
			(xy 84.530947 -295.85939) (xy 84.550238 -295.814114) (xy 84.576541 -295.772518) (xy 84.609176 -295.735681)
			(xy 84.647297 -295.704556) (xy 84.689918 -295.679949) (xy 84.735934 -295.662497) (xy 84.784153 -295.652653)
			(xy 84.833328 -295.650672) (xy 84.882183 -295.656604) (xy 84.929454 -295.670296) (xy 84.973916 -295.691394)
			(xy 85.014419 -295.71935) (xy 85.049912 -295.753442) (xy 85.079477 -295.792786) (xy 85.102348 -295.836363)
			(xy 85.117932 -295.883044) (xy 85.125827 -295.931621) (xy 85.126322 -295.956228) (xy 85.455264 -295.956228)
			(xy 85.459224 -295.907174) (xy 85.471001 -295.85939) (xy 85.490292 -295.814114) (xy 85.516595 -295.772518)
			(xy 85.54923 -295.735681) (xy 85.587351 -295.704556) (xy 85.629972 -295.679949) (xy 85.675988 -295.662497)
			(xy 85.724207 -295.652653) (xy 85.773382 -295.650672) (xy 85.822237 -295.656604) (xy 85.869508 -295.670296)
			(xy 85.91397 -295.691394) (xy 85.954473 -295.71935) (xy 85.989966 -295.753442) (xy 86.019531 -295.792786)
			(xy 86.042402 -295.836363) (xy 86.057986 -295.883044) (xy 86.065881 -295.931621) (xy 86.066376 -295.956228)
			(xy 86.395318 -295.956228) (xy 86.399278 -295.907174) (xy 86.411055 -295.85939) (xy 86.430346 -295.814114)
			(xy 86.456649 -295.772518) (xy 86.489284 -295.735681) (xy 86.527405 -295.704556) (xy 86.570026 -295.679949)
			(xy 86.616042 -295.662497) (xy 86.664261 -295.652653) (xy 86.713436 -295.650672) (xy 86.762291 -295.656604)
			(xy 86.809562 -295.670296) (xy 86.854024 -295.691394) (xy 86.894527 -295.71935) (xy 86.93002 -295.753442)
			(xy 86.959585 -295.792786) (xy 86.982456 -295.836363) (xy 86.99804 -295.883044) (xy 87.005935 -295.931621)
			(xy 87.00643 -295.956228) (xy 88.275172 -295.956228) (xy 88.279132 -295.907174) (xy 88.290909 -295.85939)
			(xy 88.3102 -295.814114) (xy 88.336503 -295.772518) (xy 88.369138 -295.735681) (xy 88.407259 -295.704556)
			(xy 88.44988 -295.679949) (xy 88.495896 -295.662497) (xy 88.544115 -295.652653) (xy 88.59329 -295.650672)
			(xy 88.642145 -295.656604) (xy 88.689416 -295.670296) (xy 88.733878 -295.691394) (xy 88.774381 -295.71935)
			(xy 88.809874 -295.753442) (xy 88.839439 -295.792786) (xy 88.86231 -295.836363) (xy 88.877894 -295.883044)
			(xy 88.885789 -295.931621) (xy 88.886284 -295.956228) (xy 89.215226 -295.956228) (xy 89.219186 -295.907174)
			(xy 89.230963 -295.85939) (xy 89.250254 -295.814114) (xy 89.276557 -295.772518) (xy 89.309192 -295.735681)
			(xy 89.347313 -295.704556) (xy 89.389934 -295.679949) (xy 89.43595 -295.662497) (xy 89.484169 -295.652653)
			(xy 89.533344 -295.650672) (xy 89.582199 -295.656604) (xy 89.62947 -295.670296) (xy 89.673932 -295.691394)
			(xy 89.714435 -295.71935) (xy 89.749928 -295.753442) (xy 89.779493 -295.792786) (xy 89.802364 -295.836363)
			(xy 89.817948 -295.883044) (xy 89.825843 -295.931621) (xy 89.826338 -295.956228) (xy 90.15528 -295.956228)
			(xy 90.15924 -295.907174) (xy 90.171017 -295.85939) (xy 90.190308 -295.814114) (xy 90.216611 -295.772518)
			(xy 90.249246 -295.735681) (xy 90.287367 -295.704556) (xy 90.329988 -295.679949) (xy 90.376004 -295.662497)
			(xy 90.424223 -295.652653) (xy 90.473398 -295.650672) (xy 90.522253 -295.656604) (xy 90.569524 -295.670296)
			(xy 90.613986 -295.691394) (xy 90.654489 -295.71935) (xy 90.689982 -295.753442) (xy 90.719547 -295.792786)
			(xy 90.742418 -295.836363) (xy 90.758002 -295.883044) (xy 90.765897 -295.931621) (xy 90.766392 -295.956228)
			(xy 91.095334 -295.956228) (xy 91.099294 -295.907174) (xy 91.111071 -295.85939) (xy 91.130362 -295.814114)
			(xy 91.156665 -295.772518) (xy 91.1893 -295.735681) (xy 91.227421 -295.704556) (xy 91.270042 -295.679949)
			(xy 91.316058 -295.662497) (xy 91.364277 -295.652653) (xy 91.413452 -295.650672) (xy 91.462307 -295.656604)
			(xy 91.509578 -295.670296) (xy 91.55404 -295.691394) (xy 91.594543 -295.71935) (xy 91.630036 -295.753442)
			(xy 91.659601 -295.792786) (xy 91.682472 -295.836363) (xy 91.698056 -295.883044) (xy 91.705951 -295.931621)
			(xy 91.706446 -295.956228) (xy 92.035134 -295.956228) (xy 92.039094 -295.907174) (xy 92.050871 -295.85939)
			(xy 92.070162 -295.814114) (xy 92.096465 -295.772518) (xy 92.1291 -295.735681) (xy 92.167221 -295.704556)
			(xy 92.209842 -295.679949) (xy 92.255858 -295.662497) (xy 92.304077 -295.652653) (xy 92.353252 -295.650672)
			(xy 92.402107 -295.656604) (xy 92.449378 -295.670296) (xy 92.49384 -295.691394) (xy 92.534343 -295.71935)
			(xy 92.569836 -295.753442) (xy 92.599401 -295.792786) (xy 92.622272 -295.836363) (xy 92.637856 -295.883044)
			(xy 92.645751 -295.931621) (xy 92.646246 -295.956228) (xy 94.855296 -295.956228) (xy 94.859256 -295.907174)
			(xy 94.871033 -295.85939) (xy 94.890324 -295.814114) (xy 94.916627 -295.772518) (xy 94.949262 -295.735681)
			(xy 94.987383 -295.704556) (xy 95.030004 -295.679949) (xy 95.07602 -295.662497) (xy 95.124239 -295.652653)
			(xy 95.173414 -295.650672) (xy 95.222269 -295.656604) (xy 95.26954 -295.670296) (xy 95.314002 -295.691394)
			(xy 95.354505 -295.71935) (xy 95.389998 -295.753442) (xy 95.419563 -295.792786) (xy 95.442434 -295.836363)
			(xy 95.458018 -295.883044) (xy 95.465913 -295.931621) (xy 95.466408 -295.956228) (xy 95.465913 -295.980835)
			(xy 95.458018 -296.029412) (xy 95.442434 -296.076093) (xy 95.419563 -296.11967) (xy 95.389998 -296.159014)
			(xy 95.354505 -296.193106) (xy 95.314002 -296.221062) (xy 95.26954 -296.24216) (xy 95.222269 -296.255852)
			(xy 95.173414 -296.261784) (xy 95.124239 -296.259803) (xy 95.07602 -296.249959) (xy 95.030004 -296.232507)
			(xy 94.987383 -296.2079) (xy 94.949262 -296.176775) (xy 94.916627 -296.139938) (xy 94.890324 -296.098342)
			(xy 94.871033 -296.053066) (xy 94.859256 -296.005282) (xy 94.855296 -295.956228) (xy 92.646246 -295.956228)
			(xy 92.645751 -295.980835) (xy 92.637856 -296.029412) (xy 92.622272 -296.076093) (xy 92.599401 -296.11967)
			(xy 92.569836 -296.159014) (xy 92.534343 -296.193106) (xy 92.49384 -296.221062) (xy 92.449378 -296.24216)
			(xy 92.402107 -296.255852) (xy 92.353252 -296.261784) (xy 92.304077 -296.259803) (xy 92.255858 -296.249959)
			(xy 92.209842 -296.232507) (xy 92.167221 -296.2079) (xy 92.1291 -296.176775) (xy 92.096465 -296.139938)
			(xy 92.070162 -296.098342) (xy 92.050871 -296.053066) (xy 92.039094 -296.005282) (xy 92.035134 -295.956228)
			(xy 91.706446 -295.956228) (xy 91.705951 -295.980835) (xy 91.698056 -296.029412) (xy 91.682472 -296.076093)
			(xy 91.659601 -296.11967) (xy 91.630036 -296.159014) (xy 91.594543 -296.193106) (xy 91.55404 -296.221062)
			(xy 91.509578 -296.24216) (xy 91.462307 -296.255852) (xy 91.413452 -296.261784) (xy 91.364277 -296.259803)
			(xy 91.316058 -296.249959) (xy 91.270042 -296.232507) (xy 91.227421 -296.2079) (xy 91.1893 -296.176775)
			(xy 91.156665 -296.139938) (xy 91.130362 -296.098342) (xy 91.111071 -296.053066) (xy 91.099294 -296.005282)
			(xy 91.095334 -295.956228) (xy 90.766392 -295.956228) (xy 90.765897 -295.980835) (xy 90.758002 -296.029412)
			(xy 90.742418 -296.076093) (xy 90.719547 -296.11967) (xy 90.689982 -296.159014) (xy 90.654489 -296.193106)
			(xy 90.613986 -296.221062) (xy 90.569524 -296.24216) (xy 90.522253 -296.255852) (xy 90.473398 -296.261784)
			(xy 90.424223 -296.259803) (xy 90.376004 -296.249959) (xy 90.329988 -296.232507) (xy 90.287367 -296.2079)
			(xy 90.249246 -296.176775) (xy 90.216611 -296.139938) (xy 90.190308 -296.098342) (xy 90.171017 -296.053066)
			(xy 90.15924 -296.005282) (xy 90.15528 -295.956228) (xy 89.826338 -295.956228) (xy 89.825843 -295.980835)
			(xy 89.817948 -296.029412) (xy 89.802364 -296.076093) (xy 89.779493 -296.11967) (xy 89.749928 -296.159014)
			(xy 89.714435 -296.193106) (xy 89.673932 -296.221062) (xy 89.62947 -296.24216) (xy 89.582199 -296.255852)
			(xy 89.533344 -296.261784) (xy 89.484169 -296.259803) (xy 89.43595 -296.249959) (xy 89.389934 -296.232507)
			(xy 89.347313 -296.2079) (xy 89.309192 -296.176775) (xy 89.276557 -296.139938) (xy 89.250254 -296.098342)
			(xy 89.230963 -296.053066) (xy 89.219186 -296.005282) (xy 89.215226 -295.956228) (xy 88.886284 -295.956228)
			(xy 88.885789 -295.980835) (xy 88.877894 -296.029412) (xy 88.86231 -296.076093) (xy 88.839439 -296.11967)
			(xy 88.809874 -296.159014) (xy 88.774381 -296.193106) (xy 88.733878 -296.221062) (xy 88.689416 -296.24216)
			(xy 88.642145 -296.255852) (xy 88.59329 -296.261784) (xy 88.544115 -296.259803) (xy 88.495896 -296.249959)
			(xy 88.44988 -296.232507) (xy 88.407259 -296.2079) (xy 88.369138 -296.176775) (xy 88.336503 -296.139938)
			(xy 88.3102 -296.098342) (xy 88.290909 -296.053066) (xy 88.279132 -296.005282) (xy 88.275172 -295.956228)
			(xy 87.00643 -295.956228) (xy 87.005935 -295.980835) (xy 86.99804 -296.029412) (xy 86.982456 -296.076093)
			(xy 86.959585 -296.11967) (xy 86.93002 -296.159014) (xy 86.894527 -296.193106) (xy 86.854024 -296.221062)
			(xy 86.809562 -296.24216) (xy 86.762291 -296.255852) (xy 86.713436 -296.261784) (xy 86.664261 -296.259803)
			(xy 86.616042 -296.249959) (xy 86.570026 -296.232507) (xy 86.527405 -296.2079) (xy 86.489284 -296.176775)
			(xy 86.456649 -296.139938) (xy 86.430346 -296.098342) (xy 86.411055 -296.053066) (xy 86.399278 -296.005282)
			(xy 86.395318 -295.956228) (xy 86.066376 -295.956228) (xy 86.065881 -295.980835) (xy 86.057986 -296.029412)
			(xy 86.042402 -296.076093) (xy 86.019531 -296.11967) (xy 85.989966 -296.159014) (xy 85.954473 -296.193106)
			(xy 85.91397 -296.221062) (xy 85.869508 -296.24216) (xy 85.822237 -296.255852) (xy 85.773382 -296.261784)
			(xy 85.724207 -296.259803) (xy 85.675988 -296.249959) (xy 85.629972 -296.232507) (xy 85.587351 -296.2079)
			(xy 85.54923 -296.176775) (xy 85.516595 -296.139938) (xy 85.490292 -296.098342) (xy 85.471001 -296.053066)
			(xy 85.459224 -296.005282) (xy 85.455264 -295.956228) (xy 85.126322 -295.956228) (xy 85.125827 -295.980835)
			(xy 85.117932 -296.029412) (xy 85.102348 -296.076093) (xy 85.079477 -296.11967) (xy 85.049912 -296.159014)
			(xy 85.014419 -296.193106) (xy 84.973916 -296.221062) (xy 84.929454 -296.24216) (xy 84.882183 -296.255852)
			(xy 84.833328 -296.261784) (xy 84.784153 -296.259803) (xy 84.735934 -296.249959) (xy 84.689918 -296.232507)
			(xy 84.647297 -296.2079) (xy 84.609176 -296.176775) (xy 84.576541 -296.139938) (xy 84.550238 -296.098342)
			(xy 84.530947 -296.053066) (xy 84.51917 -296.005282) (xy 84.51521 -295.956228) (xy 84.186268 -295.956228)
			(xy 84.185773 -295.980835) (xy 84.177878 -296.029412) (xy 84.162294 -296.076093) (xy 84.139423 -296.11967)
			(xy 84.109858 -296.159014) (xy 84.074365 -296.193106) (xy 84.033862 -296.221062) (xy 83.9894 -296.24216)
			(xy 83.942129 -296.255852) (xy 83.893274 -296.261784) (xy 83.844099 -296.259803) (xy 83.79588 -296.249959)
			(xy 83.749864 -296.232507) (xy 83.707243 -296.2079) (xy 83.669122 -296.176775) (xy 83.636487 -296.139938)
			(xy 83.610184 -296.098342) (xy 83.590893 -296.053066) (xy 83.579116 -296.005282) (xy 83.575156 -295.956228)
			(xy 83.246214 -295.956228) (xy 83.245719 -295.980835) (xy 83.237824 -296.029412) (xy 83.22224 -296.076093)
			(xy 83.199369 -296.11967) (xy 83.169804 -296.159014) (xy 83.134311 -296.193106) (xy 83.093808 -296.221062)
			(xy 83.049346 -296.24216) (xy 83.002075 -296.255852) (xy 82.95322 -296.261784) (xy 82.904045 -296.259803)
			(xy 82.855826 -296.249959) (xy 82.80981 -296.232507) (xy 82.767189 -296.2079) (xy 82.729068 -296.176775)
			(xy 82.696433 -296.139938) (xy 82.67013 -296.098342) (xy 82.650839 -296.053066) (xy 82.639062 -296.005282)
			(xy 82.635102 -295.956228) (xy 81.661254 -295.956228) (xy 81.070196 -296.547286) (xy 81.067148 -296.552112)
			(xy 81.042909 -296.589754) (xy 80.989275 -296.66145) (xy 80.930079 -296.728627) (xy 80.8657 -296.790855)
			(xy 80.796552 -296.847735) (xy 80.760062 -296.873676) (xy 80.723232 -296.897298) (xy 80.71612 -296.901362)
			(xy 79.302399 -298.315083) (xy 87.657172 -298.315083) (xy 87.657172 -298.251161) (xy 87.665183 -298.187743)
			(xy 87.68108 -298.125829) (xy 87.704612 -298.066396) (xy 87.735406 -298.010381) (xy 87.772979 -297.958666)
			(xy 87.816736 -297.912069) (xy 87.865989 -297.871324) (xy 87.91996 -297.837073) (xy 87.977799 -297.809856)
			(xy 88.038592 -297.790103) (xy 88.101382 -297.778125) (xy 88.165178 -297.774112) (xy 88.228974 -297.778125)
			(xy 88.291764 -297.790103) (xy 88.352557 -297.809856) (xy 88.410396 -297.837073) (xy 88.464367 -297.871324)
			(xy 88.51362 -297.912069) (xy 88.557377 -297.958666) (xy 88.59495 -298.010381) (xy 88.625744 -298.066396)
			(xy 88.649276 -298.125829) (xy 88.665173 -298.187743) (xy 88.673184 -298.251161) (xy 88.673686 -298.283122)
			(xy 88.673184 -298.315083) (xy 88.665173 -298.378501) (xy 88.649276 -298.440415) (xy 88.625744 -298.499848)
			(xy 88.59495 -298.555863) (xy 88.557377 -298.607578) (xy 88.51362 -298.654175) (xy 88.464367 -298.69492)
			(xy 88.410396 -298.729171) (xy 88.352557 -298.756388) (xy 88.291764 -298.776141) (xy 88.228974 -298.788119)
			(xy 88.165178 -298.792133) (xy 88.101382 -298.788119) (xy 88.038592 -298.776141) (xy 87.977799 -298.756388)
			(xy 87.91996 -298.729171) (xy 87.865989 -298.69492) (xy 87.816736 -298.654175) (xy 87.772979 -298.607578)
			(xy 87.735406 -298.555863) (xy 87.704612 -298.499848) (xy 87.68108 -298.440415) (xy 87.665183 -298.378501)
			(xy 87.657172 -298.315083) (xy 79.302399 -298.315083) (xy 78.553056 -299.064426) (xy 78.546208 -299.071823)
			(xy 78.538474 -299.090422) (xy 78.53807 -299.100494) (xy 78.53807 -301.759366) (xy 78.537634 -301.76943)
			(xy 78.533366 -301.779686) (xy 92.19006 -301.779686) (xy 92.194131 -301.724064) (xy 92.206257 -301.669627)
			(xy 92.22618 -301.617536) (xy 92.253476 -301.568901) (xy 92.287562 -301.524758) (xy 92.327711 -301.486049)
			(xy 92.373069 -301.453598) (xy 92.422669 -301.428097) (xy 92.475453 -301.41009) (xy 92.530296 -301.39996)
			(xy 92.58603 -301.397923) (xy 92.641467 -301.404023) (xy 92.695424 -301.418129) (xy 92.746753 -301.439941)
			(xy 92.794359 -301.468995) (xy 92.837227 -301.50467) (xy 92.874444 -301.546207) (xy 92.905217 -301.59272)
			(xy 92.928889 -301.643217) (xy 92.944957 -301.696624) (xy 92.953077 -301.7518) (xy 92.953586 -301.779686)
			(xy 92.953077 -301.807572) (xy 92.944957 -301.862748) (xy 92.928889 -301.916155) (xy 92.905217 -301.966652)
			(xy 92.874444 -302.013165) (xy 92.837227 -302.054702) (xy 92.794359 -302.090377) (xy 92.746753 -302.119431)
			(xy 92.695424 -302.141243) (xy 92.641467 -302.155349) (xy 92.58603 -302.161449) (xy 92.530296 -302.159412)
			(xy 92.475453 -302.149282) (xy 92.422669 -302.131275) (xy 92.373069 -302.105774) (xy 92.327711 -302.073323)
			(xy 92.287562 -302.034614) (xy 92.253476 -301.990471) (xy 92.22618 -301.941836) (xy 92.206257 -301.889745)
			(xy 92.194131 -301.835308) (xy 92.19006 -301.779686) (xy 78.533366 -301.779686) (xy 78.5299 -301.788015)
			(xy 78.523084 -301.795434) (xy 75.538076 -304.780442) (xy 78.81214 -304.780442) (xy 78.81617 -304.638107)
			(xy 78.828245 -304.496227) (xy 78.848328 -304.355259) (xy 78.876355 -304.215652) (xy 78.912235 -304.077854)
			(xy 78.955853 -303.942307) (xy 79.00707 -303.809445) (xy 79.065721 -303.679693) (xy 79.131619 -303.553467)
			(xy 79.204553 -303.431171) (xy 79.28429 -303.313198) (xy 79.370572 -303.199925) (xy 79.463125 -303.091714)
			(xy 79.561652 -302.988913) (xy 79.665837 -302.891851) (xy 79.775346 -302.800839) (xy 79.889829 -302.716167)
			(xy 80.008919 -302.638109) (xy 80.132234 -302.566913) (xy 80.25938 -302.502807) (xy 80.389949 -302.445998)
			(xy 80.523523 -302.396666) (xy 80.659674 -302.35497) (xy 80.797965 -302.321044) (xy 80.937955 -302.294996)
			(xy 81.079194 -302.27691) (xy 81.22123 -302.266843) (xy 81.363608 -302.264828) (xy 81.505872 -302.270871)
			(xy 81.647566 -302.284953) (xy 81.788236 -302.307029) (xy 81.927433 -302.337029) (xy 82.064709 -302.374855)
			(xy 82.199625 -302.420387) (xy 82.331749 -302.473478) (xy 82.460658 -302.53396) (xy 82.585939 -302.601638)
			(xy 82.70719 -302.676295) (xy 82.824023 -302.757693) (xy 82.873373 -302.7964) (xy 84.778634 -302.7964)
			(xy 84.782549 -302.719211) (xy 84.794252 -302.642815) (xy 84.813625 -302.567994) (xy 84.840468 -302.495517)
			(xy 84.874505 -302.426128) (xy 84.915388 -302.360538) (xy 84.962697 -302.299421) (xy 85.015946 -302.243403)
			(xy 85.074589 -302.193061) (xy 85.138025 -302.148909) (xy 85.205602 -302.111402) (xy 85.276627 -302.080924)
			(xy 85.35037 -302.057788) (xy 85.426076 -302.042231) (xy 85.502968 -302.034413) (xy 85.541612 -302.03394)
			(xy 85.579854 -302.034414) (xy 85.655949 -302.042117) (xy 85.730889 -302.057403) (xy 85.803921 -302.08012)
			(xy 85.8393 -302.094646) (xy 85.848893 -302.098199) (xy 85.869331 -302.098199) (xy 85.878924 -302.094646)
			(xy 85.91431 -302.08014) (xy 85.987342 -302.057433) (xy 86.06228 -302.042148) (xy 86.138372 -302.034437)
			(xy 86.176612 -302.03394) (xy 86.215259 -302.034334) (xy 86.292157 -302.042155) (xy 86.367869 -302.057715)
			(xy 86.441619 -302.080855) (xy 86.512649 -302.111338) (xy 86.58023 -302.148849) (xy 86.643671 -302.193006)
			(xy 86.702318 -302.243354) (xy 86.755571 -302.299377) (xy 86.802883 -302.3605) (xy 86.843769 -302.426096)
			(xy 86.877808 -302.495491) (xy 86.904653 -302.567974) (xy 86.924027 -302.642801) (xy 86.935731 -302.719205)
			(xy 86.939646 -302.7964) (xy 86.935731 -302.873595) (xy 86.924027 -302.949999) (xy 86.904653 -303.024826)
			(xy 86.877808 -303.097309) (xy 86.843769 -303.166704) (xy 86.802883 -303.2323) (xy 86.785179 -303.255172)
			(xy 92.274134 -303.255172) (xy 92.278205 -303.19955) (xy 92.290331 -303.145113) (xy 92.310254 -303.093022)
			(xy 92.33755 -303.044387) (xy 92.371636 -303.000244) (xy 92.411785 -302.961535) (xy 92.457143 -302.929084)
			(xy 92.506743 -302.903583) (xy 92.559527 -302.885576) (xy 92.61437 -302.875446) (xy 92.670104 -302.873409)
			(xy 92.725541 -302.879509) (xy 92.779498 -302.893615) (xy 92.830827 -302.915427) (xy 92.878433 -302.944481)
			(xy 92.921301 -302.980156) (xy 92.958518 -303.021693) (xy 92.989291 -303.068206) (xy 93.012963 -303.118703)
			(xy 93.029031 -303.17211) (xy 93.037151 -303.227286) (xy 93.03766 -303.255172) (xy 93.037151 -303.283058)
			(xy 93.029031 -303.338234) (xy 93.012963 -303.391641) (xy 92.989291 -303.442138) (xy 92.958518 -303.488651)
			(xy 92.921301 -303.530188) (xy 92.878433 -303.565863) (xy 92.830827 -303.594917) (xy 92.779498 -303.616729)
			(xy 92.725541 -303.630835) (xy 92.670104 -303.636935) (xy 92.61437 -303.634898) (xy 92.559527 -303.624768)
			(xy 92.506743 -303.606761) (xy 92.457143 -303.58126) (xy 92.411785 -303.548809) (xy 92.371636 -303.5101)
			(xy 92.33755 -303.465957) (xy 92.310254 -303.417322) (xy 92.290331 -303.365231) (xy 92.278205 -303.310794)
			(xy 92.274134 -303.255172) (xy 86.785179 -303.255172) (xy 86.755571 -303.293423) (xy 86.702318 -303.349446)
			(xy 86.643671 -303.399794) (xy 86.58023 -303.443951) (xy 86.512649 -303.481462) (xy 86.441619 -303.511945)
			(xy 86.367869 -303.535085) (xy 86.292157 -303.550645) (xy 86.215259 -303.558466) (xy 86.176612 -303.558956)
			(xy 86.138371 -303.558474) (xy 86.062276 -303.550774) (xy 85.987335 -303.53549) (xy 85.914303 -303.512775)
			(xy 85.878924 -303.49825) (xy 85.869331 -303.494697) (xy 85.848893 -303.494697) (xy 85.8393 -303.49825)
			(xy 85.803924 -303.512781) (xy 85.730888 -303.535481) (xy 85.655947 -303.550759) (xy 85.579853 -303.558462)
			(xy 85.541612 -303.558956) (xy 85.502968 -303.558387) (xy 85.426076 -303.550569) (xy 85.35037 -303.535012)
			(xy 85.276627 -303.511876) (xy 85.205602 -303.481398) (xy 85.138025 -303.443891) (xy 85.074589 -303.399739)
			(xy 85.015946 -303.349397) (xy 84.962697 -303.293379) (xy 84.915388 -303.232262) (xy 84.874505 -303.166672)
			(xy 84.840468 -303.097283) (xy 84.813625 -303.024806) (xy 84.794252 -302.949985) (xy 84.782549 -302.873589)
			(xy 84.778634 -302.7964) (xy 82.873373 -302.7964) (xy 82.936064 -302.84557) (xy 83.042954 -302.939645)
			(xy 83.144351 -303.039617) (xy 83.239929 -303.145165) (xy 83.329383 -303.255951) (xy 83.412425 -303.37162)
			(xy 83.488791 -303.491803) (xy 83.558235 -303.616113) (xy 83.620535 -303.744154) (xy 83.675491 -303.875513)
			(xy 83.722928 -304.009772) (xy 83.729734 -304.033174) (xy 92.945966 -304.033174) (xy 92.946468 -304.001213)
			(xy 92.954479 -303.937795) (xy 92.970376 -303.875881) (xy 92.993908 -303.816448) (xy 93.024702 -303.760433)
			(xy 93.062275 -303.708718) (xy 93.106032 -303.662121) (xy 93.155285 -303.621376) (xy 93.209256 -303.587125)
			(xy 93.267095 -303.559908) (xy 93.327888 -303.540155) (xy 93.390678 -303.528177) (xy 93.454474 -303.524164)
			(xy 93.51827 -303.528177) (xy 93.58106 -303.540155) (xy 93.641853 -303.559908) (xy 93.699692 -303.587125)
			(xy 93.753663 -303.621376) (xy 93.802916 -303.662121) (xy 93.846673 -303.708718) (xy 93.884246 -303.760433)
			(xy 93.91504 -303.816448) (xy 93.938572 -303.875881) (xy 93.954469 -303.937795) (xy 93.96248 -304.001213)
			(xy 93.962982 -304.033174) (xy 93.962469 -304.065957) (xy 93.954045 -304.13098) (xy 93.937332 -304.19438)
			(xy 93.912609 -304.255106) (xy 93.880284 -304.312151) (xy 93.840896 -304.364567) (xy 93.795096 -304.411486)
			(xy 93.769688 -304.432208) (xy 93.762771 -304.438106) (xy 93.753283 -304.453598) (xy 93.751146 -304.462434)
			(xy 93.745304 -304.492152) (xy 93.743955 -304.500954) (xy 93.74683 -304.518517) (xy 93.750892 -304.526442)
			(xy 93.765761 -304.554834) (xy 93.786839 -304.615355) (xy 93.797504 -304.678548) (xy 93.798136 -304.710592)
			(xy 93.79765 -304.737843) (xy 93.789894 -304.791791) (xy 93.774539 -304.844086) (xy 93.751897 -304.893663)
			(xy 93.722431 -304.939513) (xy 93.68674 -304.980704) (xy 93.645549 -305.016395) (xy 93.599699 -305.045861)
			(xy 93.550122 -305.068503) (xy 93.497827 -305.083858) (xy 93.443879 -305.091614) (xy 93.389377 -305.091614)
			(xy 93.335429 -305.083858) (xy 93.283134 -305.068503) (xy 93.233557 -305.045861) (xy 93.187707 -305.016395)
			(xy 93.146516 -304.980704) (xy 93.110825 -304.939513) (xy 93.081359 -304.893663) (xy 93.058717 -304.844086)
			(xy 93.043362 -304.791791) (xy 93.035606 -304.737843) (xy 93.03512 -304.710592) (xy 93.035659 -304.681226)
			(xy 93.0447 -304.623194) (xy 93.062521 -304.567231) (xy 93.088702 -304.514657) (xy 93.105224 -304.490374)
			(xy 93.110038 -304.482893) (xy 93.114699 -304.465737) (xy 93.114368 -304.456846) (xy 93.111574 -304.426366)
			(xy 93.110508 -304.417453) (xy 93.102963 -304.401181) (xy 93.096842 -304.394616) (xy 93.073395 -304.370658)
			(xy 93.032348 -304.317659) (xy 92.99862 -304.259726) (xy 92.972796 -304.197864) (xy 92.955324 -304.133145)
			(xy 92.946506 -304.066692) (xy 92.945966 -304.033174) (xy 83.729734 -304.033174) (xy 83.762692 -304.146499)
			(xy 83.794658 -304.285257) (xy 83.818723 -304.425601) (xy 83.834809 -304.567082) (xy 83.842864 -304.709246)
			(xy 83.843071 -304.738489) (xy 91.753938 -304.738489) (xy 91.753938 -304.674567) (xy 91.761949 -304.611149)
			(xy 91.777846 -304.549235) (xy 91.801378 -304.489802) (xy 91.832172 -304.433787) (xy 91.869745 -304.382072)
			(xy 91.913502 -304.335475) (xy 91.962755 -304.29473) (xy 92.016726 -304.260479) (xy 92.074565 -304.233262)
			(xy 92.135358 -304.213509) (xy 92.198148 -304.201531) (xy 92.261944 -304.197518) (xy 92.32574 -304.201531)
			(xy 92.38853 -304.213509) (xy 92.449323 -304.233262) (xy 92.507162 -304.260479) (xy 92.561133 -304.29473)
			(xy 92.610386 -304.335475) (xy 92.654143 -304.382072) (xy 92.691716 -304.433787) (xy 92.72251 -304.489802)
			(xy 92.746042 -304.549235) (xy 92.761939 -304.611149) (xy 92.76995 -304.674567) (xy 92.770452 -304.706528)
			(xy 92.76995 -304.738489) (xy 92.761939 -304.801907) (xy 92.746042 -304.863821) (xy 92.72251 -304.923254)
			(xy 92.691716 -304.979269) (xy 92.654143 -305.030984) (xy 92.610386 -305.077581) (xy 92.561133 -305.118326)
			(xy 92.507162 -305.152577) (xy 92.449323 -305.179794) (xy 92.38853 -305.199547) (xy 92.32574 -305.211525)
			(xy 92.261944 -305.215539) (xy 92.198148 -305.211525) (xy 92.135358 -305.199547) (xy 92.074565 -305.179794)
			(xy 92.016726 -305.152577) (xy 91.962755 -305.118326) (xy 91.913502 -305.077581) (xy 91.869745 -305.030984)
			(xy 91.832172 -304.979269) (xy 91.801378 -304.923254) (xy 91.777846 -304.863821) (xy 91.761949 -304.801907)
			(xy 91.753938 -304.738489) (xy 83.843071 -304.738489) (xy 83.843368 -304.780442) (xy 83.842864 -304.851638)
			(xy 83.834809 -304.993802) (xy 83.818723 -305.135283) (xy 83.794658 -305.275627) (xy 83.762692 -305.414385)
			(xy 83.722928 -305.551112) (xy 83.675491 -305.685371) (xy 83.620535 -305.81673) (xy 83.558235 -305.944771)
			(xy 83.488791 -306.069081) (xy 83.412425 -306.189264) (xy 83.329383 -306.304933) (xy 83.239929 -306.415719)
			(xy 83.196059 -306.464165) (xy 87.854784 -306.464165) (xy 87.854784 -306.400243) (xy 87.862795 -306.336825)
			(xy 87.878692 -306.274911) (xy 87.902224 -306.215478) (xy 87.933018 -306.159463) (xy 87.970591 -306.107748)
			(xy 88.014348 -306.061151) (xy 88.063601 -306.020406) (xy 88.117572 -305.986155) (xy 88.175411 -305.958938)
			(xy 88.236204 -305.939185) (xy 88.298994 -305.927207) (xy 88.36279 -305.923194) (xy 88.426586 -305.927207)
			(xy 88.489376 -305.939185) (xy 88.550169 -305.958938) (xy 88.608008 -305.986155) (xy 88.659611 -306.018903)
			(xy 93.552258 -306.018903) (xy 93.552258 -305.954981) (xy 93.560269 -305.891563) (xy 93.576166 -305.829649)
			(xy 93.599698 -305.770216) (xy 93.630492 -305.714201) (xy 93.668065 -305.662486) (xy 93.711822 -305.615889)
			(xy 93.761075 -305.575144) (xy 93.815046 -305.540893) (xy 93.872885 -305.513676) (xy 93.933678 -305.493923)
			(xy 93.996468 -305.481945) (xy 94.060264 -305.477932) (xy 94.12406 -305.481945) (xy 94.18685 -305.493923)
			(xy 94.247643 -305.513676) (xy 94.305482 -305.540893) (xy 94.359453 -305.575144) (xy 94.408706 -305.615889)
			(xy 94.452463 -305.662486) (xy 94.490036 -305.714201) (xy 94.52083 -305.770216) (xy 94.544362 -305.829649)
			(xy 94.560259 -305.891563) (xy 94.56827 -305.954981) (xy 94.568772 -305.986942) (xy 94.56827 -306.018903)
			(xy 94.560259 -306.082321) (xy 94.544362 -306.144235) (xy 94.52083 -306.203668) (xy 94.490036 -306.259683)
			(xy 94.452463 -306.311398) (xy 94.408706 -306.357995) (xy 94.359453 -306.39874) (xy 94.305482 -306.432991)
			(xy 94.247643 -306.460208) (xy 94.18685 -306.479961) (xy 94.12406 -306.491939) (xy 94.060264 -306.495953)
			(xy 93.996468 -306.491939) (xy 93.933678 -306.479961) (xy 93.872885 -306.460208) (xy 93.815046 -306.432991)
			(xy 93.761075 -306.39874) (xy 93.711822 -306.357995) (xy 93.668065 -306.311398) (xy 93.630492 -306.259683)
			(xy 93.599698 -306.203668) (xy 93.576166 -306.144235) (xy 93.560269 -306.082321) (xy 93.552258 -306.018903)
			(xy 88.659611 -306.018903) (xy 88.661979 -306.020406) (xy 88.711232 -306.061151) (xy 88.754989 -306.107748)
			(xy 88.792562 -306.159463) (xy 88.823356 -306.215478) (xy 88.846888 -306.274911) (xy 88.862785 -306.336825)
			(xy 88.870796 -306.400243) (xy 88.871298 -306.432204) (xy 88.870796 -306.464165) (xy 88.862785 -306.527583)
			(xy 88.846888 -306.589497) (xy 88.823356 -306.64893) (xy 88.792562 -306.704945) (xy 88.754989 -306.75666)
			(xy 88.711232 -306.803257) (xy 88.661979 -306.844002) (xy 88.608008 -306.878253) (xy 88.550169 -306.90547)
			(xy 88.489376 -306.925223) (xy 88.426586 -306.937201) (xy 88.36279 -306.941215) (xy 88.298994 -306.937201)
			(xy 88.236204 -306.925223) (xy 88.175411 -306.90547) (xy 88.117572 -306.878253) (xy 88.063601 -306.844002)
			(xy 88.014348 -306.803257) (xy 87.970591 -306.75666) (xy 87.933018 -306.704945) (xy 87.902224 -306.64893)
			(xy 87.878692 -306.589497) (xy 87.862795 -306.527583) (xy 87.854784 -306.464165) (xy 83.196059 -306.464165)
			(xy 83.144351 -306.521267) (xy 83.042954 -306.621239) (xy 82.936064 -306.715314) (xy 82.824023 -306.803191)
			(xy 82.70719 -306.884589) (xy 82.585939 -306.959246) (xy 82.460658 -307.026924) (xy 82.331749 -307.087406)
			(xy 82.199625 -307.140497) (xy 82.064709 -307.186029) (xy 81.927433 -307.223855) (xy 81.788236 -307.253855)
			(xy 81.647566 -307.275931) (xy 81.505872 -307.290013) (xy 81.363608 -307.296056) (xy 81.22123 -307.294041)
			(xy 81.079194 -307.283974) (xy 80.937955 -307.265888) (xy 80.797965 -307.23984) (xy 80.659674 -307.205914)
			(xy 80.523523 -307.164218) (xy 80.389949 -307.114886) (xy 80.25938 -307.058077) (xy 80.132234 -306.993971)
			(xy 80.008919 -306.922775) (xy 79.889829 -306.844717) (xy 79.775346 -306.760045) (xy 79.665837 -306.669033)
			(xy 79.561652 -306.571971) (xy 79.463125 -306.46917) (xy 79.370572 -306.360959) (xy 79.28429 -306.247686)
			(xy 79.204553 -306.129713) (xy 79.131619 -306.007417) (xy 79.065721 -305.881191) (xy 79.00707 -305.751439)
			(xy 78.955853 -305.618577) (xy 78.912235 -305.48303) (xy 78.876355 -305.345232) (xy 78.848328 -305.205625)
			(xy 78.828245 -305.064657) (xy 78.81617 -304.922777) (xy 78.81214 -304.780442) (xy 75.538076 -304.780442)
			(xy 72.933349 -307.385169) (xy 88.750896 -307.385169) (xy 88.750896 -307.321247) (xy 88.758907 -307.257829)
			(xy 88.774804 -307.195915) (xy 88.798336 -307.136482) (xy 88.82913 -307.080467) (xy 88.866703 -307.028752)
			(xy 88.91046 -306.982155) (xy 88.959713 -306.94141) (xy 89.013684 -306.907159) (xy 89.071523 -306.879942)
			(xy 89.132316 -306.860189) (xy 89.195106 -306.848211) (xy 89.258902 -306.844198) (xy 89.322698 -306.848211)
			(xy 89.385488 -306.860189) (xy 89.446281 -306.879942) (xy 89.50412 -306.907159) (xy 89.558091 -306.94141)
			(xy 89.607344 -306.982155) (xy 89.651101 -307.028752) (xy 89.688674 -307.080467) (xy 89.707611 -307.114913)
			(xy 90.238828 -307.114913) (xy 90.238828 -307.050991) (xy 90.246839 -306.987573) (xy 90.262736 -306.925659)
			(xy 90.286268 -306.866226) (xy 90.317062 -306.810211) (xy 90.354635 -306.758496) (xy 90.398392 -306.711899)
			(xy 90.447645 -306.671154) (xy 90.501616 -306.636903) (xy 90.559455 -306.609686) (xy 90.620248 -306.589933)
			(xy 90.683038 -306.577955) (xy 90.746834 -306.573942) (xy 90.81063 -306.577955) (xy 90.833276 -306.582275)
			(xy 91.420182 -306.582275) (xy 91.420182 -306.518353) (xy 91.428193 -306.454935) (xy 91.44409 -306.393021)
			(xy 91.467622 -306.333588) (xy 91.498416 -306.277573) (xy 91.535989 -306.225858) (xy 91.579746 -306.179261)
			(xy 91.628999 -306.138516) (xy 91.68297 -306.104265) (xy 91.740809 -306.077048) (xy 91.801602 -306.057295)
			(xy 91.864392 -306.045317) (xy 91.928188 -306.041304) (xy 91.991984 -306.045317) (xy 92.054774 -306.057295)
			(xy 92.115567 -306.077048) (xy 92.173406 -306.104265) (xy 92.227377 -306.138516) (xy 92.27663 -306.179261)
			(xy 92.320387 -306.225858) (xy 92.35796 -306.277573) (xy 92.388754 -306.333588) (xy 92.412286 -306.393021)
			(xy 92.428183 -306.454935) (xy 92.436194 -306.518353) (xy 92.436696 -306.550314) (xy 92.436194 -306.582275)
			(xy 92.428183 -306.645693) (xy 92.412286 -306.707607) (xy 92.40187 -306.733913) (xy 95.064828 -306.733913)
			(xy 95.064828 -306.669991) (xy 95.072839 -306.606573) (xy 95.088736 -306.544659) (xy 95.112268 -306.485226)
			(xy 95.143062 -306.429211) (xy 95.180635 -306.377496) (xy 95.224392 -306.330899) (xy 95.273645 -306.290154)
			(xy 95.327616 -306.255903) (xy 95.385455 -306.228686) (xy 95.446248 -306.208933) (xy 95.509038 -306.196955)
			(xy 95.572834 -306.192942) (xy 95.63663 -306.196955) (xy 95.69942 -306.208933) (xy 95.760213 -306.228686)
			(xy 95.818052 -306.255903) (xy 95.872023 -306.290154) (xy 95.921276 -306.330899) (xy 95.965033 -306.377496)
			(xy 96.002606 -306.429211) (xy 96.0334 -306.485226) (xy 96.056932 -306.544659) (xy 96.072829 -306.606573)
			(xy 96.08084 -306.669991) (xy 96.081342 -306.701952) (xy 96.08084 -306.733913) (xy 96.072829 -306.797331)
			(xy 96.056932 -306.859245) (xy 96.0334 -306.918678) (xy 96.002606 -306.974693) (xy 95.965033 -307.026408)
			(xy 95.921276 -307.073005) (xy 95.872023 -307.11375) (xy 95.818052 -307.148001) (xy 95.760213 -307.175218)
			(xy 95.69942 -307.194971) (xy 95.63663 -307.206949) (xy 95.572834 -307.210963) (xy 95.509038 -307.206949)
			(xy 95.446248 -307.194971) (xy 95.385455 -307.175218) (xy 95.327616 -307.148001) (xy 95.273645 -307.11375)
			(xy 95.224392 -307.073005) (xy 95.180635 -307.026408) (xy 95.143062 -306.974693) (xy 95.112268 -306.918678)
			(xy 95.088736 -306.859245) (xy 95.072839 -306.797331) (xy 95.064828 -306.733913) (xy 92.40187 -306.733913)
			(xy 92.388754 -306.76704) (xy 92.35796 -306.823055) (xy 92.320387 -306.87477) (xy 92.27663 -306.921367)
			(xy 92.227377 -306.962112) (xy 92.173406 -306.996363) (xy 92.115567 -307.02358) (xy 92.054774 -307.043333)
			(xy 91.991984 -307.055311) (xy 91.928188 -307.059325) (xy 91.864392 -307.055311) (xy 91.801602 -307.043333)
			(xy 91.740809 -307.02358) (xy 91.68297 -306.996363) (xy 91.628999 -306.962112) (xy 91.579746 -306.921367)
			(xy 91.535989 -306.87477) (xy 91.498416 -306.823055) (xy 91.467622 -306.76704) (xy 91.44409 -306.707607)
			(xy 91.428193 -306.645693) (xy 91.420182 -306.582275) (xy 90.833276 -306.582275) (xy 90.87342 -306.589933)
			(xy 90.934213 -306.609686) (xy 90.992052 -306.636903) (xy 91.046023 -306.671154) (xy 91.095276 -306.711899)
			(xy 91.139033 -306.758496) (xy 91.176606 -306.810211) (xy 91.2074 -306.866226) (xy 91.230932 -306.925659)
			(xy 91.246829 -306.987573) (xy 91.25484 -307.050991) (xy 91.255342 -307.082952) (xy 91.25484 -307.114913)
			(xy 91.246829 -307.178331) (xy 91.237536 -307.214524) (xy 93.048326 -307.214524) (xy 93.052397 -307.158902)
			(xy 93.064523 -307.104465) (xy 93.084446 -307.052374) (xy 93.111742 -307.003739) (xy 93.145828 -306.959596)
			(xy 93.185977 -306.920887) (xy 93.231335 -306.888436) (xy 93.280935 -306.862935) (xy 93.333719 -306.844928)
			(xy 93.388562 -306.834798) (xy 93.444296 -306.832761) (xy 93.499733 -306.838861) (xy 93.55369 -306.852967)
			(xy 93.605019 -306.874779) (xy 93.652625 -306.903833) (xy 93.695493 -306.939508) (xy 93.73271 -306.981045)
			(xy 93.763483 -307.027558) (xy 93.787155 -307.078055) (xy 93.803223 -307.131462) (xy 93.811343 -307.186638)
			(xy 93.811852 -307.214524) (xy 93.811343 -307.24241) (xy 93.803223 -307.297586) (xy 93.787155 -307.350993)
			(xy 93.763483 -307.40149) (xy 93.73271 -307.448003) (xy 93.695493 -307.48954) (xy 93.652625 -307.525215)
			(xy 93.605019 -307.554269) (xy 93.55369 -307.576081) (xy 93.499733 -307.590187) (xy 93.444296 -307.596287)
			(xy 93.388562 -307.59425) (xy 93.333719 -307.58412) (xy 93.280935 -307.566113) (xy 93.231335 -307.540612)
			(xy 93.185977 -307.508161) (xy 93.145828 -307.469452) (xy 93.111742 -307.425309) (xy 93.084446 -307.376674)
			(xy 93.064523 -307.324583) (xy 93.052397 -307.270146) (xy 93.048326 -307.214524) (xy 91.237536 -307.214524)
			(xy 91.230932 -307.240245) (xy 91.2074 -307.299678) (xy 91.176606 -307.355693) (xy 91.139033 -307.407408)
			(xy 91.095276 -307.454005) (xy 91.046023 -307.49475) (xy 90.992052 -307.529001) (xy 90.934213 -307.556218)
			(xy 90.87342 -307.575971) (xy 90.81063 -307.587949) (xy 90.746834 -307.591963) (xy 90.683038 -307.587949)
			(xy 90.620248 -307.575971) (xy 90.559455 -307.556218) (xy 90.501616 -307.529001) (xy 90.447645 -307.49475)
			(xy 90.398392 -307.454005) (xy 90.354635 -307.407408) (xy 90.317062 -307.355693) (xy 90.286268 -307.299678)
			(xy 90.262736 -307.240245) (xy 90.246839 -307.178331) (xy 90.238828 -307.114913) (xy 89.707611 -307.114913)
			(xy 89.719468 -307.136482) (xy 89.743 -307.195915) (xy 89.758897 -307.257829) (xy 89.766908 -307.321247)
			(xy 89.76741 -307.353208) (xy 89.766908 -307.385169) (xy 89.758897 -307.448587) (xy 89.743 -307.510501)
			(xy 89.719468 -307.569934) (xy 89.688674 -307.625949) (xy 89.651101 -307.677664) (xy 89.607344 -307.724261)
			(xy 89.558091 -307.765006) (xy 89.50412 -307.799257) (xy 89.446281 -307.826474) (xy 89.385488 -307.846227)
			(xy 89.322698 -307.858205) (xy 89.258902 -307.862219) (xy 89.195106 -307.858205) (xy 89.132316 -307.846227)
			(xy 89.071523 -307.826474) (xy 89.013684 -307.799257) (xy 88.959713 -307.765006) (xy 88.91046 -307.724261)
			(xy 88.866703 -307.677664) (xy 88.82913 -307.625949) (xy 88.798336 -307.569934) (xy 88.774804 -307.510501)
			(xy 88.758907 -307.448587) (xy 88.750896 -307.385169) (xy 72.933349 -307.385169) (xy 70.634532 -309.683986)
			(xy 78.652905 -309.683986) (xy 78.652905 -309.632014) (xy 78.661035 -309.580682) (xy 78.677095 -309.531254)
			(xy 78.700688 -309.484947) (xy 78.731235 -309.4429) (xy 78.767984 -309.40615) (xy 78.810028 -309.3756)
			(xy 78.856334 -309.352003) (xy 78.905761 -309.33594) (xy 78.957092 -309.327807) (xy 78.983078 -309.327296)
			(xy 78.999899 -309.32751) (xy 79.033366 -309.330946) (xy 79.04988 -309.334154) (xy 79.061407 -309.335998)
			(xy 79.083983 -309.330144) (xy 79.101664 -309.314933) (xy 79.106776 -309.304436) (xy 79.121518 -309.271638)
			(xy 79.158868 -309.210193) (xy 79.181198 -309.182008) (xy 79.186433 -309.175061) (xy 79.192281 -309.158695)
			(xy 79.192628 -309.150004) (xy 79.192628 -308.995826) (xy 79.192246 -308.987081) (xy 79.186421 -308.97059)
			(xy 79.181198 -308.963568) (xy 79.162531 -308.940162) (xy 79.130217 -308.889761) (xy 79.104057 -308.835909)
			(xy 79.084417 -308.779352) (xy 79.077566 -308.750208) (xy 79.074502 -308.738946) (xy 79.06001 -308.720689)
			(xy 79.038937 -308.710723) (xy 79.027274 -308.71033) (xy 79.023464 -308.71033) (xy 79.02321 -308.71033)
			(xy 78.997222 -308.709804) (xy 78.945886 -308.701674) (xy 78.896453 -308.685614) (xy 78.850141 -308.662018)
			(xy 78.808091 -308.631468) (xy 78.771338 -308.594716) (xy 78.740787 -308.552667) (xy 78.71719 -308.506356)
			(xy 78.701128 -308.456924) (xy 78.692997 -308.405588) (xy 78.692997 -308.353612) (xy 78.701128 -308.302276)
			(xy 78.71719 -308.252844) (xy 78.740787 -308.206533) (xy 78.771338 -308.164484) (xy 78.808091 -308.127732)
			(xy 78.850141 -308.097182) (xy 78.896453 -308.073586) (xy 78.945886 -308.057526) (xy 78.997222 -308.049396)
			(xy 79.02321 -308.048914) (xy 79.047989 -308.049367) (xy 79.096992 -308.056757) (xy 79.144345 -308.07137)
			(xy 79.188991 -308.092881) (xy 79.22993 -308.120807) (xy 79.266249 -308.154525) (xy 79.282036 -308.173628)
			(xy 79.289703 -308.182366) (xy 79.310676 -308.192336) (xy 79.333897 -308.192065) (xy 79.34452 -308.187344)
			(xy 79.371291 -308.174267) (xy 79.427222 -308.153727) (xy 79.485172 -308.139877) (xy 79.544345 -308.132906)
			(xy 79.574136 -308.13248) (xy 79.604867 -308.132922) (xy 79.665881 -308.140334) (xy 79.725557 -308.155046)
			(xy 79.783025 -308.176844) (xy 79.837446 -308.20541) (xy 79.888028 -308.240326) (xy 79.934032 -308.281085)
			(xy 79.974789 -308.327091) (xy 80.009703 -308.377674) (xy 80.038266 -308.432097) (xy 80.060061 -308.489566)
			(xy 80.062386 -308.499) (xy 88.375291 -308.499) (xy 88.379305 -308.435208) (xy 88.391281 -308.372422)
			(xy 88.411032 -308.311632) (xy 88.438245 -308.253797) (xy 88.472492 -308.199828) (xy 88.513233 -308.150577)
			(xy 88.559825 -308.106819) (xy 88.611534 -308.069246) (xy 88.667543 -308.03845) (xy 88.726971 -308.014916)
			(xy 88.78888 -307.999015) (xy 88.852293 -307.990999) (xy 88.884252 -307.990494) (xy 88.915807 -307.990985)
			(xy 88.978432 -307.998793) (xy 89.039608 -308.014296) (xy 89.098393 -308.037255) (xy 89.153883 -308.067316)
			(xy 89.205224 -308.104017) (xy 89.251626 -308.146792) (xy 89.272364 -308.17058) (xy 89.279033 -308.177673)
			(xy 89.296261 -308.186696) (xy 89.305892 -308.188106) (xy 89.386156 -308.196488) (xy 89.404698 -308.191154)
			(xy 89.412572 -308.185058) (xy 89.432771 -308.169776) (xy 89.476437 -308.144108) (xy 89.523118 -308.124452)
			(xy 89.571992 -308.111153) (xy 89.622197 -308.104446) (xy 89.647522 -308.104032) (xy 89.674775 -308.104439)
			(xy 89.728726 -308.112199) (xy 89.781024 -308.127558) (xy 89.830603 -308.150203) (xy 89.876456 -308.179673)
			(xy 89.917648 -308.215368) (xy 89.953341 -308.256562) (xy 89.982808 -308.302416) (xy 90.00545 -308.351997)
			(xy 90.020805 -308.404295) (xy 90.028562 -308.458247) (xy 90.028562 -308.512753) (xy 90.020805 -308.566705)
			(xy 90.00545 -308.619003) (xy 89.982808 -308.668584) (xy 89.953341 -308.714438) (xy 89.917648 -308.755632)
			(xy 89.876456 -308.791327) (xy 89.830603 -308.820797) (xy 89.781024 -308.843442) (xy 89.728726 -308.858801)
			(xy 89.674775 -308.866561) (xy 89.647522 -308.867048) (xy 89.617533 -308.866515) (xy 89.558297 -308.85712)
			(xy 89.501259 -308.838573) (xy 89.447825 -308.811331) (xy 89.42324 -308.79415) (xy 89.415112 -308.788308)
			(xy 89.396316 -308.783736) (xy 89.306908 -308.795928) (xy 89.290144 -308.80558) (xy 89.283794 -308.813454)
			(xy 89.263071 -308.838942) (xy 89.216142 -308.884911) (xy 89.163684 -308.924452) (xy 89.10657 -308.956907)
			(xy 89.045751 -308.981735) (xy 88.982241 -308.998523) (xy 88.917098 -309.006991) (xy 88.884252 -309.00751)
			(xy 88.852293 -309.007001) (xy 88.78888 -308.998985) (xy 88.726971 -308.983084) (xy 88.667543 -308.95955)
			(xy 88.611534 -308.928754) (xy 88.559825 -308.891181) (xy 88.513233 -308.847423) (xy 88.472492 -308.798172)
			(xy 88.438245 -308.744203) (xy 88.411032 -308.686368) (xy 88.391281 -308.625578) (xy 88.379305 -308.562792)
			(xy 88.375291 -308.499) (xy 80.062386 -308.499) (xy 80.07477 -308.549242) (xy 80.08218 -308.610257)
			(xy 80.082644 -308.640988) (xy 80.082051 -308.675953) (xy 80.072452 -308.745222) (xy 80.053446 -308.81252)
			(xy 80.025393 -308.876577) (xy 79.988823 -308.936184) (xy 79.967074 -308.963568) (xy 79.961814 -308.970574)
			(xy 79.955962 -308.987071) (xy 79.955644 -308.995826) (xy 79.955644 -309.14975) (xy 79.955977 -309.1585)
			(xy 79.961834 -309.174992) (xy 79.967074 -309.182008) (xy 79.988812 -309.209399) (xy 80.025366 -309.269012)
			(xy 80.053413 -309.333068) (xy 80.072425 -309.400362) (xy 80.082043 -309.469625) (xy 80.082644 -309.504588)
			(xy 80.082133 -309.535317) (xy 80.079424 -309.557631) (xy 85.733122 -309.557631) (xy 85.733122 -309.493709)
			(xy 85.741133 -309.430291) (xy 85.75703 -309.368377) (xy 85.780562 -309.308944) (xy 85.811356 -309.252929)
			(xy 85.848929 -309.201214) (xy 85.892686 -309.154617) (xy 85.941939 -309.113872) (xy 85.99591 -309.079621)
			(xy 86.053749 -309.052404) (xy 86.114542 -309.032651) (xy 86.177332 -309.020673) (xy 86.241128 -309.01666)
			(xy 86.304924 -309.020673) (xy 86.31448 -309.022496) (xy 93.06433 -309.022496) (xy 93.064781 -308.997717)
			(xy 93.07217 -308.948714) (xy 93.086784 -308.90136) (xy 93.108295 -308.856714) (xy 93.136221 -308.815775)
			(xy 93.16994 -308.779457) (xy 93.189044 -308.76367) (xy 93.197771 -308.75599) (xy 93.207755 -308.735026)
			(xy 93.207484 -308.711807) (xy 93.20276 -308.701186) (xy 93.189687 -308.674413) (xy 93.169146 -308.618484)
			(xy 93.155294 -308.560534) (xy 93.148322 -308.501361) (xy 93.147896 -308.47157) (xy 93.148328 -308.440838)
			(xy 93.15574 -308.379823) (xy 93.170452 -308.320146) (xy 93.19225 -308.262678) (xy 93.220816 -308.208256)
			(xy 93.255733 -308.157674) (xy 93.296493 -308.111669) (xy 93.3425 -308.070912) (xy 93.393085 -308.035998)
			(xy 93.447509 -308.007436) (xy 93.504979 -307.985642) (xy 93.564657 -307.970934) (xy 93.625672 -307.963526)
			(xy 93.656404 -307.963062) (xy 93.691359 -307.96365) (xy 93.760612 -307.973211) (xy 93.827902 -307.992167)
			(xy 93.891963 -308.020161) (xy 93.951585 -308.056664) (xy 93.978984 -308.078378) (xy 93.985926 -308.083618)
			(xy 94.002297 -308.089461) (xy 94.010988 -308.089808) (xy 94.16542 -308.089808) (xy 94.174105 -308.089439)
			(xy 94.190462 -308.083585) (xy 94.197424 -308.078378) (xy 94.224812 -308.056651) (xy 94.284441 -308.020156)
			(xy 94.348505 -307.992167) (xy 94.415796 -307.973209) (xy 94.485049 -307.963641) (xy 94.520004 -307.963062)
			(xy 94.550734 -307.963552) (xy 94.611746 -307.970961) (xy 94.67142 -307.985669) (xy 94.728886 -308.007462)
			(xy 94.783306 -308.036023) (xy 94.833887 -308.070936) (xy 94.879892 -308.11169) (xy 94.920648 -308.157692)
			(xy 94.955563 -308.208272) (xy 94.984127 -308.26269) (xy 95.005923 -308.320156) (xy 95.020635 -308.379829)
			(xy 95.028046 -308.44084) (xy 95.028512 -308.47157) (xy 95.027985 -308.50506) (xy 95.019202 -308.571463)
			(xy 95.001785 -308.636139) (xy 94.976033 -308.697971) (xy 94.942393 -308.755891) (xy 94.92234 -308.78272)
			(xy 94.915633 -308.792284) (xy 94.910912 -308.815137) (xy 94.916721 -308.837738) (xy 94.923864 -308.846982)
			(xy 94.938905 -308.865058) (xy 94.964266 -308.904657) (xy 94.98376 -308.947449) (xy 94.996992 -308.992573)
			(xy 95.003694 -309.039117) (xy 95.004128 -309.062628) (xy 95.003618 -309.088615) (xy 94.995488 -309.13995)
			(xy 94.979427 -309.18938) (xy 94.955831 -309.23569) (xy 94.925281 -309.277738) (xy 94.88853 -309.314489)
			(xy 94.846482 -309.345039) (xy 94.800172 -309.368635) (xy 94.750742 -309.384696) (xy 94.699407 -309.392826)
			(xy 94.647433 -309.392826) (xy 94.596098 -309.384696) (xy 94.546668 -309.368635) (xy 94.500358 -309.345039)
			(xy 94.45831 -309.314489) (xy 94.421559 -309.277738) (xy 94.391009 -309.23569) (xy 94.367413 -309.18938)
			(xy 94.351352 -309.13995) (xy 94.343222 -309.088615) (xy 94.342712 -309.062628) (xy 94.342928 -309.045807)
			(xy 94.346363 -309.01234) (xy 94.34957 -308.995826) (xy 94.351399 -308.984299) (xy 94.345549 -308.961725)
			(xy 94.330346 -308.944044) (xy 94.319852 -308.93893) (xy 94.287059 -308.924257) (xy 94.225612 -308.887035)
			(xy 94.197424 -308.864762) (xy 94.190476 -308.85953) (xy 94.17411 -308.853682) (xy 94.16542 -308.853332)
			(xy 94.010988 -308.853332) (xy 94.002303 -308.853696) (xy 93.985945 -308.859553) (xy 93.978984 -308.864762)
			(xy 93.955564 -308.883387) (xy 93.905149 -308.915622) (xy 93.851298 -308.941716) (xy 93.794756 -308.961308)
			(xy 93.765624 -308.96814) (xy 93.754345 -308.971151) (xy 93.736094 -308.985673) (xy 93.726136 -309.006763)
			(xy 93.725746 -309.018432) (xy 93.725746 -309.022242) (xy 93.725746 -309.022496) (xy 93.725236 -309.048483)
			(xy 93.717106 -309.099818) (xy 93.701045 -309.149248) (xy 93.677449 -309.195558) (xy 93.646899 -309.237606)
			(xy 93.610148 -309.274357) (xy 93.5681 -309.304907) (xy 93.52179 -309.328503) (xy 93.47236 -309.344564)
			(xy 93.421025 -309.352694) (xy 93.369051 -309.352694) (xy 93.317716 -309.344564) (xy 93.268286 -309.328503)
			(xy 93.221976 -309.304907) (xy 93.179928 -309.274357) (xy 93.143177 -309.237606) (xy 93.112627 -309.195558)
			(xy 93.089031 -309.149248) (xy 93.07297 -309.099818) (xy 93.06484 -309.048483) (xy 93.06433 -309.022496)
			(xy 86.31448 -309.022496) (xy 86.367714 -309.032651) (xy 86.428507 -309.052404) (xy 86.486346 -309.079621)
			(xy 86.540317 -309.113872) (xy 86.58957 -309.154617) (xy 86.633327 -309.201214) (xy 86.6709 -309.252929)
			(xy 86.701694 -309.308944) (xy 86.725226 -309.368377) (xy 86.741123 -309.430291) (xy 86.749134 -309.493709)
			(xy 86.749636 -309.52567) (xy 86.749134 -309.557631) (xy 86.741123 -309.621049) (xy 86.725226 -309.682963)
			(xy 86.701694 -309.742396) (xy 86.6709 -309.798411) (xy 86.633327 -309.850126) (xy 86.58957 -309.896723)
			(xy 86.540317 -309.937468) (xy 86.486346 -309.971719) (xy 86.428507 -309.998936) (xy 86.367714 -310.018689)
			(xy 86.304924 -310.030667) (xy 86.241128 -310.034681) (xy 86.177332 -310.030667) (xy 86.114542 -310.018689)
			(xy 86.053749 -309.998936) (xy 85.99591 -309.971719) (xy 85.941939 -309.937468) (xy 85.892686 -309.896723)
			(xy 85.848929 -309.850126) (xy 85.811356 -309.798411) (xy 85.780562 -309.742396) (xy 85.75703 -309.682963)
			(xy 85.741133 -309.621049) (xy 85.733122 -309.557631) (xy 80.079424 -309.557631) (xy 80.074726 -309.596328)
			(xy 80.06002 -309.656001) (xy 80.038229 -309.713467) (xy 80.009669 -309.767887) (xy 79.974759 -309.818468)
			(xy 79.934006 -309.864472) (xy 79.888006 -309.905229) (xy 79.837428 -309.940145) (xy 79.783011 -309.968709)
			(xy 79.725547 -309.990506) (xy 79.665875 -310.005218) (xy 79.604865 -310.01263) (xy 79.574136 -310.013096)
			(xy 79.540646 -310.012569) (xy 79.474243 -310.003787) (xy 79.409567 -309.986369) (xy 79.347734 -309.960618)
			(xy 79.289815 -309.926977) (xy 79.262986 -309.906924) (xy 79.253418 -309.900225) (xy 79.230568 -309.895504)
			(xy 79.207968 -309.901308) (xy 79.198724 -309.908448) (xy 79.180643 -309.923484) (xy 79.141047 -309.948846)
			(xy 79.098255 -309.968341) (xy 79.053132 -309.981574) (xy 79.006589 -309.988278) (xy 78.983078 -309.988712)
			(xy 78.957092 -309.988193) (xy 78.905761 -309.98006) (xy 78.856334 -309.963997) (xy 78.810028 -309.9404)
			(xy 78.767984 -309.90985) (xy 78.731235 -309.8731) (xy 78.700688 -309.831053) (xy 78.677095 -309.784746)
			(xy 78.661035 -309.735318) (xy 78.652905 -309.683986) (xy 70.634532 -309.683986) (xy 69.860922 -310.457596)
			(xy 95.560134 -310.457596) (xy 95.560638 -310.430439) (xy 95.569513 -310.376856) (xy 95.587025 -310.325444)
			(xy 95.612702 -310.277583) (xy 95.645854 -310.234562) (xy 95.68559 -310.197535) (xy 95.730842 -310.1675)
			(xy 95.780394 -310.145262) (xy 95.806514 -310.13781) (xy 95.81769 -310.135016) (xy 95.834962 -310.12003)
			(xy 95.876872 -310.026304) (xy 95.87611 -310.003444) (xy 95.870776 -309.99303) (xy 95.857253 -309.965923)
			(xy 95.836061 -309.90917) (xy 95.821766 -309.8503) (xy 95.81457 -309.790148) (xy 95.814134 -309.759858)
			(xy 95.814636 -309.727897) (xy 95.822647 -309.664479) (xy 95.838544 -309.602565) (xy 95.862076 -309.543132)
			(xy 95.89287 -309.487117) (xy 95.930443 -309.435402) (xy 95.9742 -309.388805) (xy 96.023453 -309.34806)
			(xy 96.077424 -309.313809) (xy 96.135263 -309.286592) (xy 96.196056 -309.266839) (xy 96.258846 -309.254861)
			(xy 96.322642 -309.250848) (xy 96.386438 -309.254861) (xy 96.449228 -309.266839) (xy 96.510021 -309.286592)
			(xy 96.56786 -309.313809) (xy 96.621831 -309.34806) (xy 96.671084 -309.388805) (xy 96.714841 -309.435402)
			(xy 96.752414 -309.487117) (xy 96.783208 -309.543132) (xy 96.80674 -309.602565) (xy 96.822637 -309.664479)
			(xy 96.830648 -309.727897) (xy 96.83115 -309.759858) (xy 96.831022 -309.776543) (xy 96.828861 -309.809844)
			(xy 96.826832 -309.826406) (xy 96.825922 -309.838178) (xy 96.833566 -309.860481) (xy 96.850359 -309.877031)
			(xy 96.861376 -309.88127) (xy 96.891489 -309.89168) (xy 96.949054 -309.918993) (xy 97.002753 -309.953287)
			(xy 97.051746 -309.994023) (xy 97.095262 -310.040563) (xy 97.132621 -310.092178) (xy 97.163235 -310.148057)
			(xy 97.186626 -310.207324) (xy 97.202425 -310.26905) (xy 97.210386 -310.332266) (xy 97.21088 -310.364124)
			(xy 97.210485 -310.394858) (xy 97.203073 -310.455877) (xy 97.18836 -310.515557) (xy 97.16656 -310.573029)
			(xy 97.137992 -310.627454) (xy 97.103072 -310.678039) (xy 97.06231 -310.724046) (xy 97.016298 -310.764804)
			(xy 96.96571 -310.799719) (xy 96.911282 -310.828282) (xy 96.853807 -310.850075) (xy 96.794125 -310.864782)
			(xy 96.733106 -310.872188) (xy 96.702372 -310.872632) (xy 96.669241 -310.872089) (xy 96.603542 -310.863473)
			(xy 96.539516 -310.846403) (xy 96.478248 -310.821168) (xy 96.420773 -310.788194) (xy 96.368063 -310.74804)
			(xy 96.321011 -310.701385) (xy 96.30029 -310.675528) (xy 96.293432 -310.666638) (xy 96.272858 -310.656224)
			(xy 96.171004 -310.653684) (xy 96.150176 -310.663082) (xy 96.14281 -310.671972) (xy 96.126999 -310.689866)
			(xy 96.091127 -310.721383) (xy 96.0511 -310.747419) (xy 96.007748 -310.767436) (xy 95.961971 -310.781018)
			(xy 95.914717 -310.787883) (xy 95.890842 -310.788304) (xy 95.864854 -310.787786) (xy 95.813516 -310.779661)
			(xy 95.764082 -310.763604) (xy 95.717769 -310.740011) (xy 95.675716 -310.709463) (xy 95.638961 -310.672713)
			(xy 95.608408 -310.630664) (xy 95.58481 -310.584353) (xy 95.568748 -310.534921) (xy 95.560617 -310.483584)
			(xy 95.560134 -310.457596) (xy 69.860922 -310.457596) (xy 65.141729 -315.176789) (xy 97.790756 -315.176789)
			(xy 97.790756 -315.124811) (xy 97.798886 -315.073473) (xy 97.814947 -315.024039) (xy 97.838543 -314.977726)
			(xy 97.869093 -314.935673) (xy 97.905844 -314.898917) (xy 97.947893 -314.868363) (xy 97.994204 -314.844762)
			(xy 98.043636 -314.828695) (xy 98.094973 -314.820559) (xy 98.120962 -314.820046) (xy 98.137783 -314.820263)
			(xy 98.17125 -314.823697) (xy 98.187764 -314.826904) (xy 98.199293 -314.828703) (xy 98.221859 -314.822862)
			(xy 98.239541 -314.807673) (xy 98.24466 -314.797186) (xy 98.259395 -314.764385) (xy 98.29675 -314.702942)
			(xy 98.319082 -314.674758) (xy 98.324305 -314.667804) (xy 98.330158 -314.651443) (xy 98.330512 -314.642754)
			(xy 98.330512 -314.488576) (xy 98.330156 -314.479828) (xy 98.324314 -314.463337) (xy 98.319082 -314.456318)
			(xy 98.300398 -314.432925) (xy 98.268088 -314.38252) (xy 98.241933 -314.328663) (xy 98.222298 -314.272103)
			(xy 98.21545 -314.242958) (xy 98.212428 -314.231682) (xy 98.197914 -314.213428) (xy 98.176827 -314.203469)
			(xy 98.165158 -314.20308) (xy 98.161348 -314.20308) (xy 98.161094 -314.20308) (xy 98.135105 -314.202626)
			(xy 98.083767 -314.194494) (xy 98.034333 -314.178431) (xy 97.98802 -314.154833) (xy 97.945969 -314.12428)
			(xy 97.909216 -314.087526) (xy 97.878664 -314.045475) (xy 97.855067 -313.999162) (xy 97.839005 -313.949727)
			(xy 97.830874 -313.898389) (xy 97.830874 -313.846411) (xy 97.839005 -313.795073) (xy 97.855067 -313.745638)
			(xy 97.878664 -313.699325) (xy 97.909216 -313.657274) (xy 97.945969 -313.62052) (xy 97.98802 -313.589967)
			(xy 98.034333 -313.566369) (xy 98.083767 -313.550306) (xy 98.135105 -313.542174) (xy 98.161094 -313.541664)
			(xy 98.185871 -313.542147) (xy 98.234872 -313.549533) (xy 98.282224 -313.564142) (xy 98.32687 -313.585647)
			(xy 98.36781 -313.613567) (xy 98.404131 -313.647278) (xy 98.41992 -313.666378) (xy 98.427604 -313.6751)
			(xy 98.448567 -313.68508) (xy 98.471783 -313.684814) (xy 98.482404 -313.680094) (xy 98.509163 -313.666991)
			(xy 98.565097 -313.646457) (xy 98.623051 -313.632613) (xy 98.682228 -313.625651) (xy 98.71202 -313.62523)
			(xy 98.742754 -313.625619) (xy 98.803774 -313.633031) (xy 98.863455 -313.647744) (xy 98.920927 -313.669543)
			(xy 98.975353 -313.698112) (xy 99.025938 -313.733032) (xy 99.071946 -313.773795) (xy 99.112704 -313.819807)
			(xy 99.147619 -313.870397) (xy 99.176181 -313.924826) (xy 99.197974 -313.982301) (xy 99.21268 -314.041984)
			(xy 99.220085 -314.103004) (xy 99.220528 -314.133738) (xy 99.219911 -314.168702) (xy 99.210318 -314.23797)
			(xy 99.191318 -314.305268) (xy 99.16327 -314.369326) (xy 99.126705 -314.428933) (xy 99.104958 -314.456318)
			(xy 99.099675 -314.463309) (xy 99.093837 -314.479818) (xy 99.093528 -314.488576) (xy 99.093528 -314.6425)
			(xy 99.093887 -314.651247) (xy 99.099726 -314.667739) (xy 99.104958 -314.674758) (xy 99.12667 -314.702169)
			(xy 99.163229 -314.761775) (xy 99.191282 -314.825827) (xy 99.210299 -314.893116) (xy 99.219924 -314.962376)
			(xy 99.220528 -314.997338) (xy 99.22008 -315.028069) (xy 99.212668 -315.089083) (xy 99.197955 -315.148758)
			(xy 99.176158 -315.206225) (xy 99.147593 -315.260646) (xy 99.112677 -315.311227) (xy 99.071919 -315.357232)
			(xy 99.025913 -315.397988) (xy 98.975331 -315.432902) (xy 98.920909 -315.461465) (xy 98.863441 -315.483261)
			(xy 98.803765 -315.497971) (xy 98.742751 -315.505381) (xy 98.71202 -315.505846) (xy 98.67853 -315.505318)
			(xy 98.612128 -315.496534) (xy 98.547452 -315.479116) (xy 98.485619 -315.453365) (xy 98.427699 -315.419726)
			(xy 98.40087 -315.399674) (xy 98.391313 -315.392954) (xy 98.368455 -315.388232) (xy 98.34585 -315.394049)
			(xy 98.336608 -315.401198) (xy 98.31854 -315.416249) (xy 98.278939 -315.441608) (xy 98.236144 -315.461099)
			(xy 98.191019 -315.474328) (xy 98.144474 -315.481029) (xy 98.120962 -315.481462) (xy 98.094973 -315.481041)
			(xy 98.043636 -315.472905) (xy 97.994204 -315.456838) (xy 97.947893 -315.433237) (xy 97.905844 -315.402683)
			(xy 97.869093 -315.365927) (xy 97.838543 -315.323874) (xy 97.814947 -315.277561) (xy 97.798886 -315.228127)
			(xy 97.790756 -315.176789) (xy 65.141729 -315.176789) (xy 61.739272 -318.579246) (xy 61.732425 -318.586643)
			(xy 61.724696 -318.605243) (xy 61.724286 -318.615314) (xy 61.724286 -318.621156) (xy 61.723852 -318.631221)
			(xy 61.716122 -318.64981) (xy 61.7093 -318.657224) (xy 59.426602 -320.939922) (xy 59.419759 -320.947322)
			(xy 59.412032 -320.96592) (xy 59.411616 -320.97599) (xy 59.411616 -325.830184) (xy 59.411178 -325.840248)
			(xy 59.403444 -325.858832) (xy 59.39663 -325.866252) (xy 59.110626 -326.152256) (xy 59.103226 -326.159096)
			(xy 59.084627 -326.16681) (xy 59.074558 -326.167242) (xy 58.021728 -326.167242) (xy 58.015719 -326.167411)
			(xy 58.004037 -326.170236) (xy 57.998614 -326.17283) (xy 57.995139 -326.174669) (xy 57.988759 -326.179261)
			(xy 57.985914 -326.181974) (xy 57.73928 -326.428608) (xy 57.732599 -326.436019) (xy 57.725023 -326.454455)
			(xy 57.724548 -326.464422) (xy 57.724548 -328.129256) (xy 68.577615 -328.129256) (xy 68.577615 -328.074744)
			(xy 68.585373 -328.020786) (xy 68.600732 -327.968481) (xy 68.623377 -327.918895) (xy 68.65285 -327.873036)
			(xy 68.688549 -327.831839) (xy 68.729748 -327.796141) (xy 68.775607 -327.766671) (xy 68.825194 -327.744027)
			(xy 68.877499 -327.72867) (xy 68.931458 -327.720914) (xy 68.958714 -327.720452) (xy 68.987453 -327.72098)
			(xy 69.044279 -327.729604) (xy 69.099169 -327.746653) (xy 69.150881 -327.771744) (xy 69.198244 -327.804307)
			(xy 69.219572 -327.823576) (xy 69.22643 -327.83018) (xy 69.244464 -327.837292) (xy 69.333364 -327.837292)
			(xy 69.351398 -327.83018) (xy 69.358256 -327.823576) (xy 69.379583 -327.804305) (xy 69.426944 -327.771737)
			(xy 69.478656 -327.746644) (xy 69.533547 -327.729594) (xy 69.590375 -327.720972) (xy 69.619114 -327.720452)
			(xy 69.646362 -327.721019) (xy 69.700302 -327.728776) (xy 69.75259 -327.744131) (xy 69.80216 -327.766771)
			(xy 69.848004 -327.796234) (xy 69.889188 -327.831922) (xy 69.924874 -327.873107) (xy 69.954336 -327.918952)
			(xy 69.976974 -327.968523) (xy 69.992327 -328.020811) (xy 70.000082 -328.074752) (xy 70.000082 -328.129248)
			(xy 70.000081 -328.129257) (xy 71.074415 -328.129257) (xy 71.074415 -328.074743) (xy 71.082174 -328.020783)
			(xy 71.097533 -327.968477) (xy 71.12018 -327.918889) (xy 71.149655 -327.87303) (xy 71.185356 -327.831832)
			(xy 71.226557 -327.796134) (xy 71.272419 -327.766664) (xy 71.322009 -327.744021) (xy 71.374316 -327.728666)
			(xy 71.428277 -327.720913) (xy 71.455534 -327.720452) (xy 71.484273 -327.720968) (xy 71.5411 -327.729594)
			(xy 71.595991 -327.746647) (xy 71.647702 -327.77174) (xy 71.695065 -327.804305) (xy 71.716392 -327.823576)
			(xy 71.72325 -327.83018) (xy 71.741284 -327.837292) (xy 71.830184 -327.837292) (xy 71.848218 -327.83018)
			(xy 71.855076 -327.823576) (xy 71.876395 -327.804295) (xy 71.923758 -327.771729) (xy 71.975472 -327.746638)
			(xy 72.030365 -327.72959) (xy 72.087194 -327.720971) (xy 72.115934 -327.720452) (xy 72.143181 -327.72102)
			(xy 72.197119 -327.72878) (xy 72.249404 -327.744137) (xy 72.298972 -327.766777) (xy 72.344813 -327.796241)
			(xy 72.385995 -327.831929) (xy 72.421679 -327.873114) (xy 72.451139 -327.918958) (xy 72.473775 -327.968528)
			(xy 72.489127 -328.020814) (xy 72.49149 -328.037253) (xy 73.771967 -328.037253) (xy 73.771967 -327.982747)
			(xy 73.779724 -327.928797) (xy 73.795081 -327.8765) (xy 73.817723 -327.82692) (xy 73.847192 -327.781068)
			(xy 73.882886 -327.739876) (xy 73.924079 -327.704183) (xy 73.969932 -327.674717) (xy 74.019513 -327.652076)
			(xy 74.071811 -327.636721) (xy 74.125761 -327.628966) (xy 74.153014 -327.628504) (xy 74.181753 -327.629018)
			(xy 74.238581 -327.637643) (xy 74.293472 -327.654695) (xy 74.345184 -327.679789) (xy 74.392546 -327.712356)
			(xy 74.413872 -327.731628) (xy 74.42073 -327.738232) (xy 74.438764 -327.745344) (xy 74.527664 -327.745344)
			(xy 74.545698 -327.738232) (xy 74.552556 -327.731628) (xy 74.573876 -327.712349) (xy 74.62124 -327.679784)
			(xy 74.672953 -327.654694) (xy 74.727846 -327.637645) (xy 74.784675 -327.629024) (xy 74.813414 -327.628504)
			(xy 74.840665 -327.628967) (xy 74.894613 -327.636725) (xy 74.946908 -327.652082) (xy 74.996485 -327.674725)
			(xy 75.042335 -327.704192) (xy 75.083525 -327.739885) (xy 75.119216 -327.781076) (xy 75.148682 -327.826927)
			(xy 75.171323 -327.876505) (xy 75.186678 -327.9288) (xy 75.194434 -327.982749) (xy 75.194434 -328.037251)
			(xy 75.186678 -328.0912) (xy 75.175504 -328.129257) (xy 80.802615 -328.129257) (xy 80.802615 -328.074743)
			(xy 80.810374 -328.020783) (xy 80.825733 -327.968477) (xy 80.84838 -327.918889) (xy 80.877855 -327.87303)
			(xy 80.913556 -327.831832) (xy 80.954757 -327.796134) (xy 81.000619 -327.766664) (xy 81.050209 -327.744021)
			(xy 81.102516 -327.728666) (xy 81.156477 -327.720913) (xy 81.183734 -327.720452) (xy 81.212473 -327.720968)
			(xy 81.2693 -327.729594) (xy 81.324191 -327.746647) (xy 81.375902 -327.77174) (xy 81.423265 -327.804305)
			(xy 81.444592 -327.823576) (xy 81.45145 -327.83018) (xy 81.469484 -327.837292) (xy 81.558384 -327.837292)
			(xy 81.576418 -327.83018) (xy 81.583276 -327.823576) (xy 81.604595 -327.804295) (xy 81.651958 -327.771729)
			(xy 81.703672 -327.746638) (xy 81.758565 -327.72959) (xy 81.815394 -327.720971) (xy 81.844134 -327.720452)
			(xy 81.871381 -327.72102) (xy 81.925319 -327.72878) (xy 81.977604 -327.744137) (xy 82.027172 -327.766777)
			(xy 82.073013 -327.796241) (xy 82.114195 -327.831929) (xy 82.149879 -327.873114) (xy 82.179339 -327.918958)
			(xy 82.201975 -327.968528) (xy 82.217327 -328.020814) (xy 82.225082 -328.074753) (xy 82.225082 -328.129247)
			(xy 82.223701 -328.13885) (xy 82.61629 -328.13885) (xy 82.61629 -328.08435) (xy 82.624046 -328.030404)
			(xy 82.639401 -327.978112) (xy 82.662041 -327.928537) (xy 82.691505 -327.882688) (xy 82.727195 -327.841499)
			(xy 82.768383 -327.805809) (xy 82.814231 -327.776344) (xy 82.863806 -327.753703) (xy 82.916099 -327.738348)
			(xy 82.970044 -327.730591) (xy 82.997294 -327.730104) (xy 83.027562 -327.730666) (xy 83.087337 -327.740238)
			(xy 83.144852 -327.759127) (xy 83.198663 -327.786859) (xy 83.24742 -327.822739) (xy 83.269074 -327.843896)
			(xy 83.276492 -327.85085) (xy 83.295236 -327.858695) (xy 83.305396 -327.859136) (xy 83.377532 -327.859136)
			(xy 83.387695 -327.858729) (xy 83.406431 -327.850852) (xy 83.413854 -327.843896) (xy 83.435501 -327.822732)
			(xy 83.484258 -327.78685) (xy 83.53807 -327.75912) (xy 83.595588 -327.740239) (xy 83.655365 -327.730682)
			(xy 83.685634 -327.730104) (xy 83.712885 -327.730568) (xy 83.76683 -327.738329) (xy 83.819123 -327.753687)
			(xy 83.868697 -327.776331) (xy 83.914545 -327.805799) (xy 83.955732 -327.841492) (xy 83.991421 -327.882683)
			(xy 84.020885 -327.928533) (xy 84.043525 -327.978109) (xy 84.058878 -328.030403) (xy 84.066634 -328.084349)
			(xy 84.066634 -328.138851) (xy 84.062911 -328.164748) (xy 89.522598 -328.164748) (xy 89.522598 -328.110252)
			(xy 89.530353 -328.056312) (xy 89.545705 -328.004023) (xy 89.568342 -327.954452) (xy 89.597802 -327.908606)
			(xy 89.633487 -327.867419) (xy 89.674669 -327.83173) (xy 89.720511 -327.802264) (xy 89.77008 -327.779621)
			(xy 89.822367 -327.764263) (xy 89.876306 -327.756501) (xy 89.903554 -327.756012) (xy 89.932294 -327.7565)
			(xy 89.989123 -327.765131) (xy 90.044015 -327.782189) (xy 90.095726 -327.807289) (xy 90.143087 -327.839862)
			(xy 90.164412 -327.859136) (xy 90.17127 -327.86574) (xy 90.189304 -327.872852) (xy 90.278204 -327.872852)
			(xy 90.296238 -327.86574) (xy 90.303096 -327.859136) (xy 90.324401 -327.839839) (xy 90.371769 -327.807277)
			(xy 90.423486 -327.782189) (xy 90.478382 -327.765145) (xy 90.535213 -327.756529) (xy 90.563954 -327.756012)
			(xy 90.593124 -327.756542) (xy 90.65078 -327.765449) (xy 90.706407 -327.783033) (xy 90.758708 -327.808882)
			(xy 90.806462 -327.842395) (xy 90.848556 -327.882788) (xy 90.866722 -327.905618) (xy 90.873834 -327.915016)
			(xy 90.894662 -327.92543) (xy 90.998294 -327.926446) (xy 91.019122 -327.916794) (xy 91.026488 -327.90765)
			(xy 91.044703 -327.885891) (xy 91.086476 -327.847486) (xy 91.133477 -327.815692) (xy 91.184669 -327.791213)
			(xy 91.238923 -327.774588) (xy 91.295042 -327.766183) (xy 91.323414 -327.765664) (xy 91.349933 -327.766137)
			(xy 91.402457 -327.773501) (xy 91.453455 -327.788071) (xy 91.501942 -327.809566) (xy 91.546983 -327.837571)
			(xy 91.58771 -327.871547) (xy 91.605862 -327.890886) (xy 91.612974 -327.89876) (xy 91.632024 -327.907396)
			(xy 91.716606 -327.90892) (xy 91.726957 -327.908567) (xy 91.7461 -327.900724) (xy 91.75369 -327.89368)
			(xy 91.753944 -327.893426) (xy 91.771958 -327.875559) (xy 91.811895 -327.844265) (xy 91.855626 -327.81854)
			(xy 91.902382 -327.798838) (xy 91.951336 -327.785506) (xy 92.001625 -327.778781) (xy 92.026994 -327.778364)
			(xy 92.054245 -327.778883) (xy 92.108193 -327.786639) (xy 92.160487 -327.801993) (xy 92.210065 -327.824633)
			(xy 92.255915 -327.854099) (xy 92.297106 -327.88979) (xy 92.332797 -327.93098) (xy 92.362264 -327.97683)
			(xy 92.384905 -328.026407) (xy 92.40026 -328.078701) (xy 92.408017 -328.132649) (xy 92.408017 -328.151513)
			(xy 97.587122 -328.151513) (xy 97.587127 -328.097018) (xy 97.594887 -328.043078) (xy 97.610244 -327.990792)
			(xy 97.632886 -327.941224) (xy 97.662352 -327.895382) (xy 97.698042 -327.854201) (xy 97.739229 -327.818517)
			(xy 97.785075 -327.789058) (xy 97.834647 -327.766424) (xy 97.886935 -327.751074) (xy 97.940876 -327.743322)
			(xy 97.995371 -327.743326) (xy 98.04931 -327.751084) (xy 98.101597 -327.76644) (xy 98.151166 -327.789081)
			(xy 98.197008 -327.818545) (xy 98.238191 -327.854234) (xy 98.273876 -327.89542) (xy 98.303336 -327.941265)
			(xy 98.325972 -327.990836) (xy 98.341323 -328.043124) (xy 98.349077 -328.097065) (xy 98.349562 -328.124312)
			(xy 98.348546 -328.153014) (xy 98.347936 -328.167961) (xy 98.354484 -328.197139) (xy 98.369195 -328.223174)
			(xy 98.390809 -328.243839) (xy 98.417477 -328.257367) (xy 98.446919 -328.262601) (xy 98.476616 -328.259092)
			(xy 98.490532 -328.253598) (xy 98.514701 -328.243495) (xy 98.565109 -328.229249) (xy 98.616995 -328.222044)
			(xy 98.643186 -328.221594) (xy 98.643694 -328.221594) (xy 98.670947 -328.222049) (xy 98.724899 -328.229805)
			(xy 98.777198 -328.245161) (xy 98.82678 -328.267803) (xy 98.872634 -328.297271) (xy 98.913828 -328.332964)
			(xy 98.949523 -328.374157) (xy 98.978992 -328.420011) (xy 99.001636 -328.469592) (xy 99.016993 -328.52189)
			(xy 99.02475 -328.575842) (xy 99.024751 -328.630349) (xy 99.016995 -328.684301) (xy 99.001639 -328.7366)
			(xy 98.978996 -328.786181) (xy 98.949528 -328.832035) (xy 98.913835 -328.873229) (xy 98.872642 -328.908924)
			(xy 98.826788 -328.938393) (xy 98.777207 -328.961036) (xy 98.724908 -328.976393) (xy 98.670957 -328.98415)
			(xy 98.61645 -328.984151) (xy 98.562498 -328.976394) (xy 98.510199 -328.961038) (xy 98.460618 -328.938396)
			(xy 98.414764 -328.908928) (xy 98.37357 -328.873234) (xy 98.337876 -328.83204) (xy 98.308407 -328.786187)
			(xy 98.285764 -328.736606) (xy 98.270407 -328.684307) (xy 98.26265 -328.630355) (xy 98.262186 -328.603102)
			(xy 98.263202 -328.5744) (xy 98.263733 -328.559454) (xy 98.257192 -328.530288) (xy 98.242493 -328.504262)
			(xy 98.220893 -328.483601) (xy 98.19424 -328.470072) (xy 98.164812 -328.464832) (xy 98.135127 -328.468329)
			(xy 98.121216 -328.473816) (xy 98.097054 -328.483936) (xy 98.046642 -328.498175) (xy 97.994754 -328.505374)
			(xy 97.968562 -328.50582) (xy 97.968054 -328.50582) (xy 97.940807 -328.505273) (xy 97.886867 -328.497511)
			(xy 97.834582 -328.482152) (xy 97.785014 -328.459508) (xy 97.739173 -328.430041) (xy 97.697993 -328.39435)
			(xy 97.66231 -328.353162) (xy 97.632853 -328.307315) (xy 97.61022 -328.257743) (xy 97.594872 -328.205454)
			(xy 97.587122 -328.151513) (xy 92.408017 -328.151513) (xy 92.408017 -328.187151) (xy 92.40026 -328.241099)
			(xy 92.384905 -328.293393) (xy 92.362264 -328.34297) (xy 92.332797 -328.38882) (xy 92.297106 -328.43001)
			(xy 92.255915 -328.465701) (xy 92.210065 -328.495167) (xy 92.160487 -328.517807) (xy 92.108193 -328.533161)
			(xy 92.054245 -328.540917) (xy 92.026994 -328.54138) (xy 92.000474 -328.54092) (xy 91.947949 -328.533556)
			(xy 91.89695 -328.518985) (xy 91.848463 -328.497487) (xy 91.803422 -328.469479) (xy 91.762696 -328.435499)
			(xy 91.744546 -328.416158) (xy 91.737434 -328.408284) (xy 91.718384 -328.399648) (xy 91.633802 -328.398124)
			(xy 91.623444 -328.398416) (xy 91.604301 -328.4063) (xy 91.596718 -328.413364) (xy 91.596464 -328.413618)
			(xy 91.578436 -328.43147) (xy 91.538504 -328.462768) (xy 91.494775 -328.488497) (xy 91.448022 -328.508202)
			(xy 91.39907 -328.521535) (xy 91.348782 -328.528263) (xy 91.323414 -328.52868) (xy 91.294246 -328.528105)
			(xy 91.236592 -328.519207) (xy 91.180965 -328.501633) (xy 91.128664 -328.475792) (xy 91.080909 -328.442287)
			(xy 91.038813 -328.4019) (xy 91.020646 -328.379074) (xy 91.013534 -328.369676) (xy 90.992706 -328.359262)
			(xy 90.889074 -328.358246) (xy 90.868246 -328.367898) (xy 90.86088 -328.377042) (xy 90.84268 -328.398815)
			(xy 90.800905 -328.437219) (xy 90.753901 -328.469011) (xy 90.702705 -328.493489) (xy 90.648448 -328.510111)
			(xy 90.592327 -328.518511) (xy 90.563954 -328.519028) (xy 90.535214 -328.518525) (xy 90.478386 -328.509896)
			(xy 90.423496 -328.492841) (xy 90.371784 -328.467745) (xy 90.324423 -328.435176) (xy 90.303096 -328.415904)
			(xy 90.296238 -328.4093) (xy 90.278204 -328.402188) (xy 90.189304 -328.402188) (xy 90.17127 -328.4093)
			(xy 90.164412 -328.415904) (xy 90.143095 -328.435187) (xy 90.095731 -328.467753) (xy 90.044017 -328.492844)
			(xy 89.989124 -328.509892) (xy 89.932294 -328.51851) (xy 89.903554 -328.519028) (xy 89.876306 -328.518499)
			(xy 89.822367 -328.510737) (xy 89.77008 -328.495379) (xy 89.720511 -328.472736) (xy 89.674669 -328.44327)
			(xy 89.633487 -328.407581) (xy 89.597802 -328.366394) (xy 89.568342 -328.320548) (xy 89.545705 -328.270977)
			(xy 89.530353 -328.218688) (xy 89.522598 -328.164748) (xy 84.062911 -328.164748) (xy 84.058878 -328.192797)
			(xy 84.043525 -328.245091) (xy 84.020885 -328.294667) (xy 83.991421 -328.340517) (xy 83.955732 -328.381708)
			(xy 83.914545 -328.417401) (xy 83.868697 -328.446869) (xy 83.819123 -328.469513) (xy 83.76683 -328.484871)
			(xy 83.712885 -328.492632) (xy 83.685634 -328.49312) (xy 83.655367 -328.492533) (xy 83.595593 -328.482966)
			(xy 83.53808 -328.464082) (xy 83.484268 -328.436356) (xy 83.435509 -328.400482) (xy 83.413854 -328.379328)
			(xy 83.406423 -328.37239) (xy 83.387689 -328.364534) (xy 83.377532 -328.364088) (xy 83.305396 -328.364088)
			(xy 83.295234 -328.364503) (xy 83.276497 -328.372374) (xy 83.269074 -328.379328) (xy 83.247419 -328.400483)
			(xy 83.198664 -328.436365) (xy 83.144853 -328.464096) (xy 83.087338 -328.482979) (xy 83.027562 -328.49254)
			(xy 82.997294 -328.49312) (xy 82.970044 -328.492609) (xy 82.916099 -328.484852) (xy 82.863806 -328.469497)
			(xy 82.814231 -328.446856) (xy 82.768383 -328.417391) (xy 82.727195 -328.381701) (xy 82.691505 -328.340512)
			(xy 82.662041 -328.294663) (xy 82.639401 -328.245088) (xy 82.624046 -328.192796) (xy 82.61629 -328.13885)
			(xy 82.223701 -328.13885) (xy 82.217327 -328.183186) (xy 82.201975 -328.235472) (xy 82.179339 -328.285042)
			(xy 82.149879 -328.330886) (xy 82.114195 -328.372071) (xy 82.073013 -328.407759) (xy 82.027172 -328.437223)
			(xy 81.977604 -328.459863) (xy 81.925319 -328.47522) (xy 81.871381 -328.48298) (xy 81.844134 -328.483468)
			(xy 81.815394 -328.482966) (xy 81.758567 -328.474336) (xy 81.703677 -328.457279) (xy 81.651965 -328.432183)
			(xy 81.604603 -328.399616) (xy 81.583276 -328.380344) (xy 81.576418 -328.37374) (xy 81.558384 -328.366628)
			(xy 81.469484 -328.366628) (xy 81.45145 -328.37374) (xy 81.444592 -328.380344) (xy 81.423248 -328.399596)
			(xy 81.375891 -328.432165) (xy 81.324184 -328.457262) (xy 81.269297 -328.474317) (xy 81.212472 -328.482945)
			(xy 81.183734 -328.483468) (xy 81.156477 -328.483087) (xy 81.102516 -328.475334) (xy 81.050209 -328.459979)
			(xy 81.000619 -328.437336) (xy 80.954757 -328.407866) (xy 80.913556 -328.372168) (xy 80.877855 -328.33097)
			(xy 80.84838 -328.285111) (xy 80.825733 -328.235523) (xy 80.810374 -328.183217) (xy 80.802615 -328.129257)
			(xy 75.175504 -328.129257) (xy 75.171323 -328.143495) (xy 75.148682 -328.193073) (xy 75.119216 -328.238924)
			(xy 75.083525 -328.280115) (xy 75.042335 -328.315808) (xy 74.996485 -328.345275) (xy 74.946908 -328.367918)
			(xy 74.894613 -328.383275) (xy 74.840665 -328.391033) (xy 74.813414 -328.39152) (xy 74.784676 -328.390982)
			(xy 74.727849 -328.382362) (xy 74.672959 -328.365315) (xy 74.621247 -328.340227) (xy 74.573883 -328.307665)
			(xy 74.552556 -328.288396) (xy 74.545698 -328.281792) (xy 74.527664 -328.27468) (xy 74.438764 -328.27468)
			(xy 74.42073 -328.281792) (xy 74.413872 -328.288396) (xy 74.392529 -328.307649) (xy 74.345173 -328.34022)
			(xy 74.293465 -328.365317) (xy 74.238577 -328.382371) (xy 74.181752 -328.390997) (xy 74.153014 -328.39152)
			(xy 74.125761 -328.391034) (xy 74.071811 -328.383279) (xy 74.019513 -328.367924) (xy 73.969932 -328.345283)
			(xy 73.924079 -328.315817) (xy 73.882886 -328.280124) (xy 73.847192 -328.238932) (xy 73.817723 -328.19308)
			(xy 73.795081 -328.1435) (xy 73.779724 -328.091203) (xy 73.771967 -328.037253) (xy 72.49149 -328.037253)
			(xy 72.496882 -328.074753) (xy 72.496882 -328.129247) (xy 72.489127 -328.183186) (xy 72.473775 -328.235472)
			(xy 72.451139 -328.285042) (xy 72.421679 -328.330886) (xy 72.385995 -328.372071) (xy 72.344813 -328.407759)
			(xy 72.298972 -328.437223) (xy 72.249404 -328.459863) (xy 72.197119 -328.47522) (xy 72.143181 -328.48298)
			(xy 72.115934 -328.483468) (xy 72.087194 -328.482966) (xy 72.030367 -328.474336) (xy 71.975477 -328.457279)
			(xy 71.923765 -328.432183) (xy 71.876403 -328.399616) (xy 71.855076 -328.380344) (xy 71.848218 -328.37374)
			(xy 71.830184 -328.366628) (xy 71.741284 -328.366628) (xy 71.72325 -328.37374) (xy 71.716392 -328.380344)
			(xy 71.695048 -328.399596) (xy 71.647691 -328.432165) (xy 71.595984 -328.457262) (xy 71.541097 -328.474317)
			(xy 71.484272 -328.482945) (xy 71.455534 -328.483468) (xy 71.428277 -328.483087) (xy 71.374316 -328.475334)
			(xy 71.322009 -328.459979) (xy 71.272419 -328.437336) (xy 71.226557 -328.407866) (xy 71.185356 -328.372168)
			(xy 71.149655 -328.33097) (xy 71.12018 -328.285111) (xy 71.097533 -328.235523) (xy 71.082174 -328.183217)
			(xy 71.074415 -328.129257) (xy 70.000081 -328.129257) (xy 69.992327 -328.183189) (xy 69.976974 -328.235477)
			(xy 69.954336 -328.285048) (xy 69.924874 -328.330893) (xy 69.889188 -328.372078) (xy 69.848004 -328.407766)
			(xy 69.80216 -328.437229) (xy 69.75259 -328.459869) (xy 69.700302 -328.475224) (xy 69.646362 -328.482981)
			(xy 69.619114 -328.483468) (xy 69.590376 -328.482918) (xy 69.533551 -328.474299) (xy 69.478661 -328.457254)
			(xy 69.426949 -328.432169) (xy 69.379585 -328.399611) (xy 69.358256 -328.380344) (xy 69.351398 -328.37374)
			(xy 69.333364 -328.366628) (xy 69.244464 -328.366628) (xy 69.22643 -328.37374) (xy 69.219572 -328.380344)
			(xy 69.198237 -328.399605) (xy 69.150877 -328.432173) (xy 69.099168 -328.457268) (xy 69.044279 -328.474321)
			(xy 68.987452 -328.482946) (xy 68.958714 -328.483468) (xy 68.931458 -328.483086) (xy 68.877499 -328.47533)
			(xy 68.825194 -328.459973) (xy 68.775607 -328.437329) (xy 68.729748 -328.407859) (xy 68.688549 -328.372161)
			(xy 68.65285 -328.330964) (xy 68.623377 -328.285105) (xy 68.600732 -328.235519) (xy 68.585373 -328.183214)
			(xy 68.577615 -328.129256) (xy 57.724548 -328.129256) (xy 57.724548 -334.866996) (xy 57.72501 -334.876631)
			(xy 57.73218 -334.894523) (xy 57.738518 -334.901794) (xy 57.828942 -334.991964) (xy 57.920128 -335.08315)
			(xy 57.927472 -335.089961) (xy 57.945935 -335.097692) (xy 57.955942 -335.098136) (xy 64.958722 -335.098136)
		)
		(stroke
			(width 0)
			(type solid)
		)
		(fill yes)
		(layer "In4.Cu")
		(net "PVDDCR_CPU1_P1")
	)
	(gr_poly
		(pts
			(xy 310.913526 -335.10982) (xy 310.923595 -335.109393) (xy 310.942194 -335.101674) (xy 310.949594 -335.094834)
			(xy 311.062116 -334.982312) (xy 311.068974 -334.974918) (xy 311.076726 -334.956319) (xy 311.077102 -334.946244)
			(xy 311.077102 -330.708) (xy 311.077525 -330.69793) (xy 311.08524 -330.679326) (xy 311.092088 -330.671932)
			(xy 318.29883 -323.46519) (xy 318.306226 -323.458338) (xy 318.324825 -323.450601) (xy 318.334898 -323.450204)
			(xy 341.920068 -323.450204) (xy 341.930133 -323.45064) (xy 341.948719 -323.458372) (xy 341.956136 -323.46519)
			(xy 342.388698 -323.897752) (xy 342.39327 -323.901816) (xy 342.4003 -323.907439) (xy 342.413772 -323.919383)
			(xy 342.420194 -323.925692) (xy 346.720668 -328.226166) (xy 346.726942 -328.233322) (xy 346.743546 -328.242583)
			(xy 346.752926 -328.2442) (xy 346.756736 -328.244708) (xy 346.770452 -328.24674) (xy 346.777818 -328.247248)
			(xy 354.618544 -328.247248) (xy 354.628609 -328.246815) (xy 354.647197 -328.239084) (xy 354.654612 -328.232262)
			(xy 354.914962 -327.971912) (xy 354.921814 -327.964516) (xy 354.929559 -327.945918) (xy 354.929948 -327.935844)
			(xy 354.929948 -319.852802) (xy 354.929626 -319.844049) (xy 354.923767 -319.827557) (xy 354.918518 -319.820544)
			(xy 354.886006 -319.781174) (xy 354.882704 -319.777364) (xy 350.495362 -315.390022) (xy 350.488521 -315.382622)
			(xy 350.480806 -315.364023) (xy 350.480376 -315.353954) (xy 350.480376 -314.045346) (xy 350.480072 -314.037855)
			(xy 350.475689 -314.023524) (xy 350.47174 -314.017152) (xy 348.837758 -311.57164) (xy 348.831726 -311.563552)
			(xy 348.814933 -311.552405) (xy 348.795154 -311.548529) (xy 348.78518 -311.55005) (xy 348.678246 -311.57164)
			(xy 348.656402 -311.593738) (xy 348.653608 -311.608978) (xy 348.647112 -311.640279) (xy 348.627334 -311.701072)
			(xy 348.600097 -311.758908) (xy 348.56583 -311.812877) (xy 348.525073 -311.862129) (xy 348.478468 -311.905887)
			(xy 348.426748 -311.943464) (xy 348.370729 -311.974266) (xy 348.311293 -311.997808) (xy 348.249376 -312.01372)
			(xy 348.185954 -312.021752) (xy 348.15399 -312.022236) (xy 348.122937 -312.02175) (xy 348.061297 -312.014156)
			(xy 348.001036 -311.999131) (xy 347.971872 -311.988454) (xy 347.962982 -311.985152) (xy 347.944694 -311.985152)
			(xy 347.863414 -312.015886) (xy 347.849698 -312.028332) (xy 347.84538 -312.03646) (xy 347.832984 -312.059372)
			(xy 347.802913 -312.101908) (xy 347.767335 -312.139958) (xy 347.726912 -312.172815) (xy 347.682395 -312.199868)
			(xy 347.634611 -312.220614) (xy 347.58445 -312.234667) (xy 347.532844 -312.241767) (xy 347.506798 -312.2422)
			(xy 347.479547 -312.241714) (xy 347.425601 -312.233958) (xy 347.373308 -312.218603) (xy 347.323732 -312.195962)
			(xy 347.277882 -312.166496) (xy 347.236693 -312.130805) (xy 347.201003 -312.089616) (xy 347.171537 -312.043767)
			(xy 347.148897 -311.994191) (xy 347.133542 -311.941897) (xy 347.125786 -311.887951) (xy 347.125786 -311.833449)
			(xy 347.133542 -311.779503) (xy 347.148897 -311.727209) (xy 347.171537 -311.677633) (xy 347.201003 -311.631784)
			(xy 347.236693 -311.590595) (xy 347.277882 -311.554904) (xy 347.323732 -311.525438) (xy 347.373308 -311.502797)
			(xy 347.425601 -311.487442) (xy 347.479547 -311.479686) (xy 347.506798 -311.479184) (xy 347.517043 -311.479272)
			(xy 347.537501 -311.480415) (xy 347.547692 -311.48147) (xy 347.556971 -311.482088) (xy 347.57495 -311.477399)
			(xy 347.582744 -311.472326) (xy 347.645228 -311.427368) (xy 347.655642 -311.41162) (xy 347.657674 -311.402476)
			(xy 347.664567 -311.373613) (xy 347.684196 -311.317609) (xy 347.710221 -311.264276) (xy 347.742286 -311.214341)
			(xy 347.760798 -311.191148) (xy 347.765992 -311.184182) (xy 347.77182 -311.167825) (xy 347.772228 -311.159144)
			(xy 347.772228 -311.004712) (xy 347.771883 -310.99602) (xy 347.766039 -310.97965) (xy 347.760798 -310.972708)
			(xy 347.741909 -310.948955) (xy 347.70931 -310.897763) (xy 347.695774 -310.8706) (xy 347.691508 -310.862713)
			(xy 347.678638 -310.850248) (xy 347.670628 -310.846216) (xy 347.642942 -310.83377) (xy 347.634755 -310.830552)
			(xy 347.617223 -310.82925) (xy 347.608652 -310.83123) (xy 347.583692 -310.837739) (xy 347.532589 -310.844745)
			(xy 347.506798 -310.8452) (xy 347.479547 -310.844714) (xy 347.425601 -310.836958) (xy 347.373308 -310.821603)
			(xy 347.323732 -310.798962) (xy 347.277882 -310.769496) (xy 347.236693 -310.733805) (xy 347.201003 -310.692616)
			(xy 347.171537 -310.646767) (xy 347.148897 -310.597191) (xy 347.133542 -310.544897) (xy 347.125786 -310.490951)
			(xy 347.125786 -310.436449) (xy 347.133542 -310.382503) (xy 347.148897 -310.330209) (xy 347.171537 -310.280633)
			(xy 347.201003 -310.234784) (xy 347.236693 -310.193595) (xy 347.277882 -310.157904) (xy 347.323732 -310.128438)
			(xy 347.373308 -310.105797) (xy 347.425601 -310.090442) (xy 347.479547 -310.082686) (xy 347.506798 -310.082184)
			(xy 347.533247 -310.082634) (xy 347.585638 -310.08994) (xy 347.636517 -310.104412) (xy 347.684911 -310.125772)
			(xy 347.72989 -310.153611) (xy 347.770594 -310.187395) (xy 347.788738 -310.206644) (xy 347.794894 -310.213006)
			(xy 347.810505 -310.221331) (xy 347.819218 -310.2229) (xy 347.848936 -310.226964) (xy 347.857857 -310.227867)
			(xy 347.875402 -310.224232) (xy 347.883226 -310.219852) (xy 347.903861 -310.207135) (xy 347.947117 -310.185257)
			(xy 347.969586 -310.176164) (xy 347.979238 -310.172608) (xy 347.99397 -310.158384) (xy 348.026482 -310.08193)
			(xy 348.030091 -310.072423) (xy 348.030239 -310.052105) (xy 348.026736 -310.04256) (xy 347.760798 -309.400702)
			(xy 347.758785 -309.396142) (xy 347.753276 -309.387837) (xy 347.749876 -309.384192) (xy 346.429584 -308.0639)
			(xy 346.397326 -308.05882) (xy 346.382594 -308.066186) (xy 346.355931 -308.079163) (xy 346.300232 -308.099514)
			(xy 346.242541 -308.113237) (xy 346.183644 -308.120146) (xy 346.153994 -308.120542) (xy 346.15374 -308.120542)
			(xy 346.123006 -308.120099) (xy 346.061984 -308.112694) (xy 346.002301 -308.097988) (xy 345.944825 -308.076196)
			(xy 345.890395 -308.047634) (xy 345.839804 -308.012719) (xy 345.793791 -307.971961) (xy 345.753026 -307.925954)
			(xy 345.718105 -307.875369) (xy 345.689535 -307.820943) (xy 345.667734 -307.76347) (xy 345.653019 -307.703788)
			(xy 345.645606 -307.642768) (xy 345.645232 -307.612034) (xy 345.645741 -307.579353) (xy 345.654125 -307.514531)
			(xy 345.670747 -307.451317) (xy 345.695332 -307.390755) (xy 345.727475 -307.333843) (xy 345.766646 -307.281519)
			(xy 345.812199 -307.234645) (xy 345.863384 -307.193996) (xy 345.891104 -307.176678) (xy 345.891358 -307.176424)
			(xy 345.898573 -307.171627) (xy 345.909511 -307.158205) (xy 345.91534 -307.1419) (xy 345.915742 -307.133244)
			(xy 345.915742 -307.114448) (xy 345.915178 -307.104001) (xy 345.906788 -307.084857) (xy 345.899486 -307.077364)
			(xy 345.836748 -307.019452) (xy 345.816936 -307.012594) (xy 345.806268 -307.013356) (xy 345.76639 -307.01488)
			(xy 345.734431 -307.014378) (xy 345.671018 -307.006365) (xy 345.609108 -306.990469) (xy 345.549679 -306.966938)
			(xy 345.493668 -306.936145) (xy 345.441958 -306.898574) (xy 345.395364 -306.854819) (xy 345.354622 -306.805569)
			(xy 345.320374 -306.751601) (xy 345.293159 -306.693767) (xy 345.273408 -306.632977) (xy 345.261431 -306.570192)
			(xy 345.257417 -306.5064) (xy 345.261431 -306.442608) (xy 345.273408 -306.379823) (xy 345.293159 -306.319033)
			(xy 345.320374 -306.261199) (xy 345.354622 -306.207231) (xy 345.395364 -306.157981) (xy 345.441958 -306.114226)
			(xy 345.493668 -306.076655) (xy 345.549679 -306.045862) (xy 345.609108 -306.022331) (xy 345.671018 -306.006435)
			(xy 345.734431 -305.998422) (xy 345.76639 -305.997864) (xy 345.806268 -305.999388) (xy 345.816936 -306.00015)
			(xy 345.836748 -305.993292) (xy 345.899486 -305.93538) (xy 345.906822 -305.927909) (xy 345.915215 -305.908753)
			(xy 345.915742 -305.898296) (xy 345.915742 -304.95621) (xy 345.915646 -304.951192) (xy 345.91372 -304.941342)
			(xy 345.911932 -304.936652) (xy 343.83472 -299.92193) (xy 343.82076 -299.886645) (xy 343.801091 -299.813357)
			(xy 343.791152 -299.738129) (xy 343.790524 -299.700188) (xy 343.790524 -296.234104) (xy 343.790956 -296.202139)
			(xy 343.798015 -296.138599) (xy 343.812035 -296.076224) (xy 343.832845 -296.015776) (xy 343.84615 -295.986708)
			(xy 343.848212 -295.982003) (xy 343.850639 -295.972022) (xy 343.850976 -295.966896) (xy 343.853063 -295.925716)
			(xy 343.863952 -295.843977) (xy 343.882414 -295.76361) (xy 343.908288 -295.685314) (xy 343.941347 -295.60977)
			(xy 343.981306 -295.537638) (xy 344.027814 -295.469544) (xy 344.080469 -295.406083) (xy 344.109294 -295.3766)
			(xy 344.184732 -295.301162) (xy 344.191008 -295.29426) (xy 344.19853 -295.277207) (xy 344.199422 -295.25859)
			(xy 344.196924 -295.2496) (xy 344.189223 -295.224517) (xy 344.18093 -295.172709) (xy 344.180414 -295.146476)
			(xy 344.180414 -295.145968) (xy 344.180849 -295.121545) (xy 344.188033 -295.073229) (xy 344.202255 -295.026499)
			(xy 344.223205 -294.982372) (xy 344.250425 -294.941813) (xy 344.283321 -294.905705) (xy 344.321177 -294.874835)
			(xy 344.341958 -294.861996) (xy 344.350039 -294.856722) (xy 344.361796 -294.841442) (xy 344.364818 -294.832278)
			(xy 344.37787 -294.788668) (xy 344.410047 -294.703507) (xy 344.448966 -294.621208) (xy 344.494375 -294.542303)
			(xy 344.54598 -294.467305) (xy 344.574368 -294.43172) (xy 344.579956 -294.424862) (xy 344.585798 -294.408606)
			(xy 344.585798 -294.263318) (xy 344.579956 -294.247062) (xy 344.574368 -294.240204) (xy 344.542423 -294.20004)
			(xy 344.485114 -294.1149) (xy 344.435752 -294.02492) (xy 344.394741 -293.930838) (xy 344.378026 -293.882318)
			(xy 344.375995 -293.876705) (xy 344.369708 -293.866563) (xy 344.36558 -293.862252) (xy 344.180668 -293.67734)
			(xy 344.173823 -293.669942) (xy 344.1661 -293.651343) (xy 344.165682 -293.641272) (xy 344.165682 -293.381938)
			(xy 344.166116 -293.371872) (xy 344.173844 -293.353283) (xy 344.180668 -293.34587) (xy 344.381328 -293.14521)
			(xy 344.385074 -293.141292) (xy 344.390959 -293.132193) (xy 344.393012 -293.127176) (xy 344.412438 -293.077417)
			(xy 344.459383 -292.98146) (xy 344.515165 -292.890355) (xy 344.579285 -292.804913) (xy 344.614754 -292.764972)
			(xy 344.620811 -292.757801) (xy 344.627601 -292.740315) (xy 344.627962 -292.730936) (xy 344.627962 -292.70071)
			(xy 344.627486 -292.691354) (xy 344.620714 -292.673902) (xy 344.614754 -292.666674) (xy 344.585261 -292.633667)
			(xy 344.530938 -292.56377) (xy 344.482246 -292.48984) (xy 344.439484 -292.412329) (xy 344.402913 -292.331712)
			(xy 344.387424 -292.290246) (xy 344.383413 -292.280639) (xy 344.369157 -292.265495) (xy 344.35007 -292.257233)
			(xy 344.339672 -292.256718) (xy 344.268806 -292.256718) (xy 344.258735 -292.256297) (xy 344.240127 -292.248586)
			(xy 344.232738 -292.241732) (xy 344.030808 -292.039802) (xy 344.033094 -292.037516) (xy 344.033094 -291.727636)
			(xy 344.03284 -291.720457) (xy 344.028832 -291.706669) (xy 344.02522 -291.700458) (xy 343.994447 -291.650426)
			(xy 343.94227 -291.545183) (xy 343.92108 -291.4904) (xy 343.91727 -291.479986) (xy 343.684098 -291.246814)
			(xy 343.677265 -291.239411) (xy 343.669563 -291.220812) (xy 343.669112 -291.210746) (xy 343.669112 -290.968684)
			(xy 343.669538 -290.958615) (xy 343.677258 -290.940016) (xy 343.684098 -290.932616) (xy 343.92489 -290.691824)
			(xy 343.9287 -290.682172) (xy 343.946549 -290.638146) (xy 343.988627 -290.552963) (xy 344.037695 -290.471605)
			(xy 344.093406 -290.394645) (xy 344.124026 -290.358322) (xy 344.129868 -290.351464) (xy 344.136218 -290.334446)
			(xy 344.136218 -290.152836) (xy 344.136653 -290.142771) (xy 344.144386 -290.124185) (xy 344.151204 -290.116768)
			(xy 344.393266 -289.874706) (xy 344.396782 -289.871043) (xy 344.402411 -289.862596) (xy 344.404442 -289.857942)
			(xy 344.424918 -289.809429) (xy 344.473641 -289.71607) (xy 344.530827 -289.627642) (xy 344.562938 -289.585908)
			(xy 344.568272 -289.57905) (xy 344.57386 -289.563302) (xy 344.57386 -289.38855) (xy 344.568272 -289.372802)
			(xy 344.562938 -289.365944) (xy 344.53705 -289.332458) (xy 344.489785 -289.262234) (xy 344.447904 -289.188671)
			(xy 344.411644 -289.112181) (xy 344.39606 -289.072828) (xy 344.39225 -289.062922) (xy 344.174826 -288.845498)
			(xy 344.167977 -288.838101) (xy 344.160239 -288.819502) (xy 344.15984 -288.80943) (xy 344.15984 -288.502344)
			(xy 344.160275 -288.492279) (xy 344.168008 -288.473693) (xy 344.174826 -288.466276) (xy 344.405204 -288.235898)
			(xy 344.409014 -288.226754) (xy 344.432749 -288.17241) (xy 344.490017 -288.06856) (xy 344.523314 -288.01949)
			(xy 344.523314 -288.019236) (xy 344.527442 -288.01278) (xy 344.532096 -287.998188) (xy 344.532458 -287.990534)
			(xy 344.532458 -287.751774) (xy 344.532887 -287.741707) (xy 344.540615 -287.723115) (xy 344.547444 -287.715706)
			(xy 344.906346 -287.356804) (xy 344.910156 -287.349438) (xy 344.929422 -287.311864) (xy 344.972777 -287.239396)
			(xy 345.021414 -287.170362) (xy 345.075063 -287.105146) (xy 345.103958 -287.074356) (xy 345.11107 -287.06699)
			(xy 345.118182 -287.04921) (xy 345.118182 -286.894016) (xy 345.11862 -286.883952) (xy 345.126354 -286.865368)
			(xy 345.133168 -286.857948) (xy 345.318588 -286.672528) (xy 345.32234 -286.668542) (xy 345.328235 -286.659321)
			(xy 345.330272 -286.65424) (xy 345.345029 -286.615387) (xy 345.37948 -286.539745) (xy 345.399106 -286.50311)
			(xy 345.40399 -286.492692) (xy 345.405044 -286.469738) (xy 345.401138 -286.458914) (xy 345.396566 -286.447738)
			(xy 345.391486 -286.435292) (xy 345.37015 -286.418274) (xy 345.255342 -286.402272) (xy 345.23045 -286.412432)
			(xy 345.222068 -286.423354) (xy 345.207526 -286.441402) (xy 345.17391 -286.473308) (xy 345.135854 -286.499763)
			(xy 345.094234 -286.520156) (xy 345.050009 -286.53402) (xy 345.004196 -286.541034) (xy 344.981022 -286.541464)
			(xy 344.955767 -286.540973) (xy 344.905945 -286.532663) (xy 344.85817 -286.516265) (xy 344.813746 -286.492227)
			(xy 344.773885 -286.461204) (xy 344.739674 -286.424043) (xy 344.712046 -286.381758) (xy 344.691755 -286.335503)
			(xy 344.679355 -286.286538) (xy 344.675184 -286.2362) (xy 344.679355 -286.185862) (xy 344.691755 -286.136897)
			(xy 344.712046 -286.090642) (xy 344.739674 -286.048357) (xy 344.773885 -286.011196) (xy 344.813746 -285.980173)
			(xy 344.85817 -285.956135) (xy 344.905945 -285.939737) (xy 344.955767 -285.931427) (xy 344.981022 -285.930848)
			(xy 345.004194 -285.931282) (xy 345.050005 -285.938297) (xy 345.094226 -285.952164) (xy 345.13584 -285.972562)
			(xy 345.173889 -285.999023) (xy 345.207495 -286.030935) (xy 345.222068 -286.048958) (xy 345.23045 -286.05988)
			(xy 345.255342 -286.07004) (xy 345.37015 -286.054038) (xy 345.391486 -286.03702) (xy 345.396566 -286.024574)
			(xy 345.411644 -285.988978) (xy 345.450133 -285.921936) (xy 345.473274 -285.89097) (xy 345.481656 -285.880048)
			(xy 345.485212 -285.853378) (xy 345.442032 -285.746952) (xy 345.42095 -285.730442) (xy 345.407234 -285.72841)
			(xy 345.383347 -285.724447) (xy 345.337144 -285.709968) (xy 345.293801 -285.688386) (xy 345.254404 -285.66024)
			(xy 345.219937 -285.626234) (xy 345.191263 -285.58722) (xy 345.169098 -285.544172) (xy 345.153999 -285.498168)
			(xy 345.146341 -285.450359) (xy 345.145868 -285.42615) (xy 345.14639 -285.400895) (xy 345.154703 -285.351073)
			(xy 345.171104 -285.303299) (xy 345.195145 -285.258876) (xy 345.226169 -285.219016) (xy 345.263331 -285.184806)
			(xy 345.305617 -285.15718) (xy 345.351873 -285.13689) (xy 345.400838 -285.12449) (xy 345.451176 -285.120319)
			(xy 345.501514 -285.12449) (xy 345.550479 -285.13689) (xy 345.596735 -285.15718) (xy 345.639021 -285.184806)
			(xy 345.676183 -285.219016) (xy 345.707207 -285.258876) (xy 345.731248 -285.303299) (xy 345.747649 -285.351073)
			(xy 345.755962 -285.400895) (xy 345.756484 -285.42615) (xy 345.755835 -285.45485) (xy 345.745101 -285.511237)
			(xy 345.735148 -285.538164) (xy 345.730068 -285.55061) (xy 345.734132 -285.57728) (xy 345.805252 -285.667704)
			(xy 345.830144 -285.67761) (xy 345.843606 -285.675832) (xy 345.86288 -285.673396) (xy 345.901649 -285.670857)
			(xy 345.921076 -285.670752) (xy 346.01023 -285.670752) (xy 346.022626 -285.670215) (xy 346.044607 -285.658766)
			(xy 346.05214 -285.648908) (xy 346.099638 -285.57982) (xy 346.105931 -285.569391) (xy 346.10898 -285.545259)
			(xy 346.10548 -285.533592) (xy 346.10548 -285.533338) (xy 346.096414 -285.50747) (xy 346.086583 -285.453553)
			(xy 346.085922 -285.42615) (xy 346.086444 -285.400895) (xy 346.094757 -285.351073) (xy 346.111158 -285.303299)
			(xy 346.135199 -285.258876) (xy 346.166223 -285.219016) (xy 346.203385 -285.184806) (xy 346.245671 -285.15718)
			(xy 346.291927 -285.13689) (xy 346.340892 -285.12449) (xy 346.39123 -285.120319) (xy 346.441568 -285.12449)
			(xy 346.490533 -285.13689) (xy 346.536789 -285.15718) (xy 346.579075 -285.184806) (xy 346.616237 -285.219016)
			(xy 346.647261 -285.258876) (xy 346.671302 -285.303299) (xy 346.687703 -285.351073) (xy 346.696016 -285.400895)
			(xy 346.696538 -285.42615) (xy 346.695885 -285.453491) (xy 346.686043 -285.507281) (xy 346.67698 -285.533084)
			(xy 346.67698 -285.533592) (xy 346.672662 -285.545276) (xy 346.67571 -285.569406) (xy 346.73032 -285.648908)
			(xy 346.737982 -285.65862) (xy 346.759881 -285.670038) (xy 346.77223 -285.670752) (xy 346.86113 -285.670752)
			(xy 346.880557 -285.670855) (xy 346.919326 -285.673395) (xy 346.9386 -285.675832) (xy 346.952062 -285.67761)
			(xy 346.976954 -285.667704) (xy 347.048074 -285.57728) (xy 347.052138 -285.55061) (xy 347.047058 -285.538164)
			(xy 347.037138 -285.511228) (xy 347.026397 -285.454847) (xy 347.025722 -285.42615) (xy 347.026244 -285.400895)
			(xy 347.034557 -285.351073) (xy 347.050958 -285.303299) (xy 347.074999 -285.258876) (xy 347.106023 -285.219016)
			(xy 347.143185 -285.184806) (xy 347.185471 -285.15718) (xy 347.231727 -285.13689) (xy 347.280692 -285.12449)
			(xy 347.33103 -285.120319) (xy 347.381368 -285.12449) (xy 347.430333 -285.13689) (xy 347.476589 -285.15718)
			(xy 347.518875 -285.184806) (xy 347.556037 -285.219016) (xy 347.587061 -285.258876) (xy 347.611102 -285.303299)
			(xy 347.627503 -285.351073) (xy 347.635816 -285.400895) (xy 347.636338 -285.42615) (xy 347.96528 -285.42615)
			(xy 347.96924 -285.377096) (xy 347.981017 -285.329312) (xy 348.000308 -285.284036) (xy 348.026611 -285.24244)
			(xy 348.059246 -285.205603) (xy 348.097367 -285.174478) (xy 348.139988 -285.149871) (xy 348.186004 -285.132419)
			(xy 348.234223 -285.122575) (xy 348.283398 -285.120594) (xy 348.332253 -285.126526) (xy 348.379524 -285.140218)
			(xy 348.423986 -285.161316) (xy 348.464489 -285.189272) (xy 348.499982 -285.223364) (xy 348.529547 -285.262708)
			(xy 348.552418 -285.306285) (xy 348.568002 -285.352966) (xy 348.575897 -285.401543) (xy 348.576392 -285.42615)
			(xy 348.905334 -285.42615) (xy 348.909294 -285.377096) (xy 348.921071 -285.329312) (xy 348.940362 -285.284036)
			(xy 348.966665 -285.24244) (xy 348.9993 -285.205603) (xy 349.037421 -285.174478) (xy 349.080042 -285.149871)
			(xy 349.126058 -285.132419) (xy 349.174277 -285.122575) (xy 349.223452 -285.120594) (xy 349.272307 -285.126526)
			(xy 349.319578 -285.140218) (xy 349.36404 -285.161316) (xy 349.404543 -285.189272) (xy 349.440036 -285.223364)
			(xy 349.469601 -285.262708) (xy 349.492472 -285.306285) (xy 349.508056 -285.352966) (xy 349.515951 -285.401543)
			(xy 349.516446 -285.42615) (xy 349.845388 -285.42615) (xy 349.849348 -285.377096) (xy 349.861125 -285.329312)
			(xy 349.880416 -285.284036) (xy 349.906719 -285.24244) (xy 349.939354 -285.205603) (xy 349.977475 -285.174478)
			(xy 350.020096 -285.149871) (xy 350.066112 -285.132419) (xy 350.114331 -285.122575) (xy 350.163506 -285.120594)
			(xy 350.212361 -285.126526) (xy 350.259632 -285.140218) (xy 350.304094 -285.161316) (xy 350.344597 -285.189272)
			(xy 350.38009 -285.223364) (xy 350.409655 -285.262708) (xy 350.432526 -285.306285) (xy 350.44811 -285.352966)
			(xy 350.456005 -285.401543) (xy 350.4565 -285.42615) (xy 350.785442 -285.42615) (xy 350.789402 -285.377096)
			(xy 350.801179 -285.329312) (xy 350.82047 -285.284036) (xy 350.846773 -285.24244) (xy 350.879408 -285.205603)
			(xy 350.917529 -285.174478) (xy 350.96015 -285.149871) (xy 351.006166 -285.132419) (xy 351.054385 -285.122575)
			(xy 351.10356 -285.120594) (xy 351.152415 -285.126526) (xy 351.199686 -285.140218) (xy 351.244148 -285.161316)
			(xy 351.284651 -285.189272) (xy 351.320144 -285.223364) (xy 351.349709 -285.262708) (xy 351.37258 -285.306285)
			(xy 351.388164 -285.352966) (xy 351.396059 -285.401543) (xy 351.396554 -285.42615) (xy 351.725242 -285.42615)
			(xy 351.729202 -285.377096) (xy 351.740979 -285.329312) (xy 351.76027 -285.284036) (xy 351.786573 -285.24244)
			(xy 351.819208 -285.205603) (xy 351.857329 -285.174478) (xy 351.89995 -285.149871) (xy 351.945966 -285.132419)
			(xy 351.994185 -285.122575) (xy 352.04336 -285.120594) (xy 352.092215 -285.126526) (xy 352.139486 -285.140218)
			(xy 352.183948 -285.161316) (xy 352.224451 -285.189272) (xy 352.259944 -285.223364) (xy 352.289509 -285.262708)
			(xy 352.31238 -285.306285) (xy 352.327964 -285.352966) (xy 352.335859 -285.401543) (xy 352.336354 -285.42615)
			(xy 352.665296 -285.42615) (xy 352.669256 -285.377096) (xy 352.681033 -285.329312) (xy 352.700324 -285.284036)
			(xy 352.726627 -285.24244) (xy 352.759262 -285.205603) (xy 352.797383 -285.174478) (xy 352.840004 -285.149871)
			(xy 352.88602 -285.132419) (xy 352.934239 -285.122575) (xy 352.983414 -285.120594) (xy 353.032269 -285.126526)
			(xy 353.07954 -285.140218) (xy 353.124002 -285.161316) (xy 353.164505 -285.189272) (xy 353.199998 -285.223364)
			(xy 353.229563 -285.262708) (xy 353.252434 -285.306285) (xy 353.268018 -285.352966) (xy 353.275913 -285.401543)
			(xy 353.276408 -285.42615) (xy 353.60535 -285.42615) (xy 353.60931 -285.377096) (xy 353.621087 -285.329312)
			(xy 353.640378 -285.284036) (xy 353.666681 -285.24244) (xy 353.699316 -285.205603) (xy 353.737437 -285.174478)
			(xy 353.780058 -285.149871) (xy 353.826074 -285.132419) (xy 353.874293 -285.122575) (xy 353.923468 -285.120594)
			(xy 353.972323 -285.126526) (xy 354.019594 -285.140218) (xy 354.064056 -285.161316) (xy 354.104559 -285.189272)
			(xy 354.140052 -285.223364) (xy 354.169617 -285.262708) (xy 354.192488 -285.306285) (xy 354.208072 -285.352966)
			(xy 354.215967 -285.401543) (xy 354.216462 -285.42615) (xy 354.545404 -285.42615) (xy 354.549364 -285.377096)
			(xy 354.561141 -285.329312) (xy 354.580432 -285.284036) (xy 354.606735 -285.24244) (xy 354.63937 -285.205603)
			(xy 354.677491 -285.174478) (xy 354.720112 -285.149871) (xy 354.766128 -285.132419) (xy 354.814347 -285.122575)
			(xy 354.863522 -285.120594) (xy 354.912377 -285.126526) (xy 354.959648 -285.140218) (xy 355.00411 -285.161316)
			(xy 355.044613 -285.189272) (xy 355.080106 -285.223364) (xy 355.109671 -285.262708) (xy 355.132542 -285.306285)
			(xy 355.148126 -285.352966) (xy 355.156021 -285.401543) (xy 355.156516 -285.42615) (xy 355.485204 -285.42615)
			(xy 355.489164 -285.377096) (xy 355.500941 -285.329312) (xy 355.520232 -285.284036) (xy 355.546535 -285.24244)
			(xy 355.57917 -285.205603) (xy 355.617291 -285.174478) (xy 355.659912 -285.149871) (xy 355.705928 -285.132419)
			(xy 355.754147 -285.122575) (xy 355.803322 -285.120594) (xy 355.852177 -285.126526) (xy 355.899448 -285.140218)
			(xy 355.94391 -285.161316) (xy 355.984413 -285.189272) (xy 356.019906 -285.223364) (xy 356.049471 -285.262708)
			(xy 356.072342 -285.306285) (xy 356.087926 -285.352966) (xy 356.095821 -285.401543) (xy 356.096315 -285.4261)
			(xy 356.425064 -285.4261) (xy 356.429238 -285.375732) (xy 356.441644 -285.326738) (xy 356.461944 -285.280454)
			(xy 356.489585 -285.238142) (xy 356.523813 -285.200956) (xy 356.563694 -285.16991) (xy 356.608141 -285.145852)
			(xy 356.655942 -285.129437) (xy 356.705792 -285.121113) (xy 356.731062 -285.120588) (xy 357.671116 -285.120588)
			(xy 357.696396 -285.121011) (xy 357.746265 -285.129335) (xy 357.794084 -285.145754) (xy 357.838549 -285.169819)
			(xy 357.878446 -285.200875) (xy 357.912688 -285.238073) (xy 357.940341 -285.2804) (xy 357.960649 -285.326701)
			(xy 357.97306 -285.375713) (xy 357.977236 -285.4261) (xy 357.977232 -285.42615) (xy 358.305366 -285.42615)
			(xy 358.309326 -285.377096) (xy 358.321103 -285.329312) (xy 358.340394 -285.284036) (xy 358.366697 -285.24244)
			(xy 358.399332 -285.205603) (xy 358.437453 -285.174478) (xy 358.480074 -285.149871) (xy 358.52609 -285.132419)
			(xy 358.574309 -285.122575) (xy 358.623484 -285.120594) (xy 358.672339 -285.126526) (xy 358.71961 -285.140218)
			(xy 358.764072 -285.161316) (xy 358.804575 -285.189272) (xy 358.840068 -285.223364) (xy 358.869633 -285.262708)
			(xy 358.892504 -285.306285) (xy 358.908088 -285.352966) (xy 358.915983 -285.401543) (xy 358.916478 -285.42615)
			(xy 361.118924 -285.42615) (xy 361.122884 -285.377096) (xy 361.134661 -285.329312) (xy 361.153952 -285.284036)
			(xy 361.180255 -285.24244) (xy 361.21289 -285.205603) (xy 361.251011 -285.174478) (xy 361.293632 -285.149871)
			(xy 361.339648 -285.132419) (xy 361.387867 -285.122575) (xy 361.437042 -285.120594) (xy 361.485897 -285.126526)
			(xy 361.533168 -285.140218) (xy 361.57763 -285.161316) (xy 361.618133 -285.189272) (xy 361.653626 -285.223364)
			(xy 361.683191 -285.262708) (xy 361.706062 -285.306285) (xy 361.721646 -285.352966) (xy 361.729541 -285.401543)
			(xy 361.730035 -285.4261) (xy 362.058764 -285.4261) (xy 362.062938 -285.37573) (xy 362.075345 -285.326734)
			(xy 362.095647 -285.280448) (xy 362.12329 -285.238135) (xy 362.157521 -285.200949) (xy 362.197405 -285.169904)
			(xy 362.241855 -285.145846) (xy 362.289658 -285.129433) (xy 362.339511 -285.121111) (xy 362.364782 -285.120588)
			(xy 363.304836 -285.120588) (xy 363.330115 -285.121013) (xy 363.379981 -285.12934) (xy 363.427798 -285.14576)
			(xy 363.472259 -285.169826) (xy 363.512154 -285.200882) (xy 363.546393 -285.23808) (xy 363.574044 -285.280406)
			(xy 363.594351 -285.326705) (xy 363.606761 -285.375716) (xy 363.610936 -285.4261) (xy 363.610932 -285.42615)
			(xy 363.939086 -285.42615) (xy 363.943046 -285.377096) (xy 363.954823 -285.329312) (xy 363.974114 -285.284036)
			(xy 364.000417 -285.24244) (xy 364.033052 -285.205603) (xy 364.071173 -285.174478) (xy 364.113794 -285.149871)
			(xy 364.15981 -285.132419) (xy 364.208029 -285.122575) (xy 364.257204 -285.120594) (xy 364.306059 -285.126526)
			(xy 364.35333 -285.140218) (xy 364.397792 -285.161316) (xy 364.438295 -285.189272) (xy 364.473788 -285.223364)
			(xy 364.503353 -285.262708) (xy 364.526224 -285.306285) (xy 364.541808 -285.352966) (xy 364.549703 -285.401543)
			(xy 364.550198 -285.42615) (xy 364.878886 -285.42615) (xy 364.882846 -285.377096) (xy 364.894623 -285.329312)
			(xy 364.913914 -285.284036) (xy 364.940217 -285.24244) (xy 364.972852 -285.205603) (xy 365.010973 -285.174478)
			(xy 365.053594 -285.149871) (xy 365.09961 -285.132419) (xy 365.147829 -285.122575) (xy 365.197004 -285.120594)
			(xy 365.245859 -285.126526) (xy 365.29313 -285.140218) (xy 365.337592 -285.161316) (xy 365.378095 -285.189272)
			(xy 365.413588 -285.223364) (xy 365.443153 -285.262708) (xy 365.466024 -285.306285) (xy 365.481608 -285.352966)
			(xy 365.489503 -285.401543) (xy 365.489998 -285.42615) (xy 365.81894 -285.42615) (xy 365.8229 -285.377096)
			(xy 365.834677 -285.329312) (xy 365.853968 -285.284036) (xy 365.880271 -285.24244) (xy 365.912906 -285.205603)
			(xy 365.951027 -285.174478) (xy 365.993648 -285.149871) (xy 366.039664 -285.132419) (xy 366.087883 -285.122575)
			(xy 366.137058 -285.120594) (xy 366.185913 -285.126526) (xy 366.233184 -285.140218) (xy 366.277646 -285.161316)
			(xy 366.318149 -285.189272) (xy 366.353642 -285.223364) (xy 366.383207 -285.262708) (xy 366.406078 -285.306285)
			(xy 366.421662 -285.352966) (xy 366.429557 -285.401543) (xy 366.430052 -285.42615) (xy 366.758994 -285.42615)
			(xy 366.762954 -285.377096) (xy 366.774731 -285.329312) (xy 366.794022 -285.284036) (xy 366.820325 -285.24244)
			(xy 366.85296 -285.205603) (xy 366.891081 -285.174478) (xy 366.933702 -285.149871) (xy 366.979718 -285.132419)
			(xy 367.027937 -285.122575) (xy 367.077112 -285.120594) (xy 367.125967 -285.126526) (xy 367.173238 -285.140218)
			(xy 367.2177 -285.161316) (xy 367.258203 -285.189272) (xy 367.293696 -285.223364) (xy 367.323261 -285.262708)
			(xy 367.346132 -285.306285) (xy 367.361716 -285.352966) (xy 367.369611 -285.401543) (xy 367.370106 -285.42615)
			(xy 367.699048 -285.42615) (xy 367.703008 -285.377096) (xy 367.714785 -285.329312) (xy 367.734076 -285.284036)
			(xy 367.760379 -285.24244) (xy 367.793014 -285.205603) (xy 367.831135 -285.174478) (xy 367.873756 -285.149871)
			(xy 367.919772 -285.132419) (xy 367.967991 -285.122575) (xy 368.017166 -285.120594) (xy 368.066021 -285.126526)
			(xy 368.113292 -285.140218) (xy 368.157754 -285.161316) (xy 368.198257 -285.189272) (xy 368.23375 -285.223364)
			(xy 368.263315 -285.262708) (xy 368.286186 -285.306285) (xy 368.30177 -285.352966) (xy 368.309665 -285.401543)
			(xy 368.31016 -285.42615) (xy 368.639102 -285.42615) (xy 368.643062 -285.377096) (xy 368.654839 -285.329312)
			(xy 368.67413 -285.284036) (xy 368.700433 -285.24244) (xy 368.733068 -285.205603) (xy 368.771189 -285.174478)
			(xy 368.81381 -285.149871) (xy 368.859826 -285.132419) (xy 368.908045 -285.122575) (xy 368.95722 -285.120594)
			(xy 369.006075 -285.126526) (xy 369.053346 -285.140218) (xy 369.097808 -285.161316) (xy 369.138311 -285.189272)
			(xy 369.173804 -285.223364) (xy 369.203369 -285.262708) (xy 369.22624 -285.306285) (xy 369.241824 -285.352966)
			(xy 369.249719 -285.401543) (xy 369.250214 -285.42615) (xy 369.578902 -285.42615) (xy 369.582862 -285.377096)
			(xy 369.594639 -285.329312) (xy 369.61393 -285.284036) (xy 369.640233 -285.24244) (xy 369.672868 -285.205603)
			(xy 369.710989 -285.174478) (xy 369.75361 -285.149871) (xy 369.799626 -285.132419) (xy 369.847845 -285.122575)
			(xy 369.89702 -285.120594) (xy 369.945875 -285.126526) (xy 369.993146 -285.140218) (xy 370.037608 -285.161316)
			(xy 370.078111 -285.189272) (xy 370.113604 -285.223364) (xy 370.143169 -285.262708) (xy 370.16604 -285.306285)
			(xy 370.181624 -285.352966) (xy 370.189519 -285.401543) (xy 370.190014 -285.42615) (xy 370.518956 -285.42615)
			(xy 370.522916 -285.377096) (xy 370.534693 -285.329312) (xy 370.553984 -285.284036) (xy 370.580287 -285.24244)
			(xy 370.612922 -285.205603) (xy 370.651043 -285.174478) (xy 370.693664 -285.149871) (xy 370.73968 -285.132419)
			(xy 370.787899 -285.122575) (xy 370.837074 -285.120594) (xy 370.885929 -285.126526) (xy 370.9332 -285.140218)
			(xy 370.977662 -285.161316) (xy 371.018165 -285.189272) (xy 371.053658 -285.223364) (xy 371.083223 -285.262708)
			(xy 371.106094 -285.306285) (xy 371.121678 -285.352966) (xy 371.129573 -285.401543) (xy 371.130068 -285.42615)
			(xy 371.45901 -285.42615) (xy 371.46297 -285.377096) (xy 371.474747 -285.329312) (xy 371.494038 -285.284036)
			(xy 371.520341 -285.24244) (xy 371.552976 -285.205603) (xy 371.591097 -285.174478) (xy 371.633718 -285.149871)
			(xy 371.679734 -285.132419) (xy 371.727953 -285.122575) (xy 371.777128 -285.120594) (xy 371.825983 -285.126526)
			(xy 371.873254 -285.140218) (xy 371.917716 -285.161316) (xy 371.958219 -285.189272) (xy 371.993712 -285.223364)
			(xy 372.023277 -285.262708) (xy 372.046148 -285.306285) (xy 372.061732 -285.352966) (xy 372.069627 -285.401543)
			(xy 372.070122 -285.42615) (xy 372.069627 -285.450757) (xy 372.061732 -285.499334) (xy 372.046148 -285.546015)
			(xy 372.023277 -285.589592) (xy 371.993712 -285.628936) (xy 371.958219 -285.663028) (xy 371.917716 -285.690984)
			(xy 371.873254 -285.712082) (xy 371.825983 -285.725774) (xy 371.777128 -285.731706) (xy 371.727953 -285.729725)
			(xy 371.679734 -285.719881) (xy 371.633718 -285.702429) (xy 371.591097 -285.677822) (xy 371.552976 -285.646697)
			(xy 371.520341 -285.60986) (xy 371.494038 -285.568264) (xy 371.474747 -285.522988) (xy 371.46297 -285.475204)
			(xy 371.45901 -285.42615) (xy 371.130068 -285.42615) (xy 371.129573 -285.450757) (xy 371.121678 -285.499334)
			(xy 371.106094 -285.546015) (xy 371.083223 -285.589592) (xy 371.053658 -285.628936) (xy 371.018165 -285.663028)
			(xy 370.977662 -285.690984) (xy 370.9332 -285.712082) (xy 370.885929 -285.725774) (xy 370.837074 -285.731706)
			(xy 370.787899 -285.729725) (xy 370.73968 -285.719881) (xy 370.693664 -285.702429) (xy 370.651043 -285.677822)
			(xy 370.612922 -285.646697) (xy 370.580287 -285.60986) (xy 370.553984 -285.568264) (xy 370.534693 -285.522988)
			(xy 370.522916 -285.475204) (xy 370.518956 -285.42615) (xy 370.190014 -285.42615) (xy 370.189519 -285.450757)
			(xy 370.181624 -285.499334) (xy 370.16604 -285.546015) (xy 370.143169 -285.589592) (xy 370.113604 -285.628936)
			(xy 370.078111 -285.663028) (xy 370.037608 -285.690984) (xy 369.993146 -285.712082) (xy 369.945875 -285.725774)
			(xy 369.89702 -285.731706) (xy 369.847845 -285.729725) (xy 369.799626 -285.719881) (xy 369.75361 -285.702429)
			(xy 369.710989 -285.677822) (xy 369.672868 -285.646697) (xy 369.640233 -285.60986) (xy 369.61393 -285.568264)
			(xy 369.594639 -285.522988) (xy 369.582862 -285.475204) (xy 369.578902 -285.42615) (xy 369.250214 -285.42615)
			(xy 369.249719 -285.450757) (xy 369.241824 -285.499334) (xy 369.22624 -285.546015) (xy 369.203369 -285.589592)
			(xy 369.173804 -285.628936) (xy 369.138311 -285.663028) (xy 369.097808 -285.690984) (xy 369.053346 -285.712082)
			(xy 369.006075 -285.725774) (xy 368.95722 -285.731706) (xy 368.908045 -285.729725) (xy 368.859826 -285.719881)
			(xy 368.81381 -285.702429) (xy 368.771189 -285.677822) (xy 368.733068 -285.646697) (xy 368.700433 -285.60986)
			(xy 368.67413 -285.568264) (xy 368.654839 -285.522988) (xy 368.643062 -285.475204) (xy 368.639102 -285.42615)
			(xy 368.31016 -285.42615) (xy 368.309665 -285.450757) (xy 368.30177 -285.499334) (xy 368.286186 -285.546015)
			(xy 368.263315 -285.589592) (xy 368.23375 -285.628936) (xy 368.198257 -285.663028) (xy 368.157754 -285.690984)
			(xy 368.113292 -285.712082) (xy 368.066021 -285.725774) (xy 368.017166 -285.731706) (xy 367.967991 -285.729725)
			(xy 367.919772 -285.719881) (xy 367.873756 -285.702429) (xy 367.831135 -285.677822) (xy 367.793014 -285.646697)
			(xy 367.760379 -285.60986) (xy 367.734076 -285.568264) (xy 367.714785 -285.522988) (xy 367.703008 -285.475204)
			(xy 367.699048 -285.42615) (xy 367.370106 -285.42615) (xy 367.369611 -285.450757) (xy 367.361716 -285.499334)
			(xy 367.346132 -285.546015) (xy 367.323261 -285.589592) (xy 367.293696 -285.628936) (xy 367.258203 -285.663028)
			(xy 367.2177 -285.690984) (xy 367.173238 -285.712082) (xy 367.125967 -285.725774) (xy 367.077112 -285.731706)
			(xy 367.027937 -285.729725) (xy 366.979718 -285.719881) (xy 366.933702 -285.702429) (xy 366.891081 -285.677822)
			(xy 366.85296 -285.646697) (xy 366.820325 -285.60986) (xy 366.794022 -285.568264) (xy 366.774731 -285.522988)
			(xy 366.762954 -285.475204) (xy 366.758994 -285.42615) (xy 366.430052 -285.42615) (xy 366.429557 -285.450757)
			(xy 366.421662 -285.499334) (xy 366.406078 -285.546015) (xy 366.383207 -285.589592) (xy 366.353642 -285.628936)
			(xy 366.318149 -285.663028) (xy 366.277646 -285.690984) (xy 366.233184 -285.712082) (xy 366.185913 -285.725774)
			(xy 366.137058 -285.731706) (xy 366.087883 -285.729725) (xy 366.039664 -285.719881) (xy 365.993648 -285.702429)
			(xy 365.951027 -285.677822) (xy 365.912906 -285.646697) (xy 365.880271 -285.60986) (xy 365.853968 -285.568264)
			(xy 365.834677 -285.522988) (xy 365.8229 -285.475204) (xy 365.81894 -285.42615) (xy 365.489998 -285.42615)
			(xy 365.489503 -285.450757) (xy 365.481608 -285.499334) (xy 365.466024 -285.546015) (xy 365.443153 -285.589592)
			(xy 365.413588 -285.628936) (xy 365.378095 -285.663028) (xy 365.337592 -285.690984) (xy 365.29313 -285.712082)
			(xy 365.245859 -285.725774) (xy 365.197004 -285.731706) (xy 365.147829 -285.729725) (xy 365.09961 -285.719881)
			(xy 365.053594 -285.702429) (xy 365.010973 -285.677822) (xy 364.972852 -285.646697) (xy 364.940217 -285.60986)
			(xy 364.913914 -285.568264) (xy 364.894623 -285.522988) (xy 364.882846 -285.475204) (xy 364.878886 -285.42615)
			(xy 364.550198 -285.42615) (xy 364.549703 -285.450757) (xy 364.541808 -285.499334) (xy 364.526224 -285.546015)
			(xy 364.503353 -285.589592) (xy 364.473788 -285.628936) (xy 364.438295 -285.663028) (xy 364.397792 -285.690984)
			(xy 364.35333 -285.712082) (xy 364.306059 -285.725774) (xy 364.257204 -285.731706) (xy 364.208029 -285.729725)
			(xy 364.15981 -285.719881) (xy 364.113794 -285.702429) (xy 364.071173 -285.677822) (xy 364.033052 -285.646697)
			(xy 364.000417 -285.60986) (xy 363.974114 -285.568264) (xy 363.954823 -285.522988) (xy 363.943046 -285.475204)
			(xy 363.939086 -285.42615) (xy 363.610932 -285.42615) (xy 363.606761 -285.476485) (xy 363.594351 -285.525495)
			(xy 363.574044 -285.571794) (xy 363.546393 -285.61412) (xy 363.512154 -285.651318) (xy 363.472259 -285.682374)
			(xy 363.427798 -285.70644) (xy 363.379981 -285.72286) (xy 363.330115 -285.731187) (xy 363.304836 -285.731712)
			(xy 362.364782 -285.731712) (xy 362.339511 -285.731089) (xy 362.289658 -285.722767) (xy 362.241855 -285.706354)
			(xy 362.197405 -285.682296) (xy 362.157521 -285.651251) (xy 362.12329 -285.614065) (xy 362.095647 -285.571752)
			(xy 362.075345 -285.525466) (xy 362.062938 -285.47647) (xy 362.058764 -285.4261) (xy 361.730035 -285.4261)
			(xy 361.730036 -285.42615) (xy 361.729541 -285.450757) (xy 361.721646 -285.499334) (xy 361.706062 -285.546015)
			(xy 361.683191 -285.589592) (xy 361.653626 -285.628936) (xy 361.618133 -285.663028) (xy 361.57763 -285.690984)
			(xy 361.533168 -285.712082) (xy 361.485897 -285.725774) (xy 361.437042 -285.731706) (xy 361.387867 -285.729725)
			(xy 361.339648 -285.719881) (xy 361.293632 -285.702429) (xy 361.251011 -285.677822) (xy 361.21289 -285.646697)
			(xy 361.180255 -285.60986) (xy 361.153952 -285.568264) (xy 361.134661 -285.522988) (xy 361.122884 -285.475204)
			(xy 361.118924 -285.42615) (xy 358.916478 -285.42615) (xy 358.915983 -285.450757) (xy 358.908088 -285.499334)
			(xy 358.892504 -285.546015) (xy 358.869633 -285.589592) (xy 358.840068 -285.628936) (xy 358.804575 -285.663028)
			(xy 358.764072 -285.690984) (xy 358.71961 -285.712082) (xy 358.672339 -285.725774) (xy 358.623484 -285.731706)
			(xy 358.574309 -285.729725) (xy 358.52609 -285.719881) (xy 358.480074 -285.702429) (xy 358.437453 -285.677822)
			(xy 358.399332 -285.646697) (xy 358.366697 -285.60986) (xy 358.340394 -285.568264) (xy 358.321103 -285.522988)
			(xy 358.309326 -285.475204) (xy 358.305366 -285.42615) (xy 357.977232 -285.42615) (xy 357.97306 -285.476487)
			(xy 357.960649 -285.525499) (xy 357.940341 -285.5718) (xy 357.912688 -285.614127) (xy 357.878446 -285.651325)
			(xy 357.838549 -285.682381) (xy 357.794084 -285.706446) (xy 357.746265 -285.722865) (xy 357.696396 -285.731189)
			(xy 357.671116 -285.731712) (xy 356.731062 -285.731712) (xy 356.705792 -285.731087) (xy 356.655942 -285.722763)
			(xy 356.608141 -285.706348) (xy 356.563694 -285.68229) (xy 356.523813 -285.651244) (xy 356.489585 -285.614058)
			(xy 356.461944 -285.571746) (xy 356.441644 -285.525462) (xy 356.429238 -285.476468) (xy 356.425064 -285.4261)
			(xy 356.096315 -285.4261) (xy 356.096316 -285.42615) (xy 356.095821 -285.450757) (xy 356.087926 -285.499334)
			(xy 356.072342 -285.546015) (xy 356.049471 -285.589592) (xy 356.019906 -285.628936) (xy 355.984413 -285.663028)
			(xy 355.94391 -285.690984) (xy 355.899448 -285.712082) (xy 355.852177 -285.725774) (xy 355.803322 -285.731706)
			(xy 355.754147 -285.729725) (xy 355.705928 -285.719881) (xy 355.659912 -285.702429) (xy 355.617291 -285.677822)
			(xy 355.57917 -285.646697) (xy 355.546535 -285.60986) (xy 355.520232 -285.568264) (xy 355.500941 -285.522988)
			(xy 355.489164 -285.475204) (xy 355.485204 -285.42615) (xy 355.156516 -285.42615) (xy 355.156021 -285.450757)
			(xy 355.148126 -285.499334) (xy 355.132542 -285.546015) (xy 355.109671 -285.589592) (xy 355.080106 -285.628936)
			(xy 355.044613 -285.663028) (xy 355.00411 -285.690984) (xy 354.959648 -285.712082) (xy 354.912377 -285.725774)
			(xy 354.863522 -285.731706) (xy 354.814347 -285.729725) (xy 354.766128 -285.719881) (xy 354.720112 -285.702429)
			(xy 354.677491 -285.677822) (xy 354.63937 -285.646697) (xy 354.606735 -285.60986) (xy 354.580432 -285.568264)
			(xy 354.561141 -285.522988) (xy 354.549364 -285.475204) (xy 354.545404 -285.42615) (xy 354.216462 -285.42615)
			(xy 354.215967 -285.450757) (xy 354.208072 -285.499334) (xy 354.192488 -285.546015) (xy 354.169617 -285.589592)
			(xy 354.140052 -285.628936) (xy 354.104559 -285.663028) (xy 354.064056 -285.690984) (xy 354.019594 -285.712082)
			(xy 353.972323 -285.725774) (xy 353.923468 -285.731706) (xy 353.874293 -285.729725) (xy 353.826074 -285.719881)
			(xy 353.780058 -285.702429) (xy 353.737437 -285.677822) (xy 353.699316 -285.646697) (xy 353.666681 -285.60986)
			(xy 353.640378 -285.568264) (xy 353.621087 -285.522988) (xy 353.60931 -285.475204) (xy 353.60535 -285.42615)
			(xy 353.276408 -285.42615) (xy 353.275913 -285.450757) (xy 353.268018 -285.499334) (xy 353.252434 -285.546015)
			(xy 353.229563 -285.589592) (xy 353.199998 -285.628936) (xy 353.164505 -285.663028) (xy 353.124002 -285.690984)
			(xy 353.07954 -285.712082) (xy 353.032269 -285.725774) (xy 352.983414 -285.731706) (xy 352.934239 -285.729725)
			(xy 352.88602 -285.719881) (xy 352.840004 -285.702429) (xy 352.797383 -285.677822) (xy 352.759262 -285.646697)
			(xy 352.726627 -285.60986) (xy 352.700324 -285.568264) (xy 352.681033 -285.522988) (xy 352.669256 -285.475204)
			(xy 352.665296 -285.42615) (xy 352.336354 -285.42615) (xy 352.335859 -285.450757) (xy 352.327964 -285.499334)
			(xy 352.31238 -285.546015) (xy 352.289509 -285.589592) (xy 352.259944 -285.628936) (xy 352.224451 -285.663028)
			(xy 352.183948 -285.690984) (xy 352.139486 -285.712082) (xy 352.092215 -285.725774) (xy 352.04336 -285.731706)
			(xy 351.994185 -285.729725) (xy 351.945966 -285.719881) (xy 351.89995 -285.702429) (xy 351.857329 -285.677822)
			(xy 351.819208 -285.646697) (xy 351.786573 -285.60986) (xy 351.76027 -285.568264) (xy 351.740979 -285.522988)
			(xy 351.729202 -285.475204) (xy 351.725242 -285.42615) (xy 351.396554 -285.42615) (xy 351.396059 -285.450757)
			(xy 351.388164 -285.499334) (xy 351.37258 -285.546015) (xy 351.349709 -285.589592) (xy 351.320144 -285.628936)
			(xy 351.284651 -285.663028) (xy 351.244148 -285.690984) (xy 351.199686 -285.712082) (xy 351.152415 -285.725774)
			(xy 351.10356 -285.731706) (xy 351.054385 -285.729725) (xy 351.006166 -285.719881) (xy 350.96015 -285.702429)
			(xy 350.917529 -285.677822) (xy 350.879408 -285.646697) (xy 350.846773 -285.60986) (xy 350.82047 -285.568264)
			(xy 350.801179 -285.522988) (xy 350.789402 -285.475204) (xy 350.785442 -285.42615) (xy 350.4565 -285.42615)
			(xy 350.456005 -285.450757) (xy 350.44811 -285.499334) (xy 350.432526 -285.546015) (xy 350.409655 -285.589592)
			(xy 350.38009 -285.628936) (xy 350.344597 -285.663028) (xy 350.304094 -285.690984) (xy 350.259632 -285.712082)
			(xy 350.212361 -285.725774) (xy 350.163506 -285.731706) (xy 350.114331 -285.729725) (xy 350.066112 -285.719881)
			(xy 350.020096 -285.702429) (xy 349.977475 -285.677822) (xy 349.939354 -285.646697) (xy 349.906719 -285.60986)
			(xy 349.880416 -285.568264) (xy 349.861125 -285.522988) (xy 349.849348 -285.475204) (xy 349.845388 -285.42615)
			(xy 349.516446 -285.42615) (xy 349.515951 -285.450757) (xy 349.508056 -285.499334) (xy 349.492472 -285.546015)
			(xy 349.469601 -285.589592) (xy 349.440036 -285.628936) (xy 349.404543 -285.663028) (xy 349.36404 -285.690984)
			(xy 349.319578 -285.712082) (xy 349.272307 -285.725774) (xy 349.223452 -285.731706) (xy 349.174277 -285.729725)
			(xy 349.126058 -285.719881) (xy 349.080042 -285.702429) (xy 349.037421 -285.677822) (xy 348.9993 -285.646697)
			(xy 348.966665 -285.60986) (xy 348.940362 -285.568264) (xy 348.921071 -285.522988) (xy 348.909294 -285.475204)
			(xy 348.905334 -285.42615) (xy 348.576392 -285.42615) (xy 348.575897 -285.450757) (xy 348.568002 -285.499334)
			(xy 348.552418 -285.546015) (xy 348.529547 -285.589592) (xy 348.499982 -285.628936) (xy 348.464489 -285.663028)
			(xy 348.423986 -285.690984) (xy 348.379524 -285.712082) (xy 348.332253 -285.725774) (xy 348.283398 -285.731706)
			(xy 348.234223 -285.729725) (xy 348.186004 -285.719881) (xy 348.139988 -285.702429) (xy 348.097367 -285.677822)
			(xy 348.059246 -285.646697) (xy 348.026611 -285.60986) (xy 348.000308 -285.568264) (xy 347.981017 -285.522988)
			(xy 347.96924 -285.475204) (xy 347.96528 -285.42615) (xy 347.636338 -285.42615) (xy 347.635879 -285.450362)
			(xy 347.628244 -285.498179) (xy 347.613157 -285.544192) (xy 347.590997 -285.587247) (xy 347.56232 -285.626265)
			(xy 347.527843 -285.660267) (xy 347.488432 -285.688402) (xy 347.445074 -285.709964) (xy 347.398857 -285.724412)
			(xy 347.374972 -285.72841) (xy 347.361256 -285.730442) (xy 347.340174 -285.746952) (xy 347.302074 -285.840932)
			(xy 347.299104 -285.849263) (xy 347.298434 -285.866923) (xy 347.303817 -285.883756) (xy 347.308932 -285.89097)
			(xy 347.332037 -285.92196) (xy 347.37053 -285.988994) (xy 347.38564 -286.024574) (xy 347.39072 -286.03702)
			(xy 347.412056 -286.054038) (xy 347.526864 -286.07004) (xy 347.551756 -286.05988) (xy 347.560138 -286.048958)
			(xy 347.57468 -286.03091) (xy 347.608296 -285.999003) (xy 347.646351 -285.972548) (xy 347.687971 -285.952154)
			(xy 347.732197 -285.938291) (xy 347.77801 -285.931278) (xy 347.801184 -285.930848) (xy 347.826446 -285.93134)
			(xy 347.876282 -285.939653) (xy 347.924069 -285.956057) (xy 347.968505 -285.980102) (xy 348.008377 -286.011133)
			(xy 348.042597 -286.048305) (xy 348.070232 -286.090601) (xy 348.090528 -286.13687) (xy 348.102932 -286.185848)
			(xy 348.107104 -286.2362) (xy 348.435296 -286.2362) (xy 348.439469 -286.185846) (xy 348.451873 -286.136866)
			(xy 348.472171 -286.090595) (xy 348.499809 -286.048297) (xy 348.534032 -286.011126) (xy 348.573906 -285.980094)
			(xy 348.618345 -285.95605) (xy 348.666136 -285.939649) (xy 348.715975 -285.931338) (xy 348.741238 -285.930848)
			(xy 349.681292 -285.930848) (xy 349.706547 -285.931428) (xy 349.756367 -285.93974) (xy 349.804139 -285.956139)
			(xy 349.848561 -285.980178) (xy 349.88842 -286.011201) (xy 349.92263 -286.048361) (xy 349.950256 -286.090645)
			(xy 349.970545 -286.1369) (xy 349.982945 -286.185864) (xy 349.987112 -286.236156) (xy 350.315288 -286.236156)
			(xy 350.319248 -286.187102) (xy 350.331025 -286.139318) (xy 350.350316 -286.094042) (xy 350.376619 -286.052446)
			(xy 350.409254 -286.015609) (xy 350.447375 -285.984484) (xy 350.489996 -285.959877) (xy 350.536012 -285.942425)
			(xy 350.584231 -285.932581) (xy 350.633406 -285.9306) (xy 350.682261 -285.936532) (xy 350.729532 -285.950224)
			(xy 350.773994 -285.971322) (xy 350.814497 -285.999278) (xy 350.84999 -286.03337) (xy 350.879555 -286.072714)
			(xy 350.902426 -286.116291) (xy 350.91801 -286.162972) (xy 350.925905 -286.211549) (xy 350.9264 -286.236156)
			(xy 350.926399 -286.2362) (xy 351.255196 -286.2362) (xy 351.259369 -286.185845) (xy 351.271774 -286.136864)
			(xy 351.292072 -286.090593) (xy 351.319711 -286.048295) (xy 351.353935 -286.011123) (xy 351.393811 -285.980092)
			(xy 351.438251 -285.956048) (xy 351.486043 -285.939647) (xy 351.535882 -285.931337) (xy 351.561146 -285.930848)
			(xy 352.5012 -285.930848) (xy 352.526452 -285.931457) (xy 352.576266 -285.93977) (xy 352.624033 -285.956168)
			(xy 352.66845 -285.980205) (xy 352.708304 -286.011225) (xy 352.742509 -286.048382) (xy 352.770132 -286.090661)
			(xy 352.790419 -286.136911) (xy 352.802816 -286.185869) (xy 352.806983 -286.236156) (xy 353.135196 -286.236156)
			(xy 353.139156 -286.187102) (xy 353.150933 -286.139318) (xy 353.170224 -286.094042) (xy 353.196527 -286.052446)
			(xy 353.229162 -286.015609) (xy 353.267283 -285.984484) (xy 353.309904 -285.959877) (xy 353.35592 -285.942425)
			(xy 353.404139 -285.932581) (xy 353.453314 -285.9306) (xy 353.502169 -285.936532) (xy 353.54944 -285.950224)
			(xy 353.593902 -285.971322) (xy 353.634405 -285.999278) (xy 353.669898 -286.03337) (xy 353.699463 -286.072714)
			(xy 353.722334 -286.116291) (xy 353.737918 -286.162972) (xy 353.745813 -286.211549) (xy 353.746308 -286.236156)
			(xy 353.746307 -286.2362) (xy 354.075224 -286.2362) (xy 354.079395 -286.185859) (xy 354.091795 -286.136892)
			(xy 354.112084 -286.090632) (xy 354.139709 -286.048343) (xy 354.173918 -286.011177) (xy 354.213778 -285.980147)
			(xy 354.2582 -285.956101) (xy 354.305974 -285.939694) (xy 354.355797 -285.931373) (xy 354.381054 -285.930848)
			(xy 355.321108 -285.930848) (xy 355.346359 -285.931458) (xy 355.396173 -285.939772) (xy 355.443939 -285.956171)
			(xy 355.488354 -285.980208) (xy 355.528207 -286.011228) (xy 355.562411 -286.048384) (xy 355.590033 -286.090664)
			(xy 355.610319 -286.136913) (xy 355.622717 -286.18587) (xy 355.626887 -286.2362) (xy 355.622717 -286.28653)
			(xy 355.610319 -286.335487) (xy 355.590033 -286.381736) (xy 355.562411 -286.424016) (xy 355.528207 -286.461172)
			(xy 355.488354 -286.492192) (xy 355.443939 -286.516229) (xy 355.396173 -286.532628) (xy 355.346359 -286.540942)
			(xy 355.321108 -286.541464) (xy 354.381054 -286.541464) (xy 354.355797 -286.541027) (xy 354.305974 -286.532706)
			(xy 354.2582 -286.516299) (xy 354.213778 -286.492253) (xy 354.173918 -286.461223) (xy 354.139709 -286.424057)
			(xy 354.112084 -286.381768) (xy 354.091795 -286.335508) (xy 354.079395 -286.286541) (xy 354.075224 -286.2362)
			(xy 353.746307 -286.2362) (xy 353.745813 -286.260763) (xy 353.737918 -286.30934) (xy 353.722334 -286.356021)
			(xy 353.699463 -286.399598) (xy 353.669898 -286.438942) (xy 353.634405 -286.473034) (xy 353.593902 -286.50099)
			(xy 353.54944 -286.522088) (xy 353.502169 -286.53578) (xy 353.453314 -286.541712) (xy 353.404139 -286.539731)
			(xy 353.35592 -286.529887) (xy 353.309904 -286.512435) (xy 353.267283 -286.487828) (xy 353.229162 -286.456703)
			(xy 353.196527 -286.419866) (xy 353.170224 -286.37827) (xy 353.150933 -286.332994) (xy 353.139156 -286.28521)
			(xy 353.135196 -286.236156) (xy 352.806983 -286.236156) (xy 352.806987 -286.2362) (xy 352.802816 -286.286531)
			(xy 352.790419 -286.335489) (xy 352.770132 -286.381739) (xy 352.742509 -286.424018) (xy 352.708304 -286.461175)
			(xy 352.66845 -286.492195) (xy 352.624033 -286.516232) (xy 352.576266 -286.53263) (xy 352.526452 -286.540943)
			(xy 352.5012 -286.541464) (xy 351.561146 -286.541464) (xy 351.535882 -286.541063) (xy 351.486043 -286.532753)
			(xy 351.438251 -286.516352) (xy 351.393811 -286.492309) (xy 351.353935 -286.461277) (xy 351.319711 -286.424105)
			(xy 351.292072 -286.381807) (xy 351.271774 -286.335536) (xy 351.259369 -286.286555) (xy 351.255196 -286.2362)
			(xy 350.926399 -286.2362) (xy 350.925905 -286.260763) (xy 350.91801 -286.30934) (xy 350.902426 -286.356021)
			(xy 350.879555 -286.399598) (xy 350.84999 -286.438942) (xy 350.814497 -286.473034) (xy 350.773994 -286.50099)
			(xy 350.729532 -286.522088) (xy 350.682261 -286.53578) (xy 350.633406 -286.541712) (xy 350.584231 -286.539731)
			(xy 350.536012 -286.529887) (xy 350.489996 -286.512435) (xy 350.447375 -286.487828) (xy 350.409254 -286.456703)
			(xy 350.376619 -286.419866) (xy 350.350316 -286.37827) (xy 350.331025 -286.332994) (xy 350.319248 -286.28521)
			(xy 350.315288 -286.236156) (xy 349.987112 -286.236156) (xy 349.987116 -286.2362) (xy 349.982945 -286.286536)
			(xy 349.970545 -286.3355) (xy 349.950256 -286.381755) (xy 349.92263 -286.424039) (xy 349.88842 -286.461199)
			(xy 349.848561 -286.492222) (xy 349.804139 -286.516261) (xy 349.756367 -286.53266) (xy 349.706547 -286.540972)
			(xy 349.681292 -286.541464) (xy 348.741238 -286.541464) (xy 348.715975 -286.541062) (xy 348.666136 -286.532751)
			(xy 348.618345 -286.51635) (xy 348.573907 -286.492306) (xy 348.534032 -286.461274) (xy 348.499809 -286.424103)
			(xy 348.472171 -286.381805) (xy 348.451873 -286.335534) (xy 348.439469 -286.286554) (xy 348.435296 -286.2362)
			(xy 348.107104 -286.2362) (xy 348.102932 -286.286552) (xy 348.090528 -286.33553) (xy 348.070232 -286.381799)
			(xy 348.042597 -286.424095) (xy 348.008377 -286.461267) (xy 347.968505 -286.492298) (xy 347.924069 -286.516343)
			(xy 347.876282 -286.532747) (xy 347.826446 -286.54106) (xy 347.801184 -286.541464) (xy 347.778011 -286.541031)
			(xy 347.7322 -286.534016) (xy 347.687978 -286.52015) (xy 347.646363 -286.499753) (xy 347.608313 -286.473294)
			(xy 347.574705 -286.441382) (xy 347.560138 -286.423354) (xy 347.551756 -286.412432) (xy 347.526864 -286.402272)
			(xy 347.412056 -286.418274) (xy 347.39072 -286.435292) (xy 347.38564 -286.447738) (xy 347.381068 -286.458406)
			(xy 347.381068 -286.458914) (xy 347.377552 -286.468339) (xy 347.377428 -286.48844) (xy 347.385009 -286.507057)
			(xy 347.391736 -286.51454) (xy 347.800168 -286.922972) (xy 347.807007 -286.930373) (xy 347.81472 -286.948971)
			(xy 347.815154 -286.95904) (xy 347.815154 -287.27781) (xy 347.81558 -287.287878) (xy 347.823303 -287.306475)
			(xy 347.83014 -287.313878) (xy 347.99524 -287.478978) (xy 348.00264 -287.485821) (xy 348.021238 -287.493544)
			(xy 348.031308 -287.493964) (xy 348.283784 -287.493964) (xy 348.294444 -287.493507) (xy 348.313912 -287.484824)
			(xy 348.321376 -287.4772) (xy 348.344384 -287.452455) (xy 348.395322 -287.408059) (xy 348.451188 -287.370052)
			(xy 348.511187 -287.338974) (xy 348.574462 -287.315268) (xy 348.640111 -287.299274) (xy 348.707199 -287.291218)
			(xy 348.740984 -287.290764) (xy 349.03918 -287.290764) (xy 349.079222 -287.291426) (xy 349.158514 -287.302646)
			(xy 349.197168 -287.313116) (xy 349.204171 -287.314896) (xy 349.218613 -287.314896) (xy 349.225616 -287.313116)
			(xy 349.264018 -287.302681) (xy 349.3428 -287.291459) (xy 349.382588 -287.290764) (xy 349.681546 -287.290764)
			(xy 349.700849 -287.290944) (xy 349.739364 -287.293617) (xy 349.758508 -287.296098) (xy 349.759016 -287.296098)
			(xy 349.767778 -287.296889) (xy 349.784954 -287.293144) (xy 349.799827 -287.283773) (xy 349.805498 -287.277048)
			(xy 349.868236 -287.197292) (xy 349.8723 -287.170622) (xy 349.86722 -287.158176) (xy 349.8573 -287.13124)
			(xy 349.846558 -287.074859) (xy 349.845884 -287.046162) (xy 349.845884 -287.045908) (xy 349.846369 -287.021086)
			(xy 349.8544 -286.972096) (xy 349.87025 -286.925051) (xy 349.893502 -286.88119) (xy 349.923545 -286.841669)
			(xy 349.959585 -286.807528) (xy 350.000674 -286.779668) (xy 350.045729 -286.758823) (xy 350.093563 -286.745541)
			(xy 350.142915 -286.740173) (xy 350.192486 -286.74286) (xy 350.240969 -286.753532) (xy 350.287087 -286.771907)
			(xy 350.329624 -286.797501) (xy 350.367461 -286.829639) (xy 350.399599 -286.867476) (xy 350.425193 -286.910013)
			(xy 350.443568 -286.956131) (xy 350.45424 -287.004614) (xy 350.456927 -287.054185) (xy 350.451559 -287.103537)
			(xy 350.438277 -287.151371) (xy 350.417432 -287.196426) (xy 350.389572 -287.237515) (xy 350.355431 -287.273555)
			(xy 350.31591 -287.303598) (xy 350.272049 -287.32685) (xy 350.225004 -287.3427) (xy 350.176014 -287.350731)
			(xy 350.151192 -287.351216) (xy 350.138493 -287.351069) (xy 350.113186 -287.348906) (xy 350.100646 -287.346898)
			(xy 350.096582 -287.34639) (xy 350.085956 -287.346055) (xy 350.06589 -287.353005) (xy 350.05034 -287.367467)
			(xy 350.041955 -287.386977) (xy 350.042163 -287.408211) (xy 350.05093 -287.427553) (xy 350.058482 -287.435036)
			(xy 350.06957 -287.44508) (xy 350.09079 -287.466173) (xy 350.1009 -287.4772) (xy 350.108447 -287.484704)
			(xy 350.127866 -287.493357) (xy 350.138492 -287.493964) (xy 351.103692 -287.493964) (xy 351.114351 -287.493505)
			(xy 351.133817 -287.48482) (xy 351.141284 -287.4772) (xy 351.164292 -287.452455) (xy 351.21523 -287.408061)
			(xy 351.271097 -287.370054) (xy 351.331095 -287.338976) (xy 351.39437 -287.315272) (xy 351.46002 -287.299278)
			(xy 351.527107 -287.291224) (xy 351.560892 -287.290764) (xy 351.859088 -287.290764) (xy 351.899129 -287.291427)
			(xy 351.978421 -287.302648) (xy 352.017076 -287.313116) (xy 352.024079 -287.314896) (xy 352.038521 -287.314896)
			(xy 352.045524 -287.313116) (xy 352.083926 -287.302682) (xy 352.162708 -287.291461) (xy 352.202496 -287.290764)
			(xy 352.5012 -287.290764) (xy 352.520567 -287.290938) (xy 352.559209 -287.29361) (xy 352.578416 -287.296098)
			(xy 352.578924 -287.296098) (xy 352.587686 -287.296888) (xy 352.60486 -287.293141) (xy 352.61973 -287.283768)
			(xy 352.625406 -287.277048) (xy 352.679762 -287.20796) (xy 352.684948 -287.200782) (xy 352.690514 -287.183987)
			(xy 352.69 -287.1663) (xy 352.687128 -287.157922) (xy 352.677213 -287.130985) (xy 352.66648 -287.074604)
			(xy 352.665792 -287.045908) (xy 352.666277 -287.021087) (xy 352.674307 -286.972099) (xy 352.690157 -286.925055)
			(xy 352.713408 -286.881195) (xy 352.74345 -286.841675) (xy 352.779489 -286.807535) (xy 352.820576 -286.779676)
			(xy 352.86563 -286.758831) (xy 352.913462 -286.745549) (xy 352.962813 -286.740181) (xy 353.012382 -286.742868)
			(xy 353.060864 -286.753539) (xy 353.10698 -286.771912) (xy 353.149517 -286.797505) (xy 353.187352 -286.829642)
			(xy 353.21949 -286.867477) (xy 353.245084 -286.910013) (xy 353.263459 -286.956129) (xy 353.274131 -287.00461)
			(xy 353.276819 -287.054179) (xy 353.271452 -287.10353) (xy 353.258172 -287.151363) (xy 353.237328 -287.196417)
			(xy 353.20947 -287.237505) (xy 353.175331 -287.273545) (xy 353.135812 -287.303587) (xy 353.091952 -287.32684)
			(xy 353.044909 -287.342691) (xy 352.995921 -287.350722) (xy 352.9711 -287.351216) (xy 352.95847 -287.351106)
			(xy 352.933292 -287.349073) (xy 352.920808 -287.347152) (xy 352.912426 -287.34639) (xy 352.902454 -287.346925)
			(xy 352.884054 -287.354633) (xy 352.869985 -287.368776) (xy 352.862373 -287.387216) (xy 352.86188 -287.39719)
			(xy 352.874326 -287.425384) (xy 352.87654 -287.430019) (xy 352.88255 -287.438346) (xy 352.886264 -287.441894)
			(xy 352.895298 -287.450384) (xy 352.912704 -287.468043) (xy 352.921062 -287.4772) (xy 352.928607 -287.48471)
			(xy 352.948025 -287.493377) (xy 352.958654 -287.493964) (xy 353.9236 -287.493964) (xy 353.934258 -287.493504)
			(xy 353.953722 -287.484817) (xy 353.961192 -287.4772) (xy 353.9842 -287.452456) (xy 354.035138 -287.408062)
			(xy 354.091005 -287.370055) (xy 354.151004 -287.338979) (xy 354.214279 -287.315276) (xy 354.279928 -287.299283)
			(xy 354.347015 -287.291229) (xy 354.3808 -287.290764) (xy 354.678996 -287.290764) (xy 354.719037 -287.291427)
			(xy 354.798329 -287.30265) (xy 354.836984 -287.313116) (xy 354.843987 -287.314896) (xy 354.858429 -287.314896)
			(xy 354.865432 -287.313116) (xy 354.903834 -287.302683) (xy 354.982616 -287.291462) (xy 355.022404 -287.290764)
			(xy 355.321108 -287.290764) (xy 355.340535 -287.29087) (xy 355.379304 -287.293415) (xy 355.398578 -287.295844)
			(xy 355.41204 -287.297622) (xy 355.436932 -287.287716) (xy 355.508052 -287.197292) (xy 355.512116 -287.170622)
			(xy 355.507036 -287.158176) (xy 355.497116 -287.13124) (xy 355.486373 -287.074859) (xy 355.4857 -287.046162)
			(xy 355.486173 -287.022173) (xy 355.493684 -286.974786) (xy 355.508515 -286.929158) (xy 355.530301 -286.886411)
			(xy 355.558505 -286.847598) (xy 355.592433 -286.813675) (xy 355.63125 -286.785477) (xy 355.674 -286.763698)
			(xy 355.719631 -286.748874) (xy 355.767019 -286.74137) (xy 355.791008 -286.740854) (xy 355.81417 -286.741283)
			(xy 355.859963 -286.748277) (xy 355.904176 -286.762104) (xy 355.945795 -286.782446) (xy 355.983866 -286.808837)
			(xy 356.017517 -286.840674) (xy 356.032054 -286.85871) (xy 356.037834 -286.865527) (xy 356.052944 -286.875044)
			(xy 356.070397 -286.878825) (xy 356.079298 -286.878014) (xy 356.180136 -286.864044) (xy 356.201472 -286.847026)
			(xy 356.206552 -286.83458) (xy 356.221553 -286.798926) (xy 356.259916 -286.731756) (xy 356.283006 -286.700722)
			(xy 356.288113 -286.693499) (xy 356.293517 -286.676669) (xy 356.292863 -286.659005) (xy 356.289864 -286.650684)
			(xy 356.256844 -286.569404) (xy 356.253176 -286.561375) (xy 356.241399 -286.548244) (xy 356.225883 -286.539855)
			(xy 356.21722 -286.538162) (xy 356.193327 -286.534243) (xy 356.147102 -286.519841) (xy 356.103734 -286.498317)
			(xy 356.06431 -286.470211) (xy 356.029823 -286.43623) (xy 356.001137 -286.397227) (xy 355.978973 -286.354182)
			(xy 355.963888 -286.308176) (xy 355.956262 -286.260364) (xy 355.955854 -286.236156) (xy 355.956376 -286.210901)
			(xy 355.964689 -286.161079) (xy 355.98109 -286.113305) (xy 356.005131 -286.068882) (xy 356.036155 -286.029022)
			(xy 356.073317 -285.994812) (xy 356.115603 -285.967186) (xy 356.161859 -285.946896) (xy 356.210824 -285.934496)
			(xy 356.261162 -285.930325) (xy 356.3115 -285.934496) (xy 356.360465 -285.946896) (xy 356.406721 -285.967186)
			(xy 356.449007 -285.994812) (xy 356.486169 -286.029022) (xy 356.517193 -286.068882) (xy 356.541234 -286.113305)
			(xy 356.557635 -286.161079) (xy 356.565948 -286.210901) (xy 356.56647 -286.236156) (xy 356.56647 -286.236664)
			(xy 356.565812 -286.26516) (xy 356.555204 -286.321156) (xy 356.545388 -286.347916) (xy 356.542513 -286.356289)
			(xy 356.542035 -286.373973) (xy 356.547579 -286.390772) (xy 356.552754 -286.397954) (xy 356.606856 -286.466788)
			(xy 356.612637 -286.473509) (xy 356.627691 -286.482847) (xy 356.645028 -286.486486) (xy 356.653846 -286.485584)
			(xy 356.673056 -286.483153) (xy 356.711699 -286.480609) (xy 356.731062 -286.480504) (xy 357.029004 -286.480504)
			(xy 357.069045 -286.481168) (xy 357.148336 -286.492392) (xy 357.186992 -286.502856) (xy 357.193995 -286.504636)
			(xy 357.208437 -286.504636) (xy 357.21544 -286.502856) (xy 357.253842 -286.492424) (xy 357.332624 -286.481206)
			(xy 357.372412 -286.480504) (xy 357.671624 -286.480504) (xy 357.706561 -286.481021) (xy 357.775904 -286.489625)
			(xy 357.843658 -286.506711) (xy 357.908788 -286.53202) (xy 357.970302 -286.565164) (xy 358.02726 -286.605638)
			(xy 358.053386 -286.62884) (xy 358.06059 -286.634994) (xy 358.07821 -286.64192) (xy 358.087676 -286.642302)
			(xy 358.878886 -286.642302) (xy 358.888949 -286.642741) (xy 358.907531 -286.650478) (xy 358.914954 -286.657288)
			(xy 359.274618 -287.016952) (xy 359.282015 -287.023801) (xy 359.300614 -287.031536) (xy 359.310686 -287.031938)
			(xy 361.093258 -287.031938) (xy 361.121198 -287.008824) (xy 361.123738 -286.995616) (xy 361.123738 -286.9946)
			(xy 361.128185 -286.971221) (xy 361.143362 -286.92612) (xy 361.165354 -286.88392) (xy 361.193626 -286.845642)
			(xy 361.227495 -286.812215) (xy 361.266141 -286.784448) (xy 361.308627 -286.763013) (xy 361.353923 -286.748429)
			(xy 361.400935 -286.74105) (xy 361.424728 -286.7406) (xy 361.447871 -286.741031) (xy 361.493625 -286.748029)
			(xy 361.537796 -286.76186) (xy 361.57937 -286.782206) (xy 361.617393 -286.808601) (xy 361.650991 -286.840437)
			(xy 361.66552 -286.858456) (xy 361.666028 -286.858964) (xy 361.666282 -286.859218) (xy 361.670426 -286.864187)
			(xy 361.680715 -286.872026) (xy 361.686602 -286.874712) (xy 361.692698 -286.877252) (xy 361.705906 -286.878776)
			(xy 361.744768 -286.873442) (xy 361.80014 -286.865822) (xy 361.806848 -286.864655) (xy 361.819336 -286.859245)
			(xy 361.824778 -286.855154) (xy 361.830112 -286.850836) (xy 361.837732 -286.840676) (xy 361.840272 -286.834072)
			(xy 361.852963 -286.803901) (xy 361.88432 -286.746444) (xy 361.9221 -286.692992) (xy 361.965799 -286.644258)
			(xy 362.014831 -286.600894) (xy 362.068541 -286.563481) (xy 362.12621 -286.532518) (xy 362.187069 -286.508419)
			(xy 362.250303 -286.491507) (xy 362.315066 -286.482007) (xy 362.347764 -286.480504) (xy 362.662724 -286.480504)
			(xy 362.702766 -286.481162) (xy 362.78206 -286.492376) (xy 362.820712 -286.502856) (xy 362.827517 -286.504604)
			(xy 362.841561 -286.504731) (xy 362.848398 -286.50311) (xy 362.88698 -286.492581) (xy 362.966145 -286.48123)
			(xy 363.006132 -286.480504) (xy 363.304836 -286.480504) (xy 363.323365 -286.48059) (xy 363.360352 -286.482876)
			(xy 363.37875 -286.485076) (xy 363.382306 -286.485584) (xy 363.383068 -286.485838) (xy 363.393591 -286.486573)
			(xy 363.413781 -286.480532) (xy 363.422184 -286.474154) (xy 363.429296 -286.466534) (xy 363.445806 -286.445198)
			(xy 363.484668 -286.395668) (xy 363.488906 -286.389253) (xy 363.493679 -286.374645) (xy 363.494066 -286.366966)
			(xy 363.491272 -286.352488) (xy 363.488986 -286.343852) (xy 363.479953 -286.318107) (xy 363.47012 -286.264447)
			(xy 363.469428 -286.237172) (xy 363.469428 -286.231584) (xy 363.470233 -286.207826) (xy 363.478294 -286.16098)
			(xy 363.493518 -286.115949) (xy 363.515537 -286.073822) (xy 363.543819 -286.035616) (xy 363.577681 -286.002256)
			(xy 363.616304 -285.974546) (xy 363.658755 -285.953157) (xy 363.704007 -285.938607) (xy 363.750969 -285.931245)
			(xy 363.774736 -285.930848) (xy 363.798727 -285.931321) (xy 363.846117 -285.938832) (xy 363.891749 -285.953662)
			(xy 363.934499 -285.975446) (xy 363.973317 -286.00365) (xy 364.007245 -286.037577) (xy 364.035449 -286.076394)
			(xy 364.057235 -286.119144) (xy 364.072067 -286.164776) (xy 364.079578 -286.212165) (xy 364.080044 -286.236156)
			(xy 364.080043 -286.2362) (xy 364.408924 -286.2362) (xy 364.413096 -286.185856) (xy 364.425497 -286.136884)
			(xy 364.445789 -286.090622) (xy 364.473419 -286.048331) (xy 364.507632 -286.011164) (xy 364.547497 -285.980135)
			(xy 364.591924 -285.95609) (xy 364.639704 -285.939686) (xy 364.689532 -285.93137) (xy 364.71479 -285.930848)
			(xy 365.654844 -285.930848) (xy 365.680093 -285.931461) (xy 365.729902 -285.939779) (xy 365.777663 -285.956181)
			(xy 365.822073 -285.980221) (xy 365.861921 -286.011241) (xy 365.89612 -286.048396) (xy 365.923738 -286.090674)
			(xy 365.944022 -286.13692) (xy 365.956417 -286.185874) (xy 365.960583 -286.236156) (xy 366.289094 -286.236156)
			(xy 366.293054 -286.187102) (xy 366.304831 -286.139318) (xy 366.324122 -286.094042) (xy 366.350425 -286.052446)
			(xy 366.38306 -286.015609) (xy 366.421181 -285.984484) (xy 366.463802 -285.959877) (xy 366.509818 -285.942425)
			(xy 366.558037 -285.932581) (xy 366.607212 -285.9306) (xy 366.656067 -285.936532) (xy 366.703338 -285.950224)
			(xy 366.7478 -285.971322) (xy 366.788303 -285.999278) (xy 366.823796 -286.03337) (xy 366.853361 -286.072714)
			(xy 366.876232 -286.116291) (xy 366.891816 -286.162972) (xy 366.899711 -286.211549) (xy 366.900206 -286.236156)
			(xy 366.900205 -286.2362) (xy 367.228824 -286.2362) (xy 367.232996 -286.185855) (xy 367.245398 -286.136883)
			(xy 367.26569 -286.09062) (xy 367.293321 -286.048328) (xy 367.327535 -286.011161) (xy 367.367401 -285.980132)
			(xy 367.41183 -285.956088) (xy 367.45961 -285.939685) (xy 367.509439 -285.931369) (xy 367.534698 -285.930848)
			(xy 368.474752 -285.930848) (xy 368.500009 -285.931425) (xy 368.549834 -285.939732) (xy 368.597612 -285.956128)
			(xy 368.64204 -285.980164) (xy 368.681905 -286.011187) (xy 368.716119 -286.048348) (xy 368.74375 -286.090634)
			(xy 368.764043 -286.136892) (xy 368.776444 -286.185859) (xy 368.780612 -286.236156) (xy 369.109002 -286.236156)
			(xy 369.112962 -286.187102) (xy 369.124739 -286.139318) (xy 369.14403 -286.094042) (xy 369.170333 -286.052446)
			(xy 369.202968 -286.015609) (xy 369.241089 -285.984484) (xy 369.28371 -285.959877) (xy 369.329726 -285.942425)
			(xy 369.377945 -285.932581) (xy 369.42712 -285.9306) (xy 369.475975 -285.936532) (xy 369.523246 -285.950224)
			(xy 369.567708 -285.971322) (xy 369.608211 -285.999278) (xy 369.643704 -286.03337) (xy 369.673269 -286.072714)
			(xy 369.69614 -286.116291) (xy 369.711724 -286.162972) (xy 369.719619 -286.211549) (xy 369.720114 -286.236156)
			(xy 369.720113 -286.2362) (xy 370.049024 -286.2362) (xy 370.053196 -286.185859) (xy 370.065595 -286.13689)
			(xy 370.085885 -286.09063) (xy 370.113511 -286.048341) (xy 370.147721 -286.011174) (xy 370.187581 -285.980145)
			(xy 370.232004 -285.956099) (xy 370.279779 -285.939692) (xy 370.329603 -285.931372) (xy 370.35486 -285.930848)
			(xy 371.294914 -285.930848) (xy 371.320165 -285.931459) (xy 371.369978 -285.939773) (xy 371.417743 -285.956173)
			(xy 371.462157 -285.98021) (xy 371.502009 -286.01123) (xy 371.536213 -286.048386) (xy 371.563834 -286.090665)
			(xy 371.58412 -286.136914) (xy 371.596517 -286.185871) (xy 371.600687 -286.2362) (xy 371.596517 -286.286529)
			(xy 371.58412 -286.335486) (xy 371.563834 -286.381735) (xy 371.536213 -286.424014) (xy 371.502009 -286.46117)
			(xy 371.462157 -286.49219) (xy 371.417743 -286.516227) (xy 371.369978 -286.532627) (xy 371.320165 -286.540941)
			(xy 371.294914 -286.541464) (xy 370.35486 -286.541464) (xy 370.329603 -286.541028) (xy 370.279779 -286.532708)
			(xy 370.232004 -286.516301) (xy 370.187581 -286.492255) (xy 370.147721 -286.461226) (xy 370.113511 -286.424059)
			(xy 370.085884 -286.38177) (xy 370.065595 -286.33551) (xy 370.053196 -286.286541) (xy 370.049024 -286.2362)
			(xy 369.720113 -286.2362) (xy 369.719619 -286.260763) (xy 369.711724 -286.30934) (xy 369.69614 -286.356021)
			(xy 369.673269 -286.399598) (xy 369.643704 -286.438942) (xy 369.608211 -286.473034) (xy 369.567708 -286.50099)
			(xy 369.523246 -286.522088) (xy 369.475975 -286.53578) (xy 369.42712 -286.541712) (xy 369.377945 -286.539731)
			(xy 369.329726 -286.529887) (xy 369.28371 -286.512435) (xy 369.241089 -286.487828) (xy 369.202968 -286.456703)
			(xy 369.170333 -286.419866) (xy 369.14403 -286.37827) (xy 369.124739 -286.332994) (xy 369.112962 -286.28521)
			(xy 369.109002 -286.236156) (xy 368.780612 -286.236156) (xy 368.780616 -286.2362) (xy 368.776444 -286.286541)
			(xy 368.764043 -286.335508) (xy 368.74375 -286.381766) (xy 368.716119 -286.424052) (xy 368.681905 -286.461213)
			(xy 368.64204 -286.492236) (xy 368.597612 -286.516272) (xy 368.549834 -286.532668) (xy 368.500009 -286.540975)
			(xy 368.474752 -286.541464) (xy 367.534698 -286.541464) (xy 367.509439 -286.541031) (xy 367.45961 -286.532715)
			(xy 367.41183 -286.516312) (xy 367.367401 -286.492268) (xy 367.327535 -286.461239) (xy 367.293321 -286.424072)
			(xy 367.26569 -286.38178) (xy 367.245398 -286.335517) (xy 367.232996 -286.286545) (xy 367.228824 -286.2362)
			(xy 366.900205 -286.2362) (xy 366.899711 -286.260763) (xy 366.891816 -286.30934) (xy 366.876232 -286.356021)
			(xy 366.853361 -286.399598) (xy 366.823796 -286.438942) (xy 366.788303 -286.473034) (xy 366.7478 -286.50099)
			(xy 366.703338 -286.522088) (xy 366.656067 -286.53578) (xy 366.607212 -286.541712) (xy 366.558037 -286.539731)
			(xy 366.509818 -286.529887) (xy 366.463802 -286.512435) (xy 366.421181 -286.487828) (xy 366.38306 -286.456703)
			(xy 366.350425 -286.419866) (xy 366.324122 -286.37827) (xy 366.304831 -286.332994) (xy 366.293054 -286.28521)
			(xy 366.289094 -286.236156) (xy 365.960583 -286.236156) (xy 365.960587 -286.2362) (xy 365.956417 -286.286526)
			(xy 365.944022 -286.33548) (xy 365.923738 -286.381726) (xy 365.89612 -286.424004) (xy 365.861921 -286.461159)
			(xy 365.822073 -286.492179) (xy 365.777663 -286.516219) (xy 365.729902 -286.532621) (xy 365.680093 -286.540939)
			(xy 365.654844 -286.541464) (xy 364.71479 -286.541464) (xy 364.689532 -286.54103) (xy 364.639704 -286.532714)
			(xy 364.591924 -286.51631) (xy 364.547497 -286.492265) (xy 364.507632 -286.461236) (xy 364.473419 -286.424069)
			(xy 364.445789 -286.381778) (xy 364.425497 -286.335516) (xy 364.413096 -286.286544) (xy 364.408924 -286.2362)
			(xy 364.080043 -286.2362) (xy 364.079577 -286.260358) (xy 364.071929 -286.308155) (xy 364.056833 -286.354145)
			(xy 364.034668 -286.397176) (xy 364.00599 -286.436171) (xy 363.971517 -286.47015) (xy 363.932114 -286.498263)
			(xy 363.888767 -286.519805) (xy 363.842564 -286.534236) (xy 363.818678 -286.538162) (xy 363.818424 -286.538162)
			(xy 363.811862 -286.539316) (xy 363.799627 -286.544583) (xy 363.794294 -286.548576) (xy 363.789214 -286.55264)
			(xy 363.781594 -286.5628) (xy 363.74578 -286.651446) (xy 363.742989 -286.659685) (xy 363.742533 -286.677061)
			(xy 363.747906 -286.693593) (xy 363.752892 -286.700722) (xy 363.756956 -286.705802) (xy 363.757972 -286.707326)
			(xy 363.779363 -286.73695) (xy 363.815162 -286.800651) (xy 363.829346 -286.834326) (xy 363.829346 -286.83458)
			(xy 363.832007 -286.840536) (xy 363.83985 -286.850954) (xy 363.84484 -286.855154) (xy 363.850287 -286.859235)
			(xy 363.862775 -286.864636) (xy 363.869478 -286.865822) (xy 363.957108 -286.87776) (xy 363.963816 -286.878494)
			(xy 363.977201 -286.876817) (xy 363.983524 -286.874458) (xy 363.989112 -286.872172) (xy 363.999272 -286.864552)
			(xy 364.003844 -286.85871) (xy 364.018388 -286.840665) (xy 364.052006 -286.808763) (xy 364.090062 -286.782313)
			(xy 364.131681 -286.761924) (xy 364.175906 -286.748064) (xy 364.221717 -286.741053) (xy 364.24489 -286.7406)
			(xy 364.269124 -286.741072) (xy 364.316982 -286.748741) (xy 364.363028 -286.763874) (xy 364.406106 -286.786089)
			(xy 364.445134 -286.81483) (xy 364.479132 -286.849375) (xy 364.507247 -286.888856) (xy 364.528774 -286.932282)
			(xy 364.543171 -286.978563) (xy 364.54715 -287.002474) (xy 364.54715 -287.002728) (xy 364.548854 -287.011572)
			(xy 364.55759 -287.027307) (xy 364.564168 -287.033462) (xy 364.571026 -287.039558) (xy 364.588044 -287.045908)
			(xy 366.712246 -287.045908) (xy 366.721352 -287.045538) (xy 366.738411 -287.039163) (xy 366.74552 -287.033462)
			(xy 366.752378 -287.02762) (xy 366.761268 -287.011618) (xy 366.762538 -287.002474) (xy 366.766447 -286.978546)
			(xy 366.780839 -286.93225) (xy 366.802365 -286.888809) (xy 366.830485 -286.849316) (xy 366.864492 -286.814761)
			(xy 366.903532 -286.786015) (xy 366.946624 -286.763798) (xy 366.992685 -286.748669) (xy 367.040557 -286.741009)
			(xy 367.089039 -286.741009) (xy 367.136911 -286.748669) (xy 367.182972 -286.763798) (xy 367.226064 -286.786015)
			(xy 367.265104 -286.814761) (xy 367.299111 -286.849316) (xy 367.327231 -286.888809) (xy 367.348757 -286.93225)
			(xy 367.363149 -286.978546) (xy 367.367058 -287.002474) (xy 367.367058 -287.002728) (xy 367.368758 -287.011575)
			(xy 367.377483 -287.027321) (xy 367.384076 -287.033462) (xy 367.390934 -287.039558) (xy 367.407952 -287.045908)
			(xy 368.566954 -287.045908) (xy 368.576098 -287.045531) (xy 368.593221 -287.039114) (xy 368.606993 -287.027084)
			(xy 368.615653 -287.010977) (xy 368.617246 -287.001966) (xy 368.621287 -286.975867) (xy 368.636576 -286.925319)
			(xy 368.659705 -286.877844) (xy 368.690087 -286.834649) (xy 368.726949 -286.796832) (xy 368.769353 -286.765357)
			(xy 368.816222 -286.741021) (xy 368.866363 -286.724446) (xy 368.918501 -286.716051) (xy 368.971311 -286.716051)
			(xy 369.023449 -286.724446) (xy 369.07359 -286.741021) (xy 369.120459 -286.765357) (xy 369.162863 -286.796832)
			(xy 369.199725 -286.834649) (xy 369.230107 -286.877844) (xy 369.253236 -286.925319) (xy 369.268525 -286.975867)
			(xy 369.272566 -287.001966) (xy 369.274179 -287.010969) (xy 369.282848 -287.027059) (xy 369.296612 -287.039083)
			(xy 369.31372 -287.045511) (xy 369.322858 -287.045908) (xy 369.532154 -287.045908) (xy 369.541259 -287.045536)
			(xy 369.558316 -287.03916) (xy 369.565428 -287.033462) (xy 369.572286 -287.02762) (xy 369.581176 -287.011618)
			(xy 369.582446 -287.002474) (xy 369.586355 -286.978546) (xy 369.600747 -286.93225) (xy 369.622273 -286.888809)
			(xy 369.650393 -286.849316) (xy 369.6844 -286.814761) (xy 369.72344 -286.786015) (xy 369.766532 -286.763798)
			(xy 369.812593 -286.748669) (xy 369.860465 -286.741009) (xy 369.908947 -286.741009) (xy 369.956819 -286.748669)
			(xy 370.00288 -286.763798) (xy 370.045972 -286.786015) (xy 370.085012 -286.814761) (xy 370.119019 -286.849316)
			(xy 370.147139 -286.888809) (xy 370.168665 -286.93225) (xy 370.183057 -286.978546) (xy 370.186966 -287.002474)
			(xy 370.186966 -287.002728) (xy 370.188666 -287.011575) (xy 370.197393 -287.02732) (xy 370.203984 -287.033462)
			(xy 370.210842 -287.039558) (xy 370.22786 -287.045908) (xy 372.343934 -287.045908) (xy 372.353586 -287.044892)
			(xy 372.360828 -287.043261) (xy 372.373993 -287.036416) (xy 372.379494 -287.03143) (xy 372.390162 -287.020762)
			(xy 372.395413 -287.015097) (xy 372.402528 -287.001394) (xy 372.404132 -286.993838) (xy 372.408551 -286.970817)
			(xy 372.423513 -286.926394) (xy 372.445091 -286.884781) (xy 372.472777 -286.846955) (xy 372.50592 -286.813807)
			(xy 372.543741 -286.786115) (xy 372.585351 -286.764531) (xy 372.629772 -286.749562) (xy 372.652798 -286.745172)
			(xy 372.660672 -286.743902) (xy 372.667784 -286.740092) (xy 372.671035 -286.738252) (xy 372.677022 -286.733785)
			(xy 372.679722 -286.731202) (xy 372.740428 -286.670496) (xy 372.743222 -286.667448) (xy 372.743222 -286.60217)
			(xy 372.736618 -286.593788) (xy 372.718934 -286.571573) (xy 372.687614 -286.524206) (xy 372.661198 -286.47394)
			(xy 372.650258 -286.447738) (xy 372.650258 -286.447484) (xy 372.647594 -286.441531) (xy 372.639747 -286.431118)
			(xy 372.634764 -286.42691) (xy 372.629316 -286.422831) (xy 372.616828 -286.417433) (xy 372.610126 -286.416242)
			(xy 372.522496 -286.404304) (xy 372.515788 -286.403569) (xy 372.502403 -286.405247) (xy 372.49608 -286.407606)
			(xy 372.490492 -286.409892) (xy 372.480332 -286.417512) (xy 372.47576 -286.423354) (xy 372.461218 -286.441402)
			(xy 372.427601 -286.473307) (xy 372.389545 -286.499761) (xy 372.347926 -286.520153) (xy 372.303701 -286.534015)
			(xy 372.257887 -286.541028) (xy 372.234714 -286.541464) (xy 372.209459 -286.540973) (xy 372.159638 -286.532661)
			(xy 372.111865 -286.516262) (xy 372.067442 -286.492224) (xy 372.027582 -286.461201) (xy 371.993372 -286.424041)
			(xy 371.965745 -286.381756) (xy 371.945455 -286.335501) (xy 371.933055 -286.286537) (xy 371.928884 -286.2362)
			(xy 371.933055 -286.185863) (xy 371.945455 -286.136899) (xy 371.965745 -286.090644) (xy 371.993372 -286.048359)
			(xy 372.027582 -286.011199) (xy 372.067442 -285.980176) (xy 372.111865 -285.956138) (xy 372.159638 -285.939739)
			(xy 372.209459 -285.931427) (xy 372.234714 -285.930848) (xy 372.257858 -285.931278) (xy 372.303614 -285.938273)
			(xy 372.347788 -285.952101) (xy 372.389366 -285.972444) (xy 372.427394 -285.998835) (xy 372.460998 -286.030668)
			(xy 372.475506 -286.048704) (xy 372.476014 -286.049212) (xy 372.476268 -286.049466) (xy 372.480408 -286.05444)
			(xy 372.490694 -286.062289) (xy 372.496588 -286.06496) (xy 372.50243 -286.0675) (xy 372.515638 -286.069024)
			(xy 372.610126 -286.05607) (xy 372.616835 -286.054906) (xy 372.629329 -286.049503) (xy 372.634764 -286.045402)
			(xy 372.639755 -286.041202) (xy 372.647593 -286.030782) (xy 372.650258 -286.024828) (xy 372.650258 -286.024574)
			(xy 372.656851 -286.008568) (xy 372.671719 -285.977304) (xy 372.679976 -285.96209) (xy 372.690521 -285.943482)
			(xy 372.71404 -285.907756) (xy 372.726966 -285.890716) (xy 372.72722 -285.890462) (xy 372.731075 -285.88509)
			(xy 372.736102 -285.872864) (xy 372.737126 -285.866332) (xy 372.738904 -285.853378) (xy 372.717314 -285.800292)
			(xy 372.700804 -285.759398) (xy 372.6981 -285.753361) (xy 372.690137 -285.742804) (xy 372.685056 -285.73857)
			(xy 372.679722 -285.734506) (xy 372.668038 -285.729426) (xy 372.660926 -285.72841) (xy 372.637039 -285.724446)
			(xy 372.590837 -285.709967) (xy 372.547496 -285.688384) (xy 372.508099 -285.660238) (xy 372.473633 -285.626232)
			(xy 372.44496 -285.587218) (xy 372.422796 -285.544171) (xy 372.407697 -285.498167) (xy 372.40004 -285.450359)
			(xy 372.39956 -285.42615) (xy 372.400082 -285.400895) (xy 372.408395 -285.351073) (xy 372.424796 -285.303299)
			(xy 372.448837 -285.258876) (xy 372.479861 -285.219016) (xy 372.517023 -285.184806) (xy 372.559309 -285.15718)
			(xy 372.605565 -285.13689) (xy 372.65453 -285.12449) (xy 372.704868 -285.120319) (xy 372.755206 -285.12449)
			(xy 372.804171 -285.13689) (xy 372.850427 -285.15718) (xy 372.892713 -285.184806) (xy 372.929875 -285.219016)
			(xy 372.960899 -285.258876) (xy 372.98494 -285.303299) (xy 373.001341 -285.351073) (xy 373.009654 -285.400895)
			(xy 373.010176 -285.42615) (xy 373.009527 -285.45485) (xy 372.998793 -285.511237) (xy 372.98884 -285.538164)
			(xy 372.9863 -285.544514) (xy 372.984776 -285.557722) (xy 372.985792 -285.564072) (xy 372.986959 -285.57048)
			(xy 372.992098 -285.582444) (xy 372.995952 -285.587694) (xy 373.05742 -285.665926) (xy 373.058944 -285.667704)
			(xy 373.071644 -285.672784) (xy 373.077743 -285.674969) (xy 373.090601 -285.676512) (xy 373.097044 -285.675832)
			(xy 373.097298 -285.675832) (xy 373.116572 -285.673396) (xy 373.155341 -285.670856) (xy 373.174768 -285.670752)
			(xy 373.264176 -285.670752) (xy 373.267732 -285.670498) (xy 373.27808 -285.669274) (xy 373.29656 -285.65969)
			(xy 373.303546 -285.651956) (xy 373.305832 -285.648908) (xy 373.329708 -285.614364) (xy 373.354092 -285.578804)
			(xy 373.359649 -285.569244) (xy 373.362813 -285.547382) (xy 373.360188 -285.53664) (xy 373.358918 -285.533338)
			(xy 373.349947 -285.507649) (xy 373.34024 -285.454115) (xy 373.339614 -285.426912) (xy 373.339614 -285.42615)
			(xy 373.340136 -285.400895) (xy 373.348449 -285.351073) (xy 373.36485 -285.303299) (xy 373.388891 -285.258876)
			(xy 373.419915 -285.219016) (xy 373.457077 -285.184806) (xy 373.499363 -285.15718) (xy 373.545619 -285.13689)
			(xy 373.594584 -285.12449) (xy 373.644922 -285.120319) (xy 373.69526 -285.12449) (xy 373.744225 -285.13689)
			(xy 373.790481 -285.15718) (xy 373.832767 -285.184806) (xy 373.869929 -285.219016) (xy 373.900953 -285.258876)
			(xy 373.924994 -285.303299) (xy 373.941395 -285.351073) (xy 373.949708 -285.400895) (xy 373.95023 -285.42615)
			(xy 373.95023 -285.426912) (xy 373.949587 -285.454113) (xy 373.939875 -285.507643) (xy 373.930926 -285.533338)
			(xy 373.928848 -285.539263) (xy 373.927311 -285.551722) (xy 373.927878 -285.557976) (xy 373.929402 -285.569406)
			(xy 373.983758 -285.648654) (xy 373.9896 -285.655512) (xy 373.996321 -285.661773) (xy 374.012986 -285.669465)
			(xy 374.022112 -285.670498) (xy 374.025668 -285.670752) (xy 374.114822 -285.670752) (xy 374.134249 -285.670855)
			(xy 374.173018 -285.673395) (xy 374.192292 -285.675832) (xy 374.205754 -285.67761) (xy 374.230646 -285.667704)
			(xy 374.23217 -285.665926) (xy 374.293638 -285.587694) (xy 374.29748 -285.582436) (xy 374.302621 -285.570477)
			(xy 374.303798 -285.564072) (xy 374.304814 -285.557722) (xy 374.30329 -285.544514) (xy 374.30075 -285.538164)
			(xy 374.29083 -285.511228) (xy 374.280089 -285.454847) (xy 374.279414 -285.42615) (xy 374.279936 -285.400895)
			(xy 374.288249 -285.351073) (xy 374.30465 -285.303299) (xy 374.328691 -285.258876) (xy 374.359715 -285.219016)
			(xy 374.396877 -285.184806) (xy 374.439163 -285.15718) (xy 374.485419 -285.13689) (xy 374.534384 -285.12449)
			(xy 374.584722 -285.120319) (xy 374.63506 -285.12449) (xy 374.684025 -285.13689) (xy 374.730281 -285.15718)
			(xy 374.772567 -285.184806) (xy 374.809729 -285.219016) (xy 374.840753 -285.258876) (xy 374.864794 -285.303299)
			(xy 374.881195 -285.351073) (xy 374.889508 -285.400895) (xy 374.89003 -285.42615) (xy 375.218972 -285.42615)
			(xy 375.222932 -285.377096) (xy 375.234709 -285.329312) (xy 375.254 -285.284036) (xy 375.280303 -285.24244)
			(xy 375.312938 -285.205603) (xy 375.351059 -285.174478) (xy 375.39368 -285.149871) (xy 375.439696 -285.132419)
			(xy 375.487915 -285.122575) (xy 375.53709 -285.120594) (xy 375.585945 -285.126526) (xy 375.633216 -285.140218)
			(xy 375.677678 -285.161316) (xy 375.718181 -285.189272) (xy 375.753674 -285.223364) (xy 375.783239 -285.262708)
			(xy 375.80611 -285.306285) (xy 375.821694 -285.352966) (xy 375.829589 -285.401543) (xy 375.830084 -285.42615)
			(xy 376.148595 -285.42615) (xy 376.15269 -285.375422) (xy 376.164869 -285.326008) (xy 376.184817 -285.279188)
			(xy 376.212018 -285.236174) (xy 376.245766 -285.19808) (xy 376.285188 -285.165893) (xy 376.329262 -285.140447)
			(xy 376.376848 -285.1224) (xy 376.426712 -285.11222) (xy 376.477564 -285.110171) (xy 376.528085 -285.116305)
			(xy 376.576969 -285.130465) (xy 376.622948 -285.152282) (xy 376.664832 -285.181192) (xy 376.701536 -285.216447)
			(xy 376.732109 -285.257133) (xy 376.75576 -285.302196) (xy 376.771876 -285.35047) (xy 376.78004 -285.400704)
			(xy 376.780552 -285.42615) (xy 377.088649 -285.42615) (xy 377.092744 -285.375422) (xy 377.104923 -285.326008)
			(xy 377.124871 -285.279188) (xy 377.152072 -285.236174) (xy 377.18582 -285.19808) (xy 377.225242 -285.165893)
			(xy 377.269316 -285.140447) (xy 377.316902 -285.1224) (xy 377.366766 -285.11222) (xy 377.417618 -285.110171)
			(xy 377.468139 -285.116305) (xy 377.517023 -285.130465) (xy 377.563002 -285.152282) (xy 377.604886 -285.181192)
			(xy 377.64159 -285.216447) (xy 377.672163 -285.257133) (xy 377.695814 -285.302196) (xy 377.71193 -285.35047)
			(xy 377.720094 -285.400704) (xy 377.720606 -285.42615) (xy 377.720094 -285.451596) (xy 377.71193 -285.50183)
			(xy 377.695814 -285.550104) (xy 377.672163 -285.595167) (xy 377.64159 -285.635853) (xy 377.604886 -285.671108)
			(xy 377.563002 -285.700018) (xy 377.517023 -285.721835) (xy 377.468139 -285.735995) (xy 377.417618 -285.742129)
			(xy 377.366766 -285.74008) (xy 377.316902 -285.7299) (xy 377.269316 -285.711853) (xy 377.225242 -285.686407)
			(xy 377.18582 -285.65422) (xy 377.152072 -285.616126) (xy 377.124871 -285.573112) (xy 377.104923 -285.526292)
			(xy 377.092744 -285.476878) (xy 377.088649 -285.42615) (xy 376.780552 -285.42615) (xy 376.78004 -285.451596)
			(xy 376.771876 -285.50183) (xy 376.75576 -285.550104) (xy 376.732109 -285.595167) (xy 376.701536 -285.635853)
			(xy 376.664832 -285.671108) (xy 376.622948 -285.700018) (xy 376.576969 -285.721835) (xy 376.528085 -285.735995)
			(xy 376.477564 -285.742129) (xy 376.426712 -285.74008) (xy 376.376848 -285.7299) (xy 376.329262 -285.711853)
			(xy 376.285188 -285.686407) (xy 376.245766 -285.65422) (xy 376.212018 -285.616126) (xy 376.184817 -285.573112)
			(xy 376.164869 -285.526292) (xy 376.15269 -285.476878) (xy 376.148595 -285.42615) (xy 375.830084 -285.42615)
			(xy 375.829589 -285.450757) (xy 375.821694 -285.499334) (xy 375.80611 -285.546015) (xy 375.783239 -285.589592)
			(xy 375.753674 -285.628936) (xy 375.718181 -285.663028) (xy 375.677678 -285.690984) (xy 375.633216 -285.712082)
			(xy 375.585945 -285.725774) (xy 375.53709 -285.731706) (xy 375.487915 -285.729725) (xy 375.439696 -285.719881)
			(xy 375.39368 -285.702429) (xy 375.351059 -285.677822) (xy 375.312938 -285.646697) (xy 375.280303 -285.60986)
			(xy 375.254 -285.568264) (xy 375.234709 -285.522988) (xy 375.222932 -285.475204) (xy 375.218972 -285.42615)
			(xy 374.89003 -285.42615) (xy 374.889891 -285.438913) (xy 374.887728 -285.464347) (xy 374.885712 -285.47695)
			(xy 374.885966 -285.47695) (xy 374.881527 -285.500585) (xy 374.866204 -285.546167) (xy 374.843927 -285.588785)
			(xy 374.815246 -285.627384) (xy 374.78087 -285.661012) (xy 374.74165 -285.688838) (xy 374.698553 -285.710173)
			(xy 374.652645 -285.724491) (xy 374.628918 -285.72841) (xy 374.62841 -285.72841) (xy 374.621849 -285.729567)
			(xy 374.60962 -285.734841) (xy 374.60428 -285.738824) (xy 374.5992 -285.742634) (xy 374.591326 -285.753302)
			(xy 374.555766 -285.840932) (xy 374.553995 -285.84556) (xy 374.552081 -285.855282) (xy 374.551956 -285.860236)
			(xy 374.56237 -285.890462) (xy 374.567196 -285.896812) (xy 374.577414 -285.91065) (xy 374.596349 -285.939372)
			(xy 374.605042 -285.954216) (xy 374.61468 -285.971267) (xy 374.631839 -286.006478) (xy 374.639332 -286.024574)
			(xy 374.639332 -286.024828) (xy 374.641996 -286.030781) (xy 374.649844 -286.041192) (xy 374.654826 -286.045402)
			(xy 374.660271 -286.049488) (xy 374.672758 -286.054898) (xy 374.679464 -286.05607) (xy 374.767094 -286.068008)
			(xy 374.773802 -286.068744) (xy 374.787189 -286.067069) (xy 374.79351 -286.064706) (xy 374.799098 -286.06242)
			(xy 374.809258 -286.0548) (xy 374.81383 -286.048958) (xy 374.828372 -286.030909) (xy 374.861987 -285.999001)
			(xy 374.900043 -285.972546) (xy 374.941662 -285.952151) (xy 374.985888 -285.938287) (xy 375.031702 -285.931272)
			(xy 375.054876 -285.930848) (xy 375.067639 -285.930988) (xy 375.093072 -285.933154) (xy 375.105676 -285.935166)
			(xy 375.105676 -285.934912) (xy 375.130625 -285.939627) (xy 375.178602 -285.956235) (xy 375.223167 -285.980557)
			(xy 375.263091 -286.011922) (xy 375.29727 -286.049464) (xy 375.311416 -286.070548) (xy 375.322986 -286.08917)
			(xy 375.341254 -286.129024) (xy 375.353639 -286.171079) (xy 375.357136 -286.192722) (xy 375.358406 -286.201612)
			(xy 375.367042 -286.217614) (xy 375.374154 -286.22371) (xy 375.381277 -286.229387) (xy 375.398328 -286.235757)
			(xy 375.407428 -286.236156) (xy 375.638568 -286.236156) (xy 375.642632 -286.235902) (xy 375.65322 -286.234546)
			(xy 375.67199 -286.224435) (xy 375.678954 -286.216344) (xy 375.682256 -286.192468) (xy 375.686233 -286.167661)
			(xy 375.701014 -286.119646) (xy 375.723212 -286.074578) (xy 375.752266 -286.033593) (xy 375.787444 -285.997726)
			(xy 375.827858 -285.967882) (xy 375.872487 -285.944814) (xy 375.920206 -285.929104) (xy 375.969811 -285.921149)
			(xy 376.020049 -285.921149) (xy 376.069654 -285.929104) (xy 376.117373 -285.944814) (xy 376.162002 -285.967882)
			(xy 376.202416 -285.997726) (xy 376.237594 -286.033593) (xy 376.266648 -286.074578) (xy 376.288846 -286.119646)
			(xy 376.303627 -286.167661) (xy 376.307604 -286.192468) (xy 376.310906 -286.216344) (xy 376.317806 -286.22451)
			(xy 376.336612 -286.234638) (xy 376.347228 -286.235902) (xy 376.351292 -286.236156) (xy 376.582178 -286.236156)
			(xy 376.591282 -286.235781) (xy 376.608337 -286.229403) (xy 376.615452 -286.22371) (xy 376.62231 -286.217868)
			(xy 376.6312 -286.201866) (xy 376.63247 -286.192722) (xy 376.636379 -286.168794) (xy 376.650771 -286.122498)
			(xy 376.672297 -286.079057) (xy 376.700417 -286.039564) (xy 376.734424 -286.005009) (xy 376.773464 -285.976263)
			(xy 376.816556 -285.954046) (xy 376.862617 -285.938917) (xy 376.910489 -285.931257) (xy 376.958971 -285.931257)
			(xy 377.006843 -285.938917) (xy 377.052904 -285.954046) (xy 377.095996 -285.976263) (xy 377.135036 -286.005009)
			(xy 377.169043 -286.039564) (xy 377.197163 -286.079057) (xy 377.218689 -286.122498) (xy 377.233081 -286.168794)
			(xy 377.23699 -286.192722) (xy 377.23699 -286.192976) (xy 377.238683 -286.201827) (xy 377.247402 -286.217582)
			(xy 377.254008 -286.22371) (xy 377.260866 -286.229806) (xy 377.277884 -286.236156) (xy 377.518422 -286.236156)
			(xy 377.522486 -286.235902) (xy 377.533079 -286.234555) (xy 377.551863 -286.224453) (xy 377.558808 -286.216344)
			(xy 377.56211 -286.192468) (xy 377.566087 -286.167663) (xy 377.580868 -286.119653) (xy 377.603067 -286.07459)
			(xy 377.632123 -286.033611) (xy 377.667302 -285.997752) (xy 377.707717 -285.967916) (xy 377.752346 -285.944858)
			(xy 377.800064 -285.92916) (xy 377.849667 -285.921217) (xy 377.874784 -285.920688) (xy 377.875038 -285.920688)
			(xy 377.900505 -285.921172) (xy 377.950776 -285.929357) (xy 377.999076 -285.945522) (xy 378.044146 -285.969248)
			(xy 378.064776 -285.984188) (xy 378.083572 -285.998412) (xy 378.091175 -285.999226) (xy 378.106279 -285.996892)
			(xy 378.11329 -285.99384) (xy 378.116974 -285.991905) (xy 378.123736 -285.987056) (xy 378.126752 -285.984188)
			(xy 378.244608 -285.866332) (xy 378.251212 -285.858204) (xy 378.256098 -285.84994) (xy 378.259897 -285.831137)
			(xy 378.258578 -285.821628) (xy 378.244354 -285.740094) (xy 378.243066 -285.734016) (xy 378.237926 -285.722709)
			(xy 378.234194 -285.717742) (xy 378.234194 -285.717488) (xy 378.230421 -285.712959) (xy 378.221181 -285.705642)
			(xy 378.215906 -285.70301) (xy 378.215652 -285.702756) (xy 378.215398 -285.702756) (xy 378.193218 -285.691823)
			(xy 378.152419 -285.663887) (xy 378.11665 -285.629747) (xy 378.086844 -285.590293) (xy 378.063779 -285.546555)
			(xy 378.048057 -285.499674) (xy 378.040088 -285.450873) (xy 378.03963 -285.42615) (xy 378.040104 -285.402162)
			(xy 378.047617 -285.354779) (xy 378.062449 -285.309154) (xy 378.084236 -285.266411) (xy 378.112441 -285.227602)
			(xy 378.14637 -285.193684) (xy 378.185186 -285.16549) (xy 378.227936 -285.143716) (xy 378.273565 -285.128896)
			(xy 378.32095 -285.121397) (xy 378.344938 -285.120842) (xy 378.3577 -285.120997) (xy 378.383133 -285.12316)
			(xy 378.395738 -285.12516) (xy 378.395738 -285.124906) (xy 378.418607 -285.129211) (xy 378.462785 -285.143826)
			(xy 378.504239 -285.164966) (xy 378.542012 -285.192143) (xy 378.57523 -285.22473) (xy 378.603127 -285.261973)
			(xy 378.625058 -285.303014) (xy 378.633228 -285.324804) (xy 378.635514 -285.331662) (xy 378.652786 -285.355538)
			(xy 378.656088 -285.358078) (xy 378.659803 -285.360744) (xy 378.667981 -285.364835) (xy 378.672344 -285.366206)
			(xy 378.688854 -285.368492) (xy 378.697074 -285.367843) (xy 378.712489 -285.362016) (xy 378.71908 -285.357062)
			(xy 378.725684 -285.35122) (xy 378.731497 -285.345619) (xy 378.73954 -285.331634) (xy 378.741432 -285.323788)
			(xy 378.741686 -285.323026) (xy 378.744724 -285.30754) (xy 378.752348 -285.276914) (xy 378.756926 -285.261812)
			(xy 378.759212 -285.254446) (xy 378.759212 -284.955742) (xy 378.758846 -284.947706) (xy 378.753796 -284.932445)
			(xy 378.749306 -284.92577) (xy 378.744734 -284.91942) (xy 378.73178 -284.910022) (xy 378.723652 -284.907482)
			(xy 378.700692 -284.899815) (xy 378.657355 -284.878257) (xy 378.617963 -284.85013) (xy 378.583502 -284.81614)
			(xy 378.554836 -284.777139) (xy 378.532683 -284.734103) (xy 378.517598 -284.688111) (xy 378.509958 -284.640315)
			(xy 378.509956 -284.591912) (xy 378.517591 -284.544115) (xy 378.532673 -284.498121) (xy 378.554822 -284.455083)
			(xy 378.583485 -284.416079) (xy 378.617943 -284.382087) (xy 378.657333 -284.353957) (xy 378.700668 -284.332395)
			(xy 378.723652 -284.324806) (xy 378.723906 -284.324806) (xy 378.731505 -284.322077) (xy 378.744581 -284.31262)
			(xy 378.74956 -284.306264) (xy 378.754132 -284.299914) (xy 378.759212 -284.284674) (xy 378.759212 -283.977842)
			(xy 378.756926 -283.970476) (xy 378.752357 -283.955371) (xy 378.744735 -283.924745) (xy 378.741686 -283.909262)
			(xy 378.741432 -283.9085) (xy 378.739459 -283.900686) (xy 378.731427 -283.886724) (xy 378.725684 -283.881068)
			(xy 378.71908 -283.875226) (xy 378.712505 -283.870241) (xy 378.697082 -283.864407) (xy 378.688854 -283.863796)
			(xy 378.672344 -283.866082) (xy 378.667983 -283.867456) (xy 378.659805 -283.871546) (xy 378.656088 -283.87421)
			(xy 378.652786 -283.87675) (xy 378.635514 -283.90088) (xy 378.633736 -283.90596) (xy 378.625579 -283.928159)
			(xy 378.6034 -283.969929) (xy 378.575048 -284.00778) (xy 378.541201 -284.04081) (xy 378.502668 -284.068229)
			(xy 378.460369 -284.089381) (xy 378.415316 -284.103761) (xy 378.368585 -284.111025) (xy 378.344938 -284.111446)
			(xy 378.319675 -284.110956) (xy 378.269838 -284.102645) (xy 378.222048 -284.086244) (xy 378.17761 -284.062201)
			(xy 378.137736 -284.03117) (xy 378.103513 -283.993999) (xy 378.075876 -283.951702) (xy 378.055579 -283.905432)
			(xy 378.043175 -283.856453) (xy 378.039002 -283.8061) (xy 378.043175 -283.755747) (xy 378.055579 -283.706767)
			(xy 378.075876 -283.660498) (xy 378.103513 -283.618201) (xy 378.137736 -283.58103) (xy 378.17761 -283.549999)
			(xy 378.222048 -283.525955) (xy 378.269838 -283.509555) (xy 378.319675 -283.501244) (xy 378.344938 -283.50083)
			(xy 378.3577 -283.500985) (xy 378.383133 -283.503148) (xy 378.395738 -283.505148) (xy 378.395738 -283.504894)
			(xy 378.418607 -283.509199) (xy 378.462786 -283.523813) (xy 378.504241 -283.544953) (xy 378.542014 -283.57213)
			(xy 378.575233 -283.604716) (xy 378.603131 -283.641959) (xy 378.625065 -283.682999) (xy 378.633228 -283.704792)
			(xy 378.635514 -283.71165) (xy 378.652786 -283.735526) (xy 378.656088 -283.738066) (xy 378.659803 -283.740733)
			(xy 378.667981 -283.744825) (xy 378.672344 -283.746194) (xy 378.688854 -283.74848) (xy 378.697074 -283.747831)
			(xy 378.712488 -283.742002) (xy 378.71908 -283.73705) (xy 378.725684 -283.731208) (xy 378.731496 -283.725607)
			(xy 378.739535 -283.711621) (xy 378.741432 -283.703776) (xy 378.741686 -283.703014) (xy 378.744724 -283.687528)
			(xy 378.752349 -283.656902) (xy 378.756926 -283.6418) (xy 378.759212 -283.634434) (xy 378.759212 -283.33573)
			(xy 378.758845 -283.327695) (xy 378.753791 -283.312436) (xy 378.749306 -283.305758) (xy 378.744734 -283.299408)
			(xy 378.73178 -283.29001) (xy 378.723652 -283.28747) (xy 378.700693 -283.279803) (xy 378.657358 -283.258245)
			(xy 378.617968 -283.230119) (xy 378.583509 -283.19613) (xy 378.554844 -283.15713) (xy 378.532692 -283.114096)
			(xy 378.517608 -283.068105) (xy 378.509969 -283.02031) (xy 378.509968 -282.971909) (xy 378.517603 -282.924114)
			(xy 378.532685 -282.878122) (xy 378.554834 -282.835086) (xy 378.583496 -282.796084) (xy 378.617953 -282.762093)
			(xy 378.657342 -282.733965) (xy 378.700676 -282.712404) (xy 378.723652 -282.704794) (xy 378.723906 -282.704794)
			(xy 378.731504 -282.702064) (xy 378.744578 -282.692606) (xy 378.74956 -282.686252) (xy 378.754132 -282.679902)
			(xy 378.759212 -282.664662) (xy 378.759212 -282.36799) (xy 378.756672 -282.360116) (xy 378.751071 -282.342616)
			(xy 378.74192 -282.307027) (xy 378.738384 -282.288996) (xy 378.736098 -282.277312) (xy 378.709936 -282.24226)
			(xy 378.704464 -282.239587) (xy 378.692654 -282.236632) (xy 378.686568 -282.236418) (xy 378.644658 -282.26766)
			(xy 378.635768 -282.279598) (xy 378.633228 -282.286964) (xy 378.625016 -282.309059) (xy 378.602772 -282.350616)
			(xy 378.574412 -282.388265) (xy 378.540609 -282.421114) (xy 378.502163 -282.448385) (xy 378.459986 -282.46943)
			(xy 378.415079 -282.483751) (xy 378.368506 -282.491008) (xy 378.344938 -282.491434) (xy 378.319676 -282.490944)
			(xy 378.269841 -282.482634) (xy 378.222053 -282.466234) (xy 378.177616 -282.442191) (xy 378.137744 -282.411161)
			(xy 378.103523 -282.373992) (xy 378.075887 -282.331696) (xy 378.05559 -282.285429) (xy 378.043187 -282.236451)
			(xy 378.039014 -282.1861) (xy 378.043187 -282.135749) (xy 378.05559 -282.086771) (xy 378.075887 -282.040504)
			(xy 378.103523 -281.998208) (xy 378.137744 -281.961039) (xy 378.177616 -281.930009) (xy 378.222053 -281.905966)
			(xy 378.269841 -281.889566) (xy 378.319676 -281.881256) (xy 378.344938 -281.880818) (xy 378.368508 -281.881251)
			(xy 378.415089 -281.888485) (xy 378.460006 -281.902792) (xy 378.50219 -281.92383) (xy 378.540641 -281.951101)
			(xy 378.574444 -281.983957) (xy 378.602797 -282.021617) (xy 378.625026 -282.063187) (xy 378.633228 -282.085288)
			(xy 378.635768 -282.092654) (xy 378.644658 -282.104592) (xy 378.686568 -282.135834) (xy 378.692653 -282.135621)
			(xy 378.70446 -282.132658) (xy 378.709936 -282.129992) (xy 378.736098 -282.09494) (xy 378.738384 -282.083256)
			(xy 378.741924 -282.065226) (xy 378.751073 -282.029636) (xy 378.756672 -282.012136) (xy 378.759212 -282.004262)
			(xy 378.759212 -281.715718) (xy 378.758843 -281.707684) (xy 378.753786 -281.692426) (xy 378.749306 -281.685746)
			(xy 378.744734 -281.679396) (xy 378.73178 -281.669998) (xy 378.723652 -281.667458) (xy 378.700694 -281.659791)
			(xy 378.657361 -281.638233) (xy 378.617972 -281.610108) (xy 378.583515 -281.57612) (xy 378.554852 -281.537121)
			(xy 378.532701 -281.494088) (xy 378.517618 -281.448099) (xy 378.509981 -281.400306) (xy 378.50998 -281.351906)
			(xy 378.517615 -281.304113) (xy 378.532697 -281.258123) (xy 378.554845 -281.215089) (xy 378.583507 -281.176089)
			(xy 378.617963 -281.1421) (xy 378.657351 -281.113973) (xy 378.700683 -281.092413) (xy 378.723652 -281.084782)
			(xy 378.723906 -281.084782) (xy 378.731504 -281.082052) (xy 378.744576 -281.072592) (xy 378.74956 -281.06624)
			(xy 378.754132 -281.05989) (xy 378.759212 -281.04465) (xy 378.759212 -280.765504) (xy 378.759162 -280.761634)
			(xy 378.758009 -280.75398) (xy 378.756926 -280.750264) (xy 378.75464 -280.743914) (xy 378.748908 -280.726358)
			(xy 378.739503 -280.690642) (xy 378.735844 -280.67254) (xy 378.733558 -280.661872) (xy 378.715524 -280.646632)
			(xy 378.708158 -280.641552) (xy 378.702316 -280.638504) (xy 378.694104 -280.635407) (xy 378.676596 -280.634411)
			(xy 378.659788 -280.639412) (xy 378.652532 -280.644346) (xy 378.637292 -280.655522) (xy 378.633482 -280.665682)
			(xy 378.625347 -280.687884) (xy 378.603211 -280.729665) (xy 378.5749 -280.767535) (xy 378.541092 -280.800589)
			(xy 378.502592 -280.828038) (xy 378.460323 -280.849226) (xy 378.415293 -280.863646) (xy 378.368579 -280.870954)
			(xy 378.344938 -280.871422) (xy 378.319677 -280.870932) (xy 378.269843 -280.862622) (xy 378.222058 -280.846223)
			(xy 378.177623 -280.822181) (xy 378.137752 -280.791152) (xy 378.103532 -280.753984) (xy 378.075898 -280.711691)
			(xy 378.055602 -280.665425) (xy 378.043198 -280.616449) (xy 378.039026 -280.5661) (xy 378.043198 -280.515751)
			(xy 378.055602 -280.466775) (xy 378.075898 -280.420509) (xy 378.103532 -280.378216) (xy 378.137752 -280.341048)
			(xy 378.177623 -280.310019) (xy 378.222058 -280.285977) (xy 378.269843 -280.269578) (xy 378.319677 -280.261268)
			(xy 378.344938 -280.260806) (xy 378.368415 -280.26124) (xy 378.414815 -280.268435) (xy 378.459567 -280.282649)
			(xy 378.501614 -280.303548) (xy 378.539966 -280.330638) (xy 378.573717 -280.363281) (xy 378.58827 -280.38171)
			(xy 378.592842 -280.38679) (xy 378.601986 -280.395934) (xy 378.6124 -280.401776) (xy 378.617226 -280.403808)
			(xy 378.630434 -280.405332) (xy 378.72416 -280.39314) (xy 378.730846 -280.392013) (xy 378.743336 -280.386743)
			(xy 378.748798 -280.382726) (xy 378.753878 -280.378916) (xy 378.761752 -280.368248) (xy 378.764292 -280.361898)
			(xy 378.772207 -280.342126) (xy 378.790639 -280.303729) (xy 378.801122 -280.28519) (xy 378.81814 -280.25598)
			(xy 378.821319 -280.250186) (xy 378.824794 -280.23744) (xy 378.824998 -280.230834) (xy 378.824998 -280.109168)
			(xy 378.82459 -280.099889) (xy 378.81794 -280.082564) (xy 378.812044 -280.075386) (xy 378.799852 -280.06167)
			(xy 378.791216 -280.060654) (xy 378.78004 -280.059384) (xy 378.755535 -280.056095) (xy 378.707967 -280.042623)
			(xy 378.66319 -280.021663) (xy 378.622377 -279.99376) (xy 378.586594 -279.959646) (xy 378.556775 -279.920211)
			(xy 378.533702 -279.876486) (xy 378.517976 -279.829614) (xy 378.510008 -279.780821) (xy 378.510008 -279.731381)
			(xy 378.517975 -279.682588) (xy 378.533701 -279.635716) (xy 378.556774 -279.591991) (xy 378.586592 -279.552556)
			(xy 378.622376 -279.518441) (xy 378.663189 -279.490538) (xy 378.707965 -279.469577) (xy 378.755534 -279.456106)
			(xy 378.78004 -279.452832) (xy 378.791216 -279.451562) (xy 378.799852 -279.450546) (xy 378.812044 -279.43683)
			(xy 378.817903 -279.429635) (xy 378.824528 -279.412317) (xy 378.824998 -279.403048) (xy 378.824998 -279.27935)
			(xy 378.823474 -279.267412) (xy 378.822966 -279.265126) (xy 378.820934 -279.258522) (xy 378.819664 -279.25649)
			(xy 378.816616 -279.251918) (xy 378.807532 -279.237697) (xy 378.790884 -279.20834) (xy 378.783342 -279.193244)
			(xy 378.764292 -279.150318) (xy 378.761752 -279.143968) (xy 378.753878 -279.1333) (xy 378.748798 -279.12949)
			(xy 378.743349 -279.125445) (xy 378.730859 -279.120154) (xy 378.72416 -279.119076) (xy 378.637038 -279.107646)
			(xy 378.630455 -279.106942) (xy 378.617328 -279.108621) (xy 378.61113 -279.110948) (xy 378.605542 -279.113234)
			(xy 378.594874 -279.12187) (xy 378.590302 -279.127966) (xy 378.575784 -279.14677) (xy 378.54191 -279.180072)
			(xy 378.503288 -279.20773) (xy 378.460851 -279.229076) (xy 378.415622 -279.243595) (xy 378.36869 -279.250939)
			(xy 378.344938 -279.25141) (xy 378.319678 -279.25092) (xy 378.269846 -279.242611) (xy 378.222062 -279.226212)
			(xy 378.177629 -279.202171) (xy 378.13776 -279.171144) (xy 378.103542 -279.133977) (xy 378.075908 -279.091685)
			(xy 378.055613 -279.045421) (xy 378.04321 -278.996447) (xy 378.039038 -278.9461) (xy 378.04321 -278.895753)
			(xy 378.055613 -278.846779) (xy 378.075908 -278.800515) (xy 378.103542 -278.758223) (xy 378.13776 -278.721056)
			(xy 378.177629 -278.690029) (xy 378.222062 -278.665988) (xy 378.269846 -278.649589) (xy 378.319678 -278.64128)
			(xy 378.344938 -278.640794) (xy 378.368415 -278.641228) (xy 378.414816 -278.648422) (xy 378.459567 -278.662636)
			(xy 378.501615 -278.683535) (xy 378.539968 -278.710624) (xy 378.57372 -278.743267) (xy 378.58827 -278.761698)
			(xy 378.592842 -278.766778) (xy 378.601986 -278.775922) (xy 378.6124 -278.781764) (xy 378.617226 -278.783796)
			(xy 378.630434 -278.78532) (xy 378.72416 -278.773128) (xy 378.730846 -278.772) (xy 378.743335 -278.76673)
			(xy 378.748798 -278.762714) (xy 378.753878 -278.758904) (xy 378.761752 -278.748236) (xy 378.764292 -278.741886)
			(xy 378.772208 -278.722115) (xy 378.79064 -278.683717) (xy 378.801122 -278.665178) (xy 378.81814 -278.635968)
			(xy 378.821318 -278.630173) (xy 378.82479 -278.617428) (xy 378.824998 -278.610822) (xy 378.824998 -278.489156)
			(xy 378.824588 -278.479878) (xy 378.817935 -278.462555) (xy 378.812044 -278.455374) (xy 378.799852 -278.441658)
			(xy 378.791216 -278.440642) (xy 378.78004 -278.439372) (xy 378.755536 -278.436083) (xy 378.70797 -278.422612)
			(xy 378.663195 -278.401652) (xy 378.622384 -278.37375) (xy 378.586602 -278.339637) (xy 378.556785 -278.300203)
			(xy 378.533712 -278.25648) (xy 378.517987 -278.20961) (xy 378.51002 -278.160818) (xy 378.51002 -278.111381)
			(xy 378.517987 -278.062589) (xy 378.533712 -278.015719) (xy 378.556785 -277.971996) (xy 378.586602 -277.932563)
			(xy 378.622384 -277.898449) (xy 378.663196 -277.870548) (xy 378.70797 -277.849588) (xy 378.755537 -277.836117)
			(xy 378.78004 -277.83282) (xy 378.791216 -277.83155) (xy 378.799852 -277.830534) (xy 378.812044 -277.816818)
			(xy 378.817902 -277.809622) (xy 378.824522 -277.792304) (xy 378.824998 -277.783036) (xy 378.824998 -277.659338)
			(xy 378.823474 -277.6474) (xy 378.822966 -277.645114) (xy 378.820934 -277.63851) (xy 378.819664 -277.636478)
			(xy 378.816616 -277.631906) (xy 378.807532 -277.617685) (xy 378.790885 -277.588327) (xy 378.783342 -277.573232)
			(xy 378.764292 -277.530306) (xy 378.761752 -277.523956) (xy 378.753878 -277.513288) (xy 378.748798 -277.509478)
			(xy 378.743349 -277.505434) (xy 378.730859 -277.500144) (xy 378.72416 -277.499064) (xy 378.637038 -277.487634)
			(xy 378.630455 -277.48693) (xy 378.617328 -277.488608) (xy 378.61113 -277.490936) (xy 378.605542 -277.493222)
			(xy 378.594874 -277.501858) (xy 378.590302 -277.507954) (xy 378.575785 -277.526758) (xy 378.541911 -277.560062)
			(xy 378.503289 -277.587721) (xy 378.460852 -277.609068) (xy 378.415622 -277.623588) (xy 378.36869 -277.630932)
			(xy 378.344938 -277.631398) (xy 378.319679 -277.630908) (xy 378.269849 -277.622599) (xy 378.222067 -277.606201)
			(xy 378.177636 -277.582161) (xy 378.137768 -277.551135) (xy 378.103551 -277.51397) (xy 378.075919 -277.471679)
			(xy 378.055624 -277.425417) (xy 378.043222 -277.376445) (xy 378.03905 -277.3261) (xy 378.043222 -277.275755)
			(xy 378.055624 -277.226783) (xy 378.075919 -277.180521) (xy 378.103551 -277.13823) (xy 378.137768 -277.101065)
			(xy 378.177636 -277.070039) (xy 378.222067 -277.045999) (xy 378.269849 -277.029601) (xy 378.319679 -277.021292)
			(xy 378.344938 -277.020782) (xy 378.368415 -277.021216) (xy 378.414816 -277.02841) (xy 378.459568 -277.042624)
			(xy 378.501617 -277.063522) (xy 378.53997 -277.090611) (xy 378.573724 -277.123252) (xy 378.58827 -277.141686)
			(xy 378.592842 -277.146766) (xy 378.601986 -277.15591) (xy 378.6124 -277.161752) (xy 378.617226 -277.163784)
			(xy 378.630434 -277.165308) (xy 378.72416 -277.153116) (xy 378.730846 -277.151988) (xy 378.743334 -277.146716)
			(xy 378.748798 -277.142702) (xy 378.753878 -277.138892) (xy 378.761752 -277.128224) (xy 378.764292 -277.121874)
			(xy 378.772208 -277.102103) (xy 378.790642 -277.063706) (xy 378.801122 -277.045166) (xy 378.81814 -277.015956)
			(xy 378.821316 -277.010161) (xy 378.824785 -276.997415) (xy 378.824998 -276.99081) (xy 378.824998 -276.869144)
			(xy 378.824603 -276.859859) (xy 378.817973 -276.842516) (xy 378.812044 -276.835362) (xy 378.799852 -276.821646)
			(xy 378.791216 -276.82063) (xy 378.78004 -276.81936) (xy 378.755537 -276.816071) (xy 378.707972 -276.8026)
			(xy 378.6632 -276.781641) (xy 378.62239 -276.75374) (xy 378.58661 -276.719628) (xy 378.556794 -276.680195)
			(xy 378.533722 -276.636474) (xy 378.517998 -276.589606) (xy 378.510032 -276.540816) (xy 378.510032 -276.49138)
			(xy 378.517999 -276.442591) (xy 378.533724 -276.395723) (xy 378.556796 -276.352001) (xy 378.586612 -276.312569)
			(xy 378.622393 -276.278458) (xy 378.663203 -276.250558) (xy 378.707976 -276.229599) (xy 378.755541 -276.216129)
			(xy 378.78004 -276.212808) (xy 378.791216 -276.211538) (xy 378.799852 -276.210522) (xy 378.812044 -276.196806)
			(xy 378.817915 -276.189614) (xy 378.824565 -276.172297) (xy 378.824998 -276.163024) (xy 378.824998 -276.039326)
			(xy 378.823474 -276.027388) (xy 378.822966 -276.025102) (xy 378.820934 -276.018498) (xy 378.819664 -276.016466)
			(xy 378.816616 -276.011894) (xy 378.807532 -275.997673) (xy 378.790886 -275.968315) (xy 378.783342 -275.95322)
			(xy 378.764292 -275.910294) (xy 378.761752 -275.903944) (xy 378.753878 -275.893276) (xy 378.748798 -275.889466)
			(xy 378.743348 -275.885423) (xy 378.730858 -275.880134) (xy 378.72416 -275.879052) (xy 378.637038 -275.867622)
			(xy 378.630455 -275.866917) (xy 378.617328 -275.868596) (xy 378.61113 -275.870924) (xy 378.605542 -275.87321)
			(xy 378.594874 -275.881846) (xy 378.590302 -275.887942) (xy 378.575782 -275.906742) (xy 378.541904 -275.940036)
			(xy 378.503281 -275.967687) (xy 378.460845 -275.989027) (xy 378.415617 -276.003543) (xy 378.368688 -276.010885)
			(xy 378.344938 -276.011386) (xy 378.31968 -276.010896) (xy 378.269852 -276.002587) (xy 378.222072 -275.98619)
			(xy 378.177643 -275.96215) (xy 378.137776 -275.931126) (xy 378.103561 -275.893962) (xy 378.075929 -275.851673)
			(xy 378.055636 -275.805413) (xy 378.043234 -275.756443) (xy 378.039062 -275.7061) (xy 378.043234 -275.655757)
			(xy 378.055636 -275.606787) (xy 378.075929 -275.560527) (xy 378.103561 -275.518238) (xy 378.137776 -275.481074)
			(xy 378.177643 -275.45005) (xy 378.222072 -275.42601) (xy 378.269852 -275.409613) (xy 378.31968 -275.401304)
			(xy 378.344938 -275.40077) (xy 378.368416 -275.401203) (xy 378.414817 -275.408398) (xy 378.459569 -275.422611)
			(xy 378.501618 -275.443508) (xy 378.539972 -275.470597) (xy 378.573727 -275.503238) (xy 378.58827 -275.521674)
			(xy 378.592842 -275.526754) (xy 378.601986 -275.535898) (xy 378.6124 -275.54174) (xy 378.617226 -275.543772)
			(xy 378.630434 -275.545296) (xy 378.72416 -275.533104) (xy 378.730846 -275.531976) (xy 378.743333 -275.526703)
			(xy 378.748798 -275.52269) (xy 378.753878 -275.51888) (xy 378.761752 -275.508212) (xy 378.764292 -275.501862)
			(xy 378.772208 -275.482091) (xy 378.790643 -275.443694) (xy 378.801122 -275.425154) (xy 378.81814 -275.395944)
			(xy 378.821315 -275.390149) (xy 378.824781 -275.377403) (xy 378.824998 -275.370798) (xy 378.824998 -275.249132)
			(xy 378.824601 -275.239848) (xy 378.817968 -275.222508) (xy 378.812044 -275.21535) (xy 378.799852 -275.201634)
			(xy 378.791216 -275.200618) (xy 378.78004 -275.199348) (xy 378.755538 -275.196059) (xy 378.707975 -275.182588)
			(xy 378.663205 -275.16163) (xy 378.622396 -275.13373) (xy 378.586618 -275.099619) (xy 378.556803 -275.060188)
			(xy 378.533733 -275.016468) (xy 378.518009 -274.969601) (xy 378.510044 -274.920814) (xy 378.510044 -274.87138)
			(xy 378.518011 -274.822592) (xy 378.533735 -274.775726) (xy 378.556807 -274.732007) (xy 378.586622 -274.692576)
			(xy 378.622401 -274.658466) (xy 378.66321 -274.630567) (xy 378.707981 -274.609609) (xy 378.755545 -274.59614)
			(xy 378.78004 -274.592796) (xy 378.791216 -274.591526) (xy 378.799852 -274.59051) (xy 378.812044 -274.576794)
			(xy 378.817913 -274.569602) (xy 378.824559 -274.552284) (xy 378.824998 -274.543012) (xy 378.824998 -274.419314)
			(xy 378.823474 -274.407376) (xy 378.822966 -274.40509) (xy 378.820934 -274.398486) (xy 378.819664 -274.396454)
			(xy 378.816616 -274.391882) (xy 378.807533 -274.37766) (xy 378.790887 -274.348302) (xy 378.783342 -274.333208)
			(xy 378.764292 -274.290282) (xy 378.761752 -274.283932) (xy 378.753878 -274.273264) (xy 378.748798 -274.269454)
			(xy 378.743348 -274.265412) (xy 378.730858 -274.260124) (xy 378.72416 -274.25904) (xy 378.637038 -274.24761)
			(xy 378.630455 -274.246905) (xy 378.617328 -274.248583) (xy 378.61113 -274.250912) (xy 378.605542 -274.253198)
			(xy 378.594874 -274.261834) (xy 378.590302 -274.26793) (xy 378.575782 -274.28673) (xy 378.541905 -274.320026)
			(xy 378.503282 -274.347678) (xy 378.460846 -274.369019) (xy 378.415618 -274.383536) (xy 378.368688 -274.390877)
			(xy 378.344938 -274.391374) (xy 378.319681 -274.390884) (xy 378.269855 -274.382576) (xy 378.222077 -274.366179)
			(xy 378.177649 -274.34214) (xy 378.137784 -274.311117) (xy 378.10357 -274.273955) (xy 378.07594 -274.231668)
			(xy 378.055647 -274.185409) (xy 378.043246 -274.136441) (xy 378.039074 -274.0861) (xy 378.043246 -274.035759)
			(xy 378.055647 -273.986791) (xy 378.07594 -273.940532) (xy 378.10357 -273.898245) (xy 378.137784 -273.861083)
			(xy 378.177649 -273.83006) (xy 378.222077 -273.806021) (xy 378.269855 -273.789624) (xy 378.319681 -273.781316)
			(xy 378.344938 -273.780758) (xy 378.368416 -273.781191) (xy 378.414817 -273.788386) (xy 378.45957 -273.802599)
			(xy 378.501619 -273.823495) (xy 378.539974 -273.850583) (xy 378.57373 -273.883223) (xy 378.58827 -273.901662)
			(xy 378.592842 -273.906742) (xy 378.601986 -273.915886) (xy 378.6124 -273.921728) (xy 378.617226 -273.92376)
			(xy 378.630434 -273.925284) (xy 378.72416 -273.913092) (xy 378.730846 -273.911964) (xy 378.743332 -273.90669)
			(xy 378.748798 -273.902678) (xy 378.753878 -273.898868) (xy 378.761752 -273.8882) (xy 378.764292 -273.88185)
			(xy 378.772209 -273.862079) (xy 378.790644 -273.823683) (xy 378.801122 -273.805142) (xy 378.81814 -273.775932)
			(xy 378.821313 -273.770137) (xy 378.824776 -273.757391) (xy 378.824998 -273.750786) (xy 378.824998 -273.62912)
			(xy 378.824599 -273.619837) (xy 378.817962 -273.6025) (xy 378.812044 -273.595338) (xy 378.799852 -273.581622)
			(xy 378.791216 -273.580606) (xy 378.78004 -273.579336) (xy 378.755539 -273.576047) (xy 378.707978 -273.562577)
			(xy 378.663209 -273.541619) (xy 378.622403 -273.51372) (xy 378.586626 -273.47961) (xy 378.556813 -273.44018)
			(xy 378.533743 -273.396462) (xy 378.518021 -273.349597) (xy 378.510055 -273.300811) (xy 378.510056 -273.25138)
			(xy 378.518023 -273.202594) (xy 378.533747 -273.15573) (xy 378.556818 -273.112012) (xy 378.586632 -273.072583)
			(xy 378.62241 -273.038474) (xy 378.663217 -273.010577) (xy 378.707987 -272.98962) (xy 378.755548 -272.976152)
			(xy 378.78004 -272.972784) (xy 378.791216 -272.971514) (xy 378.799852 -272.970498) (xy 378.812044 -272.956782)
			(xy 378.817911 -272.949589) (xy 378.824553 -272.932271) (xy 378.824998 -272.923) (xy 378.824998 -272.799302)
			(xy 378.823474 -272.787364) (xy 378.822966 -272.785078) (xy 378.820934 -272.778474) (xy 378.819664 -272.776442)
			(xy 378.816616 -272.77187) (xy 378.807533 -272.757648) (xy 378.790888 -272.72829) (xy 378.783342 -272.713196)
			(xy 378.764292 -272.67027) (xy 378.761752 -272.66392) (xy 378.753878 -272.653252) (xy 378.748798 -272.649442)
			(xy 378.743348 -272.645401) (xy 378.730857 -272.640114) (xy 378.72416 -272.639028) (xy 378.637038 -272.627598)
			(xy 378.630455 -272.626894) (xy 378.617328 -272.628571) (xy 378.61113 -272.6309) (xy 378.605542 -272.633186)
			(xy 378.594874 -272.641822) (xy 378.590302 -272.647918) (xy 378.575783 -272.666719) (xy 378.541906 -272.700016)
			(xy 378.503284 -272.727669) (xy 378.460847 -272.749011) (xy 378.415619 -272.763528) (xy 378.368689 -272.77087)
			(xy 378.344938 -272.771362) (xy 378.319682 -272.770872) (xy 378.269858 -272.762564) (xy 378.222082 -272.746168)
			(xy 378.177656 -272.72213) (xy 378.137793 -272.691108) (xy 378.10358 -272.653947) (xy 378.07595 -272.611662)
			(xy 378.055658 -272.565405) (xy 378.043258 -272.516439) (xy 378.039086 -272.4661) (xy 378.043258 -272.415761)
			(xy 378.055658 -272.366795) (xy 378.07595 -272.320538) (xy 378.10358 -272.278253) (xy 378.137793 -272.241092)
			(xy 378.177656 -272.21007) (xy 378.222082 -272.186032) (xy 378.269858 -272.169636) (xy 378.319682 -272.161328)
			(xy 378.344938 -272.160746) (xy 378.368416 -272.161179) (xy 378.414817 -272.168373) (xy 378.459571 -272.182586)
			(xy 378.501621 -272.203482) (xy 378.539976 -272.230569) (xy 378.573733 -272.263208) (xy 378.58827 -272.28165)
			(xy 378.592842 -272.28673) (xy 378.601986 -272.295874) (xy 378.6124 -272.301716) (xy 378.617226 -272.303748)
			(xy 378.630434 -272.305272) (xy 378.72416 -272.29308) (xy 378.730846 -272.291951) (xy 378.743331 -272.286677)
			(xy 378.748798 -272.282666) (xy 378.753878 -272.278856) (xy 378.761752 -272.268188) (xy 378.764292 -272.261838)
			(xy 378.772209 -272.242067) (xy 378.790645 -272.203672) (xy 378.801122 -272.18513) (xy 378.81814 -272.15592)
			(xy 378.821324 -272.150127) (xy 378.82481 -272.137381) (xy 378.824998 -272.130774) (xy 378.824998 -272.009108)
			(xy 378.824597 -271.999826) (xy 378.817957 -271.982491) (xy 378.812044 -271.975326) (xy 378.799852 -271.96161)
			(xy 378.791216 -271.960594) (xy 378.78004 -271.959324) (xy 378.755532 -271.956034) (xy 378.707957 -271.942562)
			(xy 378.663175 -271.921599) (xy 378.622356 -271.893694) (xy 378.586567 -271.859576) (xy 378.556744 -271.820136)
			(xy 378.533667 -271.776406) (xy 378.517938 -271.729528) (xy 378.509969 -271.680728) (xy 378.509968 -271.631282)
			(xy 378.517935 -271.582483) (xy 378.533663 -271.535605) (xy 378.556738 -271.491873) (xy 378.58656 -271.452433)
			(xy 378.622347 -271.418313) (xy 378.663165 -271.390406) (xy 378.707947 -271.369442) (xy 378.755521 -271.355968)
			(xy 378.78004 -271.352772) (xy 378.791216 -271.351502) (xy 378.799852 -271.350486) (xy 378.812044 -271.33677)
			(xy 378.817909 -271.329576) (xy 378.824547 -271.312259) (xy 378.824998 -271.302988) (xy 378.824998 -271.17929)
			(xy 378.823474 -271.167352) (xy 378.822966 -271.165066) (xy 378.820934 -271.158462) (xy 378.819664 -271.15643)
			(xy 378.816616 -271.151858) (xy 378.807531 -271.137637) (xy 378.790882 -271.108281) (xy 378.783342 -271.093184)
			(xy 378.764292 -271.050258) (xy 378.761752 -271.043908) (xy 378.753878 -271.03324) (xy 378.748798 -271.02943)
			(xy 378.743347 -271.025389) (xy 378.730857 -271.020104) (xy 378.72416 -271.019016) (xy 378.637038 -271.007586)
			(xy 378.630455 -271.006882) (xy 378.617327 -271.008559) (xy 378.61113 -271.010888) (xy 378.605542 -271.013174)
			(xy 378.594874 -271.02181) (xy 378.590302 -271.027906) (xy 378.575783 -271.046708) (xy 378.541907 -271.080006)
			(xy 378.503285 -271.10766) (xy 378.460848 -271.129003) (xy 378.415619 -271.14352) (xy 378.368689 -271.150863)
			(xy 378.344938 -271.15135) (xy 378.319675 -271.15086) (xy 378.269837 -271.142549) (xy 378.222046 -271.126148)
			(xy 378.177608 -271.102104) (xy 378.137733 -271.071073) (xy 378.10351 -271.033902) (xy 378.075873 -270.991604)
			(xy 378.055575 -270.945334) (xy 378.043171 -270.896354) (xy 378.038998 -270.846) (xy 378.043171 -270.795646)
			(xy 378.055575 -270.746666) (xy 378.075873 -270.700396) (xy 378.10351 -270.658098) (xy 378.137733 -270.620927)
			(xy 378.177608 -270.589896) (xy 378.222046 -270.565852) (xy 378.269837 -270.549451) (xy 378.319675 -270.54114)
			(xy 378.344938 -270.540734) (xy 378.368416 -270.541167) (xy 378.414818 -270.548361) (xy 378.459571 -270.562573)
			(xy 378.501622 -270.583469) (xy 378.539978 -270.610555) (xy 378.573736 -270.643194) (xy 378.58827 -270.661638)
			(xy 378.592842 -270.666718) (xy 378.601986 -270.675862) (xy 378.6124 -270.681704) (xy 378.617226 -270.683736)
			(xy 378.630434 -270.68526) (xy 378.72416 -270.673068) (xy 378.730845 -270.671939) (xy 378.74333 -270.666663)
			(xy 378.748798 -270.662654) (xy 378.753878 -270.658844) (xy 378.761752 -270.648176) (xy 378.764292 -270.641826)
			(xy 378.77221 -270.622055) (xy 378.790646 -270.58366) (xy 378.801122 -270.565118) (xy 378.81814 -270.535908)
			(xy 378.821323 -270.530115) (xy 378.824806 -270.517369) (xy 378.824998 -270.510762) (xy 378.824998 -270.389096)
			(xy 378.824595 -270.379815) (xy 378.817952 -270.362483) (xy 378.812044 -270.355314) (xy 378.799852 -270.341598)
			(xy 378.791216 -270.340582) (xy 378.78004 -270.339312) (xy 378.755533 -270.336022) (xy 378.70796 -270.322551)
			(xy 378.663179 -270.301588) (xy 378.622362 -270.273684) (xy 378.586575 -270.239567) (xy 378.556754 -270.200128)
			(xy 378.533677 -270.1564) (xy 378.517949 -270.109524) (xy 378.509981 -270.060726) (xy 378.50998 -270.011282)
			(xy 378.517947 -269.962484) (xy 378.533674 -269.915608) (xy 378.556749 -269.871879) (xy 378.58657 -269.832439)
			(xy 378.622356 -269.798321) (xy 378.663172 -269.770416) (xy 378.707952 -269.749452) (xy 378.755525 -269.735979)
			(xy 378.78004 -269.73276) (xy 378.791216 -269.73149) (xy 378.799852 -269.730474) (xy 378.812044 -269.716758)
			(xy 378.817907 -269.709564) (xy 378.824541 -269.692246) (xy 378.824998 -269.682976) (xy 378.824998 -269.155926)
			(xy 378.824479 -269.146178) (xy 378.817024 -269.128155) (xy 378.81052 -269.120874) (xy 378.689108 -268.999462)
			(xy 378.682447 -268.993423) (xy 378.666043 -268.986098) (xy 378.648112 -268.984985) (xy 378.630928 -268.990224)
			(xy 378.623576 -268.995398) (xy 378.611638 -269.006066) (xy 378.605462 -269.013197) (xy 378.598417 -269.030682)
			(xy 378.597922 -269.040102) (xy 378.605288 -269.066264) (xy 378.608844 -269.072106) (xy 378.621899 -269.095593)
			(xy 378.640453 -269.146018) (xy 378.649904 -269.198911) (xy 378.6505 -269.225776) (xy 378.6505 -269.226284)
			(xy 378.649738 -269.24508) (xy 378.649484 -269.248636) (xy 378.647104 -269.273937) (xy 378.635011 -269.323292)
			(xy 378.614911 -269.369964) (xy 378.587359 -269.412661) (xy 378.553117 -269.450207) (xy 378.513129 -269.481562)
			(xy 378.468501 -269.505862) (xy 378.420464 -269.522436) (xy 378.370346 -269.530825) (xy 378.344938 -269.531338)
			(xy 378.319676 -269.530848) (xy 378.26984 -269.522538) (xy 378.222051 -269.506137) (xy 378.177614 -269.482094)
			(xy 378.137741 -269.451064) (xy 378.10352 -269.413894) (xy 378.075883 -269.371598) (xy 378.055587 -269.32533)
			(xy 378.043183 -269.276352) (xy 378.03901 -269.226) (xy 378.043183 -269.175648) (xy 378.055587 -269.12667)
			(xy 378.075883 -269.080402) (xy 378.10352 -269.038106) (xy 378.137741 -269.000936) (xy 378.177614 -268.969906)
			(xy 378.222051 -268.945863) (xy 378.26984 -268.929462) (xy 378.319676 -268.921152) (xy 378.344938 -268.920722)
			(xy 378.36348 -268.92123) (xy 378.363734 -268.92123) (xy 378.3711 -268.921738) (xy 378.386086 -268.917928)
			(xy 378.392182 -268.914372) (xy 378.398377 -268.910314) (xy 378.408325 -268.899352) (xy 378.41174 -268.892782)
			(xy 378.431552 -268.849094) (xy 378.450602 -268.806676) (xy 378.45434 -268.79727) (xy 378.454773 -268.777053)
			(xy 378.447253 -268.758282) (xy 378.440442 -268.750796) (xy 378.27331 -268.583664) (xy 378.265613 -268.576738)
			(xy 378.246327 -268.569262) (xy 378.235972 -268.569186) (xy 378.158248 -268.575282) (xy 378.152645 -268.57589)
			(xy 378.141882 -268.579228) (xy 378.136912 -268.581886) (xy 378.128276 -268.586712) (xy 378.121926 -268.595348)
			(xy 378.11964 -268.598396) (xy 378.105129 -268.617126) (xy 378.071295 -268.650292) (xy 378.032744 -268.677834)
			(xy 377.990402 -268.699089) (xy 377.945283 -268.713549) (xy 377.898473 -268.720865) (xy 377.874784 -268.721332)
			(xy 377.874276 -268.721332) (xy 377.862672 -268.721215) (xy 377.839533 -268.719437) (xy 377.828048 -268.717776)
			(xy 377.825 -268.717268) (xy 377.823984 -268.717268) (xy 377.799672 -268.712684) (xy 377.752852 -268.696709)
			(xy 377.709216 -268.673402) (xy 377.669903 -268.64337) (xy 377.635941 -268.607398) (xy 377.608216 -268.566427)
			(xy 377.587452 -268.521524) (xy 377.580398 -268.497812) (xy 377.579636 -268.49451) (xy 377.576904 -268.487434)
			(xy 377.567992 -268.475169) (xy 377.56211 -268.47038) (xy 377.556014 -268.465808) (xy 377.548648 -268.463268)
			(xy 377.544641 -268.461982) (xy 377.536345 -268.460574) (xy 377.532138 -268.460474) (xy 377.277376 -268.460474)
			(xy 377.27128 -268.460728) (xy 377.264605 -268.461777) (xy 377.25212 -268.466932) (xy 377.246642 -268.470888)
			(xy 377.240546 -268.47546) (xy 377.231402 -268.488922) (xy 377.229116 -268.497558) (xy 377.222015 -268.521373)
			(xy 377.201175 -268.566484) (xy 377.173308 -268.607627) (xy 377.139149 -268.643716) (xy 377.099599 -268.673801)
			(xy 377.055701 -268.697088) (xy 377.008613 -268.712962) (xy 376.959576 -268.721005) (xy 376.909884 -268.721005)
			(xy 376.860847 -268.712962) (xy 376.813759 -268.697088) (xy 376.769861 -268.673801) (xy 376.730311 -268.643716)
			(xy 376.696152 -268.607627) (xy 376.668285 -268.566484) (xy 376.647445 -268.521373) (xy 376.640344 -268.497558)
			(xy 376.639582 -268.49451) (xy 376.636852 -268.487432) (xy 376.627946 -268.475161) (xy 376.622056 -268.47038)
			(xy 376.61596 -268.465808) (xy 376.608594 -268.463268) (xy 376.604586 -268.461987) (xy 376.59629 -268.460587)
			(xy 376.592084 -268.460474) (xy 376.337576 -268.460474) (xy 376.33148 -268.460728) (xy 376.324805 -268.461777)
			(xy 376.31232 -268.466932) (xy 376.306842 -268.470888) (xy 376.300746 -268.47546) (xy 376.291602 -268.488922)
			(xy 376.289316 -268.497558) (xy 376.282215 -268.521373) (xy 376.261375 -268.566484) (xy 376.233508 -268.607627)
			(xy 376.199349 -268.643716) (xy 376.159799 -268.673801) (xy 376.115901 -268.697088) (xy 376.068813 -268.712962)
			(xy 376.019776 -268.721005) (xy 375.970084 -268.721005) (xy 375.921047 -268.712962) (xy 375.873959 -268.697088)
			(xy 375.830061 -268.673801) (xy 375.790511 -268.643716) (xy 375.756352 -268.607627) (xy 375.728485 -268.566484)
			(xy 375.707645 -268.521373) (xy 375.700544 -268.497558) (xy 375.699782 -268.49451) (xy 375.697052 -268.487432)
			(xy 375.688146 -268.475161) (xy 375.682256 -268.47038) (xy 375.67616 -268.465808) (xy 375.668794 -268.463268)
			(xy 375.664786 -268.461987) (xy 375.65649 -268.460587) (xy 375.652284 -268.460474) (xy 375.397522 -268.460474)
			(xy 375.391426 -268.460728) (xy 375.384748 -268.461771) (xy 375.372257 -268.466917) (xy 375.366788 -268.470888)
			(xy 375.360692 -268.47546) (xy 375.351548 -268.488922) (xy 375.349262 -268.497558) (xy 375.342142 -268.521357)
			(xy 375.321274 -268.566433) (xy 375.293392 -268.607541) (xy 375.259228 -268.643599) (xy 375.219684 -268.673658)
			(xy 375.175799 -268.696926) (xy 375.128728 -268.712792) (xy 375.079712 -268.720836) (xy 375.054876 -268.721332)
			(xy 375.030885 -268.72086) (xy 374.983495 -268.713351) (xy 374.937863 -268.698521) (xy 374.895112 -268.676737)
			(xy 374.856294 -268.648534) (xy 374.822366 -268.614606) (xy 374.794163 -268.575788) (xy 374.772379 -268.533037)
			(xy 374.757549 -268.487405) (xy 374.75004 -268.440015) (xy 374.749568 -268.416024) (xy 374.750217 -268.388074)
			(xy 374.760426 -268.333114) (xy 374.780455 -268.280924) (xy 374.794526 -268.256766) (xy 374.795034 -268.256004)
			(xy 374.79605 -268.25448) (xy 374.799098 -268.2494) (xy 374.802654 -268.23289) (xy 374.801638 -268.22527)
			(xy 374.800344 -268.216859) (xy 374.792935 -268.20155) (xy 374.78716 -268.195298) (xy 374.48744 -267.895578)
			(xy 374.47728 -267.891768) (xy 374.453114 -267.882123) (xy 374.408221 -267.855827) (xy 374.368433 -267.822304)
			(xy 374.334902 -267.782522) (xy 374.308599 -267.737632) (xy 374.298972 -267.71346) (xy 374.295162 -267.7033)
			(xy 373.95531 -267.363448) (xy 373.948061 -267.356897) (xy 373.930018 -267.349453) (xy 373.920258 -267.34897)
			(xy 373.078502 -267.34897) (xy 373.066103 -267.349625) (xy 373.044259 -267.36136) (xy 373.036846 -267.371322)
			(xy 372.990872 -267.440664) (xy 372.987498 -267.445966) (xy 372.983265 -267.457795) (xy 372.98249 -267.464032)
			(xy 372.981474 -267.476224) (xy 372.986554 -267.488162) (xy 372.997547 -267.516246) (xy 373.009445 -267.57536)
			(xy 373.010176 -267.60551) (xy 373.010176 -267.608812) (xy 373.009437 -267.633916) (xy 373.000766 -267.683381)
			(xy 372.984117 -267.73076) (xy 372.959939 -267.774776) (xy 372.928884 -267.814242) (xy 372.89179 -267.848094)
			(xy 372.849656 -267.875419) (xy 372.803618 -267.895481) (xy 372.754918 -267.907739) (xy 372.704868 -267.911862)
			(xy 372.654818 -267.907739) (xy 372.606118 -267.895481) (xy 372.56008 -267.875419) (xy 372.517946 -267.848094)
			(xy 372.480852 -267.814242) (xy 372.449797 -267.774776) (xy 372.425619 -267.73076) (xy 372.40897 -267.683381)
			(xy 372.400299 -267.633916) (xy 372.39956 -267.608812) (xy 372.39956 -267.605764) (xy 372.400293 -267.575553)
			(xy 372.412188 -267.516311) (xy 372.423182 -267.488162) (xy 372.423182 -267.487908) (xy 372.425456 -267.482091)
			(xy 372.427393 -267.469756) (xy 372.426992 -267.463524) (xy 372.425976 -267.451332) (xy 372.37289 -267.371322)
			(xy 372.365479 -267.361365) (xy 372.343628 -267.349658) (xy 372.331234 -267.34897) (xy 372.112286 -267.34897)
			(xy 372.102445 -267.348443) (xy 372.084272 -267.340867) (xy 372.07698 -267.334238) (xy 371.69852 -266.955778)
			(xy 371.691145 -266.94907) (xy 371.672672 -266.941621) (xy 371.662706 -266.9413) (xy 371.608858 -266.946126)
			(xy 371.594634 -266.947396) (xy 371.582255 -266.970801) (xy 371.551264 -267.013729) (xy 371.513921 -267.051261)
			(xy 371.47115 -267.082468) (xy 371.424013 -267.106577) (xy 371.373676 -267.12299) (xy 371.321387 -267.131301)
			(xy 371.294914 -267.1318) (xy 371.268524 -267.13131) (xy 371.216395 -267.123056) (xy 371.166198 -267.106748)
			(xy 371.119171 -267.082789) (xy 371.076471 -267.051768) (xy 371.039149 -267.014449) (xy 371.008125 -266.971751)
			(xy 370.984162 -266.924726) (xy 370.96785 -266.87453) (xy 370.959592 -266.822401) (xy 370.959126 -266.796012)
			(xy 370.959627 -266.769485) (xy 370.967974 -266.717092) (xy 370.98446 -266.666664) (xy 371.008676 -266.619459)
			(xy 371.040017 -266.576652) (xy 371.077704 -266.53931) (xy 371.120797 -266.508364) (xy 371.144292 -266.496038)
			(xy 371.152467 -266.491472) (xy 371.165066 -266.477642) (xy 371.171848 -266.460206) (xy 371.171904 -266.441497)
			(xy 371.165228 -266.42402) (xy 371.159278 -266.41679) (xy 371.152249 -266.411049) (xy 371.135323 -266.404539)
			(xy 371.126258 -266.40409) (xy 370.283486 -266.40409) (xy 370.273644 -266.404615) (xy 370.255467 -266.412187)
			(xy 370.24818 -266.418822) (xy 369.398804 -267.268198) (xy 369.391568 -267.274915) (xy 369.373362 -267.282517)
			(xy 369.363498 -267.28293) (xy 369.283234 -267.28293) (xy 369.274245 -267.283364) (xy 369.257438 -267.289763)
			(xy 369.243922 -267.301627) (xy 369.239292 -267.309346) (xy 369.218464 -267.347954) (xy 369.197128 -267.387324)
			(xy 369.194339 -267.393348) (xy 369.191642 -267.406341) (xy 369.191794 -267.412978) (xy 369.192302 -267.42644)
			(xy 369.19281 -267.427202) (xy 369.200176 -267.438378) (xy 369.212003 -267.457154) (xy 369.230701 -267.497398)
			(xy 369.243388 -267.539921) (xy 369.249797 -267.58383) (xy 369.250214 -267.606018) (xy 370.518956 -267.606018)
			(xy 370.522916 -267.556964) (xy 370.534693 -267.50918) (xy 370.553984 -267.463904) (xy 370.580287 -267.422308)
			(xy 370.612922 -267.385471) (xy 370.651043 -267.354346) (xy 370.693664 -267.329739) (xy 370.73968 -267.312287)
			(xy 370.787899 -267.302443) (xy 370.837074 -267.300462) (xy 370.885929 -267.306394) (xy 370.9332 -267.320086)
			(xy 370.977662 -267.341184) (xy 371.018165 -267.36914) (xy 371.053658 -267.403232) (xy 371.083223 -267.442576)
			(xy 371.106094 -267.486153) (xy 371.121678 -267.532834) (xy 371.129573 -267.581411) (xy 371.130068 -267.606018)
			(xy 371.129573 -267.630625) (xy 371.121678 -267.679202) (xy 371.106094 -267.725883) (xy 371.083223 -267.76946)
			(xy 371.053658 -267.808804) (xy 371.018165 -267.842896) (xy 370.977662 -267.870852) (xy 370.9332 -267.89195)
			(xy 370.885929 -267.905642) (xy 370.837074 -267.911574) (xy 370.787899 -267.909593) (xy 370.73968 -267.899749)
			(xy 370.693664 -267.882297) (xy 370.651043 -267.85769) (xy 370.612922 -267.826565) (xy 370.580287 -267.789728)
			(xy 370.553984 -267.748132) (xy 370.534693 -267.702856) (xy 370.522916 -267.655072) (xy 370.518956 -267.606018)
			(xy 369.250214 -267.606018) (xy 369.250214 -267.614908) (xy 369.249706 -267.622274) (xy 369.2478 -267.64796)
			(xy 369.236466 -267.698201) (xy 369.216863 -267.745827) (xy 369.189547 -267.78949) (xy 369.155294 -267.827951)
			(xy 369.115073 -267.86012) (xy 369.070025 -267.885085) (xy 369.021427 -267.902139) (xy 368.970657 -267.910797)
			(xy 368.944906 -267.911326) (xy 368.920914 -267.910856) (xy 368.87352 -267.903351) (xy 368.827884 -267.888524)
			(xy 368.78513 -267.866741) (xy 368.746309 -267.838538) (xy 368.712378 -267.80461) (xy 368.684172 -267.765791)
			(xy 368.662385 -267.723038) (xy 368.647555 -267.677403) (xy 368.640046 -267.63001) (xy 368.639598 -267.606018)
			(xy 368.639708 -267.594351) (xy 368.641487 -267.571084) (xy 368.643154 -267.559536) (xy 368.643662 -267.555726)
			(xy 368.643662 -267.555218) (xy 368.647533 -267.534448) (xy 368.660232 -267.494152) (xy 368.678347 -267.455983)
			(xy 368.689636 -267.438124) (xy 368.69751 -267.426186) (xy 368.698018 -267.412978) (xy 368.698169 -267.406342)
			(xy 368.695469 -267.39335) (xy 368.692684 -267.387324) (xy 368.671348 -267.347954) (xy 368.65052 -267.309346)
			(xy 368.64595 -267.301578) (xy 368.632427 -267.289685) (xy 368.615582 -267.283316) (xy 368.606578 -267.28293)
			(xy 368.215926 -267.28293) (xy 368.206088 -267.282394) (xy 368.187925 -267.27481) (xy 368.18062 -267.268198)
			(xy 367.90757 -266.995148) (xy 367.900532 -266.988741) (xy 367.883031 -266.981304) (xy 367.873534 -266.98067)
			(xy 367.821464 -266.98194) (xy 367.820956 -266.98194) (xy 367.796572 -266.982702) (xy 367.791908 -266.983111)
			(xy 367.782833 -266.985411) (xy 367.778538 -266.987274) (xy 367.769648 -266.991592) (xy 367.762282 -266.99972)
			(xy 367.744761 -267.018478) (xy 367.704598 -267.050436) (xy 367.659661 -267.075236) (xy 367.611213 -267.092182)
			(xy 367.560615 -267.100797) (xy 367.534952 -267.10132) (xy 367.534698 -267.10132) (xy 367.510707 -267.100849)
			(xy 367.463314 -267.093343) (xy 367.41768 -267.078516) (xy 367.374927 -267.056732) (xy 367.336107 -267.028529)
			(xy 367.302178 -266.9946) (xy 367.273973 -266.955782) (xy 367.252188 -266.913029) (xy 367.237359 -266.867395)
			(xy 367.229852 -266.820003) (xy 367.22939 -266.796012) (xy 367.22988 -266.771479) (xy 367.237735 -266.723046)
			(xy 367.253245 -266.676497) (xy 367.264188 -266.654534) (xy 367.264442 -266.65428) (xy 367.267236 -266.648438)
			(xy 367.27003 -266.635992) (xy 367.269776 -266.629896) (xy 367.269362 -266.624038) (xy 367.266154 -266.612745)
			(xy 367.263426 -266.607544) (xy 367.240312 -266.568936) (xy 367.218214 -266.53236) (xy 367.213496 -266.525204)
			(xy 367.20024 -266.514359) (xy 367.184106 -266.508611) (xy 367.175542 -266.50823) (xy 366.404906 -266.50823)
			(xy 366.395071 -266.508771) (xy 366.376919 -266.516367) (xy 366.3696 -266.522962) (xy 365.583724 -267.308838)
			(xy 365.576487 -267.315554) (xy 365.558282 -267.323157) (xy 365.548418 -267.32357) (xy 365.54664 -267.32357)
			(xy 365.538144 -267.323947) (xy 365.52214 -267.329667) (xy 365.508938 -267.34037) (xy 365.504222 -267.347446)
			(xy 365.498634 -267.356336) (xy 365.459518 -267.419836) (xy 365.456234 -267.425482) (xy 365.452384 -267.437959)
			(xy 365.451898 -267.444474) (xy 365.45139 -267.45692) (xy 365.457486 -267.468858) (xy 365.467734 -267.490255)
			(xy 365.482221 -267.535428) (xy 365.489552 -267.582298) (xy 365.489998 -267.606018) (xy 366.758994 -267.606018)
			(xy 366.762954 -267.556964) (xy 366.774731 -267.50918) (xy 366.794022 -267.463904) (xy 366.820325 -267.422308)
			(xy 366.85296 -267.385471) (xy 366.891081 -267.354346) (xy 366.933702 -267.329739) (xy 366.979718 -267.312287)
			(xy 367.027937 -267.302443) (xy 367.077112 -267.300462) (xy 367.125967 -267.306394) (xy 367.173238 -267.320086)
			(xy 367.2177 -267.341184) (xy 367.258203 -267.36914) (xy 367.293696 -267.403232) (xy 367.323261 -267.442576)
			(xy 367.346132 -267.486153) (xy 367.361716 -267.532834) (xy 367.369611 -267.581411) (xy 367.370106 -267.606018)
			(xy 367.369611 -267.630625) (xy 367.361716 -267.679202) (xy 367.346132 -267.725883) (xy 367.323261 -267.76946)
			(xy 367.293696 -267.808804) (xy 367.258203 -267.842896) (xy 367.2177 -267.870852) (xy 367.173238 -267.89195)
			(xy 367.125967 -267.905642) (xy 367.077112 -267.911574) (xy 367.027937 -267.909593) (xy 366.979718 -267.899749)
			(xy 366.933702 -267.882297) (xy 366.891081 -267.85769) (xy 366.85296 -267.826565) (xy 366.820325 -267.789728)
			(xy 366.794022 -267.748132) (xy 366.774731 -267.702856) (xy 366.762954 -267.655072) (xy 366.758994 -267.606018)
			(xy 365.489998 -267.606018) (xy 365.489526 -267.630008) (xy 365.482018 -267.677397) (xy 365.467189 -267.723028)
			(xy 365.445404 -267.765777) (xy 365.4172 -267.804593) (xy 365.383271 -267.838518) (xy 365.344453 -267.866718)
			(xy 365.301702 -267.888499) (xy 365.25607 -267.903324) (xy 365.20868 -267.910828) (xy 365.18469 -267.911326)
			(xy 365.160451 -267.91086) (xy 365.112583 -267.903201) (xy 365.066525 -267.888076) (xy 365.023435 -267.865866)
			(xy 364.984394 -267.837128) (xy 364.950383 -267.802583) (xy 364.922256 -267.7631) (xy 364.900719 -267.719669)
			(xy 364.886312 -267.673382) (xy 364.88243 -267.649452) (xy 364.880652 -267.636752) (xy 364.879128 -267.606018)
			(xy 364.879562 -267.582256) (xy 364.886886 -267.535301) (xy 364.90139 -267.490046) (xy 364.91164 -267.468604)
			(xy 364.914434 -267.463016) (xy 364.916035 -267.458359) (xy 364.917576 -267.448635) (xy 364.917482 -267.443712)
			(xy 364.916974 -267.43152) (xy 364.870746 -267.356336) (xy 364.865158 -267.347446) (xy 364.860431 -267.340377)
			(xy 364.847238 -267.329662) (xy 364.831236 -267.323939) (xy 364.82274 -267.32357) (xy 364.438946 -267.32357)
			(xy 364.429108 -267.323036) (xy 364.410945 -267.31545) (xy 364.40364 -267.308838) (xy 364.118906 -267.024104)
			(xy 364.112575 -267.018226) (xy 364.096982 -267.010819) (xy 364.088426 -267.009626) (xy 364.029752 -267.008356)
			(xy 364.029244 -267.008356) (xy 364.013242 -267.008102) (xy 364.009015 -267.008312) (xy 364.000715 -267.009973)
			(xy 363.996732 -267.011404) (xy 363.98835 -267.014452) (xy 363.98073 -267.02131) (xy 363.963756 -267.036271)
			(xy 363.926224 -267.061538) (xy 363.885376 -267.080993) (xy 363.842105 -267.094211) (xy 363.797358 -267.100904)
			(xy 363.774736 -267.10132) (xy 363.749511 -267.100804) (xy 363.699746 -267.092516) (xy 363.65202 -267.07616)
			(xy 363.607633 -267.052181) (xy 363.567791 -267.02123) (xy 363.53358 -266.984152) (xy 363.50593 -266.941953)
			(xy 363.485592 -266.895784) (xy 363.473122 -266.846899) (xy 363.468858 -266.796629) (xy 363.472915 -266.746342)
			(xy 363.485185 -266.697406) (xy 363.494828 -266.674092) (xy 363.494828 -266.673838) (xy 363.495082 -266.67333)
			(xy 363.497419 -266.667528) (xy 363.499476 -266.655193) (xy 363.499146 -266.648946) (xy 363.49813 -266.637008)
			(xy 363.48162 -266.611862) (xy 363.44352 -266.55395) (xy 363.436035 -266.544903) (xy 363.41511 -266.534311)
			(xy 363.403388 -266.53363) (xy 362.638086 -266.53363) (xy 362.628245 -266.534157) (xy 362.610072 -266.541733)
			(xy 362.60278 -266.548362) (xy 361.88523 -267.265912) (xy 361.877832 -267.272757) (xy 361.859233 -267.28048)
			(xy 361.849162 -267.280898) (xy 361.76458 -267.280898) (xy 361.763818 -267.280898) (xy 361.751534 -267.281799)
			(xy 361.729882 -267.293458) (xy 361.722416 -267.30325) (xy 361.719876 -267.307568) (xy 361.677458 -267.386562)
			(xy 361.67352 -267.394725) (xy 361.671104 -267.412673) (xy 361.675108 -267.430336) (xy 361.679744 -267.438124)
			(xy 361.679744 -267.438378) (xy 361.69162 -267.457138) (xy 361.710407 -267.497366) (xy 361.723165 -267.539893)
			(xy 361.729626 -267.583819) (xy 361.730036 -267.606018) (xy 362.999032 -267.606018) (xy 363.002992 -267.556964)
			(xy 363.014769 -267.50918) (xy 363.03406 -267.463904) (xy 363.060363 -267.422308) (xy 363.092998 -267.385471)
			(xy 363.131119 -267.354346) (xy 363.17374 -267.329739) (xy 363.219756 -267.312287) (xy 363.267975 -267.302443)
			(xy 363.31715 -267.300462) (xy 363.366005 -267.306394) (xy 363.413276 -267.320086) (xy 363.457738 -267.341184)
			(xy 363.498241 -267.36914) (xy 363.533734 -267.403232) (xy 363.563299 -267.442576) (xy 363.58617 -267.486153)
			(xy 363.601754 -267.532834) (xy 363.609649 -267.581411) (xy 363.610144 -267.606018) (xy 363.609649 -267.630625)
			(xy 363.601754 -267.679202) (xy 363.58617 -267.725883) (xy 363.563299 -267.76946) (xy 363.533734 -267.808804)
			(xy 363.498241 -267.842896) (xy 363.457738 -267.870852) (xy 363.413276 -267.89195) (xy 363.366005 -267.905642)
			(xy 363.31715 -267.911574) (xy 363.267975 -267.909593) (xy 363.219756 -267.899749) (xy 363.17374 -267.882297)
			(xy 363.131119 -267.85769) (xy 363.092998 -267.826565) (xy 363.060363 -267.789728) (xy 363.03406 -267.748132)
			(xy 363.014769 -267.702856) (xy 363.002992 -267.655072) (xy 362.999032 -267.606018) (xy 361.730036 -267.606018)
			(xy 361.729514 -267.631273) (xy 361.721201 -267.681095) (xy 361.7048 -267.728869) (xy 361.680759 -267.773292)
			(xy 361.649735 -267.813152) (xy 361.612573 -267.847362) (xy 361.570287 -267.874988) (xy 361.524031 -267.895278)
			(xy 361.475066 -267.907678) (xy 361.424728 -267.911849) (xy 361.37439 -267.907678) (xy 361.325425 -267.895278)
			(xy 361.279169 -267.874988) (xy 361.236883 -267.847362) (xy 361.199721 -267.813152) (xy 361.168697 -267.773292)
			(xy 361.144656 -267.728869) (xy 361.128255 -267.681095) (xy 361.119942 -267.631273) (xy 361.11942 -267.606018)
			(xy 361.119876 -267.582279) (xy 361.127234 -267.535374) (xy 361.141761 -267.490173) (xy 361.163106 -267.447763)
			(xy 361.190755 -267.409166) (xy 361.20705 -267.391896) (xy 361.213449 -267.384806) (xy 361.220899 -267.367236)
			(xy 361.221392 -267.348159) (xy 361.21848 -267.339064) (xy 361.197652 -267.280898) (xy 361.19308 -267.280898)
			(xy 361.183936 -267.277088) (xy 361.179372 -267.275081) (xy 361.171057 -267.269583) (xy 361.167426 -267.266166)
			(xy 360.687112 -266.785852) (xy 360.684262 -266.783145) (xy 360.677885 -266.778549) (xy 360.674412 -266.776708)
			(xy 360.668984 -266.774129) (xy 360.657305 -266.771315) (xy 360.651298 -266.77112) (xy 359.211372 -266.77112)
			(xy 359.205362 -266.771285) (xy 359.193678 -266.774105) (xy 359.188258 -266.776708) (xy 359.184785 -266.778549)
			(xy 359.178409 -266.783145) (xy 359.175558 -266.785852) (xy 358.680766 -267.280644) (xy 358.673368 -267.287491)
			(xy 358.65477 -267.295222) (xy 358.644698 -267.29563) (xy 358.017572 -267.29563) (xy 358.00875 -267.29597)
			(xy 357.992193 -267.302062) (xy 357.978773 -267.313515) (xy 357.974138 -267.32103) (xy 357.931212 -267.39723)
			(xy 357.928161 -267.403124) (xy 357.924936 -267.415994) (xy 357.924862 -267.42263) (xy 357.924862 -267.435584)
			(xy 357.93045 -267.444728) (xy 357.932228 -267.447522) (xy 357.946073 -267.471526) (xy 357.965775 -267.523314)
			(xy 357.975808 -267.577806) (xy 357.976424 -267.60551) (xy 357.976424 -267.612368) (xy 357.975491 -267.636035)
			(xy 357.967218 -267.682668) (xy 357.951842 -267.727465) (xy 357.929732 -267.769349) (xy 357.90142 -267.807317)
			(xy 357.867583 -267.840457) (xy 357.829035 -267.867973) (xy 357.786699 -267.889206) (xy 357.741593 -267.903647)
			(xy 357.694797 -267.910948) (xy 357.671116 -267.911326) (xy 357.647123 -267.910857) (xy 357.599729 -267.903353)
			(xy 357.554091 -267.888527) (xy 357.511335 -267.866744) (xy 357.472513 -267.838542) (xy 357.438581 -267.804613)
			(xy 357.410373 -267.765794) (xy 357.388586 -267.72304) (xy 357.373755 -267.677404) (xy 357.366246 -267.630011)
			(xy 357.365808 -267.606018) (xy 357.366298 -267.581452) (xy 357.374161 -267.532953) (xy 357.389688 -267.486339)
			(xy 357.412477 -267.442811) (xy 357.441941 -267.403494) (xy 357.47732 -267.369402) (xy 357.517701 -267.341413)
			(xy 357.562042 -267.320251) (xy 357.609199 -267.30646) (xy 357.633524 -267.302996) (xy 357.635556 -267.302742)
			(xy 357.642124 -267.301496) (xy 357.654353 -267.296104) (xy 357.659686 -267.292074) (xy 357.664512 -267.28801)
			(xy 357.668322 -267.282676) (xy 357.67037 -267.279655) (xy 357.673683 -267.273153) (xy 357.674926 -267.269722)
			(xy 357.704136 -267.184632) (xy 357.706884 -267.175642) (xy 357.706182 -267.156872) (xy 357.698623 -267.139676)
			(xy 357.692198 -267.132816) (xy 357.56469 -267.005308) (xy 357.557656 -266.998891) (xy 357.540155 -266.991439)
			(xy 357.530654 -266.99083) (xy 357.512112 -266.991084) (xy 357.457248 -266.991846) (xy 357.452216 -266.991987)
			(xy 357.442361 -266.994033) (xy 357.43769 -266.99591) (xy 357.429308 -266.999466) (xy 357.422196 -267.006832)
			(xy 357.421942 -267.007086) (xy 357.404535 -267.024588) (xy 357.365114 -267.054294) (xy 357.321429 -267.077274)
			(xy 357.274617 -267.092931) (xy 357.225896 -267.100855) (xy 357.201216 -267.10132) (xy 357.177222 -267.100875)
			(xy 357.129824 -267.09337) (xy 357.084183 -267.078543) (xy 357.041424 -267.056759) (xy 357.002599 -267.028554)
			(xy 356.968664 -266.994622) (xy 356.940456 -266.9558) (xy 356.918667 -266.913043) (xy 356.903836 -266.867404)
			(xy 356.896327 -266.820006) (xy 356.895908 -266.796012) (xy 356.896367 -266.771852) (xy 356.903979 -266.724134)
			(xy 356.919016 -266.678213) (xy 356.9411 -266.635234) (xy 356.969682 -266.596272) (xy 357.004046 -266.562301)
			(xy 357.023416 -266.547854) (xy 357.025702 -266.546076) (xy 357.02748 -266.544806) (xy 357.033322 -266.538964)
			(xy 357.039112 -266.531593) (xy 357.045235 -266.513892) (xy 357.044451 -266.495178) (xy 357.036872 -266.47805)
			(xy 357.030528 -266.471146) (xy 357.02875 -266.469368) (xy 357.021504 -266.462809) (xy 357.003461 -266.455348)
			(xy 356.993698 -266.45489) (xy 356.247446 -266.45489) (xy 356.237607 -266.455423) (xy 356.219441 -266.463004)
			(xy 356.21214 -266.469622) (xy 355.426264 -267.255498) (xy 355.419025 -267.262209) (xy 355.40082 -267.269796)
			(xy 355.390958 -267.27023) (xy 354.240846 -267.27023) (xy 354.231865 -267.270595) (xy 354.215039 -267.276877)
			(xy 354.201484 -267.28866) (xy 354.196904 -267.296392) (xy 354.192586 -267.305028) (xy 354.154486 -267.37945)
			(xy 354.152101 -267.385176) (xy 354.149923 -267.397382) (xy 354.150168 -267.40358) (xy 354.151184 -267.416534)
			(xy 354.15982 -267.428726) (xy 354.17317 -267.448255) (xy 354.194327 -267.490564) (xy 354.208717 -267.535626)
			(xy 354.215998 -267.582366) (xy 354.216462 -267.606018) (xy 355.485204 -267.606018) (xy 355.489164 -267.556964)
			(xy 355.500941 -267.50918) (xy 355.520232 -267.463904) (xy 355.546535 -267.422308) (xy 355.57917 -267.385471)
			(xy 355.617291 -267.354346) (xy 355.659912 -267.329739) (xy 355.705928 -267.312287) (xy 355.754147 -267.302443)
			(xy 355.803322 -267.300462) (xy 355.852177 -267.306394) (xy 355.899448 -267.320086) (xy 355.94391 -267.341184)
			(xy 355.984413 -267.36914) (xy 356.019906 -267.403232) (xy 356.049471 -267.442576) (xy 356.072342 -267.486153)
			(xy 356.087926 -267.532834) (xy 356.095821 -267.581411) (xy 356.096316 -267.606018) (xy 356.095821 -267.630625)
			(xy 356.087926 -267.679202) (xy 356.072342 -267.725883) (xy 356.049471 -267.76946) (xy 356.019906 -267.808804)
			(xy 355.984413 -267.842896) (xy 355.94391 -267.870852) (xy 355.899448 -267.89195) (xy 355.852177 -267.905642)
			(xy 355.803322 -267.911574) (xy 355.754147 -267.909593) (xy 355.705928 -267.899749) (xy 355.659912 -267.882297)
			(xy 355.617291 -267.85769) (xy 355.57917 -267.826565) (xy 355.546535 -267.789728) (xy 355.520232 -267.748132)
			(xy 355.500941 -267.702856) (xy 355.489164 -267.655072) (xy 355.485204 -267.606018) (xy 354.216462 -267.606018)
			(xy 354.21594 -267.631273) (xy 354.207627 -267.681095) (xy 354.191226 -267.728869) (xy 354.167185 -267.773292)
			(xy 354.136161 -267.813152) (xy 354.098999 -267.847362) (xy 354.056713 -267.874988) (xy 354.010457 -267.895278)
			(xy 353.961492 -267.907678) (xy 353.911154 -267.911849) (xy 353.860816 -267.907678) (xy 353.811851 -267.895278)
			(xy 353.765595 -267.874988) (xy 353.723309 -267.847362) (xy 353.686147 -267.813152) (xy 353.655123 -267.773292)
			(xy 353.631082 -267.728869) (xy 353.614681 -267.681095) (xy 353.606368 -267.631273) (xy 353.605846 -267.606018)
			(xy 353.606354 -267.580557) (xy 353.614798 -267.530339) (xy 353.631457 -267.482218) (xy 353.655867 -267.437527)
			(xy 353.687352 -267.397504) (xy 353.725041 -267.363259) (xy 353.767888 -267.335741) (xy 353.814706 -267.315711)
			(xy 353.864199 -267.303726) (xy 353.889564 -267.301472) (xy 353.891596 -267.301218) (xy 353.898513 -267.300315)
			(xy 353.911519 -267.295289) (xy 353.91725 -267.291312) (xy 353.92233 -267.287502) (xy 353.926648 -267.28166)
			(xy 353.933252 -267.269468) (xy 353.965256 -267.18387) (xy 353.968277 -267.174739) (xy 353.9679 -267.155527)
			(xy 353.960337 -267.137863) (xy 353.953826 -267.130784) (xy 353.815904 -266.992862) (xy 353.808314 -266.986012)
			(xy 353.789299 -266.978555) (xy 353.779074 -266.978384) (xy 353.706176 -266.980924) (xy 353.705414 -266.980924)
			(xy 353.700487 -266.981224) (xy 353.690888 -266.983522) (xy 353.686364 -266.985496) (xy 353.67722 -266.989814)
			(xy 353.676712 -266.990322) (xy 353.669854 -266.998196) (xy 353.652299 -267.017225) (xy 353.611961 -267.04967)
			(xy 353.566733 -267.074857) (xy 353.517909 -267.092065) (xy 353.466884 -267.100802) (xy 353.441 -267.10132)
			(xy 353.417008 -267.100849) (xy 353.369616 -267.093343) (xy 353.323981 -267.078516) (xy 353.281228 -267.056733)
			(xy 353.242408 -267.02853) (xy 353.208478 -266.994601) (xy 353.180274 -266.955783) (xy 353.158488 -266.91303)
			(xy 353.143659 -266.867396) (xy 353.136152 -266.820004) (xy 353.135692 -266.796012) (xy 353.136182 -266.771479)
			(xy 353.144037 -266.723046) (xy 353.159547 -266.676497) (xy 353.17049 -266.654534) (xy 353.170744 -266.65428)
			(xy 353.173538 -266.648438) (xy 353.176332 -266.635992) (xy 353.176078 -266.629896) (xy 353.175664 -266.624038)
			(xy 353.172456 -266.612744) (xy 353.169728 -266.607544) (xy 353.146614 -266.568936) (xy 353.124516 -266.53236)
			(xy 353.119798 -266.525204) (xy 353.106542 -266.514358) (xy 353.090408 -266.508609) (xy 353.081844 -266.50823)
			(xy 352.429826 -266.50823) (xy 352.41999 -266.508767) (xy 352.401832 -266.516359) (xy 352.39452 -266.522962)
			(xy 351.583244 -267.334238) (xy 351.576008 -267.340957) (xy 351.557803 -267.348567) (xy 351.547938 -267.34897)
			(xy 350.524826 -267.34897) (xy 350.512424 -267.34962) (xy 350.490571 -267.361349) (xy 350.48317 -267.371322)
			(xy 350.437196 -267.440664) (xy 350.433827 -267.445968) (xy 350.4296 -267.457797) (xy 350.428814 -267.464032)
			(xy 350.427798 -267.476224) (xy 350.432878 -267.488162) (xy 350.44387 -267.516246) (xy 350.455767 -267.57536)
			(xy 350.4565 -267.60551) (xy 350.4565 -267.606018) (xy 351.725242 -267.606018) (xy 351.729202 -267.556964)
			(xy 351.740979 -267.50918) (xy 351.76027 -267.463904) (xy 351.786573 -267.422308) (xy 351.819208 -267.385471)
			(xy 351.857329 -267.354346) (xy 351.89995 -267.329739) (xy 351.945966 -267.312287) (xy 351.994185 -267.302443)
			(xy 352.04336 -267.300462) (xy 352.092215 -267.306394) (xy 352.139486 -267.320086) (xy 352.183948 -267.341184)
			(xy 352.224451 -267.36914) (xy 352.259944 -267.403232) (xy 352.289509 -267.442576) (xy 352.31238 -267.486153)
			(xy 352.327964 -267.532834) (xy 352.335859 -267.581411) (xy 352.336354 -267.606018) (xy 352.335859 -267.630625)
			(xy 352.327964 -267.679202) (xy 352.31238 -267.725883) (xy 352.289509 -267.76946) (xy 352.259944 -267.808804)
			(xy 352.224451 -267.842896) (xy 352.183948 -267.870852) (xy 352.139486 -267.89195) (xy 352.092215 -267.905642)
			(xy 352.04336 -267.911574) (xy 351.994185 -267.909593) (xy 351.945966 -267.899749) (xy 351.89995 -267.882297)
			(xy 351.857329 -267.85769) (xy 351.819208 -267.826565) (xy 351.786573 -267.789728) (xy 351.76027 -267.748132)
			(xy 351.740979 -267.702856) (xy 351.729202 -267.655072) (xy 351.725242 -267.606018) (xy 350.4565 -267.606018)
			(xy 350.4565 -267.608812) (xy 350.455821 -267.632658) (xy 350.447968 -267.679711) (xy 350.432893 -267.724969)
			(xy 350.410962 -267.767333) (xy 350.382709 -267.805769) (xy 350.348823 -267.839345) (xy 350.310126 -267.867241)
			(xy 350.267562 -267.888779) (xy 350.222167 -267.903436) (xy 350.175044 -267.910854) (xy 350.151192 -267.911326)
			(xy 350.125365 -267.910778) (xy 350.074449 -267.902074) (xy 350.025723 -267.884931) (xy 349.980572 -267.85984)
			(xy 349.940284 -267.827512) (xy 349.906006 -267.788871) (xy 349.878714 -267.745015) (xy 349.859185 -267.697195)
			(xy 349.847976 -267.646772) (xy 349.846138 -267.621004) (xy 349.845884 -267.615416) (xy 349.845884 -267.60551)
			(xy 349.846419 -267.579779) (xy 349.855033 -267.529043) (xy 349.872005 -267.48046) (xy 349.883984 -267.457682)
			(xy 349.885254 -267.45565) (xy 349.888556 -267.447776) (xy 349.891096 -267.440918) (xy 349.895414 -267.424916)
			(xy 349.895239 -267.419664) (xy 349.89294 -267.409413) (xy 349.890842 -267.404596) (xy 349.875602 -267.374878)
			(xy 349.871003 -267.367236) (xy 349.857526 -267.355572) (xy 349.840826 -267.349347) (xy 349.831914 -267.34897)
			(xy 349.831406 -267.34897) (xy 349.821571 -267.348429) (xy 349.803419 -267.340833) (xy 349.7961 -267.334238)
			(xy 349.515684 -267.053822) (xy 349.508826 -267.048234) (xy 349.507048 -267.046964) (xy 349.484896 -267.030868)
			(xy 349.446177 -266.992157) (xy 349.430086 -266.970002) (xy 349.428816 -266.968224) (xy 349.423228 -266.961366)
			(xy 349.02267 -266.560808) (xy 349.015422 -266.554252) (xy 348.99738 -266.546793) (xy 348.987618 -266.54633)
			(xy 348.627192 -266.54633) (xy 348.61735 -266.546855) (xy 348.599176 -266.55443) (xy 348.591886 -266.561062)
			(xy 347.645482 -267.507466) (xy 347.637396 -267.51659) (xy 347.630088 -267.539809) (xy 347.631512 -267.551916)
			(xy 347.631512 -267.55217) (xy 347.633768 -267.565518) (xy 347.636186 -267.592482) (xy 347.636338 -267.606018)
			(xy 347.96528 -267.606018) (xy 347.96924 -267.556964) (xy 347.981017 -267.50918) (xy 348.000308 -267.463904)
			(xy 348.026611 -267.422308) (xy 348.059246 -267.385471) (xy 348.097367 -267.354346) (xy 348.139988 -267.329739)
			(xy 348.186004 -267.312287) (xy 348.234223 -267.302443) (xy 348.283398 -267.300462) (xy 348.332253 -267.306394)
			(xy 348.379524 -267.320086) (xy 348.423986 -267.341184) (xy 348.464489 -267.36914) (xy 348.499982 -267.403232)
			(xy 348.529547 -267.442576) (xy 348.552418 -267.486153) (xy 348.568002 -267.532834) (xy 348.575897 -267.581411)
			(xy 348.576392 -267.606018) (xy 348.575897 -267.630625) (xy 348.568002 -267.679202) (xy 348.552418 -267.725883)
			(xy 348.529547 -267.76946) (xy 348.499982 -267.808804) (xy 348.464489 -267.842896) (xy 348.423986 -267.870852)
			(xy 348.379524 -267.89195) (xy 348.332253 -267.905642) (xy 348.283398 -267.911574) (xy 348.234223 -267.909593)
			(xy 348.186004 -267.899749) (xy 348.139988 -267.882297) (xy 348.097367 -267.85769) (xy 348.059246 -267.826565)
			(xy 348.026611 -267.789728) (xy 348.000308 -267.748132) (xy 347.981017 -267.702856) (xy 347.96924 -267.655072)
			(xy 347.96528 -267.606018) (xy 347.636338 -267.606018) (xy 347.635866 -267.630009) (xy 347.628358 -267.6774)
			(xy 347.613529 -267.723034) (xy 347.591745 -267.765786) (xy 347.563542 -267.804605) (xy 347.529614 -267.838534)
			(xy 347.490797 -267.866739) (xy 347.448045 -267.888525) (xy 347.402412 -267.903355) (xy 347.355021 -267.910865)
			(xy 347.33103 -267.911326) (xy 347.317494 -267.911165) (xy 347.29053 -267.90875) (xy 347.277182 -267.9065)
			(xy 347.276928 -267.9065) (xy 347.264823 -267.905119) (xy 347.241611 -267.912407) (xy 347.232478 -267.92047)
			(xy 347.147388 -268.00556) (xy 359.650541 -268.00556) (xy 359.654571 -267.953062) (xy 359.666568 -267.901794)
			(xy 359.686251 -267.852959) (xy 359.713157 -267.8077) (xy 359.746657 -267.767079) (xy 359.785965 -267.732048)
			(xy 359.83016 -267.703428) (xy 359.878205 -267.681889) (xy 359.928976 -267.667937) (xy 359.981281 -267.661899)
			(xy 360.033895 -267.663916) (xy 360.085585 -267.67394) (xy 360.135138 -267.691738) (xy 360.181394 -267.716891)
			(xy 360.223268 -267.74881) (xy 360.25978 -267.786748) (xy 360.290072 -267.829814) (xy 360.313435 -267.876999)
			(xy 360.329321 -267.927198) (xy 360.337358 -267.979234) (xy 360.337862 -268.00556) (xy 360.337358 -268.031886)
			(xy 360.329321 -268.083922) (xy 360.313435 -268.134121) (xy 360.290072 -268.181306) (xy 360.25978 -268.224372)
			(xy 360.223268 -268.26231) (xy 360.181394 -268.294229) (xy 360.135138 -268.319382) (xy 360.085585 -268.33718)
			(xy 360.033895 -268.347204) (xy 359.981281 -268.349221) (xy 359.928976 -268.343183) (xy 359.878205 -268.329231)
			(xy 359.83016 -268.307692) (xy 359.785965 -268.279072) (xy 359.746657 -268.244041) (xy 359.713157 -268.20342)
			(xy 359.686251 -268.158161) (xy 359.666568 -268.109326) (xy 359.654571 -268.058058) (xy 359.650541 -268.00556)
			(xy 347.147388 -268.00556) (xy 346.884244 -268.268704) (xy 346.876842 -268.275541) (xy 346.858244 -268.283255)
			(xy 346.848176 -268.28369) (xy 346.326714 -268.28369) (xy 346.316271 -268.284262) (xy 346.29714 -268.292664)
			(xy 346.28963 -268.299946) (xy 346.23883 -268.355064) (xy 346.235406 -268.358939) (xy 346.230035 -268.367771)
			(xy 346.228162 -268.37259) (xy 346.22486 -268.382242) (xy 346.225622 -268.39291) (xy 346.226384 -268.416024)
			(xy 347.49538 -268.416024) (xy 347.49934 -268.36697) (xy 347.511117 -268.319186) (xy 347.530408 -268.27391)
			(xy 347.556711 -268.232314) (xy 347.589346 -268.195477) (xy 347.627467 -268.164352) (xy 347.670088 -268.139745)
			(xy 347.716104 -268.122293) (xy 347.764323 -268.112449) (xy 347.813498 -268.110468) (xy 347.862353 -268.1164)
			(xy 347.909624 -268.130092) (xy 347.954086 -268.15119) (xy 347.994589 -268.179146) (xy 348.030082 -268.213238)
			(xy 348.059647 -268.252582) (xy 348.082518 -268.296159) (xy 348.098102 -268.34284) (xy 348.105997 -268.391417)
			(xy 348.106492 -268.416024) (xy 349.375234 -268.416024) (xy 349.379194 -268.36697) (xy 349.390971 -268.319186)
			(xy 349.410262 -268.27391) (xy 349.436565 -268.232314) (xy 349.4692 -268.195477) (xy 349.507321 -268.164352)
			(xy 349.549942 -268.139745) (xy 349.595958 -268.122293) (xy 349.644177 -268.112449) (xy 349.693352 -268.110468)
			(xy 349.742207 -268.1164) (xy 349.789478 -268.130092) (xy 349.83394 -268.15119) (xy 349.874443 -268.179146)
			(xy 349.909936 -268.213238) (xy 349.939501 -268.252582) (xy 349.962372 -268.296159) (xy 349.977956 -268.34284)
			(xy 349.985851 -268.391417) (xy 349.986346 -268.416024) (xy 351.255342 -268.416024) (xy 351.259302 -268.36697)
			(xy 351.271079 -268.319186) (xy 351.29037 -268.27391) (xy 351.316673 -268.232314) (xy 351.349308 -268.195477)
			(xy 351.387429 -268.164352) (xy 351.43005 -268.139745) (xy 351.476066 -268.122293) (xy 351.524285 -268.112449)
			(xy 351.57346 -268.110468) (xy 351.622315 -268.1164) (xy 351.669586 -268.130092) (xy 351.714048 -268.15119)
			(xy 351.754551 -268.179146) (xy 351.790044 -268.213238) (xy 351.819609 -268.252582) (xy 351.84248 -268.296159)
			(xy 351.858064 -268.34284) (xy 351.865959 -268.391417) (xy 351.866454 -268.416024) (xy 353.135196 -268.416024)
			(xy 353.139156 -268.36697) (xy 353.150933 -268.319186) (xy 353.170224 -268.27391) (xy 353.196527 -268.232314)
			(xy 353.229162 -268.195477) (xy 353.267283 -268.164352) (xy 353.309904 -268.139745) (xy 353.35592 -268.122293)
			(xy 353.404139 -268.112449) (xy 353.453314 -268.110468) (xy 353.502169 -268.1164) (xy 353.54944 -268.130092)
			(xy 353.593902 -268.15119) (xy 353.634405 -268.179146) (xy 353.669898 -268.213238) (xy 353.699463 -268.252582)
			(xy 353.722334 -268.296159) (xy 353.737918 -268.34284) (xy 353.745813 -268.391417) (xy 353.746308 -268.416024)
			(xy 355.015304 -268.416024) (xy 355.019264 -268.36697) (xy 355.031041 -268.319186) (xy 355.050332 -268.27391)
			(xy 355.076635 -268.232314) (xy 355.10927 -268.195477) (xy 355.147391 -268.164352) (xy 355.190012 -268.139745)
			(xy 355.236028 -268.122293) (xy 355.284247 -268.112449) (xy 355.333422 -268.110468) (xy 355.382277 -268.1164)
			(xy 355.429548 -268.130092) (xy 355.47401 -268.15119) (xy 355.514513 -268.179146) (xy 355.550006 -268.213238)
			(xy 355.579571 -268.252582) (xy 355.602442 -268.296159) (xy 355.618026 -268.34284) (xy 355.625921 -268.391417)
			(xy 355.626416 -268.416024) (xy 356.895412 -268.416024) (xy 356.899372 -268.36697) (xy 356.911149 -268.319186)
			(xy 356.93044 -268.27391) (xy 356.956743 -268.232314) (xy 356.989378 -268.195477) (xy 357.027499 -268.164352)
			(xy 357.07012 -268.139745) (xy 357.116136 -268.122293) (xy 357.164355 -268.112449) (xy 357.21353 -268.110468)
			(xy 357.262385 -268.1164) (xy 357.309656 -268.130092) (xy 357.354118 -268.15119) (xy 357.394621 -268.179146)
			(xy 357.430114 -268.213238) (xy 357.459679 -268.252582) (xy 357.48255 -268.296159) (xy 357.498134 -268.34284)
			(xy 357.506029 -268.391417) (xy 357.506524 -268.416024) (xy 361.589078 -268.416024) (xy 361.593038 -268.36697)
			(xy 361.604815 -268.319186) (xy 361.624106 -268.27391) (xy 361.650409 -268.232314) (xy 361.683044 -268.195477)
			(xy 361.721165 -268.164352) (xy 361.763786 -268.139745) (xy 361.809802 -268.122293) (xy 361.858021 -268.112449)
			(xy 361.907196 -268.110468) (xy 361.956051 -268.1164) (xy 362.003322 -268.130092) (xy 362.047784 -268.15119)
			(xy 362.088287 -268.179146) (xy 362.12378 -268.213238) (xy 362.153345 -268.252582) (xy 362.176216 -268.296159)
			(xy 362.1918 -268.34284) (xy 362.199695 -268.391417) (xy 362.20019 -268.416024) (xy 363.468932 -268.416024)
			(xy 363.472892 -268.36697) (xy 363.484669 -268.319186) (xy 363.50396 -268.27391) (xy 363.530263 -268.232314)
			(xy 363.562898 -268.195477) (xy 363.601019 -268.164352) (xy 363.64364 -268.139745) (xy 363.689656 -268.122293)
			(xy 363.737875 -268.112449) (xy 363.78705 -268.110468) (xy 363.835905 -268.1164) (xy 363.883176 -268.130092)
			(xy 363.927638 -268.15119) (xy 363.968141 -268.179146) (xy 364.003634 -268.213238) (xy 364.033199 -268.252582)
			(xy 364.05607 -268.296159) (xy 364.071654 -268.34284) (xy 364.079549 -268.391417) (xy 364.080044 -268.416024)
			(xy 365.34904 -268.416024) (xy 365.353 -268.36697) (xy 365.364777 -268.319186) (xy 365.384068 -268.27391)
			(xy 365.410371 -268.232314) (xy 365.443006 -268.195477) (xy 365.481127 -268.164352) (xy 365.523748 -268.139745)
			(xy 365.569764 -268.122293) (xy 365.617983 -268.112449) (xy 365.667158 -268.110468) (xy 365.716013 -268.1164)
			(xy 365.763284 -268.130092) (xy 365.807746 -268.15119) (xy 365.848249 -268.179146) (xy 365.883742 -268.213238)
			(xy 365.913307 -268.252582) (xy 365.936178 -268.296159) (xy 365.951762 -268.34284) (xy 365.959657 -268.391417)
			(xy 365.960152 -268.416024) (xy 367.228894 -268.416024) (xy 367.232854 -268.36697) (xy 367.244631 -268.319186)
			(xy 367.263922 -268.27391) (xy 367.290225 -268.232314) (xy 367.32286 -268.195477) (xy 367.360981 -268.164352)
			(xy 367.403602 -268.139745) (xy 367.449618 -268.122293) (xy 367.497837 -268.112449) (xy 367.547012 -268.110468)
			(xy 367.595867 -268.1164) (xy 367.643138 -268.130092) (xy 367.6876 -268.15119) (xy 367.728103 -268.179146)
			(xy 367.763596 -268.213238) (xy 367.793161 -268.252582) (xy 367.816032 -268.296159) (xy 367.831616 -268.34284)
			(xy 367.839511 -268.391417) (xy 367.840006 -268.416024) (xy 369.109002 -268.416024) (xy 369.112962 -268.36697)
			(xy 369.124739 -268.319186) (xy 369.14403 -268.27391) (xy 369.170333 -268.232314) (xy 369.202968 -268.195477)
			(xy 369.241089 -268.164352) (xy 369.28371 -268.139745) (xy 369.329726 -268.122293) (xy 369.377945 -268.112449)
			(xy 369.42712 -268.110468) (xy 369.475975 -268.1164) (xy 369.523246 -268.130092) (xy 369.567708 -268.15119)
			(xy 369.608211 -268.179146) (xy 369.643704 -268.213238) (xy 369.673269 -268.252582) (xy 369.69614 -268.296159)
			(xy 369.711724 -268.34284) (xy 369.719619 -268.391417) (xy 369.720114 -268.416024) (xy 370.98911 -268.416024)
			(xy 370.99307 -268.36697) (xy 371.004847 -268.319186) (xy 371.024138 -268.27391) (xy 371.050441 -268.232314)
			(xy 371.083076 -268.195477) (xy 371.121197 -268.164352) (xy 371.163818 -268.139745) (xy 371.209834 -268.122293)
			(xy 371.258053 -268.112449) (xy 371.307228 -268.110468) (xy 371.356083 -268.1164) (xy 371.403354 -268.130092)
			(xy 371.447816 -268.15119) (xy 371.488319 -268.179146) (xy 371.523812 -268.213238) (xy 371.553377 -268.252582)
			(xy 371.576248 -268.296159) (xy 371.591832 -268.34284) (xy 371.599727 -268.391417) (xy 371.600222 -268.416024)
			(xy 372.868964 -268.416024) (xy 372.872924 -268.36697) (xy 372.884701 -268.319186) (xy 372.903992 -268.27391)
			(xy 372.930295 -268.232314) (xy 372.96293 -268.195477) (xy 373.001051 -268.164352) (xy 373.043672 -268.139745)
			(xy 373.089688 -268.122293) (xy 373.137907 -268.112449) (xy 373.187082 -268.110468) (xy 373.235937 -268.1164)
			(xy 373.283208 -268.130092) (xy 373.32767 -268.15119) (xy 373.368173 -268.179146) (xy 373.403666 -268.213238)
			(xy 373.433231 -268.252582) (xy 373.456102 -268.296159) (xy 373.471686 -268.34284) (xy 373.479581 -268.391417)
			(xy 373.480076 -268.416024) (xy 373.479581 -268.440631) (xy 373.471686 -268.489208) (xy 373.456102 -268.535889)
			(xy 373.433231 -268.579466) (xy 373.403666 -268.61881) (xy 373.368173 -268.652902) (xy 373.32767 -268.680858)
			(xy 373.283208 -268.701956) (xy 373.235937 -268.715648) (xy 373.187082 -268.72158) (xy 373.137907 -268.719599)
			(xy 373.089688 -268.709755) (xy 373.043672 -268.692303) (xy 373.001051 -268.667696) (xy 372.96293 -268.636571)
			(xy 372.930295 -268.599734) (xy 372.903992 -268.558138) (xy 372.884701 -268.512862) (xy 372.872924 -268.465078)
			(xy 372.868964 -268.416024) (xy 371.600222 -268.416024) (xy 371.599727 -268.440631) (xy 371.591832 -268.489208)
			(xy 371.576248 -268.535889) (xy 371.553377 -268.579466) (xy 371.523812 -268.61881) (xy 371.488319 -268.652902)
			(xy 371.447816 -268.680858) (xy 371.403354 -268.701956) (xy 371.356083 -268.715648) (xy 371.307228 -268.72158)
			(xy 371.258053 -268.719599) (xy 371.209834 -268.709755) (xy 371.163818 -268.692303) (xy 371.121197 -268.667696)
			(xy 371.083076 -268.636571) (xy 371.050441 -268.599734) (xy 371.024138 -268.558138) (xy 371.004847 -268.512862)
			(xy 370.99307 -268.465078) (xy 370.98911 -268.416024) (xy 369.720114 -268.416024) (xy 369.719619 -268.440631)
			(xy 369.711724 -268.489208) (xy 369.69614 -268.535889) (xy 369.673269 -268.579466) (xy 369.643704 -268.61881)
			(xy 369.608211 -268.652902) (xy 369.567708 -268.680858) (xy 369.523246 -268.701956) (xy 369.475975 -268.715648)
			(xy 369.42712 -268.72158) (xy 369.377945 -268.719599) (xy 369.329726 -268.709755) (xy 369.28371 -268.692303)
			(xy 369.241089 -268.667696) (xy 369.202968 -268.636571) (xy 369.170333 -268.599734) (xy 369.14403 -268.558138)
			(xy 369.124739 -268.512862) (xy 369.112962 -268.465078) (xy 369.109002 -268.416024) (xy 367.840006 -268.416024)
			(xy 367.839511 -268.440631) (xy 367.831616 -268.489208) (xy 367.816032 -268.535889) (xy 367.793161 -268.579466)
			(xy 367.763596 -268.61881) (xy 367.728103 -268.652902) (xy 367.6876 -268.680858) (xy 367.643138 -268.701956)
			(xy 367.595867 -268.715648) (xy 367.547012 -268.72158) (xy 367.497837 -268.719599) (xy 367.449618 -268.709755)
			(xy 367.403602 -268.692303) (xy 367.360981 -268.667696) (xy 367.32286 -268.636571) (xy 367.290225 -268.599734)
			(xy 367.263922 -268.558138) (xy 367.244631 -268.512862) (xy 367.232854 -268.465078) (xy 367.228894 -268.416024)
			(xy 365.960152 -268.416024) (xy 365.959657 -268.440631) (xy 365.951762 -268.489208) (xy 365.936178 -268.535889)
			(xy 365.913307 -268.579466) (xy 365.883742 -268.61881) (xy 365.848249 -268.652902) (xy 365.807746 -268.680858)
			(xy 365.763284 -268.701956) (xy 365.716013 -268.715648) (xy 365.667158 -268.72158) (xy 365.617983 -268.719599)
			(xy 365.569764 -268.709755) (xy 365.523748 -268.692303) (xy 365.481127 -268.667696) (xy 365.443006 -268.636571)
			(xy 365.410371 -268.599734) (xy 365.384068 -268.558138) (xy 365.364777 -268.512862) (xy 365.353 -268.465078)
			(xy 365.34904 -268.416024) (xy 364.080044 -268.416024) (xy 364.079549 -268.440631) (xy 364.071654 -268.489208)
			(xy 364.05607 -268.535889) (xy 364.033199 -268.579466) (xy 364.003634 -268.61881) (xy 363.968141 -268.652902)
			(xy 363.927638 -268.680858) (xy 363.883176 -268.701956) (xy 363.835905 -268.715648) (xy 363.78705 -268.72158)
			(xy 363.737875 -268.719599) (xy 363.689656 -268.709755) (xy 363.64364 -268.692303) (xy 363.601019 -268.667696)
			(xy 363.562898 -268.636571) (xy 363.530263 -268.599734) (xy 363.50396 -268.558138) (xy 363.484669 -268.512862)
			(xy 363.472892 -268.465078) (xy 363.468932 -268.416024) (xy 362.20019 -268.416024) (xy 362.199695 -268.440631)
			(xy 362.1918 -268.489208) (xy 362.176216 -268.535889) (xy 362.153345 -268.579466) (xy 362.12378 -268.61881)
			(xy 362.088287 -268.652902) (xy 362.047784 -268.680858) (xy 362.003322 -268.701956) (xy 361.956051 -268.715648)
			(xy 361.907196 -268.72158) (xy 361.858021 -268.719599) (xy 361.809802 -268.709755) (xy 361.763786 -268.692303)
			(xy 361.721165 -268.667696) (xy 361.683044 -268.636571) (xy 361.650409 -268.599734) (xy 361.624106 -268.558138)
			(xy 361.604815 -268.512862) (xy 361.593038 -268.465078) (xy 361.589078 -268.416024) (xy 357.506524 -268.416024)
			(xy 357.506029 -268.440631) (xy 357.498134 -268.489208) (xy 357.48255 -268.535889) (xy 357.459679 -268.579466)
			(xy 357.430114 -268.61881) (xy 357.394621 -268.652902) (xy 357.354118 -268.680858) (xy 357.309656 -268.701956)
			(xy 357.262385 -268.715648) (xy 357.21353 -268.72158) (xy 357.164355 -268.719599) (xy 357.116136 -268.709755)
			(xy 357.07012 -268.692303) (xy 357.027499 -268.667696) (xy 356.989378 -268.636571) (xy 356.956743 -268.599734)
			(xy 356.93044 -268.558138) (xy 356.911149 -268.512862) (xy 356.899372 -268.465078) (xy 356.895412 -268.416024)
			(xy 355.626416 -268.416024) (xy 355.625921 -268.440631) (xy 355.618026 -268.489208) (xy 355.602442 -268.535889)
			(xy 355.579571 -268.579466) (xy 355.550006 -268.61881) (xy 355.514513 -268.652902) (xy 355.47401 -268.680858)
			(xy 355.429548 -268.701956) (xy 355.382277 -268.715648) (xy 355.333422 -268.72158) (xy 355.284247 -268.719599)
			(xy 355.236028 -268.709755) (xy 355.190012 -268.692303) (xy 355.147391 -268.667696) (xy 355.10927 -268.636571)
			(xy 355.076635 -268.599734) (xy 355.050332 -268.558138) (xy 355.031041 -268.512862) (xy 355.019264 -268.465078)
			(xy 355.015304 -268.416024) (xy 353.746308 -268.416024) (xy 353.745813 -268.440631) (xy 353.737918 -268.489208)
			(xy 353.722334 -268.535889) (xy 353.699463 -268.579466) (xy 353.669898 -268.61881) (xy 353.634405 -268.652902)
			(xy 353.593902 -268.680858) (xy 353.54944 -268.701956) (xy 353.502169 -268.715648) (xy 353.453314 -268.72158)
			(xy 353.404139 -268.719599) (xy 353.35592 -268.709755) (xy 353.309904 -268.692303) (xy 353.267283 -268.667696)
			(xy 353.229162 -268.636571) (xy 353.196527 -268.599734) (xy 353.170224 -268.558138) (xy 353.150933 -268.512862)
			(xy 353.139156 -268.465078) (xy 353.135196 -268.416024) (xy 351.866454 -268.416024) (xy 351.865959 -268.440631)
			(xy 351.858064 -268.489208) (xy 351.84248 -268.535889) (xy 351.819609 -268.579466) (xy 351.790044 -268.61881)
			(xy 351.754551 -268.652902) (xy 351.714048 -268.680858) (xy 351.669586 -268.701956) (xy 351.622315 -268.715648)
			(xy 351.57346 -268.72158) (xy 351.524285 -268.719599) (xy 351.476066 -268.709755) (xy 351.43005 -268.692303)
			(xy 351.387429 -268.667696) (xy 351.349308 -268.636571) (xy 351.316673 -268.599734) (xy 351.29037 -268.558138)
			(xy 351.271079 -268.512862) (xy 351.259302 -268.465078) (xy 351.255342 -268.416024) (xy 349.986346 -268.416024)
			(xy 349.985851 -268.440631) (xy 349.977956 -268.489208) (xy 349.962372 -268.535889) (xy 349.939501 -268.579466)
			(xy 349.909936 -268.61881) (xy 349.874443 -268.652902) (xy 349.83394 -268.680858) (xy 349.789478 -268.701956)
			(xy 349.742207 -268.715648) (xy 349.693352 -268.72158) (xy 349.644177 -268.719599) (xy 349.595958 -268.709755)
			(xy 349.549942 -268.692303) (xy 349.507321 -268.667696) (xy 349.4692 -268.636571) (xy 349.436565 -268.599734)
			(xy 349.410262 -268.558138) (xy 349.390971 -268.512862) (xy 349.379194 -268.465078) (xy 349.375234 -268.416024)
			(xy 348.106492 -268.416024) (xy 348.105997 -268.440631) (xy 348.098102 -268.489208) (xy 348.082518 -268.535889)
			(xy 348.059647 -268.579466) (xy 348.030082 -268.61881) (xy 347.994589 -268.652902) (xy 347.954086 -268.680858)
			(xy 347.909624 -268.701956) (xy 347.862353 -268.715648) (xy 347.813498 -268.72158) (xy 347.764323 -268.719599)
			(xy 347.716104 -268.709755) (xy 347.670088 -268.692303) (xy 347.627467 -268.667696) (xy 347.589346 -268.636571)
			(xy 347.556711 -268.599734) (xy 347.530408 -268.558138) (xy 347.511117 -268.512862) (xy 347.49934 -268.465078)
			(xy 347.49538 -268.416024) (xy 346.226384 -268.416024) (xy 346.225862 -268.441279) (xy 346.217549 -268.491101)
			(xy 346.201148 -268.538875) (xy 346.177107 -268.583298) (xy 346.146083 -268.623158) (xy 346.108921 -268.657368)
			(xy 346.066635 -268.684994) (xy 346.020379 -268.705284) (xy 345.971414 -268.717684) (xy 345.921076 -268.721855)
			(xy 345.870738 -268.717684) (xy 345.821773 -268.705284) (xy 345.775517 -268.684994) (xy 345.733231 -268.657368)
			(xy 345.696069 -268.623158) (xy 345.665045 -268.583298) (xy 345.641004 -268.538875) (xy 345.624603 -268.491101)
			(xy 345.61629 -268.441279) (xy 345.615768 -268.416024) (xy 345.61653 -268.39291) (xy 345.617292 -268.382242)
			(xy 345.61399 -268.37259) (xy 345.612148 -268.367698) (xy 345.606776 -268.358733) (xy 345.603322 -268.35481)
			(xy 345.565984 -268.314678) (xy 345.565476 -268.31417) (xy 345.552522 -268.299946) (xy 345.54505 -268.292612)
			(xy 345.525895 -268.284215) (xy 345.515438 -268.28369) (xy 345.38666 -268.28369) (xy 345.376213 -268.284253)
			(xy 345.357069 -268.292644) (xy 345.349576 -268.299946) (xy 345.298776 -268.355064) (xy 345.29535 -268.358937)
			(xy 345.289973 -268.367767) (xy 345.288108 -268.37259) (xy 345.284806 -268.382242) (xy 345.285568 -268.39291)
			(xy 345.28633 -268.416024) (xy 345.285808 -268.441279) (xy 345.277495 -268.491101) (xy 345.261094 -268.538875)
			(xy 345.237053 -268.583298) (xy 345.206029 -268.623158) (xy 345.168867 -268.657368) (xy 345.126581 -268.684994)
			(xy 345.080325 -268.705284) (xy 345.03136 -268.717684) (xy 344.981022 -268.721855) (xy 344.930684 -268.717684)
			(xy 344.881719 -268.705284) (xy 344.835463 -268.684994) (xy 344.793177 -268.657368) (xy 344.756015 -268.623158)
			(xy 344.724991 -268.583298) (xy 344.70095 -268.538875) (xy 344.684549 -268.491101) (xy 344.676236 -268.441279)
			(xy 344.675714 -268.416024) (xy 344.676476 -268.39291) (xy 344.677238 -268.382242) (xy 344.673936 -268.37259)
			(xy 344.672092 -268.367699) (xy 344.666716 -268.358738) (xy 344.663268 -268.35481) (xy 344.62593 -268.314678)
			(xy 344.625422 -268.31417) (xy 344.612468 -268.299946) (xy 344.604993 -268.29262) (xy 344.585838 -268.284243)
			(xy 344.575384 -268.28369) (xy 344.44686 -268.28369) (xy 344.436413 -268.284253) (xy 344.417269 -268.292644)
			(xy 344.409776 -268.299946) (xy 344.358976 -268.355064) (xy 344.35555 -268.358937) (xy 344.350173 -268.367767)
			(xy 344.348308 -268.37259) (xy 344.345006 -268.382242) (xy 344.345768 -268.39291) (xy 344.34653 -268.416024)
			(xy 344.346008 -268.441279) (xy 344.337695 -268.491101) (xy 344.321294 -268.538875) (xy 344.297253 -268.583298)
			(xy 344.266229 -268.623158) (xy 344.229067 -268.657368) (xy 344.186781 -268.684994) (xy 344.140525 -268.705284)
			(xy 344.09156 -268.717684) (xy 344.041222 -268.721855) (xy 343.990884 -268.717684) (xy 343.941919 -268.705284)
			(xy 343.895663 -268.684994) (xy 343.853377 -268.657368) (xy 343.816215 -268.623158) (xy 343.785191 -268.583298)
			(xy 343.76115 -268.538875) (xy 343.744749 -268.491101) (xy 343.736436 -268.441279) (xy 343.735914 -268.416024)
			(xy 343.736676 -268.39291) (xy 343.737438 -268.382242) (xy 343.734136 -268.37259) (xy 343.732292 -268.367699)
			(xy 343.726916 -268.358738) (xy 343.723468 -268.35481) (xy 343.68613 -268.314678) (xy 343.685622 -268.31417)
			(xy 343.672668 -268.299946) (xy 343.665193 -268.29262) (xy 343.646038 -268.284243) (xy 343.635584 -268.28369)
			(xy 343.506806 -268.28369) (xy 343.496354 -268.284244) (xy 343.477198 -268.292623) (xy 343.469722 -268.299946)
			(xy 343.418922 -268.355064) (xy 343.415499 -268.358939) (xy 343.410128 -268.367771) (xy 343.408254 -268.37259)
			(xy 343.404952 -268.382242) (xy 343.405714 -268.39291) (xy 343.406476 -268.416024) (xy 343.406028 -268.440015)
			(xy 343.398518 -268.487406) (xy 343.383687 -268.533038) (xy 343.3619 -268.575789) (xy 343.333693 -268.614604)
			(xy 343.299762 -268.64853) (xy 343.260941 -268.676729) (xy 343.218186 -268.698508) (xy 343.172551 -268.713331)
			(xy 343.125159 -268.720832) (xy 343.101168 -268.721332) (xy 343.078166 -268.720913) (xy 343.032683 -268.714006)
			(xy 342.988751 -268.700354) (xy 342.947364 -268.680266) (xy 342.909459 -268.654197) (xy 342.89238 -268.638782)
			(xy 342.885014 -268.631924) (xy 342.87587 -268.628368) (xy 342.871281 -268.626741) (xy 342.861689 -268.625075)
			(xy 342.85682 -268.625066) (xy 342.786208 -268.626082) (xy 342.77644 -268.626673) (xy 342.758417 -268.634253)
			(xy 342.751156 -268.640814) (xy 342.640666 -268.751304) (xy 342.634411 -268.758064) (xy 342.626803 -268.774819)
			(xy 342.625662 -268.793185) (xy 342.627966 -268.802104) (xy 342.64981 -268.874494) (xy 342.652018 -268.880992)
			(xy 342.659353 -268.892585) (xy 342.664288 -268.897354) (xy 342.67775 -268.9098) (xy 342.689434 -268.915642)
			(xy 342.696292 -268.917166) (xy 342.719594 -268.922541) (xy 342.764354 -268.939371) (xy 342.806065 -268.962758)
			(xy 342.843772 -268.992167) (xy 342.876614 -269.026925) (xy 342.903839 -269.066238) (xy 342.924825 -269.109207)
			(xy 342.939091 -269.154849) (xy 342.946312 -269.20212) (xy 342.946736 -269.22603) (xy 343.265264 -269.22603)
			(xy 343.269224 -269.176976) (xy 343.281001 -269.129192) (xy 343.300292 -269.083916) (xy 343.326595 -269.04232)
			(xy 343.35923 -269.005483) (xy 343.397351 -268.974358) (xy 343.439972 -268.949751) (xy 343.485988 -268.932299)
			(xy 343.534207 -268.922455) (xy 343.583382 -268.920474) (xy 343.632237 -268.926406) (xy 343.679508 -268.940098)
			(xy 343.72397 -268.961196) (xy 343.764473 -268.989152) (xy 343.799966 -269.023244) (xy 343.829531 -269.062588)
			(xy 343.852402 -269.106165) (xy 343.867986 -269.152846) (xy 343.875881 -269.201423) (xy 343.876376 -269.22603)
			(xy 344.205318 -269.22603) (xy 344.209278 -269.176976) (xy 344.221055 -269.129192) (xy 344.240346 -269.083916)
			(xy 344.266649 -269.04232) (xy 344.299284 -269.005483) (xy 344.337405 -268.974358) (xy 344.380026 -268.949751)
			(xy 344.426042 -268.932299) (xy 344.474261 -268.922455) (xy 344.523436 -268.920474) (xy 344.572291 -268.926406)
			(xy 344.619562 -268.940098) (xy 344.664024 -268.961196) (xy 344.704527 -268.989152) (xy 344.74002 -269.023244)
			(xy 344.769585 -269.062588) (xy 344.792456 -269.106165) (xy 344.80804 -269.152846) (xy 344.815935 -269.201423)
			(xy 344.81643 -269.22603) (xy 347.025226 -269.22603) (xy 347.029186 -269.176976) (xy 347.040963 -269.129192)
			(xy 347.060254 -269.083916) (xy 347.086557 -269.04232) (xy 347.119192 -269.005483) (xy 347.157313 -268.974358)
			(xy 347.199934 -268.949751) (xy 347.24595 -268.932299) (xy 347.294169 -268.922455) (xy 347.343344 -268.920474)
			(xy 347.392199 -268.926406) (xy 347.43947 -268.940098) (xy 347.483932 -268.961196) (xy 347.524435 -268.989152)
			(xy 347.559928 -269.023244) (xy 347.589493 -269.062588) (xy 347.612364 -269.106165) (xy 347.627948 -269.152846)
			(xy 347.635843 -269.201423) (xy 347.636338 -269.22603) (xy 349.845388 -269.22603) (xy 349.849348 -269.176976)
			(xy 349.861125 -269.129192) (xy 349.880416 -269.083916) (xy 349.906719 -269.04232) (xy 349.939354 -269.005483)
			(xy 349.977475 -268.974358) (xy 350.020096 -268.949751) (xy 350.066112 -268.932299) (xy 350.114331 -268.922455)
			(xy 350.163506 -268.920474) (xy 350.212361 -268.926406) (xy 350.259632 -268.940098) (xy 350.304094 -268.961196)
			(xy 350.344597 -268.989152) (xy 350.38009 -269.023244) (xy 350.409655 -269.062588) (xy 350.432526 -269.106165)
			(xy 350.44811 -269.152846) (xy 350.456005 -269.201423) (xy 350.4565 -269.22603) (xy 352.665296 -269.22603)
			(xy 352.669256 -269.176976) (xy 352.681033 -269.129192) (xy 352.700324 -269.083916) (xy 352.726627 -269.04232)
			(xy 352.759262 -269.005483) (xy 352.797383 -268.974358) (xy 352.840004 -268.949751) (xy 352.88602 -268.932299)
			(xy 352.934239 -268.922455) (xy 352.983414 -268.920474) (xy 353.032269 -268.926406) (xy 353.07954 -268.940098)
			(xy 353.124002 -268.961196) (xy 353.164505 -268.989152) (xy 353.199998 -269.023244) (xy 353.229563 -269.062588)
			(xy 353.252434 -269.106165) (xy 353.268018 -269.152846) (xy 353.275913 -269.201423) (xy 353.276408 -269.22603)
			(xy 355.485204 -269.22603) (xy 355.489164 -269.176976) (xy 355.500941 -269.129192) (xy 355.520232 -269.083916)
			(xy 355.546535 -269.04232) (xy 355.57917 -269.005483) (xy 355.617291 -268.974358) (xy 355.659912 -268.949751)
			(xy 355.705928 -268.932299) (xy 355.754147 -268.922455) (xy 355.803322 -268.920474) (xy 355.852177 -268.926406)
			(xy 355.899448 -268.940098) (xy 355.94391 -268.961196) (xy 355.984413 -268.989152) (xy 356.019906 -269.023244)
			(xy 356.049471 -269.062588) (xy 356.072342 -269.106165) (xy 356.087926 -269.152846) (xy 356.095821 -269.201423)
			(xy 356.096316 -269.22603) (xy 356.425258 -269.22603) (xy 356.429218 -269.176976) (xy 356.440995 -269.129192)
			(xy 356.460286 -269.083916) (xy 356.486589 -269.04232) (xy 356.519224 -269.005483) (xy 356.557345 -268.974358)
			(xy 356.599966 -268.949751) (xy 356.645982 -268.932299) (xy 356.694201 -268.922455) (xy 356.743376 -268.920474)
			(xy 356.792231 -268.926406) (xy 356.839502 -268.940098) (xy 356.883964 -268.961196) (xy 356.924467 -268.989152)
			(xy 356.95996 -269.023244) (xy 356.989525 -269.062588) (xy 357.012396 -269.106165) (xy 357.02798 -269.152846)
			(xy 357.035875 -269.201423) (xy 357.03637 -269.22603) (xy 357.365312 -269.22603) (xy 357.369272 -269.176976)
			(xy 357.381049 -269.129192) (xy 357.40034 -269.083916) (xy 357.426643 -269.04232) (xy 357.459278 -269.005483)
			(xy 357.497399 -268.974358) (xy 357.54002 -268.949751) (xy 357.586036 -268.932299) (xy 357.634255 -268.922455)
			(xy 357.68343 -268.920474) (xy 357.732285 -268.926406) (xy 357.779556 -268.940098) (xy 357.824018 -268.961196)
			(xy 357.864521 -268.989152) (xy 357.900014 -269.023244) (xy 357.929579 -269.062588) (xy 357.95245 -269.106165)
			(xy 357.968034 -269.152846) (xy 357.975929 -269.201423) (xy 357.976424 -269.22603) (xy 358.305366 -269.22603)
			(xy 358.309326 -269.176976) (xy 358.321103 -269.129192) (xy 358.340394 -269.083916) (xy 358.366697 -269.04232)
			(xy 358.399332 -269.005483) (xy 358.437453 -268.974358) (xy 358.480074 -268.949751) (xy 358.52609 -268.932299)
			(xy 358.574309 -268.922455) (xy 358.623484 -268.920474) (xy 358.672339 -268.926406) (xy 358.71961 -268.940098)
			(xy 358.764072 -268.961196) (xy 358.804575 -268.989152) (xy 358.840068 -269.023244) (xy 358.869633 -269.062588)
			(xy 358.892504 -269.106165) (xy 358.908088 -269.152846) (xy 358.915983 -269.201423) (xy 358.916478 -269.22603)
			(xy 361.118924 -269.22603) (xy 361.122884 -269.176976) (xy 361.134661 -269.129192) (xy 361.153952 -269.083916)
			(xy 361.180255 -269.04232) (xy 361.21289 -269.005483) (xy 361.251011 -268.974358) (xy 361.293632 -268.949751)
			(xy 361.339648 -268.932299) (xy 361.387867 -268.922455) (xy 361.437042 -268.920474) (xy 361.485897 -268.926406)
			(xy 361.533168 -268.940098) (xy 361.57763 -268.961196) (xy 361.618133 -268.989152) (xy 361.653626 -269.023244)
			(xy 361.683191 -269.062588) (xy 361.706062 -269.106165) (xy 361.721646 -269.152846) (xy 361.729541 -269.201423)
			(xy 361.730036 -269.22603) (xy 362.058978 -269.22603) (xy 362.062938 -269.176976) (xy 362.074715 -269.129192)
			(xy 362.094006 -269.083916) (xy 362.120309 -269.04232) (xy 362.152944 -269.005483) (xy 362.191065 -268.974358)
			(xy 362.233686 -268.949751) (xy 362.279702 -268.932299) (xy 362.327921 -268.922455) (xy 362.377096 -268.920474)
			(xy 362.425951 -268.926406) (xy 362.473222 -268.940098) (xy 362.517684 -268.961196) (xy 362.558187 -268.989152)
			(xy 362.59368 -269.023244) (xy 362.623245 -269.062588) (xy 362.646116 -269.106165) (xy 362.6617 -269.152846)
			(xy 362.669595 -269.201423) (xy 362.67009 -269.22603) (xy 362.999032 -269.22603) (xy 363.002992 -269.176976)
			(xy 363.014769 -269.129192) (xy 363.03406 -269.083916) (xy 363.060363 -269.04232) (xy 363.092998 -269.005483)
			(xy 363.131119 -268.974358) (xy 363.17374 -268.949751) (xy 363.219756 -268.932299) (xy 363.267975 -268.922455)
			(xy 363.31715 -268.920474) (xy 363.366005 -268.926406) (xy 363.413276 -268.940098) (xy 363.457738 -268.961196)
			(xy 363.498241 -268.989152) (xy 363.533734 -269.023244) (xy 363.563299 -269.062588) (xy 363.58617 -269.106165)
			(xy 363.601754 -269.152846) (xy 363.609649 -269.201423) (xy 363.610144 -269.22603) (xy 363.939086 -269.22603)
			(xy 363.943046 -269.176976) (xy 363.954823 -269.129192) (xy 363.974114 -269.083916) (xy 364.000417 -269.04232)
			(xy 364.033052 -269.005483) (xy 364.071173 -268.974358) (xy 364.113794 -268.949751) (xy 364.15981 -268.932299)
			(xy 364.208029 -268.922455) (xy 364.257204 -268.920474) (xy 364.306059 -268.926406) (xy 364.35333 -268.940098)
			(xy 364.397792 -268.961196) (xy 364.438295 -268.989152) (xy 364.473788 -269.023244) (xy 364.503353 -269.062588)
			(xy 364.526224 -269.106165) (xy 364.541808 -269.152846) (xy 364.549703 -269.201423) (xy 364.550198 -269.22603)
			(xy 366.758994 -269.22603) (xy 366.762954 -269.176976) (xy 366.774731 -269.129192) (xy 366.794022 -269.083916)
			(xy 366.820325 -269.04232) (xy 366.85296 -269.005483) (xy 366.891081 -268.974358) (xy 366.933702 -268.949751)
			(xy 366.979718 -268.932299) (xy 367.027937 -268.922455) (xy 367.077112 -268.920474) (xy 367.125967 -268.926406)
			(xy 367.173238 -268.940098) (xy 367.2177 -268.961196) (xy 367.258203 -268.989152) (xy 367.293696 -269.023244)
			(xy 367.323261 -269.062588) (xy 367.346132 -269.106165) (xy 367.361716 -269.152846) (xy 367.369611 -269.201423)
			(xy 367.370106 -269.22603) (xy 369.578902 -269.22603) (xy 369.582862 -269.176976) (xy 369.594639 -269.129192)
			(xy 369.61393 -269.083916) (xy 369.640233 -269.04232) (xy 369.672868 -269.005483) (xy 369.710989 -268.974358)
			(xy 369.75361 -268.949751) (xy 369.799626 -268.932299) (xy 369.847845 -268.922455) (xy 369.89702 -268.920474)
			(xy 369.945875 -268.926406) (xy 369.993146 -268.940098) (xy 370.037608 -268.961196) (xy 370.078111 -268.989152)
			(xy 370.113604 -269.023244) (xy 370.143169 -269.062588) (xy 370.16604 -269.106165) (xy 370.181624 -269.152846)
			(xy 370.189519 -269.201423) (xy 370.190014 -269.22603) (xy 372.399064 -269.22603) (xy 372.403024 -269.176976)
			(xy 372.414801 -269.129192) (xy 372.434092 -269.083916) (xy 372.460395 -269.04232) (xy 372.49303 -269.005483)
			(xy 372.531151 -268.974358) (xy 372.573772 -268.949751) (xy 372.619788 -268.932299) (xy 372.668007 -268.922455)
			(xy 372.717182 -268.920474) (xy 372.766037 -268.926406) (xy 372.813308 -268.940098) (xy 372.85777 -268.961196)
			(xy 372.898273 -268.989152) (xy 372.933766 -269.023244) (xy 372.963331 -269.062588) (xy 372.986202 -269.106165)
			(xy 373.001786 -269.152846) (xy 373.009681 -269.201423) (xy 373.010176 -269.22603) (xy 375.218972 -269.22603)
			(xy 375.222932 -269.176976) (xy 375.234709 -269.129192) (xy 375.254 -269.083916) (xy 375.280303 -269.04232)
			(xy 375.312938 -269.005483) (xy 375.351059 -268.974358) (xy 375.39368 -268.949751) (xy 375.439696 -268.932299)
			(xy 375.487915 -268.922455) (xy 375.53709 -268.920474) (xy 375.585945 -268.926406) (xy 375.633216 -268.940098)
			(xy 375.677678 -268.961196) (xy 375.718181 -268.989152) (xy 375.753674 -269.023244) (xy 375.783239 -269.062588)
			(xy 375.80611 -269.106165) (xy 375.821694 -269.152846) (xy 375.829589 -269.201423) (xy 375.830084 -269.22603)
			(xy 376.159026 -269.22603) (xy 376.162986 -269.176976) (xy 376.174763 -269.129192) (xy 376.194054 -269.083916)
			(xy 376.220357 -269.04232) (xy 376.252992 -269.005483) (xy 376.291113 -268.974358) (xy 376.333734 -268.949751)
			(xy 376.37975 -268.932299) (xy 376.427969 -268.922455) (xy 376.477144 -268.920474) (xy 376.525999 -268.926406)
			(xy 376.57327 -268.940098) (xy 376.617732 -268.961196) (xy 376.658235 -268.989152) (xy 376.693728 -269.023244)
			(xy 376.723293 -269.062588) (xy 376.746164 -269.106165) (xy 376.761748 -269.152846) (xy 376.769643 -269.201423)
			(xy 376.770138 -269.22603) (xy 377.088649 -269.22603) (xy 377.092744 -269.175302) (xy 377.104923 -269.125888)
			(xy 377.124871 -269.079068) (xy 377.152072 -269.036054) (xy 377.18582 -268.99796) (xy 377.225242 -268.965773)
			(xy 377.269316 -268.940327) (xy 377.316902 -268.92228) (xy 377.366766 -268.9121) (xy 377.417618 -268.910051)
			(xy 377.468139 -268.916185) (xy 377.517023 -268.930345) (xy 377.563002 -268.952162) (xy 377.604886 -268.981072)
			(xy 377.64159 -269.016327) (xy 377.672163 -269.057013) (xy 377.695814 -269.102076) (xy 377.71193 -269.15035)
			(xy 377.720094 -269.200584) (xy 377.720606 -269.22603) (xy 377.720094 -269.251476) (xy 377.71193 -269.30171)
			(xy 377.695814 -269.349984) (xy 377.672163 -269.395047) (xy 377.64159 -269.435733) (xy 377.604886 -269.470988)
			(xy 377.563002 -269.499898) (xy 377.517023 -269.521715) (xy 377.468139 -269.535875) (xy 377.417618 -269.542009)
			(xy 377.366766 -269.53996) (xy 377.316902 -269.52978) (xy 377.269316 -269.511733) (xy 377.225242 -269.486287)
			(xy 377.18582 -269.4541) (xy 377.152072 -269.416006) (xy 377.124871 -269.372992) (xy 377.104923 -269.326172)
			(xy 377.092744 -269.276758) (xy 377.088649 -269.22603) (xy 376.770138 -269.22603) (xy 376.769643 -269.250637)
			(xy 376.761748 -269.299214) (xy 376.746164 -269.345895) (xy 376.723293 -269.389472) (xy 376.693728 -269.428816)
			(xy 376.658235 -269.462908) (xy 376.617732 -269.490864) (xy 376.57327 -269.511962) (xy 376.525999 -269.525654)
			(xy 376.477144 -269.531586) (xy 376.427969 -269.529605) (xy 376.37975 -269.519761) (xy 376.333734 -269.502309)
			(xy 376.291113 -269.477702) (xy 376.252992 -269.446577) (xy 376.220357 -269.40974) (xy 376.194054 -269.368144)
			(xy 376.174763 -269.322868) (xy 376.162986 -269.275084) (xy 376.159026 -269.22603) (xy 375.830084 -269.22603)
			(xy 375.829589 -269.250637) (xy 375.821694 -269.299214) (xy 375.80611 -269.345895) (xy 375.783239 -269.389472)
			(xy 375.753674 -269.428816) (xy 375.718181 -269.462908) (xy 375.677678 -269.490864) (xy 375.633216 -269.511962)
			(xy 375.585945 -269.525654) (xy 375.53709 -269.531586) (xy 375.487915 -269.529605) (xy 375.439696 -269.519761)
			(xy 375.39368 -269.502309) (xy 375.351059 -269.477702) (xy 375.312938 -269.446577) (xy 375.280303 -269.40974)
			(xy 375.254 -269.368144) (xy 375.234709 -269.322868) (xy 375.222932 -269.275084) (xy 375.218972 -269.22603)
			(xy 373.010176 -269.22603) (xy 373.009681 -269.250637) (xy 373.001786 -269.299214) (xy 372.986202 -269.345895)
			(xy 372.963331 -269.389472) (xy 372.933766 -269.428816) (xy 372.898273 -269.462908) (xy 372.85777 -269.490864)
			(xy 372.813308 -269.511962) (xy 372.766037 -269.525654) (xy 372.717182 -269.531586) (xy 372.668007 -269.529605)
			(xy 372.619788 -269.519761) (xy 372.573772 -269.502309) (xy 372.531151 -269.477702) (xy 372.49303 -269.446577)
			(xy 372.460395 -269.40974) (xy 372.434092 -269.368144) (xy 372.414801 -269.322868) (xy 372.403024 -269.275084)
			(xy 372.399064 -269.22603) (xy 370.190014 -269.22603) (xy 370.189519 -269.250637) (xy 370.181624 -269.299214)
			(xy 370.16604 -269.345895) (xy 370.143169 -269.389472) (xy 370.113604 -269.428816) (xy 370.078111 -269.462908)
			(xy 370.037608 -269.490864) (xy 369.993146 -269.511962) (xy 369.945875 -269.525654) (xy 369.89702 -269.531586)
			(xy 369.847845 -269.529605) (xy 369.799626 -269.519761) (xy 369.75361 -269.502309) (xy 369.710989 -269.477702)
			(xy 369.672868 -269.446577) (xy 369.640233 -269.40974) (xy 369.61393 -269.368144) (xy 369.594639 -269.322868)
			(xy 369.582862 -269.275084) (xy 369.578902 -269.22603) (xy 367.370106 -269.22603) (xy 367.369611 -269.250637)
			(xy 367.361716 -269.299214) (xy 367.346132 -269.345895) (xy 367.323261 -269.389472) (xy 367.293696 -269.428816)
			(xy 367.258203 -269.462908) (xy 367.2177 -269.490864) (xy 367.173238 -269.511962) (xy 367.125967 -269.525654)
			(xy 367.077112 -269.531586) (xy 367.027937 -269.529605) (xy 366.979718 -269.519761) (xy 366.933702 -269.502309)
			(xy 366.891081 -269.477702) (xy 366.85296 -269.446577) (xy 366.820325 -269.40974) (xy 366.794022 -269.368144)
			(xy 366.774731 -269.322868) (xy 366.762954 -269.275084) (xy 366.758994 -269.22603) (xy 364.550198 -269.22603)
			(xy 364.549703 -269.250637) (xy 364.541808 -269.299214) (xy 364.526224 -269.345895) (xy 364.503353 -269.389472)
			(xy 364.473788 -269.428816) (xy 364.438295 -269.462908) (xy 364.397792 -269.490864) (xy 364.35333 -269.511962)
			(xy 364.306059 -269.525654) (xy 364.257204 -269.531586) (xy 364.208029 -269.529605) (xy 364.15981 -269.519761)
			(xy 364.113794 -269.502309) (xy 364.071173 -269.477702) (xy 364.033052 -269.446577) (xy 364.000417 -269.40974)
			(xy 363.974114 -269.368144) (xy 363.954823 -269.322868) (xy 363.943046 -269.275084) (xy 363.939086 -269.22603)
			(xy 363.610144 -269.22603) (xy 363.609649 -269.250637) (xy 363.601754 -269.299214) (xy 363.58617 -269.345895)
			(xy 363.563299 -269.389472) (xy 363.533734 -269.428816) (xy 363.498241 -269.462908) (xy 363.457738 -269.490864)
			(xy 363.413276 -269.511962) (xy 363.366005 -269.525654) (xy 363.31715 -269.531586) (xy 363.267975 -269.529605)
			(xy 363.219756 -269.519761) (xy 363.17374 -269.502309) (xy 363.131119 -269.477702) (xy 363.092998 -269.446577)
			(xy 363.060363 -269.40974) (xy 363.03406 -269.368144) (xy 363.014769 -269.322868) (xy 363.002992 -269.275084)
			(xy 362.999032 -269.22603) (xy 362.67009 -269.22603) (xy 362.669595 -269.250637) (xy 362.6617 -269.299214)
			(xy 362.646116 -269.345895) (xy 362.623245 -269.389472) (xy 362.59368 -269.428816) (xy 362.558187 -269.462908)
			(xy 362.517684 -269.490864) (xy 362.473222 -269.511962) (xy 362.425951 -269.525654) (xy 362.377096 -269.531586)
			(xy 362.327921 -269.529605) (xy 362.279702 -269.519761) (xy 362.233686 -269.502309) (xy 362.191065 -269.477702)
			(xy 362.152944 -269.446577) (xy 362.120309 -269.40974) (xy 362.094006 -269.368144) (xy 362.074715 -269.322868)
			(xy 362.062938 -269.275084) (xy 362.058978 -269.22603) (xy 361.730036 -269.22603) (xy 361.729541 -269.250637)
			(xy 361.721646 -269.299214) (xy 361.706062 -269.345895) (xy 361.683191 -269.389472) (xy 361.653626 -269.428816)
			(xy 361.618133 -269.462908) (xy 361.57763 -269.490864) (xy 361.533168 -269.511962) (xy 361.485897 -269.525654)
			(xy 361.437042 -269.531586) (xy 361.387867 -269.529605) (xy 361.339648 -269.519761) (xy 361.293632 -269.502309)
			(xy 361.251011 -269.477702) (xy 361.21289 -269.446577) (xy 361.180255 -269.40974) (xy 361.153952 -269.368144)
			(xy 361.134661 -269.322868) (xy 361.122884 -269.275084) (xy 361.118924 -269.22603) (xy 358.916478 -269.22603)
			(xy 358.915983 -269.250637) (xy 358.908088 -269.299214) (xy 358.892504 -269.345895) (xy 358.869633 -269.389472)
			(xy 358.840068 -269.428816) (xy 358.804575 -269.462908) (xy 358.764072 -269.490864) (xy 358.71961 -269.511962)
			(xy 358.672339 -269.525654) (xy 358.623484 -269.531586) (xy 358.574309 -269.529605) (xy 358.52609 -269.519761)
			(xy 358.480074 -269.502309) (xy 358.437453 -269.477702) (xy 358.399332 -269.446577) (xy 358.366697 -269.40974)
			(xy 358.340394 -269.368144) (xy 358.321103 -269.322868) (xy 358.309326 -269.275084) (xy 358.305366 -269.22603)
			(xy 357.976424 -269.22603) (xy 357.975929 -269.250637) (xy 357.968034 -269.299214) (xy 357.95245 -269.345895)
			(xy 357.929579 -269.389472) (xy 357.900014 -269.428816) (xy 357.864521 -269.462908) (xy 357.824018 -269.490864)
			(xy 357.779556 -269.511962) (xy 357.732285 -269.525654) (xy 357.68343 -269.531586) (xy 357.634255 -269.529605)
			(xy 357.586036 -269.519761) (xy 357.54002 -269.502309) (xy 357.497399 -269.477702) (xy 357.459278 -269.446577)
			(xy 357.426643 -269.40974) (xy 357.40034 -269.368144) (xy 357.381049 -269.322868) (xy 357.369272 -269.275084)
			(xy 357.365312 -269.22603) (xy 357.03637 -269.22603) (xy 357.035875 -269.250637) (xy 357.02798 -269.299214)
			(xy 357.012396 -269.345895) (xy 356.989525 -269.389472) (xy 356.95996 -269.428816) (xy 356.924467 -269.462908)
			(xy 356.883964 -269.490864) (xy 356.839502 -269.511962) (xy 356.792231 -269.525654) (xy 356.743376 -269.531586)
			(xy 356.694201 -269.529605) (xy 356.645982 -269.519761) (xy 356.599966 -269.502309) (xy 356.557345 -269.477702)
			(xy 356.519224 -269.446577) (xy 356.486589 -269.40974) (xy 356.460286 -269.368144) (xy 356.440995 -269.322868)
			(xy 356.429218 -269.275084) (xy 356.425258 -269.22603) (xy 356.096316 -269.22603) (xy 356.095821 -269.250637)
			(xy 356.087926 -269.299214) (xy 356.072342 -269.345895) (xy 356.049471 -269.389472) (xy 356.019906 -269.428816)
			(xy 355.984413 -269.462908) (xy 355.94391 -269.490864) (xy 355.899448 -269.511962) (xy 355.852177 -269.525654)
			(xy 355.803322 -269.531586) (xy 355.754147 -269.529605) (xy 355.705928 -269.519761) (xy 355.659912 -269.502309)
			(xy 355.617291 -269.477702) (xy 355.57917 -269.446577) (xy 355.546535 -269.40974) (xy 355.520232 -269.368144)
			(xy 355.500941 -269.322868) (xy 355.489164 -269.275084) (xy 355.485204 -269.22603) (xy 353.276408 -269.22603)
			(xy 353.275913 -269.250637) (xy 353.268018 -269.299214) (xy 353.252434 -269.345895) (xy 353.229563 -269.389472)
			(xy 353.199998 -269.428816) (xy 353.164505 -269.462908) (xy 353.124002 -269.490864) (xy 353.07954 -269.511962)
			(xy 353.032269 -269.525654) (xy 352.983414 -269.531586) (xy 352.934239 -269.529605) (xy 352.88602 -269.519761)
			(xy 352.840004 -269.502309) (xy 352.797383 -269.477702) (xy 352.759262 -269.446577) (xy 352.726627 -269.40974)
			(xy 352.700324 -269.368144) (xy 352.681033 -269.322868) (xy 352.669256 -269.275084) (xy 352.665296 -269.22603)
			(xy 350.4565 -269.22603) (xy 350.456005 -269.250637) (xy 350.44811 -269.299214) (xy 350.432526 -269.345895)
			(xy 350.409655 -269.389472) (xy 350.38009 -269.428816) (xy 350.344597 -269.462908) (xy 350.304094 -269.490864)
			(xy 350.259632 -269.511962) (xy 350.212361 -269.525654) (xy 350.163506 -269.531586) (xy 350.114331 -269.529605)
			(xy 350.066112 -269.519761) (xy 350.020096 -269.502309) (xy 349.977475 -269.477702) (xy 349.939354 -269.446577)
			(xy 349.906719 -269.40974) (xy 349.880416 -269.368144) (xy 349.861125 -269.322868) (xy 349.849348 -269.275084)
			(xy 349.845388 -269.22603) (xy 347.636338 -269.22603) (xy 347.635843 -269.250637) (xy 347.627948 -269.299214)
			(xy 347.612364 -269.345895) (xy 347.589493 -269.389472) (xy 347.559928 -269.428816) (xy 347.524435 -269.462908)
			(xy 347.483932 -269.490864) (xy 347.43947 -269.511962) (xy 347.392199 -269.525654) (xy 347.343344 -269.531586)
			(xy 347.294169 -269.529605) (xy 347.24595 -269.519761) (xy 347.199934 -269.502309) (xy 347.157313 -269.477702)
			(xy 347.119192 -269.446577) (xy 347.086557 -269.40974) (xy 347.060254 -269.368144) (xy 347.040963 -269.322868)
			(xy 347.029186 -269.275084) (xy 347.025226 -269.22603) (xy 344.81643 -269.22603) (xy 344.815935 -269.250637)
			(xy 344.80804 -269.299214) (xy 344.792456 -269.345895) (xy 344.769585 -269.389472) (xy 344.74002 -269.428816)
			(xy 344.704527 -269.462908) (xy 344.664024 -269.490864) (xy 344.619562 -269.511962) (xy 344.572291 -269.525654)
			(xy 344.523436 -269.531586) (xy 344.474261 -269.529605) (xy 344.426042 -269.519761) (xy 344.380026 -269.502309)
			(xy 344.337405 -269.477702) (xy 344.299284 -269.446577) (xy 344.266649 -269.40974) (xy 344.240346 -269.368144)
			(xy 344.221055 -269.322868) (xy 344.209278 -269.275084) (xy 344.205318 -269.22603) (xy 343.876376 -269.22603)
			(xy 343.875881 -269.250637) (xy 343.867986 -269.299214) (xy 343.852402 -269.345895) (xy 343.829531 -269.389472)
			(xy 343.799966 -269.428816) (xy 343.764473 -269.462908) (xy 343.72397 -269.490864) (xy 343.679508 -269.511962)
			(xy 343.632237 -269.525654) (xy 343.583382 -269.531586) (xy 343.534207 -269.529605) (xy 343.485988 -269.519761)
			(xy 343.439972 -269.502309) (xy 343.397351 -269.477702) (xy 343.35923 -269.446577) (xy 343.326595 -269.40974)
			(xy 343.300292 -269.368144) (xy 343.281001 -269.322868) (xy 343.269224 -269.275084) (xy 343.265264 -269.22603)
			(xy 342.946736 -269.22603) (xy 342.946247 -269.250838) (xy 342.938481 -269.299844) (xy 342.923146 -269.347031)
			(xy 342.900618 -269.391239) (xy 342.871452 -269.431379) (xy 342.836367 -269.466462) (xy 342.796225 -269.495626)
			(xy 342.752016 -269.518152) (xy 342.704828 -269.533485) (xy 342.655822 -269.541248) (xy 342.631014 -269.541752)
			(xy 342.606794 -269.541304) (xy 342.558924 -269.533888) (xy 342.512751 -269.519244) (xy 342.469357 -269.497715)
			(xy 342.429763 -269.469808) (xy 342.3949 -269.436178) (xy 342.365585 -269.397615) (xy 342.342508 -269.355025)
			(xy 342.32621 -269.309408) (xy 342.321134 -269.28572) (xy 342.319864 -269.279116) (xy 342.318313 -269.27213)
			(xy 342.311869 -269.259361) (xy 342.307164 -269.25397) (xy 342.306402 -269.253208) (xy 342.23325 -269.230856)
			(xy 342.207088 -269.222982) (xy 342.198173 -269.220691) (xy 342.179819 -269.221887) (xy 342.163049 -269.229439)
			(xy 342.156288 -269.235682) (xy 341.517986 -269.873984) (xy 341.517478 -269.874492) (xy 341.517224 -269.874746)
			(xy 341.510925 -269.881941) (xy 341.503736 -269.899646) (xy 341.503546 -269.918754) (xy 341.506556 -269.927832)
			(xy 341.515803 -269.953922) (xy 341.525772 -270.008363) (xy 341.526368 -270.036036) (xy 341.844879 -270.036036)
			(xy 341.848974 -269.985308) (xy 341.861153 -269.935894) (xy 341.881101 -269.889074) (xy 341.908302 -269.84606)
			(xy 341.94205 -269.807966) (xy 341.981472 -269.775779) (xy 342.025546 -269.750333) (xy 342.073132 -269.732286)
			(xy 342.122996 -269.722106) (xy 342.173848 -269.720057) (xy 342.224369 -269.726191) (xy 342.273253 -269.740351)
			(xy 342.319232 -269.762168) (xy 342.361116 -269.791078) (xy 342.39782 -269.826333) (xy 342.428393 -269.867019)
			(xy 342.452044 -269.912082) (xy 342.46816 -269.960356) (xy 342.476324 -270.01059) (xy 342.476836 -270.036036)
			(xy 342.795364 -270.036036) (xy 342.799324 -269.986982) (xy 342.811101 -269.939198) (xy 342.830392 -269.893922)
			(xy 342.856695 -269.852326) (xy 342.88933 -269.815489) (xy 342.927451 -269.784364) (xy 342.970072 -269.759757)
			(xy 343.016088 -269.742305) (xy 343.064307 -269.732461) (xy 343.113482 -269.73048) (xy 343.162337 -269.736412)
			(xy 343.209608 -269.750104) (xy 343.25407 -269.771202) (xy 343.294573 -269.799158) (xy 343.330066 -269.83325)
			(xy 343.359631 -269.872594) (xy 343.382502 -269.916171) (xy 343.398086 -269.962852) (xy 343.405981 -270.011429)
			(xy 343.406476 -270.036036) (xy 343.724987 -270.036036) (xy 343.729082 -269.985308) (xy 343.741261 -269.935894)
			(xy 343.761209 -269.889074) (xy 343.78841 -269.84606) (xy 343.822158 -269.807966) (xy 343.86158 -269.775779)
			(xy 343.905654 -269.750333) (xy 343.95324 -269.732286) (xy 344.003104 -269.722106) (xy 344.053956 -269.720057)
			(xy 344.104477 -269.726191) (xy 344.153361 -269.740351) (xy 344.19934 -269.762168) (xy 344.241224 -269.791078)
			(xy 344.277928 -269.826333) (xy 344.308501 -269.867019) (xy 344.332152 -269.912082) (xy 344.348268 -269.960356)
			(xy 344.356432 -270.01059) (xy 344.356944 -270.036036) (xy 344.675218 -270.036036) (xy 344.679178 -269.986982)
			(xy 344.690955 -269.939198) (xy 344.710246 -269.893922) (xy 344.736549 -269.852326) (xy 344.769184 -269.815489)
			(xy 344.807305 -269.784364) (xy 344.849926 -269.759757) (xy 344.895942 -269.742305) (xy 344.944161 -269.732461)
			(xy 344.993336 -269.73048) (xy 345.042191 -269.736412) (xy 345.089462 -269.750104) (xy 345.133924 -269.771202)
			(xy 345.174427 -269.799158) (xy 345.20992 -269.83325) (xy 345.239485 -269.872594) (xy 345.262356 -269.916171)
			(xy 345.27794 -269.962852) (xy 345.285835 -270.011429) (xy 345.28633 -270.036036) (xy 345.615272 -270.036036)
			(xy 345.619232 -269.986982) (xy 345.631009 -269.939198) (xy 345.6503 -269.893922) (xy 345.676603 -269.852326)
			(xy 345.709238 -269.815489) (xy 345.747359 -269.784364) (xy 345.78998 -269.759757) (xy 345.835996 -269.742305)
			(xy 345.884215 -269.732461) (xy 345.93339 -269.73048) (xy 345.982245 -269.736412) (xy 346.029516 -269.750104)
			(xy 346.073978 -269.771202) (xy 346.114481 -269.799158) (xy 346.149974 -269.83325) (xy 346.179539 -269.872594)
			(xy 346.20241 -269.916171) (xy 346.217994 -269.962852) (xy 346.225889 -270.011429) (xy 346.226384 -270.036036)
			(xy 346.555326 -270.036036) (xy 346.559286 -269.986982) (xy 346.571063 -269.939198) (xy 346.590354 -269.893922)
			(xy 346.616657 -269.852326) (xy 346.649292 -269.815489) (xy 346.687413 -269.784364) (xy 346.730034 -269.759757)
			(xy 346.77605 -269.742305) (xy 346.824269 -269.732461) (xy 346.873444 -269.73048) (xy 346.922299 -269.736412)
			(xy 346.96957 -269.750104) (xy 347.014032 -269.771202) (xy 347.054535 -269.799158) (xy 347.090028 -269.83325)
			(xy 347.119593 -269.872594) (xy 347.142464 -269.916171) (xy 347.158048 -269.962852) (xy 347.165943 -270.011429)
			(xy 347.166438 -270.036036) (xy 347.49538 -270.036036) (xy 347.49934 -269.986982) (xy 347.511117 -269.939198)
			(xy 347.530408 -269.893922) (xy 347.556711 -269.852326) (xy 347.589346 -269.815489) (xy 347.627467 -269.784364)
			(xy 347.670088 -269.759757) (xy 347.716104 -269.742305) (xy 347.764323 -269.732461) (xy 347.813498 -269.73048)
			(xy 347.862353 -269.736412) (xy 347.909624 -269.750104) (xy 347.954086 -269.771202) (xy 347.994589 -269.799158)
			(xy 348.030082 -269.83325) (xy 348.059647 -269.872594) (xy 348.082518 -269.916171) (xy 348.098102 -269.962852)
			(xy 348.105997 -270.011429) (xy 348.106492 -270.036036) (xy 348.435434 -270.036036) (xy 348.439394 -269.986982)
			(xy 348.451171 -269.939198) (xy 348.470462 -269.893922) (xy 348.496765 -269.852326) (xy 348.5294 -269.815489)
			(xy 348.567521 -269.784364) (xy 348.610142 -269.759757) (xy 348.656158 -269.742305) (xy 348.704377 -269.732461)
			(xy 348.753552 -269.73048) (xy 348.802407 -269.736412) (xy 348.849678 -269.750104) (xy 348.89414 -269.771202)
			(xy 348.934643 -269.799158) (xy 348.970136 -269.83325) (xy 348.999701 -269.872594) (xy 349.022572 -269.916171)
			(xy 349.038156 -269.962852) (xy 349.046051 -270.011429) (xy 349.046546 -270.036036) (xy 349.375234 -270.036036)
			(xy 349.379194 -269.986982) (xy 349.390971 -269.939198) (xy 349.410262 -269.893922) (xy 349.436565 -269.852326)
			(xy 349.4692 -269.815489) (xy 349.507321 -269.784364) (xy 349.549942 -269.759757) (xy 349.595958 -269.742305)
			(xy 349.644177 -269.732461) (xy 349.693352 -269.73048) (xy 349.742207 -269.736412) (xy 349.789478 -269.750104)
			(xy 349.83394 -269.771202) (xy 349.874443 -269.799158) (xy 349.909936 -269.83325) (xy 349.939501 -269.872594)
			(xy 349.962372 -269.916171) (xy 349.977956 -269.962852) (xy 349.985851 -270.011429) (xy 349.986346 -270.036036)
			(xy 350.315288 -270.036036) (xy 350.319248 -269.986982) (xy 350.331025 -269.939198) (xy 350.350316 -269.893922)
			(xy 350.376619 -269.852326) (xy 350.409254 -269.815489) (xy 350.447375 -269.784364) (xy 350.489996 -269.759757)
			(xy 350.536012 -269.742305) (xy 350.584231 -269.732461) (xy 350.633406 -269.73048) (xy 350.682261 -269.736412)
			(xy 350.729532 -269.750104) (xy 350.773994 -269.771202) (xy 350.814497 -269.799158) (xy 350.84999 -269.83325)
			(xy 350.879555 -269.872594) (xy 350.902426 -269.916171) (xy 350.91801 -269.962852) (xy 350.925905 -270.011429)
			(xy 350.9264 -270.036036) (xy 351.255342 -270.036036) (xy 351.259302 -269.986982) (xy 351.271079 -269.939198)
			(xy 351.29037 -269.893922) (xy 351.316673 -269.852326) (xy 351.349308 -269.815489) (xy 351.387429 -269.784364)
			(xy 351.43005 -269.759757) (xy 351.476066 -269.742305) (xy 351.524285 -269.732461) (xy 351.57346 -269.73048)
			(xy 351.622315 -269.736412) (xy 351.669586 -269.750104) (xy 351.714048 -269.771202) (xy 351.754551 -269.799158)
			(xy 351.790044 -269.83325) (xy 351.819609 -269.872594) (xy 351.84248 -269.916171) (xy 351.858064 -269.962852)
			(xy 351.865959 -270.011429) (xy 351.866454 -270.036036) (xy 352.195396 -270.036036) (xy 352.199356 -269.986982)
			(xy 352.211133 -269.939198) (xy 352.230424 -269.893922) (xy 352.256727 -269.852326) (xy 352.289362 -269.815489)
			(xy 352.327483 -269.784364) (xy 352.370104 -269.759757) (xy 352.41612 -269.742305) (xy 352.464339 -269.732461)
			(xy 352.513514 -269.73048) (xy 352.562369 -269.736412) (xy 352.60964 -269.750104) (xy 352.654102 -269.771202)
			(xy 352.694605 -269.799158) (xy 352.730098 -269.83325) (xy 352.759663 -269.872594) (xy 352.782534 -269.916171)
			(xy 352.798118 -269.962852) (xy 352.806013 -270.011429) (xy 352.806508 -270.036036) (xy 353.135196 -270.036036)
			(xy 353.139156 -269.986982) (xy 353.150933 -269.939198) (xy 353.170224 -269.893922) (xy 353.196527 -269.852326)
			(xy 353.229162 -269.815489) (xy 353.267283 -269.784364) (xy 353.309904 -269.759757) (xy 353.35592 -269.742305)
			(xy 353.404139 -269.732461) (xy 353.453314 -269.73048) (xy 353.502169 -269.736412) (xy 353.54944 -269.750104)
			(xy 353.593902 -269.771202) (xy 353.634405 -269.799158) (xy 353.669898 -269.83325) (xy 353.699463 -269.872594)
			(xy 353.722334 -269.916171) (xy 353.737918 -269.962852) (xy 353.745813 -270.011429) (xy 353.746308 -270.036036)
			(xy 354.07525 -270.036036) (xy 354.07921 -269.986982) (xy 354.090987 -269.939198) (xy 354.110278 -269.893922)
			(xy 354.136581 -269.852326) (xy 354.169216 -269.815489) (xy 354.207337 -269.784364) (xy 354.249958 -269.759757)
			(xy 354.295974 -269.742305) (xy 354.344193 -269.732461) (xy 354.393368 -269.73048) (xy 354.442223 -269.736412)
			(xy 354.489494 -269.750104) (xy 354.533956 -269.771202) (xy 354.574459 -269.799158) (xy 354.609952 -269.83325)
			(xy 354.639517 -269.872594) (xy 354.662388 -269.916171) (xy 354.677972 -269.962852) (xy 354.685867 -270.011429)
			(xy 354.686362 -270.036036) (xy 355.015304 -270.036036) (xy 355.019264 -269.986982) (xy 355.031041 -269.939198)
			(xy 355.050332 -269.893922) (xy 355.076635 -269.852326) (xy 355.10927 -269.815489) (xy 355.147391 -269.784364)
			(xy 355.190012 -269.759757) (xy 355.236028 -269.742305) (xy 355.284247 -269.732461) (xy 355.333422 -269.73048)
			(xy 355.382277 -269.736412) (xy 355.429548 -269.750104) (xy 355.47401 -269.771202) (xy 355.514513 -269.799158)
			(xy 355.550006 -269.83325) (xy 355.579571 -269.872594) (xy 355.602442 -269.916171) (xy 355.618026 -269.962852)
			(xy 355.625921 -270.011429) (xy 355.626416 -270.036036) (xy 355.955358 -270.036036) (xy 355.959318 -269.986982)
			(xy 355.971095 -269.939198) (xy 355.990386 -269.893922) (xy 356.016689 -269.852326) (xy 356.049324 -269.815489)
			(xy 356.087445 -269.784364) (xy 356.130066 -269.759757) (xy 356.176082 -269.742305) (xy 356.224301 -269.732461)
			(xy 356.273476 -269.73048) (xy 356.322331 -269.736412) (xy 356.369602 -269.750104) (xy 356.414064 -269.771202)
			(xy 356.454567 -269.799158) (xy 356.49006 -269.83325) (xy 356.519625 -269.872594) (xy 356.542496 -269.916171)
			(xy 356.55808 -269.962852) (xy 356.565975 -270.011429) (xy 356.56647 -270.036036) (xy 356.895412 -270.036036)
			(xy 356.899372 -269.986982) (xy 356.911149 -269.939198) (xy 356.93044 -269.893922) (xy 356.956743 -269.852326)
			(xy 356.989378 -269.815489) (xy 357.027499 -269.784364) (xy 357.07012 -269.759757) (xy 357.116136 -269.742305)
			(xy 357.164355 -269.732461) (xy 357.21353 -269.73048) (xy 357.262385 -269.736412) (xy 357.309656 -269.750104)
			(xy 357.354118 -269.771202) (xy 357.394621 -269.799158) (xy 357.430114 -269.83325) (xy 357.459679 -269.872594)
			(xy 357.48255 -269.916171) (xy 357.498134 -269.962852) (xy 357.506029 -270.011429) (xy 357.506524 -270.036036)
			(xy 357.835212 -270.036036) (xy 357.839172 -269.986982) (xy 357.850949 -269.939198) (xy 357.87024 -269.893922)
			(xy 357.896543 -269.852326) (xy 357.929178 -269.815489) (xy 357.967299 -269.784364) (xy 358.00992 -269.759757)
			(xy 358.055936 -269.742305) (xy 358.104155 -269.732461) (xy 358.15333 -269.73048) (xy 358.202185 -269.736412)
			(xy 358.249456 -269.750104) (xy 358.293918 -269.771202) (xy 358.334421 -269.799158) (xy 358.369914 -269.83325)
			(xy 358.399479 -269.872594) (xy 358.42235 -269.916171) (xy 358.437934 -269.962852) (xy 358.445829 -270.011429)
			(xy 358.446324 -270.036036) (xy 361.589078 -270.036036) (xy 361.593038 -269.986982) (xy 361.604815 -269.939198)
			(xy 361.624106 -269.893922) (xy 361.650409 -269.852326) (xy 361.683044 -269.815489) (xy 361.721165 -269.784364)
			(xy 361.763786 -269.759757) (xy 361.809802 -269.742305) (xy 361.858021 -269.732461) (xy 361.907196 -269.73048)
			(xy 361.956051 -269.736412) (xy 362.003322 -269.750104) (xy 362.047784 -269.771202) (xy 362.088287 -269.799158)
			(xy 362.12378 -269.83325) (xy 362.153345 -269.872594) (xy 362.176216 -269.916171) (xy 362.1918 -269.962852)
			(xy 362.199695 -270.011429) (xy 362.20019 -270.036036) (xy 362.528878 -270.036036) (xy 362.532838 -269.986982)
			(xy 362.544615 -269.939198) (xy 362.563906 -269.893922) (xy 362.590209 -269.852326) (xy 362.622844 -269.815489)
			(xy 362.660965 -269.784364) (xy 362.703586 -269.759757) (xy 362.749602 -269.742305) (xy 362.797821 -269.732461)
			(xy 362.846996 -269.73048) (xy 362.895851 -269.736412) (xy 362.943122 -269.750104) (xy 362.987584 -269.771202)
			(xy 363.028087 -269.799158) (xy 363.06358 -269.83325) (xy 363.093145 -269.872594) (xy 363.116016 -269.916171)
			(xy 363.1316 -269.962852) (xy 363.139495 -270.011429) (xy 363.13999 -270.036036) (xy 363.468932 -270.036036)
			(xy 363.472892 -269.986982) (xy 363.484669 -269.939198) (xy 363.50396 -269.893922) (xy 363.530263 -269.852326)
			(xy 363.562898 -269.815489) (xy 363.601019 -269.784364) (xy 363.64364 -269.759757) (xy 363.689656 -269.742305)
			(xy 363.737875 -269.732461) (xy 363.78705 -269.73048) (xy 363.835905 -269.736412) (xy 363.883176 -269.750104)
			(xy 363.927638 -269.771202) (xy 363.968141 -269.799158) (xy 364.003634 -269.83325) (xy 364.033199 -269.872594)
			(xy 364.05607 -269.916171) (xy 364.071654 -269.962852) (xy 364.079549 -270.011429) (xy 364.080044 -270.036036)
			(xy 364.408986 -270.036036) (xy 364.412946 -269.986982) (xy 364.424723 -269.939198) (xy 364.444014 -269.893922)
			(xy 364.470317 -269.852326) (xy 364.502952 -269.815489) (xy 364.541073 -269.784364) (xy 364.583694 -269.759757)
			(xy 364.62971 -269.742305) (xy 364.677929 -269.732461) (xy 364.727104 -269.73048) (xy 364.775959 -269.736412)
			(xy 364.82323 -269.750104) (xy 364.867692 -269.771202) (xy 364.908195 -269.799158) (xy 364.943688 -269.83325)
			(xy 364.973253 -269.872594) (xy 364.996124 -269.916171) (xy 365.011708 -269.962852) (xy 365.019603 -270.011429)
			(xy 365.020098 -270.036036) (xy 365.34904 -270.036036) (xy 365.353 -269.986982) (xy 365.364777 -269.939198)
			(xy 365.384068 -269.893922) (xy 365.410371 -269.852326) (xy 365.443006 -269.815489) (xy 365.481127 -269.784364)
			(xy 365.523748 -269.759757) (xy 365.569764 -269.742305) (xy 365.617983 -269.732461) (xy 365.667158 -269.73048)
			(xy 365.716013 -269.736412) (xy 365.763284 -269.750104) (xy 365.807746 -269.771202) (xy 365.848249 -269.799158)
			(xy 365.883742 -269.83325) (xy 365.913307 -269.872594) (xy 365.936178 -269.916171) (xy 365.951762 -269.962852)
			(xy 365.959657 -270.011429) (xy 365.960152 -270.036036) (xy 366.289094 -270.036036) (xy 366.293054 -269.986982)
			(xy 366.304831 -269.939198) (xy 366.324122 -269.893922) (xy 366.350425 -269.852326) (xy 366.38306 -269.815489)
			(xy 366.421181 -269.784364) (xy 366.463802 -269.759757) (xy 366.509818 -269.742305) (xy 366.558037 -269.732461)
			(xy 366.607212 -269.73048) (xy 366.656067 -269.736412) (xy 366.703338 -269.750104) (xy 366.7478 -269.771202)
			(xy 366.788303 -269.799158) (xy 366.823796 -269.83325) (xy 366.853361 -269.872594) (xy 366.876232 -269.916171)
			(xy 366.891816 -269.962852) (xy 366.899711 -270.011429) (xy 366.900206 -270.036036) (xy 367.228894 -270.036036)
			(xy 367.232854 -269.986982) (xy 367.244631 -269.939198) (xy 367.263922 -269.893922) (xy 367.290225 -269.852326)
			(xy 367.32286 -269.815489) (xy 367.360981 -269.784364) (xy 367.403602 -269.759757) (xy 367.449618 -269.742305)
			(xy 367.497837 -269.732461) (xy 367.547012 -269.73048) (xy 367.595867 -269.736412) (xy 367.643138 -269.750104)
			(xy 367.6876 -269.771202) (xy 367.728103 -269.799158) (xy 367.763596 -269.83325) (xy 367.793161 -269.872594)
			(xy 367.816032 -269.916171) (xy 367.831616 -269.962852) (xy 367.839511 -270.011429) (xy 367.840006 -270.036036)
			(xy 368.168948 -270.036036) (xy 368.172908 -269.986982) (xy 368.184685 -269.939198) (xy 368.203976 -269.893922)
			(xy 368.230279 -269.852326) (xy 368.262914 -269.815489) (xy 368.301035 -269.784364) (xy 368.343656 -269.759757)
			(xy 368.389672 -269.742305) (xy 368.437891 -269.732461) (xy 368.487066 -269.73048) (xy 368.535921 -269.736412)
			(xy 368.583192 -269.750104) (xy 368.627654 -269.771202) (xy 368.668157 -269.799158) (xy 368.70365 -269.83325)
			(xy 368.733215 -269.872594) (xy 368.756086 -269.916171) (xy 368.77167 -269.962852) (xy 368.779565 -270.011429)
			(xy 368.78006 -270.036036) (xy 369.109002 -270.036036) (xy 369.112962 -269.986982) (xy 369.124739 -269.939198)
			(xy 369.14403 -269.893922) (xy 369.170333 -269.852326) (xy 369.202968 -269.815489) (xy 369.241089 -269.784364)
			(xy 369.28371 -269.759757) (xy 369.329726 -269.742305) (xy 369.377945 -269.732461) (xy 369.42712 -269.73048)
			(xy 369.475975 -269.736412) (xy 369.523246 -269.750104) (xy 369.567708 -269.771202) (xy 369.608211 -269.799158)
			(xy 369.643704 -269.83325) (xy 369.673269 -269.872594) (xy 369.69614 -269.916171) (xy 369.711724 -269.962852)
			(xy 369.719619 -270.011429) (xy 369.720114 -270.036036) (xy 370.049056 -270.036036) (xy 370.053016 -269.986982)
			(xy 370.064793 -269.939198) (xy 370.084084 -269.893922) (xy 370.110387 -269.852326) (xy 370.143022 -269.815489)
			(xy 370.181143 -269.784364) (xy 370.223764 -269.759757) (xy 370.26978 -269.742305) (xy 370.317999 -269.732461)
			(xy 370.367174 -269.73048) (xy 370.416029 -269.736412) (xy 370.4633 -269.750104) (xy 370.507762 -269.771202)
			(xy 370.548265 -269.799158) (xy 370.583758 -269.83325) (xy 370.613323 -269.872594) (xy 370.636194 -269.916171)
			(xy 370.651778 -269.962852) (xy 370.659673 -270.011429) (xy 370.660168 -270.036036) (xy 370.98911 -270.036036)
			(xy 370.99307 -269.986982) (xy 371.004847 -269.939198) (xy 371.024138 -269.893922) (xy 371.050441 -269.852326)
			(xy 371.083076 -269.815489) (xy 371.121197 -269.784364) (xy 371.163818 -269.759757) (xy 371.209834 -269.742305)
			(xy 371.258053 -269.732461) (xy 371.307228 -269.73048) (xy 371.356083 -269.736412) (xy 371.403354 -269.750104)
			(xy 371.447816 -269.771202) (xy 371.488319 -269.799158) (xy 371.523812 -269.83325) (xy 371.553377 -269.872594)
			(xy 371.576248 -269.916171) (xy 371.591832 -269.962852) (xy 371.599727 -270.011429) (xy 371.600222 -270.036036)
			(xy 371.92891 -270.036036) (xy 371.93287 -269.986982) (xy 371.944647 -269.939198) (xy 371.963938 -269.893922)
			(xy 371.990241 -269.852326) (xy 372.022876 -269.815489) (xy 372.060997 -269.784364) (xy 372.103618 -269.759757)
			(xy 372.149634 -269.742305) (xy 372.197853 -269.732461) (xy 372.247028 -269.73048) (xy 372.295883 -269.736412)
			(xy 372.343154 -269.750104) (xy 372.387616 -269.771202) (xy 372.428119 -269.799158) (xy 372.463612 -269.83325)
			(xy 372.493177 -269.872594) (xy 372.516048 -269.916171) (xy 372.531632 -269.962852) (xy 372.539527 -270.011429)
			(xy 372.540022 -270.036036) (xy 372.868964 -270.036036) (xy 372.872924 -269.986982) (xy 372.884701 -269.939198)
			(xy 372.903992 -269.893922) (xy 372.930295 -269.852326) (xy 372.96293 -269.815489) (xy 373.001051 -269.784364)
			(xy 373.043672 -269.759757) (xy 373.089688 -269.742305) (xy 373.137907 -269.732461) (xy 373.187082 -269.73048)
			(xy 373.235937 -269.736412) (xy 373.283208 -269.750104) (xy 373.32767 -269.771202) (xy 373.368173 -269.799158)
			(xy 373.403666 -269.83325) (xy 373.433231 -269.872594) (xy 373.456102 -269.916171) (xy 373.471686 -269.962852)
			(xy 373.479581 -270.011429) (xy 373.480076 -270.036036) (xy 373.809018 -270.036036) (xy 373.812978 -269.986982)
			(xy 373.824755 -269.939198) (xy 373.844046 -269.893922) (xy 373.870349 -269.852326) (xy 373.902984 -269.815489)
			(xy 373.941105 -269.784364) (xy 373.983726 -269.759757) (xy 374.029742 -269.742305) (xy 374.077961 -269.732461)
			(xy 374.127136 -269.73048) (xy 374.175991 -269.736412) (xy 374.223262 -269.750104) (xy 374.267724 -269.771202)
			(xy 374.308227 -269.799158) (xy 374.34372 -269.83325) (xy 374.373285 -269.872594) (xy 374.396156 -269.916171)
			(xy 374.41174 -269.962852) (xy 374.419635 -270.011429) (xy 374.42013 -270.036036) (xy 374.749072 -270.036036)
			(xy 374.753032 -269.986982) (xy 374.764809 -269.939198) (xy 374.7841 -269.893922) (xy 374.810403 -269.852326)
			(xy 374.843038 -269.815489) (xy 374.881159 -269.784364) (xy 374.92378 -269.759757) (xy 374.969796 -269.742305)
			(xy 375.018015 -269.732461) (xy 375.06719 -269.73048) (xy 375.116045 -269.736412) (xy 375.163316 -269.750104)
			(xy 375.207778 -269.771202) (xy 375.248281 -269.799158) (xy 375.283774 -269.83325) (xy 375.313339 -269.872594)
			(xy 375.33621 -269.916171) (xy 375.351794 -269.962852) (xy 375.359689 -270.011429) (xy 375.360184 -270.036036)
			(xy 375.678695 -270.036036) (xy 375.68279 -269.985308) (xy 375.694969 -269.935894) (xy 375.714917 -269.889074)
			(xy 375.742118 -269.84606) (xy 375.775866 -269.807966) (xy 375.815288 -269.775779) (xy 375.859362 -269.750333)
			(xy 375.906948 -269.732286) (xy 375.956812 -269.722106) (xy 376.007664 -269.720057) (xy 376.058185 -269.726191)
			(xy 376.107069 -269.740351) (xy 376.153048 -269.762168) (xy 376.194932 -269.791078) (xy 376.231636 -269.826333)
			(xy 376.262209 -269.867019) (xy 376.28586 -269.912082) (xy 376.301976 -269.960356) (xy 376.31014 -270.01059)
			(xy 376.310652 -270.036036) (xy 376.628926 -270.036036) (xy 376.632886 -269.986982) (xy 376.644663 -269.939198)
			(xy 376.663954 -269.893922) (xy 376.690257 -269.852326) (xy 376.722892 -269.815489) (xy 376.761013 -269.784364)
			(xy 376.803634 -269.759757) (xy 376.84965 -269.742305) (xy 376.897869 -269.732461) (xy 376.947044 -269.73048)
			(xy 376.995899 -269.736412) (xy 377.04317 -269.750104) (xy 377.087632 -269.771202) (xy 377.128135 -269.799158)
			(xy 377.163628 -269.83325) (xy 377.193193 -269.872594) (xy 377.216064 -269.916171) (xy 377.231648 -269.962852)
			(xy 377.239543 -270.011429) (xy 377.240038 -270.036036) (xy 377.558549 -270.036036) (xy 377.562644 -269.985308)
			(xy 377.574823 -269.935894) (xy 377.594771 -269.889074) (xy 377.621972 -269.84606) (xy 377.65572 -269.807966)
			(xy 377.695142 -269.775779) (xy 377.739216 -269.750333) (xy 377.786802 -269.732286) (xy 377.836666 -269.722106)
			(xy 377.887518 -269.720057) (xy 377.938039 -269.726191) (xy 377.986923 -269.740351) (xy 378.032902 -269.762168)
			(xy 378.074786 -269.791078) (xy 378.11149 -269.826333) (xy 378.142063 -269.867019) (xy 378.165714 -269.912082)
			(xy 378.18183 -269.960356) (xy 378.189994 -270.01059) (xy 378.190506 -270.036036) (xy 378.189994 -270.061482)
			(xy 378.18183 -270.111716) (xy 378.165714 -270.15999) (xy 378.142063 -270.205053) (xy 378.11149 -270.245739)
			(xy 378.074786 -270.280994) (xy 378.032902 -270.309904) (xy 377.986923 -270.331721) (xy 377.938039 -270.345881)
			(xy 377.887518 -270.352015) (xy 377.836666 -270.349966) (xy 377.786802 -270.339786) (xy 377.739216 -270.321739)
			(xy 377.695142 -270.296293) (xy 377.65572 -270.264106) (xy 377.621972 -270.226012) (xy 377.594771 -270.182998)
			(xy 377.574823 -270.136178) (xy 377.562644 -270.086764) (xy 377.558549 -270.036036) (xy 377.240038 -270.036036)
			(xy 377.239543 -270.060643) (xy 377.231648 -270.10922) (xy 377.216064 -270.155901) (xy 377.193193 -270.199478)
			(xy 377.163628 -270.238822) (xy 377.128135 -270.272914) (xy 377.087632 -270.30087) (xy 377.04317 -270.321968)
			(xy 376.995899 -270.33566) (xy 376.947044 -270.341592) (xy 376.897869 -270.339611) (xy 376.84965 -270.329767)
			(xy 376.803634 -270.312315) (xy 376.761013 -270.287708) (xy 376.722892 -270.256583) (xy 376.690257 -270.219746)
			(xy 376.663954 -270.17815) (xy 376.644663 -270.132874) (xy 376.632886 -270.08509) (xy 376.628926 -270.036036)
			(xy 376.310652 -270.036036) (xy 376.31014 -270.061482) (xy 376.301976 -270.111716) (xy 376.28586 -270.15999)
			(xy 376.262209 -270.205053) (xy 376.231636 -270.245739) (xy 376.194932 -270.280994) (xy 376.153048 -270.309904)
			(xy 376.107069 -270.331721) (xy 376.058185 -270.345881) (xy 376.007664 -270.352015) (xy 375.956812 -270.349966)
			(xy 375.906948 -270.339786) (xy 375.859362 -270.321739) (xy 375.815288 -270.296293) (xy 375.775866 -270.264106)
			(xy 375.742118 -270.226012) (xy 375.714917 -270.182998) (xy 375.694969 -270.136178) (xy 375.68279 -270.086764)
			(xy 375.678695 -270.036036) (xy 375.360184 -270.036036) (xy 375.359689 -270.060643) (xy 375.351794 -270.10922)
			(xy 375.33621 -270.155901) (xy 375.313339 -270.199478) (xy 375.283774 -270.238822) (xy 375.248281 -270.272914)
			(xy 375.207778 -270.30087) (xy 375.163316 -270.321968) (xy 375.116045 -270.33566) (xy 375.06719 -270.341592)
			(xy 375.018015 -270.339611) (xy 374.969796 -270.329767) (xy 374.92378 -270.312315) (xy 374.881159 -270.287708)
			(xy 374.843038 -270.256583) (xy 374.810403 -270.219746) (xy 374.7841 -270.17815) (xy 374.764809 -270.132874)
			(xy 374.753032 -270.08509) (xy 374.749072 -270.036036) (xy 374.42013 -270.036036) (xy 374.419635 -270.060643)
			(xy 374.41174 -270.10922) (xy 374.396156 -270.155901) (xy 374.373285 -270.199478) (xy 374.34372 -270.238822)
			(xy 374.308227 -270.272914) (xy 374.267724 -270.30087) (xy 374.223262 -270.321968) (xy 374.175991 -270.33566)
			(xy 374.127136 -270.341592) (xy 374.077961 -270.339611) (xy 374.029742 -270.329767) (xy 373.983726 -270.312315)
			(xy 373.941105 -270.287708) (xy 373.902984 -270.256583) (xy 373.870349 -270.219746) (xy 373.844046 -270.17815)
			(xy 373.824755 -270.132874) (xy 373.812978 -270.08509) (xy 373.809018 -270.036036) (xy 373.480076 -270.036036)
			(xy 373.479581 -270.060643) (xy 373.471686 -270.10922) (xy 373.456102 -270.155901) (xy 373.433231 -270.199478)
			(xy 373.403666 -270.238822) (xy 373.368173 -270.272914) (xy 373.32767 -270.30087) (xy 373.283208 -270.321968)
			(xy 373.235937 -270.33566) (xy 373.187082 -270.341592) (xy 373.137907 -270.339611) (xy 373.089688 -270.329767)
			(xy 373.043672 -270.312315) (xy 373.001051 -270.287708) (xy 372.96293 -270.256583) (xy 372.930295 -270.219746)
			(xy 372.903992 -270.17815) (xy 372.884701 -270.132874) (xy 372.872924 -270.08509) (xy 372.868964 -270.036036)
			(xy 372.540022 -270.036036) (xy 372.539527 -270.060643) (xy 372.531632 -270.10922) (xy 372.516048 -270.155901)
			(xy 372.493177 -270.199478) (xy 372.463612 -270.238822) (xy 372.428119 -270.272914) (xy 372.387616 -270.30087)
			(xy 372.343154 -270.321968) (xy 372.295883 -270.33566) (xy 372.247028 -270.341592) (xy 372.197853 -270.339611)
			(xy 372.149634 -270.329767) (xy 372.103618 -270.312315) (xy 372.060997 -270.287708) (xy 372.022876 -270.256583)
			(xy 371.990241 -270.219746) (xy 371.963938 -270.17815) (xy 371.944647 -270.132874) (xy 371.93287 -270.08509)
			(xy 371.92891 -270.036036) (xy 371.600222 -270.036036) (xy 371.599727 -270.060643) (xy 371.591832 -270.10922)
			(xy 371.576248 -270.155901) (xy 371.553377 -270.199478) (xy 371.523812 -270.238822) (xy 371.488319 -270.272914)
			(xy 371.447816 -270.30087) (xy 371.403354 -270.321968) (xy 371.356083 -270.33566) (xy 371.307228 -270.341592)
			(xy 371.258053 -270.339611) (xy 371.209834 -270.329767) (xy 371.163818 -270.312315) (xy 371.121197 -270.287708)
			(xy 371.083076 -270.256583) (xy 371.050441 -270.219746) (xy 371.024138 -270.17815) (xy 371.004847 -270.132874)
			(xy 370.99307 -270.08509) (xy 370.98911 -270.036036) (xy 370.660168 -270.036036) (xy 370.659673 -270.060643)
			(xy 370.651778 -270.10922) (xy 370.636194 -270.155901) (xy 370.613323 -270.199478) (xy 370.583758 -270.238822)
			(xy 370.548265 -270.272914) (xy 370.507762 -270.30087) (xy 370.4633 -270.321968) (xy 370.416029 -270.33566)
			(xy 370.367174 -270.341592) (xy 370.317999 -270.339611) (xy 370.26978 -270.329767) (xy 370.223764 -270.312315)
			(xy 370.181143 -270.287708) (xy 370.143022 -270.256583) (xy 370.110387 -270.219746) (xy 370.084084 -270.17815)
			(xy 370.064793 -270.132874) (xy 370.053016 -270.08509) (xy 370.049056 -270.036036) (xy 369.720114 -270.036036)
			(xy 369.719619 -270.060643) (xy 369.711724 -270.10922) (xy 369.69614 -270.155901) (xy 369.673269 -270.199478)
			(xy 369.643704 -270.238822) (xy 369.608211 -270.272914) (xy 369.567708 -270.30087) (xy 369.523246 -270.321968)
			(xy 369.475975 -270.33566) (xy 369.42712 -270.341592) (xy 369.377945 -270.339611) (xy 369.329726 -270.329767)
			(xy 369.28371 -270.312315) (xy 369.241089 -270.287708) (xy 369.202968 -270.256583) (xy 369.170333 -270.219746)
			(xy 369.14403 -270.17815) (xy 369.124739 -270.132874) (xy 369.112962 -270.08509) (xy 369.109002 -270.036036)
			(xy 368.78006 -270.036036) (xy 368.779565 -270.060643) (xy 368.77167 -270.10922) (xy 368.756086 -270.155901)
			(xy 368.733215 -270.199478) (xy 368.70365 -270.238822) (xy 368.668157 -270.272914) (xy 368.627654 -270.30087)
			(xy 368.583192 -270.321968) (xy 368.535921 -270.33566) (xy 368.487066 -270.341592) (xy 368.437891 -270.339611)
			(xy 368.389672 -270.329767) (xy 368.343656 -270.312315) (xy 368.301035 -270.287708) (xy 368.262914 -270.256583)
			(xy 368.230279 -270.219746) (xy 368.203976 -270.17815) (xy 368.184685 -270.132874) (xy 368.172908 -270.08509)
			(xy 368.168948 -270.036036) (xy 367.840006 -270.036036) (xy 367.839511 -270.060643) (xy 367.831616 -270.10922)
			(xy 367.816032 -270.155901) (xy 367.793161 -270.199478) (xy 367.763596 -270.238822) (xy 367.728103 -270.272914)
			(xy 367.6876 -270.30087) (xy 367.643138 -270.321968) (xy 367.595867 -270.33566) (xy 367.547012 -270.341592)
			(xy 367.497837 -270.339611) (xy 367.449618 -270.329767) (xy 367.403602 -270.312315) (xy 367.360981 -270.287708)
			(xy 367.32286 -270.256583) (xy 367.290225 -270.219746) (xy 367.263922 -270.17815) (xy 367.244631 -270.132874)
			(xy 367.232854 -270.08509) (xy 367.228894 -270.036036) (xy 366.900206 -270.036036) (xy 366.899711 -270.060643)
			(xy 366.891816 -270.10922) (xy 366.876232 -270.155901) (xy 366.853361 -270.199478) (xy 366.823796 -270.238822)
			(xy 366.788303 -270.272914) (xy 366.7478 -270.30087) (xy 366.703338 -270.321968) (xy 366.656067 -270.33566)
			(xy 366.607212 -270.341592) (xy 366.558037 -270.339611) (xy 366.509818 -270.329767) (xy 366.463802 -270.312315)
			(xy 366.421181 -270.287708) (xy 366.38306 -270.256583) (xy 366.350425 -270.219746) (xy 366.324122 -270.17815)
			(xy 366.304831 -270.132874) (xy 366.293054 -270.08509) (xy 366.289094 -270.036036) (xy 365.960152 -270.036036)
			(xy 365.959657 -270.060643) (xy 365.951762 -270.10922) (xy 365.936178 -270.155901) (xy 365.913307 -270.199478)
			(xy 365.883742 -270.238822) (xy 365.848249 -270.272914) (xy 365.807746 -270.30087) (xy 365.763284 -270.321968)
			(xy 365.716013 -270.33566) (xy 365.667158 -270.341592) (xy 365.617983 -270.339611) (xy 365.569764 -270.329767)
			(xy 365.523748 -270.312315) (xy 365.481127 -270.287708) (xy 365.443006 -270.256583) (xy 365.410371 -270.219746)
			(xy 365.384068 -270.17815) (xy 365.364777 -270.132874) (xy 365.353 -270.08509) (xy 365.34904 -270.036036)
			(xy 365.020098 -270.036036) (xy 365.019603 -270.060643) (xy 365.011708 -270.10922) (xy 364.996124 -270.155901)
			(xy 364.973253 -270.199478) (xy 364.943688 -270.238822) (xy 364.908195 -270.272914) (xy 364.867692 -270.30087)
			(xy 364.82323 -270.321968) (xy 364.775959 -270.33566) (xy 364.727104 -270.341592) (xy 364.677929 -270.339611)
			(xy 364.62971 -270.329767) (xy 364.583694 -270.312315) (xy 364.541073 -270.287708) (xy 364.502952 -270.256583)
			(xy 364.470317 -270.219746) (xy 364.444014 -270.17815) (xy 364.424723 -270.132874) (xy 364.412946 -270.08509)
			(xy 364.408986 -270.036036) (xy 364.080044 -270.036036) (xy 364.079549 -270.060643) (xy 364.071654 -270.10922)
			(xy 364.05607 -270.155901) (xy 364.033199 -270.199478) (xy 364.003634 -270.238822) (xy 363.968141 -270.272914)
			(xy 363.927638 -270.30087) (xy 363.883176 -270.321968) (xy 363.835905 -270.33566) (xy 363.78705 -270.341592)
			(xy 363.737875 -270.339611) (xy 363.689656 -270.329767) (xy 363.64364 -270.312315) (xy 363.601019 -270.287708)
			(xy 363.562898 -270.256583) (xy 363.530263 -270.219746) (xy 363.50396 -270.17815) (xy 363.484669 -270.132874)
			(xy 363.472892 -270.08509) (xy 363.468932 -270.036036) (xy 363.13999 -270.036036) (xy 363.139495 -270.060643)
			(xy 363.1316 -270.10922) (xy 363.116016 -270.155901) (xy 363.093145 -270.199478) (xy 363.06358 -270.238822)
			(xy 363.028087 -270.272914) (xy 362.987584 -270.30087) (xy 362.943122 -270.321968) (xy 362.895851 -270.33566)
			(xy 362.846996 -270.341592) (xy 362.797821 -270.339611) (xy 362.749602 -270.329767) (xy 362.703586 -270.312315)
			(xy 362.660965 -270.287708) (xy 362.622844 -270.256583) (xy 362.590209 -270.219746) (xy 362.563906 -270.17815)
			(xy 362.544615 -270.132874) (xy 362.532838 -270.08509) (xy 362.528878 -270.036036) (xy 362.20019 -270.036036)
			(xy 362.199695 -270.060643) (xy 362.1918 -270.10922) (xy 362.176216 -270.155901) (xy 362.153345 -270.199478)
			(xy 362.12378 -270.238822) (xy 362.088287 -270.272914) (xy 362.047784 -270.30087) (xy 362.003322 -270.321968)
			(xy 361.956051 -270.33566) (xy 361.907196 -270.341592) (xy 361.858021 -270.339611) (xy 361.809802 -270.329767)
			(xy 361.763786 -270.312315) (xy 361.721165 -270.287708) (xy 361.683044 -270.256583) (xy 361.650409 -270.219746)
			(xy 361.624106 -270.17815) (xy 361.604815 -270.132874) (xy 361.593038 -270.08509) (xy 361.589078 -270.036036)
			(xy 358.446324 -270.036036) (xy 358.445829 -270.060643) (xy 358.437934 -270.10922) (xy 358.42235 -270.155901)
			(xy 358.399479 -270.199478) (xy 358.369914 -270.238822) (xy 358.334421 -270.272914) (xy 358.293918 -270.30087)
			(xy 358.249456 -270.321968) (xy 358.202185 -270.33566) (xy 358.15333 -270.341592) (xy 358.104155 -270.339611)
			(xy 358.055936 -270.329767) (xy 358.00992 -270.312315) (xy 357.967299 -270.287708) (xy 357.929178 -270.256583)
			(xy 357.896543 -270.219746) (xy 357.87024 -270.17815) (xy 357.850949 -270.132874) (xy 357.839172 -270.08509)
			(xy 357.835212 -270.036036) (xy 357.506524 -270.036036) (xy 357.506029 -270.060643) (xy 357.498134 -270.10922)
			(xy 357.48255 -270.155901) (xy 357.459679 -270.199478) (xy 357.430114 -270.238822) (xy 357.394621 -270.272914)
			(xy 357.354118 -270.30087) (xy 357.309656 -270.321968) (xy 357.262385 -270.33566) (xy 357.21353 -270.341592)
			(xy 357.164355 -270.339611) (xy 357.116136 -270.329767) (xy 357.07012 -270.312315) (xy 357.027499 -270.287708)
			(xy 356.989378 -270.256583) (xy 356.956743 -270.219746) (xy 356.93044 -270.17815) (xy 356.911149 -270.132874)
			(xy 356.899372 -270.08509) (xy 356.895412 -270.036036) (xy 356.56647 -270.036036) (xy 356.565975 -270.060643)
			(xy 356.55808 -270.10922) (xy 356.542496 -270.155901) (xy 356.519625 -270.199478) (xy 356.49006 -270.238822)
			(xy 356.454567 -270.272914) (xy 356.414064 -270.30087) (xy 356.369602 -270.321968) (xy 356.322331 -270.33566)
			(xy 356.273476 -270.341592) (xy 356.224301 -270.339611) (xy 356.176082 -270.329767) (xy 356.130066 -270.312315)
			(xy 356.087445 -270.287708) (xy 356.049324 -270.256583) (xy 356.016689 -270.219746) (xy 355.990386 -270.17815)
			(xy 355.971095 -270.132874) (xy 355.959318 -270.08509) (xy 355.955358 -270.036036) (xy 355.626416 -270.036036)
			(xy 355.625921 -270.060643) (xy 355.618026 -270.10922) (xy 355.602442 -270.155901) (xy 355.579571 -270.199478)
			(xy 355.550006 -270.238822) (xy 355.514513 -270.272914) (xy 355.47401 -270.30087) (xy 355.429548 -270.321968)
			(xy 355.382277 -270.33566) (xy 355.333422 -270.341592) (xy 355.284247 -270.339611) (xy 355.236028 -270.329767)
			(xy 355.190012 -270.312315) (xy 355.147391 -270.287708) (xy 355.10927 -270.256583) (xy 355.076635 -270.219746)
			(xy 355.050332 -270.17815) (xy 355.031041 -270.132874) (xy 355.019264 -270.08509) (xy 355.015304 -270.036036)
			(xy 354.686362 -270.036036) (xy 354.685867 -270.060643) (xy 354.677972 -270.10922) (xy 354.662388 -270.155901)
			(xy 354.639517 -270.199478) (xy 354.609952 -270.238822) (xy 354.574459 -270.272914) (xy 354.533956 -270.30087)
			(xy 354.489494 -270.321968) (xy 354.442223 -270.33566) (xy 354.393368 -270.341592) (xy 354.344193 -270.339611)
			(xy 354.295974 -270.329767) (xy 354.249958 -270.312315) (xy 354.207337 -270.287708) (xy 354.169216 -270.256583)
			(xy 354.136581 -270.219746) (xy 354.110278 -270.17815) (xy 354.090987 -270.132874) (xy 354.07921 -270.08509)
			(xy 354.07525 -270.036036) (xy 353.746308 -270.036036) (xy 353.745813 -270.060643) (xy 353.737918 -270.10922)
			(xy 353.722334 -270.155901) (xy 353.699463 -270.199478) (xy 353.669898 -270.238822) (xy 353.634405 -270.272914)
			(xy 353.593902 -270.30087) (xy 353.54944 -270.321968) (xy 353.502169 -270.33566) (xy 353.453314 -270.341592)
			(xy 353.404139 -270.339611) (xy 353.35592 -270.329767) (xy 353.309904 -270.312315) (xy 353.267283 -270.287708)
			(xy 353.229162 -270.256583) (xy 353.196527 -270.219746) (xy 353.170224 -270.17815) (xy 353.150933 -270.132874)
			(xy 353.139156 -270.08509) (xy 353.135196 -270.036036) (xy 352.806508 -270.036036) (xy 352.806013 -270.060643)
			(xy 352.798118 -270.10922) (xy 352.782534 -270.155901) (xy 352.759663 -270.199478) (xy 352.730098 -270.238822)
			(xy 352.694605 -270.272914) (xy 352.654102 -270.30087) (xy 352.60964 -270.321968) (xy 352.562369 -270.33566)
			(xy 352.513514 -270.341592) (xy 352.464339 -270.339611) (xy 352.41612 -270.329767) (xy 352.370104 -270.312315)
			(xy 352.327483 -270.287708) (xy 352.289362 -270.256583) (xy 352.256727 -270.219746) (xy 352.230424 -270.17815)
			(xy 352.211133 -270.132874) (xy 352.199356 -270.08509) (xy 352.195396 -270.036036) (xy 351.866454 -270.036036)
			(xy 351.865959 -270.060643) (xy 351.858064 -270.10922) (xy 351.84248 -270.155901) (xy 351.819609 -270.199478)
			(xy 351.790044 -270.238822) (xy 351.754551 -270.272914) (xy 351.714048 -270.30087) (xy 351.669586 -270.321968)
			(xy 351.622315 -270.33566) (xy 351.57346 -270.341592) (xy 351.524285 -270.339611) (xy 351.476066 -270.329767)
			(xy 351.43005 -270.312315) (xy 351.387429 -270.287708) (xy 351.349308 -270.256583) (xy 351.316673 -270.219746)
			(xy 351.29037 -270.17815) (xy 351.271079 -270.132874) (xy 351.259302 -270.08509) (xy 351.255342 -270.036036)
			(xy 350.9264 -270.036036) (xy 350.925905 -270.060643) (xy 350.91801 -270.10922) (xy 350.902426 -270.155901)
			(xy 350.879555 -270.199478) (xy 350.84999 -270.238822) (xy 350.814497 -270.272914) (xy 350.773994 -270.30087)
			(xy 350.729532 -270.321968) (xy 350.682261 -270.33566) (xy 350.633406 -270.341592) (xy 350.584231 -270.339611)
			(xy 350.536012 -270.329767) (xy 350.489996 -270.312315) (xy 350.447375 -270.287708) (xy 350.409254 -270.256583)
			(xy 350.376619 -270.219746) (xy 350.350316 -270.17815) (xy 350.331025 -270.132874) (xy 350.319248 -270.08509)
			(xy 350.315288 -270.036036) (xy 349.986346 -270.036036) (xy 349.985851 -270.060643) (xy 349.977956 -270.10922)
			(xy 349.962372 -270.155901) (xy 349.939501 -270.199478) (xy 349.909936 -270.238822) (xy 349.874443 -270.272914)
			(xy 349.83394 -270.30087) (xy 349.789478 -270.321968) (xy 349.742207 -270.33566) (xy 349.693352 -270.341592)
			(xy 349.644177 -270.339611) (xy 349.595958 -270.329767) (xy 349.549942 -270.312315) (xy 349.507321 -270.287708)
			(xy 349.4692 -270.256583) (xy 349.436565 -270.219746) (xy 349.410262 -270.17815) (xy 349.390971 -270.132874)
			(xy 349.379194 -270.08509) (xy 349.375234 -270.036036) (xy 349.046546 -270.036036) (xy 349.046051 -270.060643)
			(xy 349.038156 -270.10922) (xy 349.022572 -270.155901) (xy 348.999701 -270.199478) (xy 348.970136 -270.238822)
			(xy 348.934643 -270.272914) (xy 348.89414 -270.30087) (xy 348.849678 -270.321968) (xy 348.802407 -270.33566)
			(xy 348.753552 -270.341592) (xy 348.704377 -270.339611) (xy 348.656158 -270.329767) (xy 348.610142 -270.312315)
			(xy 348.567521 -270.287708) (xy 348.5294 -270.256583) (xy 348.496765 -270.219746) (xy 348.470462 -270.17815)
			(xy 348.451171 -270.132874) (xy 348.439394 -270.08509) (xy 348.435434 -270.036036) (xy 348.106492 -270.036036)
			(xy 348.105997 -270.060643) (xy 348.098102 -270.10922) (xy 348.082518 -270.155901) (xy 348.059647 -270.199478)
			(xy 348.030082 -270.238822) (xy 347.994589 -270.272914) (xy 347.954086 -270.30087) (xy 347.909624 -270.321968)
			(xy 347.862353 -270.33566) (xy 347.813498 -270.341592) (xy 347.764323 -270.339611) (xy 347.716104 -270.329767)
			(xy 347.670088 -270.312315) (xy 347.627467 -270.287708) (xy 347.589346 -270.256583) (xy 347.556711 -270.219746)
			(xy 347.530408 -270.17815) (xy 347.511117 -270.132874) (xy 347.49934 -270.08509) (xy 347.49538 -270.036036)
			(xy 347.166438 -270.036036) (xy 347.165943 -270.060643) (xy 347.158048 -270.10922) (xy 347.142464 -270.155901)
			(xy 347.119593 -270.199478) (xy 347.090028 -270.238822) (xy 347.054535 -270.272914) (xy 347.014032 -270.30087)
			(xy 346.96957 -270.321968) (xy 346.922299 -270.33566) (xy 346.873444 -270.341592) (xy 346.824269 -270.339611)
			(xy 346.77605 -270.329767) (xy 346.730034 -270.312315) (xy 346.687413 -270.287708) (xy 346.649292 -270.256583)
			(xy 346.616657 -270.219746) (xy 346.590354 -270.17815) (xy 346.571063 -270.132874) (xy 346.559286 -270.08509)
			(xy 346.555326 -270.036036) (xy 346.226384 -270.036036) (xy 346.225889 -270.060643) (xy 346.217994 -270.10922)
			(xy 346.20241 -270.155901) (xy 346.179539 -270.199478) (xy 346.149974 -270.238822) (xy 346.114481 -270.272914)
			(xy 346.073978 -270.30087) (xy 346.029516 -270.321968) (xy 345.982245 -270.33566) (xy 345.93339 -270.341592)
			(xy 345.884215 -270.339611) (xy 345.835996 -270.329767) (xy 345.78998 -270.312315) (xy 345.747359 -270.287708)
			(xy 345.709238 -270.256583) (xy 345.676603 -270.219746) (xy 345.6503 -270.17815) (xy 345.631009 -270.132874)
			(xy 345.619232 -270.08509) (xy 345.615272 -270.036036) (xy 345.28633 -270.036036) (xy 345.285835 -270.060643)
			(xy 345.27794 -270.10922) (xy 345.262356 -270.155901) (xy 345.239485 -270.199478) (xy 345.20992 -270.238822)
			(xy 345.174427 -270.272914) (xy 345.133924 -270.30087) (xy 345.089462 -270.321968) (xy 345.042191 -270.33566)
			(xy 344.993336 -270.341592) (xy 344.944161 -270.339611) (xy 344.895942 -270.329767) (xy 344.849926 -270.312315)
			(xy 344.807305 -270.287708) (xy 344.769184 -270.256583) (xy 344.736549 -270.219746) (xy 344.710246 -270.17815)
			(xy 344.690955 -270.132874) (xy 344.679178 -270.08509) (xy 344.675218 -270.036036) (xy 344.356944 -270.036036)
			(xy 344.356432 -270.061482) (xy 344.348268 -270.111716) (xy 344.332152 -270.15999) (xy 344.308501 -270.205053)
			(xy 344.277928 -270.245739) (xy 344.241224 -270.280994) (xy 344.19934 -270.309904) (xy 344.153361 -270.331721)
			(xy 344.104477 -270.345881) (xy 344.053956 -270.352015) (xy 344.003104 -270.349966) (xy 343.95324 -270.339786)
			(xy 343.905654 -270.321739) (xy 343.86158 -270.296293) (xy 343.822158 -270.264106) (xy 343.78841 -270.226012)
			(xy 343.761209 -270.182998) (xy 343.741261 -270.136178) (xy 343.729082 -270.086764) (xy 343.724987 -270.036036)
			(xy 343.406476 -270.036036) (xy 343.405981 -270.060643) (xy 343.398086 -270.10922) (xy 343.382502 -270.155901)
			(xy 343.359631 -270.199478) (xy 343.330066 -270.238822) (xy 343.294573 -270.272914) (xy 343.25407 -270.30087)
			(xy 343.209608 -270.321968) (xy 343.162337 -270.33566) (xy 343.113482 -270.341592) (xy 343.064307 -270.339611)
			(xy 343.016088 -270.329767) (xy 342.970072 -270.312315) (xy 342.927451 -270.287708) (xy 342.88933 -270.256583)
			(xy 342.856695 -270.219746) (xy 342.830392 -270.17815) (xy 342.811101 -270.132874) (xy 342.799324 -270.08509)
			(xy 342.795364 -270.036036) (xy 342.476836 -270.036036) (xy 342.476324 -270.061482) (xy 342.46816 -270.111716)
			(xy 342.452044 -270.15999) (xy 342.428393 -270.205053) (xy 342.39782 -270.245739) (xy 342.361116 -270.280994)
			(xy 342.319232 -270.309904) (xy 342.273253 -270.331721) (xy 342.224369 -270.345881) (xy 342.173848 -270.352015)
			(xy 342.122996 -270.349966) (xy 342.073132 -270.339786) (xy 342.025546 -270.321739) (xy 341.981472 -270.296293)
			(xy 341.94205 -270.264106) (xy 341.908302 -270.226012) (xy 341.881101 -270.182998) (xy 341.861153 -270.136178)
			(xy 341.848974 -270.086764) (xy 341.844879 -270.036036) (xy 341.526368 -270.036036) (xy 341.525913 -270.060098)
			(xy 341.518357 -270.107626) (xy 341.503437 -270.153379) (xy 341.481523 -270.196225) (xy 341.453157 -270.235101)
			(xy 341.419043 -270.269046) (xy 341.380026 -270.297217) (xy 341.337072 -270.318918) (xy 341.291245 -270.33361)
			(xy 341.267542 -270.337788) (xy 341.258652 -270.339058) (xy 341.24265 -270.347948) (xy 341.236808 -270.354806)
			(xy 341.231223 -270.361893) (xy 341.224982 -270.37881) (xy 341.224616 -270.387826) (xy 341.224616 -270.547084)
			(xy 341.224854 -270.5536) (xy 341.228201 -270.566197) (xy 341.23122 -270.571976) (xy 341.24116 -270.589742)
			(xy 341.258706 -270.626482) (xy 341.266272 -270.645382) (xy 341.266272 -270.645636) (xy 341.268902 -270.651823)
			(xy 341.276881 -270.662638) (xy 341.28202 -270.666972) (xy 341.293196 -270.675608) (xy 341.305642 -270.677132)
			(xy 341.395812 -270.688562) (xy 341.402691 -270.68916) (xy 341.416339 -270.687099) (xy 341.422736 -270.684498)
			(xy 341.428578 -270.681958) (xy 341.438992 -270.673576) (xy 341.44331 -270.667734) (xy 341.457776 -270.648434)
			(xy 341.491765 -270.614215) (xy 341.530704 -270.585757) (xy 341.573627 -270.563763) (xy 341.619471 -270.548781)
			(xy 341.667099 -270.541181) (xy 341.691214 -270.540734) (xy 341.716465 -270.541257) (xy 341.766278 -270.549571)
			(xy 341.814044 -270.565971) (xy 341.858458 -270.590009) (xy 341.898311 -270.621029) (xy 341.932514 -270.658185)
			(xy 341.960136 -270.700464) (xy 341.980421 -270.746713) (xy 341.992819 -270.79567) (xy 341.996989 -270.846)
			(xy 341.996986 -270.846042) (xy 342.314779 -270.846042) (xy 342.318874 -270.795314) (xy 342.331053 -270.7459)
			(xy 342.351001 -270.69908) (xy 342.378202 -270.656066) (xy 342.41195 -270.617972) (xy 342.451372 -270.585785)
			(xy 342.495446 -270.560339) (xy 342.543032 -270.542292) (xy 342.592896 -270.532112) (xy 342.643748 -270.530063)
			(xy 342.694269 -270.536197) (xy 342.743153 -270.550357) (xy 342.789132 -270.572174) (xy 342.831016 -270.601084)
			(xy 342.86772 -270.636339) (xy 342.898293 -270.677025) (xy 342.921944 -270.722088) (xy 342.93806 -270.770362)
			(xy 342.946224 -270.820596) (xy 342.946736 -270.846042) (xy 343.254833 -270.846042) (xy 343.258928 -270.795314)
			(xy 343.271107 -270.7459) (xy 343.291055 -270.69908) (xy 343.318256 -270.656066) (xy 343.352004 -270.617972)
			(xy 343.391426 -270.585785) (xy 343.4355 -270.560339) (xy 343.483086 -270.542292) (xy 343.53295 -270.532112)
			(xy 343.583802 -270.530063) (xy 343.634323 -270.536197) (xy 343.683207 -270.550357) (xy 343.729186 -270.572174)
			(xy 343.77107 -270.601084) (xy 343.807774 -270.636339) (xy 343.838347 -270.677025) (xy 343.861998 -270.722088)
			(xy 343.878114 -270.770362) (xy 343.886278 -270.820596) (xy 343.88679 -270.846042) (xy 344.205318 -270.846042)
			(xy 344.209278 -270.796988) (xy 344.221055 -270.749204) (xy 344.240346 -270.703928) (xy 344.266649 -270.662332)
			(xy 344.299284 -270.625495) (xy 344.337405 -270.59437) (xy 344.380026 -270.569763) (xy 344.426042 -270.552311)
			(xy 344.474261 -270.542467) (xy 344.523436 -270.540486) (xy 344.572291 -270.546418) (xy 344.619562 -270.56011)
			(xy 344.664024 -270.581208) (xy 344.704527 -270.609164) (xy 344.74002 -270.643256) (xy 344.769585 -270.6826)
			(xy 344.792456 -270.726177) (xy 344.80804 -270.772858) (xy 344.815935 -270.821435) (xy 344.81643 -270.846042)
			(xy 345.145372 -270.846042) (xy 345.149332 -270.796988) (xy 345.161109 -270.749204) (xy 345.1804 -270.703928)
			(xy 345.206703 -270.662332) (xy 345.239338 -270.625495) (xy 345.277459 -270.59437) (xy 345.32008 -270.569763)
			(xy 345.366096 -270.552311) (xy 345.414315 -270.542467) (xy 345.46349 -270.540486) (xy 345.512345 -270.546418)
			(xy 345.559616 -270.56011) (xy 345.604078 -270.581208) (xy 345.644581 -270.609164) (xy 345.680074 -270.643256)
			(xy 345.709639 -270.6826) (xy 345.73251 -270.726177) (xy 345.748094 -270.772858) (xy 345.755989 -270.821435)
			(xy 345.756484 -270.846042) (xy 346.085426 -270.846042) (xy 346.089386 -270.796988) (xy 346.101163 -270.749204)
			(xy 346.120454 -270.703928) (xy 346.146757 -270.662332) (xy 346.179392 -270.625495) (xy 346.217513 -270.59437)
			(xy 346.260134 -270.569763) (xy 346.30615 -270.552311) (xy 346.354369 -270.542467) (xy 346.403544 -270.540486)
			(xy 346.452399 -270.546418) (xy 346.49967 -270.56011) (xy 346.544132 -270.581208) (xy 346.584635 -270.609164)
			(xy 346.620128 -270.643256) (xy 346.649693 -270.6826) (xy 346.672564 -270.726177) (xy 346.688148 -270.772858)
			(xy 346.696043 -270.821435) (xy 346.696538 -270.846042) (xy 347.025226 -270.846042) (xy 347.029186 -270.796988)
			(xy 347.040963 -270.749204) (xy 347.060254 -270.703928) (xy 347.086557 -270.662332) (xy 347.119192 -270.625495)
			(xy 347.157313 -270.59437) (xy 347.199934 -270.569763) (xy 347.24595 -270.552311) (xy 347.294169 -270.542467)
			(xy 347.343344 -270.540486) (xy 347.392199 -270.546418) (xy 347.43947 -270.56011) (xy 347.483932 -270.581208)
			(xy 347.524435 -270.609164) (xy 347.559928 -270.643256) (xy 347.589493 -270.6826) (xy 347.612364 -270.726177)
			(xy 347.627948 -270.772858) (xy 347.635843 -270.821435) (xy 347.636338 -270.846042) (xy 347.96528 -270.846042)
			(xy 347.96924 -270.796988) (xy 347.981017 -270.749204) (xy 348.000308 -270.703928) (xy 348.026611 -270.662332)
			(xy 348.059246 -270.625495) (xy 348.097367 -270.59437) (xy 348.139988 -270.569763) (xy 348.186004 -270.552311)
			(xy 348.234223 -270.542467) (xy 348.283398 -270.540486) (xy 348.332253 -270.546418) (xy 348.379524 -270.56011)
			(xy 348.423986 -270.581208) (xy 348.464489 -270.609164) (xy 348.499982 -270.643256) (xy 348.529547 -270.6826)
			(xy 348.552418 -270.726177) (xy 348.568002 -270.772858) (xy 348.575897 -270.821435) (xy 348.576392 -270.846042)
			(xy 348.905334 -270.846042) (xy 348.909294 -270.796988) (xy 348.921071 -270.749204) (xy 348.940362 -270.703928)
			(xy 348.966665 -270.662332) (xy 348.9993 -270.625495) (xy 349.037421 -270.59437) (xy 349.080042 -270.569763)
			(xy 349.126058 -270.552311) (xy 349.174277 -270.542467) (xy 349.223452 -270.540486) (xy 349.272307 -270.546418)
			(xy 349.319578 -270.56011) (xy 349.36404 -270.581208) (xy 349.404543 -270.609164) (xy 349.440036 -270.643256)
			(xy 349.469601 -270.6826) (xy 349.492472 -270.726177) (xy 349.508056 -270.772858) (xy 349.515951 -270.821435)
			(xy 349.516446 -270.846042) (xy 349.845388 -270.846042) (xy 349.849348 -270.796988) (xy 349.861125 -270.749204)
			(xy 349.880416 -270.703928) (xy 349.906719 -270.662332) (xy 349.939354 -270.625495) (xy 349.977475 -270.59437)
			(xy 350.020096 -270.569763) (xy 350.066112 -270.552311) (xy 350.114331 -270.542467) (xy 350.163506 -270.540486)
			(xy 350.212361 -270.546418) (xy 350.259632 -270.56011) (xy 350.304094 -270.581208) (xy 350.344597 -270.609164)
			(xy 350.38009 -270.643256) (xy 350.409655 -270.6826) (xy 350.432526 -270.726177) (xy 350.44811 -270.772858)
			(xy 350.456005 -270.821435) (xy 350.4565 -270.846042) (xy 350.785442 -270.846042) (xy 350.789402 -270.796988)
			(xy 350.801179 -270.749204) (xy 350.82047 -270.703928) (xy 350.846773 -270.662332) (xy 350.879408 -270.625495)
			(xy 350.917529 -270.59437) (xy 350.96015 -270.569763) (xy 351.006166 -270.552311) (xy 351.054385 -270.542467)
			(xy 351.10356 -270.540486) (xy 351.152415 -270.546418) (xy 351.199686 -270.56011) (xy 351.244148 -270.581208)
			(xy 351.284651 -270.609164) (xy 351.320144 -270.643256) (xy 351.349709 -270.6826) (xy 351.37258 -270.726177)
			(xy 351.388164 -270.772858) (xy 351.396059 -270.821435) (xy 351.396554 -270.846042) (xy 351.725242 -270.846042)
			(xy 351.729202 -270.796988) (xy 351.740979 -270.749204) (xy 351.76027 -270.703928) (xy 351.786573 -270.662332)
			(xy 351.819208 -270.625495) (xy 351.857329 -270.59437) (xy 351.89995 -270.569763) (xy 351.945966 -270.552311)
			(xy 351.994185 -270.542467) (xy 352.04336 -270.540486) (xy 352.092215 -270.546418) (xy 352.139486 -270.56011)
			(xy 352.183948 -270.581208) (xy 352.224451 -270.609164) (xy 352.259944 -270.643256) (xy 352.289509 -270.6826)
			(xy 352.31238 -270.726177) (xy 352.327964 -270.772858) (xy 352.335859 -270.821435) (xy 352.336354 -270.846042)
			(xy 352.665296 -270.846042) (xy 352.669256 -270.796988) (xy 352.681033 -270.749204) (xy 352.700324 -270.703928)
			(xy 352.726627 -270.662332) (xy 352.759262 -270.625495) (xy 352.797383 -270.59437) (xy 352.840004 -270.569763)
			(xy 352.88602 -270.552311) (xy 352.934239 -270.542467) (xy 352.983414 -270.540486) (xy 353.032269 -270.546418)
			(xy 353.07954 -270.56011) (xy 353.124002 -270.581208) (xy 353.164505 -270.609164) (xy 353.199998 -270.643256)
			(xy 353.229563 -270.6826) (xy 353.252434 -270.726177) (xy 353.268018 -270.772858) (xy 353.275913 -270.821435)
			(xy 353.276408 -270.846042) (xy 353.60535 -270.846042) (xy 353.60931 -270.796988) (xy 353.621087 -270.749204)
			(xy 353.640378 -270.703928) (xy 353.666681 -270.662332) (xy 353.699316 -270.625495) (xy 353.737437 -270.59437)
			(xy 353.780058 -270.569763) (xy 353.826074 -270.552311) (xy 353.874293 -270.542467) (xy 353.923468 -270.540486)
			(xy 353.972323 -270.546418) (xy 354.019594 -270.56011) (xy 354.064056 -270.581208) (xy 354.104559 -270.609164)
			(xy 354.140052 -270.643256) (xy 354.169617 -270.6826) (xy 354.192488 -270.726177) (xy 354.208072 -270.772858)
			(xy 354.215967 -270.821435) (xy 354.216462 -270.846042) (xy 354.545404 -270.846042) (xy 354.549364 -270.796988)
			(xy 354.561141 -270.749204) (xy 354.580432 -270.703928) (xy 354.606735 -270.662332) (xy 354.63937 -270.625495)
			(xy 354.677491 -270.59437) (xy 354.720112 -270.569763) (xy 354.766128 -270.552311) (xy 354.814347 -270.542467)
			(xy 354.863522 -270.540486) (xy 354.912377 -270.546418) (xy 354.959648 -270.56011) (xy 355.00411 -270.581208)
			(xy 355.044613 -270.609164) (xy 355.080106 -270.643256) (xy 355.109671 -270.6826) (xy 355.132542 -270.726177)
			(xy 355.148126 -270.772858) (xy 355.156021 -270.821435) (xy 355.156516 -270.846042) (xy 355.485204 -270.846042)
			(xy 355.489164 -270.796988) (xy 355.500941 -270.749204) (xy 355.520232 -270.703928) (xy 355.546535 -270.662332)
			(xy 355.57917 -270.625495) (xy 355.617291 -270.59437) (xy 355.659912 -270.569763) (xy 355.705928 -270.552311)
			(xy 355.754147 -270.542467) (xy 355.803322 -270.540486) (xy 355.852177 -270.546418) (xy 355.899448 -270.56011)
			(xy 355.94391 -270.581208) (xy 355.984413 -270.609164) (xy 356.019906 -270.643256) (xy 356.049471 -270.6826)
			(xy 356.072342 -270.726177) (xy 356.087926 -270.772858) (xy 356.095821 -270.821435) (xy 356.096316 -270.846042)
			(xy 356.425258 -270.846042) (xy 356.429218 -270.796988) (xy 356.440995 -270.749204) (xy 356.460286 -270.703928)
			(xy 356.486589 -270.662332) (xy 356.519224 -270.625495) (xy 356.557345 -270.59437) (xy 356.599966 -270.569763)
			(xy 356.645982 -270.552311) (xy 356.694201 -270.542467) (xy 356.743376 -270.540486) (xy 356.792231 -270.546418)
			(xy 356.839502 -270.56011) (xy 356.883964 -270.581208) (xy 356.924467 -270.609164) (xy 356.95996 -270.643256)
			(xy 356.989525 -270.6826) (xy 357.012396 -270.726177) (xy 357.02798 -270.772858) (xy 357.035875 -270.821435)
			(xy 357.03637 -270.846042) (xy 357.365312 -270.846042) (xy 357.369272 -270.796988) (xy 357.381049 -270.749204)
			(xy 357.40034 -270.703928) (xy 357.426643 -270.662332) (xy 357.459278 -270.625495) (xy 357.497399 -270.59437)
			(xy 357.54002 -270.569763) (xy 357.586036 -270.552311) (xy 357.634255 -270.542467) (xy 357.68343 -270.540486)
			(xy 357.732285 -270.546418) (xy 357.779556 -270.56011) (xy 357.824018 -270.581208) (xy 357.864521 -270.609164)
			(xy 357.900014 -270.643256) (xy 357.929579 -270.6826) (xy 357.95245 -270.726177) (xy 357.968034 -270.772858)
			(xy 357.975929 -270.821435) (xy 357.976424 -270.846042) (xy 358.305366 -270.846042) (xy 358.309326 -270.796988)
			(xy 358.321103 -270.749204) (xy 358.340394 -270.703928) (xy 358.366697 -270.662332) (xy 358.399332 -270.625495)
			(xy 358.437453 -270.59437) (xy 358.480074 -270.569763) (xy 358.52609 -270.552311) (xy 358.574309 -270.542467)
			(xy 358.623484 -270.540486) (xy 358.672339 -270.546418) (xy 358.71961 -270.56011) (xy 358.764072 -270.581208)
			(xy 358.804575 -270.609164) (xy 358.840068 -270.643256) (xy 358.869633 -270.6826) (xy 358.892504 -270.726177)
			(xy 358.908088 -270.772858) (xy 358.915983 -270.821435) (xy 358.916478 -270.846042) (xy 361.118924 -270.846042)
			(xy 361.122884 -270.796988) (xy 361.134661 -270.749204) (xy 361.153952 -270.703928) (xy 361.180255 -270.662332)
			(xy 361.21289 -270.625495) (xy 361.251011 -270.59437) (xy 361.293632 -270.569763) (xy 361.339648 -270.552311)
			(xy 361.387867 -270.542467) (xy 361.437042 -270.540486) (xy 361.485897 -270.546418) (xy 361.533168 -270.56011)
			(xy 361.57763 -270.581208) (xy 361.618133 -270.609164) (xy 361.653626 -270.643256) (xy 361.683191 -270.6826)
			(xy 361.706062 -270.726177) (xy 361.721646 -270.772858) (xy 361.729541 -270.821435) (xy 361.730036 -270.846042)
			(xy 362.058978 -270.846042) (xy 362.062938 -270.796988) (xy 362.074715 -270.749204) (xy 362.094006 -270.703928)
			(xy 362.120309 -270.662332) (xy 362.152944 -270.625495) (xy 362.191065 -270.59437) (xy 362.233686 -270.569763)
			(xy 362.279702 -270.552311) (xy 362.327921 -270.542467) (xy 362.377096 -270.540486) (xy 362.425951 -270.546418)
			(xy 362.473222 -270.56011) (xy 362.517684 -270.581208) (xy 362.558187 -270.609164) (xy 362.59368 -270.643256)
			(xy 362.623245 -270.6826) (xy 362.646116 -270.726177) (xy 362.6617 -270.772858) (xy 362.669595 -270.821435)
			(xy 362.67009 -270.846042) (xy 362.999032 -270.846042) (xy 363.002992 -270.796988) (xy 363.014769 -270.749204)
			(xy 363.03406 -270.703928) (xy 363.060363 -270.662332) (xy 363.092998 -270.625495) (xy 363.131119 -270.59437)
			(xy 363.17374 -270.569763) (xy 363.219756 -270.552311) (xy 363.267975 -270.542467) (xy 363.31715 -270.540486)
			(xy 363.366005 -270.546418) (xy 363.413276 -270.56011) (xy 363.457738 -270.581208) (xy 363.498241 -270.609164)
			(xy 363.533734 -270.643256) (xy 363.563299 -270.6826) (xy 363.58617 -270.726177) (xy 363.601754 -270.772858)
			(xy 363.609649 -270.821435) (xy 363.610144 -270.846042) (xy 363.939086 -270.846042) (xy 363.943046 -270.796988)
			(xy 363.954823 -270.749204) (xy 363.974114 -270.703928) (xy 364.000417 -270.662332) (xy 364.033052 -270.625495)
			(xy 364.071173 -270.59437) (xy 364.113794 -270.569763) (xy 364.15981 -270.552311) (xy 364.208029 -270.542467)
			(xy 364.257204 -270.540486) (xy 364.306059 -270.546418) (xy 364.35333 -270.56011) (xy 364.397792 -270.581208)
			(xy 364.438295 -270.609164) (xy 364.473788 -270.643256) (xy 364.503353 -270.6826) (xy 364.526224 -270.726177)
			(xy 364.541808 -270.772858) (xy 364.549703 -270.821435) (xy 364.550198 -270.846042) (xy 364.878886 -270.846042)
			(xy 364.882846 -270.796988) (xy 364.894623 -270.749204) (xy 364.913914 -270.703928) (xy 364.940217 -270.662332)
			(xy 364.972852 -270.625495) (xy 365.010973 -270.59437) (xy 365.053594 -270.569763) (xy 365.09961 -270.552311)
			(xy 365.147829 -270.542467) (xy 365.197004 -270.540486) (xy 365.245859 -270.546418) (xy 365.29313 -270.56011)
			(xy 365.337592 -270.581208) (xy 365.378095 -270.609164) (xy 365.413588 -270.643256) (xy 365.443153 -270.6826)
			(xy 365.466024 -270.726177) (xy 365.481608 -270.772858) (xy 365.489503 -270.821435) (xy 365.489998 -270.846042)
			(xy 365.81894 -270.846042) (xy 365.8229 -270.796988) (xy 365.834677 -270.749204) (xy 365.853968 -270.703928)
			(xy 365.880271 -270.662332) (xy 365.912906 -270.625495) (xy 365.951027 -270.59437) (xy 365.993648 -270.569763)
			(xy 366.039664 -270.552311) (xy 366.087883 -270.542467) (xy 366.137058 -270.540486) (xy 366.185913 -270.546418)
			(xy 366.233184 -270.56011) (xy 366.277646 -270.581208) (xy 366.318149 -270.609164) (xy 366.353642 -270.643256)
			(xy 366.383207 -270.6826) (xy 366.406078 -270.726177) (xy 366.421662 -270.772858) (xy 366.429557 -270.821435)
			(xy 366.430052 -270.846042) (xy 366.758994 -270.846042) (xy 366.762954 -270.796988) (xy 366.774731 -270.749204)
			(xy 366.794022 -270.703928) (xy 366.820325 -270.662332) (xy 366.85296 -270.625495) (xy 366.891081 -270.59437)
			(xy 366.933702 -270.569763) (xy 366.979718 -270.552311) (xy 367.027937 -270.542467) (xy 367.077112 -270.540486)
			(xy 367.125967 -270.546418) (xy 367.173238 -270.56011) (xy 367.2177 -270.581208) (xy 367.258203 -270.609164)
			(xy 367.293696 -270.643256) (xy 367.323261 -270.6826) (xy 367.346132 -270.726177) (xy 367.361716 -270.772858)
			(xy 367.369611 -270.821435) (xy 367.370106 -270.846042) (xy 367.699048 -270.846042) (xy 367.703008 -270.796988)
			(xy 367.714785 -270.749204) (xy 367.734076 -270.703928) (xy 367.760379 -270.662332) (xy 367.793014 -270.625495)
			(xy 367.831135 -270.59437) (xy 367.873756 -270.569763) (xy 367.919772 -270.552311) (xy 367.967991 -270.542467)
			(xy 368.017166 -270.540486) (xy 368.066021 -270.546418) (xy 368.113292 -270.56011) (xy 368.157754 -270.581208)
			(xy 368.198257 -270.609164) (xy 368.23375 -270.643256) (xy 368.263315 -270.6826) (xy 368.286186 -270.726177)
			(xy 368.30177 -270.772858) (xy 368.309665 -270.821435) (xy 368.31016 -270.846042) (xy 368.639102 -270.846042)
			(xy 368.643062 -270.796988) (xy 368.654839 -270.749204) (xy 368.67413 -270.703928) (xy 368.700433 -270.662332)
			(xy 368.733068 -270.625495) (xy 368.771189 -270.59437) (xy 368.81381 -270.569763) (xy 368.859826 -270.552311)
			(xy 368.908045 -270.542467) (xy 368.95722 -270.540486) (xy 369.006075 -270.546418) (xy 369.053346 -270.56011)
			(xy 369.097808 -270.581208) (xy 369.138311 -270.609164) (xy 369.173804 -270.643256) (xy 369.203369 -270.6826)
			(xy 369.22624 -270.726177) (xy 369.241824 -270.772858) (xy 369.249719 -270.821435) (xy 369.250214 -270.846042)
			(xy 369.578902 -270.846042) (xy 369.582862 -270.796988) (xy 369.594639 -270.749204) (xy 369.61393 -270.703928)
			(xy 369.640233 -270.662332) (xy 369.672868 -270.625495) (xy 369.710989 -270.59437) (xy 369.75361 -270.569763)
			(xy 369.799626 -270.552311) (xy 369.847845 -270.542467) (xy 369.89702 -270.540486) (xy 369.945875 -270.546418)
			(xy 369.993146 -270.56011) (xy 370.037608 -270.581208) (xy 370.078111 -270.609164) (xy 370.113604 -270.643256)
			(xy 370.143169 -270.6826) (xy 370.16604 -270.726177) (xy 370.181624 -270.772858) (xy 370.189519 -270.821435)
			(xy 370.190014 -270.846042) (xy 370.518956 -270.846042) (xy 370.522916 -270.796988) (xy 370.534693 -270.749204)
			(xy 370.553984 -270.703928) (xy 370.580287 -270.662332) (xy 370.612922 -270.625495) (xy 370.651043 -270.59437)
			(xy 370.693664 -270.569763) (xy 370.73968 -270.552311) (xy 370.787899 -270.542467) (xy 370.837074 -270.540486)
			(xy 370.885929 -270.546418) (xy 370.9332 -270.56011) (xy 370.977662 -270.581208) (xy 371.018165 -270.609164)
			(xy 371.053658 -270.643256) (xy 371.083223 -270.6826) (xy 371.106094 -270.726177) (xy 371.121678 -270.772858)
			(xy 371.129573 -270.821435) (xy 371.130068 -270.846042) (xy 371.45901 -270.846042) (xy 371.46297 -270.796988)
			(xy 371.474747 -270.749204) (xy 371.494038 -270.703928) (xy 371.520341 -270.662332) (xy 371.552976 -270.625495)
			(xy 371.591097 -270.59437) (xy 371.633718 -270.569763) (xy 371.679734 -270.552311) (xy 371.727953 -270.542467)
			(xy 371.777128 -270.540486) (xy 371.825983 -270.546418) (xy 371.873254 -270.56011) (xy 371.917716 -270.581208)
			(xy 371.958219 -270.609164) (xy 371.993712 -270.643256) (xy 372.023277 -270.6826) (xy 372.046148 -270.726177)
			(xy 372.061732 -270.772858) (xy 372.069627 -270.821435) (xy 372.070122 -270.846042) (xy 372.399064 -270.846042)
			(xy 372.403024 -270.796988) (xy 372.414801 -270.749204) (xy 372.434092 -270.703928) (xy 372.460395 -270.662332)
			(xy 372.49303 -270.625495) (xy 372.531151 -270.59437) (xy 372.573772 -270.569763) (xy 372.619788 -270.552311)
			(xy 372.668007 -270.542467) (xy 372.717182 -270.540486) (xy 372.766037 -270.546418) (xy 372.813308 -270.56011)
			(xy 372.85777 -270.581208) (xy 372.898273 -270.609164) (xy 372.933766 -270.643256) (xy 372.963331 -270.6826)
			(xy 372.986202 -270.726177) (xy 373.001786 -270.772858) (xy 373.009681 -270.821435) (xy 373.010176 -270.846042)
			(xy 373.339118 -270.846042) (xy 373.343078 -270.796988) (xy 373.354855 -270.749204) (xy 373.374146 -270.703928)
			(xy 373.400449 -270.662332) (xy 373.433084 -270.625495) (xy 373.471205 -270.59437) (xy 373.513826 -270.569763)
			(xy 373.559842 -270.552311) (xy 373.608061 -270.542467) (xy 373.657236 -270.540486) (xy 373.706091 -270.546418)
			(xy 373.753362 -270.56011) (xy 373.797824 -270.581208) (xy 373.838327 -270.609164) (xy 373.87382 -270.643256)
			(xy 373.903385 -270.6826) (xy 373.926256 -270.726177) (xy 373.94184 -270.772858) (xy 373.949735 -270.821435)
			(xy 373.95023 -270.846042) (xy 374.278918 -270.846042) (xy 374.282878 -270.796988) (xy 374.294655 -270.749204)
			(xy 374.313946 -270.703928) (xy 374.340249 -270.662332) (xy 374.372884 -270.625495) (xy 374.411005 -270.59437)
			(xy 374.453626 -270.569763) (xy 374.499642 -270.552311) (xy 374.547861 -270.542467) (xy 374.597036 -270.540486)
			(xy 374.645891 -270.546418) (xy 374.693162 -270.56011) (xy 374.737624 -270.581208) (xy 374.778127 -270.609164)
			(xy 374.81362 -270.643256) (xy 374.843185 -270.6826) (xy 374.866056 -270.726177) (xy 374.88164 -270.772858)
			(xy 374.889535 -270.821435) (xy 374.89003 -270.846042) (xy 375.218972 -270.846042) (xy 375.222932 -270.796988)
			(xy 375.234709 -270.749204) (xy 375.254 -270.703928) (xy 375.280303 -270.662332) (xy 375.312938 -270.625495)
			(xy 375.351059 -270.59437) (xy 375.39368 -270.569763) (xy 375.439696 -270.552311) (xy 375.487915 -270.542467)
			(xy 375.53709 -270.540486) (xy 375.585945 -270.546418) (xy 375.633216 -270.56011) (xy 375.677678 -270.581208)
			(xy 375.718181 -270.609164) (xy 375.753674 -270.643256) (xy 375.783239 -270.6826) (xy 375.80611 -270.726177)
			(xy 375.821694 -270.772858) (xy 375.829589 -270.821435) (xy 375.830084 -270.846042) (xy 376.148595 -270.846042)
			(xy 376.15269 -270.795314) (xy 376.164869 -270.7459) (xy 376.184817 -270.69908) (xy 376.212018 -270.656066)
			(xy 376.245766 -270.617972) (xy 376.285188 -270.585785) (xy 376.329262 -270.560339) (xy 376.376848 -270.542292)
			(xy 376.426712 -270.532112) (xy 376.477564 -270.530063) (xy 376.528085 -270.536197) (xy 376.576969 -270.550357)
			(xy 376.622948 -270.572174) (xy 376.664832 -270.601084) (xy 376.701536 -270.636339) (xy 376.732109 -270.677025)
			(xy 376.75576 -270.722088) (xy 376.771876 -270.770362) (xy 376.78004 -270.820596) (xy 376.780552 -270.846042)
			(xy 377.088649 -270.846042) (xy 377.092744 -270.795314) (xy 377.104923 -270.7459) (xy 377.124871 -270.69908)
			(xy 377.152072 -270.656066) (xy 377.18582 -270.617972) (xy 377.225242 -270.585785) (xy 377.269316 -270.560339)
			(xy 377.316902 -270.542292) (xy 377.366766 -270.532112) (xy 377.417618 -270.530063) (xy 377.468139 -270.536197)
			(xy 377.517023 -270.550357) (xy 377.563002 -270.572174) (xy 377.604886 -270.601084) (xy 377.64159 -270.636339)
			(xy 377.672163 -270.677025) (xy 377.695814 -270.722088) (xy 377.71193 -270.770362) (xy 377.720094 -270.820596)
			(xy 377.720606 -270.846042) (xy 377.720094 -270.871488) (xy 377.71193 -270.921722) (xy 377.695814 -270.969996)
			(xy 377.672163 -271.015059) (xy 377.64159 -271.055745) (xy 377.604886 -271.091) (xy 377.563002 -271.11991)
			(xy 377.517023 -271.141727) (xy 377.468139 -271.155887) (xy 377.417618 -271.162021) (xy 377.366766 -271.159972)
			(xy 377.316902 -271.149792) (xy 377.269316 -271.131745) (xy 377.225242 -271.106299) (xy 377.18582 -271.074112)
			(xy 377.152072 -271.036018) (xy 377.124871 -270.993004) (xy 377.104923 -270.946184) (xy 377.092744 -270.89677)
			(xy 377.088649 -270.846042) (xy 376.780552 -270.846042) (xy 376.78004 -270.871488) (xy 376.771876 -270.921722)
			(xy 376.75576 -270.969996) (xy 376.732109 -271.015059) (xy 376.701536 -271.055745) (xy 376.664832 -271.091)
			(xy 376.622948 -271.11991) (xy 376.576969 -271.141727) (xy 376.528085 -271.155887) (xy 376.477564 -271.162021)
			(xy 376.426712 -271.159972) (xy 376.376848 -271.149792) (xy 376.329262 -271.131745) (xy 376.285188 -271.106299)
			(xy 376.245766 -271.074112) (xy 376.212018 -271.036018) (xy 376.184817 -270.993004) (xy 376.164869 -270.946184)
			(xy 376.15269 -270.89677) (xy 376.148595 -270.846042) (xy 375.830084 -270.846042) (xy 375.829589 -270.870649)
			(xy 375.821694 -270.919226) (xy 375.80611 -270.965907) (xy 375.783239 -271.009484) (xy 375.753674 -271.048828)
			(xy 375.718181 -271.08292) (xy 375.677678 -271.110876) (xy 375.633216 -271.131974) (xy 375.585945 -271.145666)
			(xy 375.53709 -271.151598) (xy 375.487915 -271.149617) (xy 375.439696 -271.139773) (xy 375.39368 -271.122321)
			(xy 375.351059 -271.097714) (xy 375.312938 -271.066589) (xy 375.280303 -271.029752) (xy 375.254 -270.988156)
			(xy 375.234709 -270.94288) (xy 375.222932 -270.895096) (xy 375.218972 -270.846042) (xy 374.89003 -270.846042)
			(xy 374.889535 -270.870649) (xy 374.88164 -270.919226) (xy 374.866056 -270.965907) (xy 374.843185 -271.009484)
			(xy 374.81362 -271.048828) (xy 374.778127 -271.08292) (xy 374.737624 -271.110876) (xy 374.693162 -271.131974)
			(xy 374.645891 -271.145666) (xy 374.597036 -271.151598) (xy 374.547861 -271.149617) (xy 374.499642 -271.139773)
			(xy 374.453626 -271.122321) (xy 374.411005 -271.097714) (xy 374.372884 -271.066589) (xy 374.340249 -271.029752)
			(xy 374.313946 -270.988156) (xy 374.294655 -270.94288) (xy 374.282878 -270.895096) (xy 374.278918 -270.846042)
			(xy 373.95023 -270.846042) (xy 373.949735 -270.870649) (xy 373.94184 -270.919226) (xy 373.926256 -270.965907)
			(xy 373.903385 -271.009484) (xy 373.87382 -271.048828) (xy 373.838327 -271.08292) (xy 373.797824 -271.110876)
			(xy 373.753362 -271.131974) (xy 373.706091 -271.145666) (xy 373.657236 -271.151598) (xy 373.608061 -271.149617)
			(xy 373.559842 -271.139773) (xy 373.513826 -271.122321) (xy 373.471205 -271.097714) (xy 373.433084 -271.066589)
			(xy 373.400449 -271.029752) (xy 373.374146 -270.988156) (xy 373.354855 -270.94288) (xy 373.343078 -270.895096)
			(xy 373.339118 -270.846042) (xy 373.010176 -270.846042) (xy 373.009681 -270.870649) (xy 373.001786 -270.919226)
			(xy 372.986202 -270.965907) (xy 372.963331 -271.009484) (xy 372.933766 -271.048828) (xy 372.898273 -271.08292)
			(xy 372.85777 -271.110876) (xy 372.813308 -271.131974) (xy 372.766037 -271.145666) (xy 372.717182 -271.151598)
			(xy 372.668007 -271.149617) (xy 372.619788 -271.139773) (xy 372.573772 -271.122321) (xy 372.531151 -271.097714)
			(xy 372.49303 -271.066589) (xy 372.460395 -271.029752) (xy 372.434092 -270.988156) (xy 372.414801 -270.94288)
			(xy 372.403024 -270.895096) (xy 372.399064 -270.846042) (xy 372.070122 -270.846042) (xy 372.069627 -270.870649)
			(xy 372.061732 -270.919226) (xy 372.046148 -270.965907) (xy 372.023277 -271.009484) (xy 371.993712 -271.048828)
			(xy 371.958219 -271.08292) (xy 371.917716 -271.110876) (xy 371.873254 -271.131974) (xy 371.825983 -271.145666)
			(xy 371.777128 -271.151598) (xy 371.727953 -271.149617) (xy 371.679734 -271.139773) (xy 371.633718 -271.122321)
			(xy 371.591097 -271.097714) (xy 371.552976 -271.066589) (xy 371.520341 -271.029752) (xy 371.494038 -270.988156)
			(xy 371.474747 -270.94288) (xy 371.46297 -270.895096) (xy 371.45901 -270.846042) (xy 371.130068 -270.846042)
			(xy 371.129573 -270.870649) (xy 371.121678 -270.919226) (xy 371.106094 -270.965907) (xy 371.083223 -271.009484)
			(xy 371.053658 -271.048828) (xy 371.018165 -271.08292) (xy 370.977662 -271.110876) (xy 370.9332 -271.131974)
			(xy 370.885929 -271.145666) (xy 370.837074 -271.151598) (xy 370.787899 -271.149617) (xy 370.73968 -271.139773)
			(xy 370.693664 -271.122321) (xy 370.651043 -271.097714) (xy 370.612922 -271.066589) (xy 370.580287 -271.029752)
			(xy 370.553984 -270.988156) (xy 370.534693 -270.94288) (xy 370.522916 -270.895096) (xy 370.518956 -270.846042)
			(xy 370.190014 -270.846042) (xy 370.189519 -270.870649) (xy 370.181624 -270.919226) (xy 370.16604 -270.965907)
			(xy 370.143169 -271.009484) (xy 370.113604 -271.048828) (xy 370.078111 -271.08292) (xy 370.037608 -271.110876)
			(xy 369.993146 -271.131974) (xy 369.945875 -271.145666) (xy 369.89702 -271.151598) (xy 369.847845 -271.149617)
			(xy 369.799626 -271.139773) (xy 369.75361 -271.122321) (xy 369.710989 -271.097714) (xy 369.672868 -271.066589)
			(xy 369.640233 -271.029752) (xy 369.61393 -270.988156) (xy 369.594639 -270.94288) (xy 369.582862 -270.895096)
			(xy 369.578902 -270.846042) (xy 369.250214 -270.846042) (xy 369.249719 -270.870649) (xy 369.241824 -270.919226)
			(xy 369.22624 -270.965907) (xy 369.203369 -271.009484) (xy 369.173804 -271.048828) (xy 369.138311 -271.08292)
			(xy 369.097808 -271.110876) (xy 369.053346 -271.131974) (xy 369.006075 -271.145666) (xy 368.95722 -271.151598)
			(xy 368.908045 -271.149617) (xy 368.859826 -271.139773) (xy 368.81381 -271.122321) (xy 368.771189 -271.097714)
			(xy 368.733068 -271.066589) (xy 368.700433 -271.029752) (xy 368.67413 -270.988156) (xy 368.654839 -270.94288)
			(xy 368.643062 -270.895096) (xy 368.639102 -270.846042) (xy 368.31016 -270.846042) (xy 368.309665 -270.870649)
			(xy 368.30177 -270.919226) (xy 368.286186 -270.965907) (xy 368.263315 -271.009484) (xy 368.23375 -271.048828)
			(xy 368.198257 -271.08292) (xy 368.157754 -271.110876) (xy 368.113292 -271.131974) (xy 368.066021 -271.145666)
			(xy 368.017166 -271.151598) (xy 367.967991 -271.149617) (xy 367.919772 -271.139773) (xy 367.873756 -271.122321)
			(xy 367.831135 -271.097714) (xy 367.793014 -271.066589) (xy 367.760379 -271.029752) (xy 367.734076 -270.988156)
			(xy 367.714785 -270.94288) (xy 367.703008 -270.895096) (xy 367.699048 -270.846042) (xy 367.370106 -270.846042)
			(xy 367.369611 -270.870649) (xy 367.361716 -270.919226) (xy 367.346132 -270.965907) (xy 367.323261 -271.009484)
			(xy 367.293696 -271.048828) (xy 367.258203 -271.08292) (xy 367.2177 -271.110876) (xy 367.173238 -271.131974)
			(xy 367.125967 -271.145666) (xy 367.077112 -271.151598) (xy 367.027937 -271.149617) (xy 366.979718 -271.139773)
			(xy 366.933702 -271.122321) (xy 366.891081 -271.097714) (xy 366.85296 -271.066589) (xy 366.820325 -271.029752)
			(xy 366.794022 -270.988156) (xy 366.774731 -270.94288) (xy 366.762954 -270.895096) (xy 366.758994 -270.846042)
			(xy 366.430052 -270.846042) (xy 366.429557 -270.870649) (xy 366.421662 -270.919226) (xy 366.406078 -270.965907)
			(xy 366.383207 -271.009484) (xy 366.353642 -271.048828) (xy 366.318149 -271.08292) (xy 366.277646 -271.110876)
			(xy 366.233184 -271.131974) (xy 366.185913 -271.145666) (xy 366.137058 -271.151598) (xy 366.087883 -271.149617)
			(xy 366.039664 -271.139773) (xy 365.993648 -271.122321) (xy 365.951027 -271.097714) (xy 365.912906 -271.066589)
			(xy 365.880271 -271.029752) (xy 365.853968 -270.988156) (xy 365.834677 -270.94288) (xy 365.8229 -270.895096)
			(xy 365.81894 -270.846042) (xy 365.489998 -270.846042) (xy 365.489503 -270.870649) (xy 365.481608 -270.919226)
			(xy 365.466024 -270.965907) (xy 365.443153 -271.009484) (xy 365.413588 -271.048828) (xy 365.378095 -271.08292)
			(xy 365.337592 -271.110876) (xy 365.29313 -271.131974) (xy 365.245859 -271.145666) (xy 365.197004 -271.151598)
			(xy 365.147829 -271.149617) (xy 365.09961 -271.139773) (xy 365.053594 -271.122321) (xy 365.010973 -271.097714)
			(xy 364.972852 -271.066589) (xy 364.940217 -271.029752) (xy 364.913914 -270.988156) (xy 364.894623 -270.94288)
			(xy 364.882846 -270.895096) (xy 364.878886 -270.846042) (xy 364.550198 -270.846042) (xy 364.549703 -270.870649)
			(xy 364.541808 -270.919226) (xy 364.526224 -270.965907) (xy 364.503353 -271.009484) (xy 364.473788 -271.048828)
			(xy 364.438295 -271.08292) (xy 364.397792 -271.110876) (xy 364.35333 -271.131974) (xy 364.306059 -271.145666)
			(xy 364.257204 -271.151598) (xy 364.208029 -271.149617) (xy 364.15981 -271.139773) (xy 364.113794 -271.122321)
			(xy 364.071173 -271.097714) (xy 364.033052 -271.066589) (xy 364.000417 -271.029752) (xy 363.974114 -270.988156)
			(xy 363.954823 -270.94288) (xy 363.943046 -270.895096) (xy 363.939086 -270.846042) (xy 363.610144 -270.846042)
			(xy 363.609649 -270.870649) (xy 363.601754 -270.919226) (xy 363.58617 -270.965907) (xy 363.563299 -271.009484)
			(xy 363.533734 -271.048828) (xy 363.498241 -271.08292) (xy 363.457738 -271.110876) (xy 363.413276 -271.131974)
			(xy 363.366005 -271.145666) (xy 363.31715 -271.151598) (xy 363.267975 -271.149617) (xy 363.219756 -271.139773)
			(xy 363.17374 -271.122321) (xy 363.131119 -271.097714) (xy 363.092998 -271.066589) (xy 363.060363 -271.029752)
			(xy 363.03406 -270.988156) (xy 363.014769 -270.94288) (xy 363.002992 -270.895096) (xy 362.999032 -270.846042)
			(xy 362.67009 -270.846042) (xy 362.669595 -270.870649) (xy 362.6617 -270.919226) (xy 362.646116 -270.965907)
			(xy 362.623245 -271.009484) (xy 362.59368 -271.048828) (xy 362.558187 -271.08292) (xy 362.517684 -271.110876)
			(xy 362.473222 -271.131974) (xy 362.425951 -271.145666) (xy 362.377096 -271.151598) (xy 362.327921 -271.149617)
			(xy 362.279702 -271.139773) (xy 362.233686 -271.122321) (xy 362.191065 -271.097714) (xy 362.152944 -271.066589)
			(xy 362.120309 -271.029752) (xy 362.094006 -270.988156) (xy 362.074715 -270.94288) (xy 362.062938 -270.895096)
			(xy 362.058978 -270.846042) (xy 361.730036 -270.846042) (xy 361.729541 -270.870649) (xy 361.721646 -270.919226)
			(xy 361.706062 -270.965907) (xy 361.683191 -271.009484) (xy 361.653626 -271.048828) (xy 361.618133 -271.08292)
			(xy 361.57763 -271.110876) (xy 361.533168 -271.131974) (xy 361.485897 -271.145666) (xy 361.437042 -271.151598)
			(xy 361.387867 -271.149617) (xy 361.339648 -271.139773) (xy 361.293632 -271.122321) (xy 361.251011 -271.097714)
			(xy 361.21289 -271.066589) (xy 361.180255 -271.029752) (xy 361.153952 -270.988156) (xy 361.134661 -270.94288)
			(xy 361.122884 -270.895096) (xy 361.118924 -270.846042) (xy 358.916478 -270.846042) (xy 358.915983 -270.870649)
			(xy 358.908088 -270.919226) (xy 358.892504 -270.965907) (xy 358.869633 -271.009484) (xy 358.840068 -271.048828)
			(xy 358.804575 -271.08292) (xy 358.764072 -271.110876) (xy 358.71961 -271.131974) (xy 358.672339 -271.145666)
			(xy 358.623484 -271.151598) (xy 358.574309 -271.149617) (xy 358.52609 -271.139773) (xy 358.480074 -271.122321)
			(xy 358.437453 -271.097714) (xy 358.399332 -271.066589) (xy 358.366697 -271.029752) (xy 358.340394 -270.988156)
			(xy 358.321103 -270.94288) (xy 358.309326 -270.895096) (xy 358.305366 -270.846042) (xy 357.976424 -270.846042)
			(xy 357.975929 -270.870649) (xy 357.968034 -270.919226) (xy 357.95245 -270.965907) (xy 357.929579 -271.009484)
			(xy 357.900014 -271.048828) (xy 357.864521 -271.08292) (xy 357.824018 -271.110876) (xy 357.779556 -271.131974)
			(xy 357.732285 -271.145666) (xy 357.68343 -271.151598) (xy 357.634255 -271.149617) (xy 357.586036 -271.139773)
			(xy 357.54002 -271.122321) (xy 357.497399 -271.097714) (xy 357.459278 -271.066589) (xy 357.426643 -271.029752)
			(xy 357.40034 -270.988156) (xy 357.381049 -270.94288) (xy 357.369272 -270.895096) (xy 357.365312 -270.846042)
			(xy 357.03637 -270.846042) (xy 357.035875 -270.870649) (xy 357.02798 -270.919226) (xy 357.012396 -270.965907)
			(xy 356.989525 -271.009484) (xy 356.95996 -271.048828) (xy 356.924467 -271.08292) (xy 356.883964 -271.110876)
			(xy 356.839502 -271.131974) (xy 356.792231 -271.145666) (xy 356.743376 -271.151598) (xy 356.694201 -271.149617)
			(xy 356.645982 -271.139773) (xy 356.599966 -271.122321) (xy 356.557345 -271.097714) (xy 356.519224 -271.066589)
			(xy 356.486589 -271.029752) (xy 356.460286 -270.988156) (xy 356.440995 -270.94288) (xy 356.429218 -270.895096)
			(xy 356.425258 -270.846042) (xy 356.096316 -270.846042) (xy 356.095821 -270.870649) (xy 356.087926 -270.919226)
			(xy 356.072342 -270.965907) (xy 356.049471 -271.009484) (xy 356.019906 -271.048828) (xy 355.984413 -271.08292)
			(xy 355.94391 -271.110876) (xy 355.899448 -271.131974) (xy 355.852177 -271.145666) (xy 355.803322 -271.151598)
			(xy 355.754147 -271.149617) (xy 355.705928 -271.139773) (xy 355.659912 -271.122321) (xy 355.617291 -271.097714)
			(xy 355.57917 -271.066589) (xy 355.546535 -271.029752) (xy 355.520232 -270.988156) (xy 355.500941 -270.94288)
			(xy 355.489164 -270.895096) (xy 355.485204 -270.846042) (xy 355.156516 -270.846042) (xy 355.156021 -270.870649)
			(xy 355.148126 -270.919226) (xy 355.132542 -270.965907) (xy 355.109671 -271.009484) (xy 355.080106 -271.048828)
			(xy 355.044613 -271.08292) (xy 355.00411 -271.110876) (xy 354.959648 -271.131974) (xy 354.912377 -271.145666)
			(xy 354.863522 -271.151598) (xy 354.814347 -271.149617) (xy 354.766128 -271.139773) (xy 354.720112 -271.122321)
			(xy 354.677491 -271.097714) (xy 354.63937 -271.066589) (xy 354.606735 -271.029752) (xy 354.580432 -270.988156)
			(xy 354.561141 -270.94288) (xy 354.549364 -270.895096) (xy 354.545404 -270.846042) (xy 354.216462 -270.846042)
			(xy 354.215967 -270.870649) (xy 354.208072 -270.919226) (xy 354.192488 -270.965907) (xy 354.169617 -271.009484)
			(xy 354.140052 -271.048828) (xy 354.104559 -271.08292) (xy 354.064056 -271.110876) (xy 354.019594 -271.131974)
			(xy 353.972323 -271.145666) (xy 353.923468 -271.151598) (xy 353.874293 -271.149617) (xy 353.826074 -271.139773)
			(xy 353.780058 -271.122321) (xy 353.737437 -271.097714) (xy 353.699316 -271.066589) (xy 353.666681 -271.029752)
			(xy 353.640378 -270.988156) (xy 353.621087 -270.94288) (xy 353.60931 -270.895096) (xy 353.60535 -270.846042)
			(xy 353.276408 -270.846042) (xy 353.275913 -270.870649) (xy 353.268018 -270.919226) (xy 353.252434 -270.965907)
			(xy 353.229563 -271.009484) (xy 353.199998 -271.048828) (xy 353.164505 -271.08292) (xy 353.124002 -271.110876)
			(xy 353.07954 -271.131974) (xy 353.032269 -271.145666) (xy 352.983414 -271.151598) (xy 352.934239 -271.149617)
			(xy 352.88602 -271.139773) (xy 352.840004 -271.122321) (xy 352.797383 -271.097714) (xy 352.759262 -271.066589)
			(xy 352.726627 -271.029752) (xy 352.700324 -270.988156) (xy 352.681033 -270.94288) (xy 352.669256 -270.895096)
			(xy 352.665296 -270.846042) (xy 352.336354 -270.846042) (xy 352.335859 -270.870649) (xy 352.327964 -270.919226)
			(xy 352.31238 -270.965907) (xy 352.289509 -271.009484) (xy 352.259944 -271.048828) (xy 352.224451 -271.08292)
			(xy 352.183948 -271.110876) (xy 352.139486 -271.131974) (xy 352.092215 -271.145666) (xy 352.04336 -271.151598)
			(xy 351.994185 -271.149617) (xy 351.945966 -271.139773) (xy 351.89995 -271.122321) (xy 351.857329 -271.097714)
			(xy 351.819208 -271.066589) (xy 351.786573 -271.029752) (xy 351.76027 -270.988156) (xy 351.740979 -270.94288)
			(xy 351.729202 -270.895096) (xy 351.725242 -270.846042) (xy 351.396554 -270.846042) (xy 351.396059 -270.870649)
			(xy 351.388164 -270.919226) (xy 351.37258 -270.965907) (xy 351.349709 -271.009484) (xy 351.320144 -271.048828)
			(xy 351.284651 -271.08292) (xy 351.244148 -271.110876) (xy 351.199686 -271.131974) (xy 351.152415 -271.145666)
			(xy 351.10356 -271.151598) (xy 351.054385 -271.149617) (xy 351.006166 -271.139773) (xy 350.96015 -271.122321)
			(xy 350.917529 -271.097714) (xy 350.879408 -271.066589) (xy 350.846773 -271.029752) (xy 350.82047 -270.988156)
			(xy 350.801179 -270.94288) (xy 350.789402 -270.895096) (xy 350.785442 -270.846042) (xy 350.4565 -270.846042)
			(xy 350.456005 -270.870649) (xy 350.44811 -270.919226) (xy 350.432526 -270.965907) (xy 350.409655 -271.009484)
			(xy 350.38009 -271.048828) (xy 350.344597 -271.08292) (xy 350.304094 -271.110876) (xy 350.259632 -271.131974)
			(xy 350.212361 -271.145666) (xy 350.163506 -271.151598) (xy 350.114331 -271.149617) (xy 350.066112 -271.139773)
			(xy 350.020096 -271.122321) (xy 349.977475 -271.097714) (xy 349.939354 -271.066589) (xy 349.906719 -271.029752)
			(xy 349.880416 -270.988156) (xy 349.861125 -270.94288) (xy 349.849348 -270.895096) (xy 349.845388 -270.846042)
			(xy 349.516446 -270.846042) (xy 349.515951 -270.870649) (xy 349.508056 -270.919226) (xy 349.492472 -270.965907)
			(xy 349.469601 -271.009484) (xy 349.440036 -271.048828) (xy 349.404543 -271.08292) (xy 349.36404 -271.110876)
			(xy 349.319578 -271.131974) (xy 349.272307 -271.145666) (xy 349.223452 -271.151598) (xy 349.174277 -271.149617)
			(xy 349.126058 -271.139773) (xy 349.080042 -271.122321) (xy 349.037421 -271.097714) (xy 348.9993 -271.066589)
			(xy 348.966665 -271.029752) (xy 348.940362 -270.988156) (xy 348.921071 -270.94288) (xy 348.909294 -270.895096)
			(xy 348.905334 -270.846042) (xy 348.576392 -270.846042) (xy 348.575897 -270.870649) (xy 348.568002 -270.919226)
			(xy 348.552418 -270.965907) (xy 348.529547 -271.009484) (xy 348.499982 -271.048828) (xy 348.464489 -271.08292)
			(xy 348.423986 -271.110876) (xy 348.379524 -271.131974) (xy 348.332253 -271.145666) (xy 348.283398 -271.151598)
			(xy 348.234223 -271.149617) (xy 348.186004 -271.139773) (xy 348.139988 -271.122321) (xy 348.097367 -271.097714)
			(xy 348.059246 -271.066589) (xy 348.026611 -271.029752) (xy 348.000308 -270.988156) (xy 347.981017 -270.94288)
			(xy 347.96924 -270.895096) (xy 347.96528 -270.846042) (xy 347.636338 -270.846042) (xy 347.635843 -270.870649)
			(xy 347.627948 -270.919226) (xy 347.612364 -270.965907) (xy 347.589493 -271.009484) (xy 347.559928 -271.048828)
			(xy 347.524435 -271.08292) (xy 347.483932 -271.110876) (xy 347.43947 -271.131974) (xy 347.392199 -271.145666)
			(xy 347.343344 -271.151598) (xy 347.294169 -271.149617) (xy 347.24595 -271.139773) (xy 347.199934 -271.122321)
			(xy 347.157313 -271.097714) (xy 347.119192 -271.066589) (xy 347.086557 -271.029752) (xy 347.060254 -270.988156)
			(xy 347.040963 -270.94288) (xy 347.029186 -270.895096) (xy 347.025226 -270.846042) (xy 346.696538 -270.846042)
			(xy 346.696043 -270.870649) (xy 346.688148 -270.919226) (xy 346.672564 -270.965907) (xy 346.649693 -271.009484)
			(xy 346.620128 -271.048828) (xy 346.584635 -271.08292) (xy 346.544132 -271.110876) (xy 346.49967 -271.131974)
			(xy 346.452399 -271.145666) (xy 346.403544 -271.151598) (xy 346.354369 -271.149617) (xy 346.30615 -271.139773)
			(xy 346.260134 -271.122321) (xy 346.217513 -271.097714) (xy 346.179392 -271.066589) (xy 346.146757 -271.029752)
			(xy 346.120454 -270.988156) (xy 346.101163 -270.94288) (xy 346.089386 -270.895096) (xy 346.085426 -270.846042)
			(xy 345.756484 -270.846042) (xy 345.755989 -270.870649) (xy 345.748094 -270.919226) (xy 345.73251 -270.965907)
			(xy 345.709639 -271.009484) (xy 345.680074 -271.048828) (xy 345.644581 -271.08292) (xy 345.604078 -271.110876)
			(xy 345.559616 -271.131974) (xy 345.512345 -271.145666) (xy 345.46349 -271.151598) (xy 345.414315 -271.149617)
			(xy 345.366096 -271.139773) (xy 345.32008 -271.122321) (xy 345.277459 -271.097714) (xy 345.239338 -271.066589)
			(xy 345.206703 -271.029752) (xy 345.1804 -270.988156) (xy 345.161109 -270.94288) (xy 345.149332 -270.895096)
			(xy 345.145372 -270.846042) (xy 344.81643 -270.846042) (xy 344.815935 -270.870649) (xy 344.80804 -270.919226)
			(xy 344.792456 -270.965907) (xy 344.769585 -271.009484) (xy 344.74002 -271.048828) (xy 344.704527 -271.08292)
			(xy 344.664024 -271.110876) (xy 344.619562 -271.131974) (xy 344.572291 -271.145666) (xy 344.523436 -271.151598)
			(xy 344.474261 -271.149617) (xy 344.426042 -271.139773) (xy 344.380026 -271.122321) (xy 344.337405 -271.097714)
			(xy 344.299284 -271.066589) (xy 344.266649 -271.029752) (xy 344.240346 -270.988156) (xy 344.221055 -270.94288)
			(xy 344.209278 -270.895096) (xy 344.205318 -270.846042) (xy 343.88679 -270.846042) (xy 343.886278 -270.871488)
			(xy 343.878114 -270.921722) (xy 343.861998 -270.969996) (xy 343.838347 -271.015059) (xy 343.807774 -271.055745)
			(xy 343.77107 -271.091) (xy 343.729186 -271.11991) (xy 343.683207 -271.141727) (xy 343.634323 -271.155887)
			(xy 343.583802 -271.162021) (xy 343.53295 -271.159972) (xy 343.483086 -271.149792) (xy 343.4355 -271.131745)
			(xy 343.391426 -271.106299) (xy 343.352004 -271.074112) (xy 343.318256 -271.036018) (xy 343.291055 -270.993004)
			(xy 343.271107 -270.946184) (xy 343.258928 -270.89677) (xy 343.254833 -270.846042) (xy 342.946736 -270.846042)
			(xy 342.946224 -270.871488) (xy 342.93806 -270.921722) (xy 342.921944 -270.969996) (xy 342.898293 -271.015059)
			(xy 342.86772 -271.055745) (xy 342.831016 -271.091) (xy 342.789132 -271.11991) (xy 342.743153 -271.141727)
			(xy 342.694269 -271.155887) (xy 342.643748 -271.162021) (xy 342.592896 -271.159972) (xy 342.543032 -271.149792)
			(xy 342.495446 -271.131745) (xy 342.451372 -271.106299) (xy 342.41195 -271.074112) (xy 342.378202 -271.036018)
			(xy 342.351001 -270.993004) (xy 342.331053 -270.946184) (xy 342.318874 -270.89677) (xy 342.314779 -270.846042)
			(xy 341.996986 -270.846042) (xy 341.992819 -270.89633) (xy 341.980421 -270.945287) (xy 341.960136 -270.991536)
			(xy 341.932514 -271.033815) (xy 341.898311 -271.070971) (xy 341.858458 -271.101991) (xy 341.814044 -271.126029)
			(xy 341.766278 -271.142429) (xy 341.716465 -271.150743) (xy 341.691214 -271.15135) (xy 341.678451 -271.151214)
			(xy 341.653016 -271.149056) (xy 341.640414 -271.147032) (xy 341.640414 -271.147286) (xy 341.616961 -271.142858)
			(xy 341.571709 -271.127695) (xy 341.529359 -271.105689) (xy 341.49094 -271.077375) (xy 341.457384 -271.043439)
			(xy 341.443056 -271.02435) (xy 341.438992 -271.018508) (xy 341.428324 -271.009872) (xy 341.422482 -271.007332)
			(xy 341.416199 -271.00481) (xy 341.402805 -271.002871) (xy 341.396066 -271.003522) (xy 341.305642 -271.014952)
			(xy 341.293196 -271.016476) (xy 341.28202 -271.025112) (xy 341.276892 -271.029457) (xy 341.268917 -271.040269)
			(xy 341.266272 -271.046448) (xy 341.266272 -271.046702) (xy 341.258703 -271.065601) (xy 341.241164 -271.102344)
			(xy 341.23122 -271.120108) (xy 341.227918 -271.12595) (xy 341.226394 -271.132046) (xy 341.224616 -271.145)
			(xy 341.224616 -271.304258) (xy 341.224969 -271.313277) (xy 341.231207 -271.330201) (xy 341.236808 -271.337278)
			(xy 341.24265 -271.344136) (xy 341.258652 -271.353026) (xy 341.267542 -271.354296) (xy 341.291256 -271.358404)
			(xy 341.337084 -271.373099) (xy 341.380039 -271.394803) (xy 341.419055 -271.422978) (xy 341.453168 -271.456927)
			(xy 341.48153 -271.495807) (xy 341.50344 -271.538657) (xy 341.518356 -271.584414) (xy 341.525906 -271.631944)
			(xy 341.525905 -271.656048) (xy 341.844879 -271.656048) (xy 341.848974 -271.60532) (xy 341.861153 -271.555906)
			(xy 341.881101 -271.509086) (xy 341.908302 -271.466072) (xy 341.94205 -271.427978) (xy 341.981472 -271.395791)
			(xy 342.025546 -271.370345) (xy 342.073132 -271.352298) (xy 342.122996 -271.342118) (xy 342.173848 -271.340069)
			(xy 342.224369 -271.346203) (xy 342.273253 -271.360363) (xy 342.319232 -271.38218) (xy 342.361116 -271.41109)
			(xy 342.39782 -271.446345) (xy 342.428393 -271.487031) (xy 342.452044 -271.532094) (xy 342.46816 -271.580368)
			(xy 342.476324 -271.630602) (xy 342.476836 -271.656048) (xy 342.795364 -271.656048) (xy 342.799324 -271.606994)
			(xy 342.811101 -271.55921) (xy 342.830392 -271.513934) (xy 342.856695 -271.472338) (xy 342.88933 -271.435501)
			(xy 342.927451 -271.404376) (xy 342.970072 -271.379769) (xy 343.016088 -271.362317) (xy 343.064307 -271.352473)
			(xy 343.113482 -271.350492) (xy 343.162337 -271.356424) (xy 343.209608 -271.370116) (xy 343.25407 -271.391214)
			(xy 343.294573 -271.41917) (xy 343.330066 -271.453262) (xy 343.359631 -271.492606) (xy 343.382502 -271.536183)
			(xy 343.398086 -271.582864) (xy 343.405981 -271.631441) (xy 343.406476 -271.656048) (xy 343.724987 -271.656048)
			(xy 343.729082 -271.60532) (xy 343.741261 -271.555906) (xy 343.761209 -271.509086) (xy 343.78841 -271.466072)
			(xy 343.822158 -271.427978) (xy 343.86158 -271.395791) (xy 343.905654 -271.370345) (xy 343.95324 -271.352298)
			(xy 344.003104 -271.342118) (xy 344.053956 -271.340069) (xy 344.104477 -271.346203) (xy 344.153361 -271.360363)
			(xy 344.19934 -271.38218) (xy 344.241224 -271.41109) (xy 344.277928 -271.446345) (xy 344.308501 -271.487031)
			(xy 344.332152 -271.532094) (xy 344.348268 -271.580368) (xy 344.356432 -271.630602) (xy 344.356944 -271.656048)
			(xy 344.675218 -271.656048) (xy 344.679178 -271.606994) (xy 344.690955 -271.55921) (xy 344.710246 -271.513934)
			(xy 344.736549 -271.472338) (xy 344.769184 -271.435501) (xy 344.807305 -271.404376) (xy 344.849926 -271.379769)
			(xy 344.895942 -271.362317) (xy 344.944161 -271.352473) (xy 344.993336 -271.350492) (xy 345.042191 -271.356424)
			(xy 345.089462 -271.370116) (xy 345.133924 -271.391214) (xy 345.174427 -271.41917) (xy 345.20992 -271.453262)
			(xy 345.239485 -271.492606) (xy 345.262356 -271.536183) (xy 345.27794 -271.582864) (xy 345.285835 -271.631441)
			(xy 345.28633 -271.656048) (xy 345.615272 -271.656048) (xy 345.619232 -271.606994) (xy 345.631009 -271.55921)
			(xy 345.6503 -271.513934) (xy 345.676603 -271.472338) (xy 345.709238 -271.435501) (xy 345.747359 -271.404376)
			(xy 345.78998 -271.379769) (xy 345.835996 -271.362317) (xy 345.884215 -271.352473) (xy 345.93339 -271.350492)
			(xy 345.982245 -271.356424) (xy 346.029516 -271.370116) (xy 346.073978 -271.391214) (xy 346.114481 -271.41917)
			(xy 346.149974 -271.453262) (xy 346.179539 -271.492606) (xy 346.20241 -271.536183) (xy 346.217994 -271.582864)
			(xy 346.225889 -271.631441) (xy 346.226384 -271.656048) (xy 346.555326 -271.656048) (xy 346.559286 -271.606994)
			(xy 346.571063 -271.55921) (xy 346.590354 -271.513934) (xy 346.616657 -271.472338) (xy 346.649292 -271.435501)
			(xy 346.687413 -271.404376) (xy 346.730034 -271.379769) (xy 346.77605 -271.362317) (xy 346.824269 -271.352473)
			(xy 346.873444 -271.350492) (xy 346.922299 -271.356424) (xy 346.96957 -271.370116) (xy 347.014032 -271.391214)
			(xy 347.054535 -271.41917) (xy 347.090028 -271.453262) (xy 347.119593 -271.492606) (xy 347.142464 -271.536183)
			(xy 347.158048 -271.582864) (xy 347.165943 -271.631441) (xy 347.166438 -271.656048) (xy 347.49538 -271.656048)
			(xy 347.49934 -271.606994) (xy 347.511117 -271.55921) (xy 347.530408 -271.513934) (xy 347.556711 -271.472338)
			(xy 347.589346 -271.435501) (xy 347.627467 -271.404376) (xy 347.670088 -271.379769) (xy 347.716104 -271.362317)
			(xy 347.764323 -271.352473) (xy 347.813498 -271.350492) (xy 347.862353 -271.356424) (xy 347.909624 -271.370116)
			(xy 347.954086 -271.391214) (xy 347.994589 -271.41917) (xy 348.030082 -271.453262) (xy 348.059647 -271.492606)
			(xy 348.082518 -271.536183) (xy 348.098102 -271.582864) (xy 348.105997 -271.631441) (xy 348.106492 -271.656048)
			(xy 348.435434 -271.656048) (xy 348.439394 -271.606994) (xy 348.451171 -271.55921) (xy 348.470462 -271.513934)
			(xy 348.496765 -271.472338) (xy 348.5294 -271.435501) (xy 348.567521 -271.404376) (xy 348.610142 -271.379769)
			(xy 348.656158 -271.362317) (xy 348.704377 -271.352473) (xy 348.753552 -271.350492) (xy 348.802407 -271.356424)
			(xy 348.849678 -271.370116) (xy 348.89414 -271.391214) (xy 348.934643 -271.41917) (xy 348.970136 -271.453262)
			(xy 348.999701 -271.492606) (xy 349.022572 -271.536183) (xy 349.038156 -271.582864) (xy 349.046051 -271.631441)
			(xy 349.046546 -271.656048) (xy 349.375234 -271.656048) (xy 349.379194 -271.606994) (xy 349.390971 -271.55921)
			(xy 349.410262 -271.513934) (xy 349.436565 -271.472338) (xy 349.4692 -271.435501) (xy 349.507321 -271.404376)
			(xy 349.549942 -271.379769) (xy 349.595958 -271.362317) (xy 349.644177 -271.352473) (xy 349.693352 -271.350492)
			(xy 349.742207 -271.356424) (xy 349.789478 -271.370116) (xy 349.83394 -271.391214) (xy 349.874443 -271.41917)
			(xy 349.909936 -271.453262) (xy 349.939501 -271.492606) (xy 349.962372 -271.536183) (xy 349.977956 -271.582864)
			(xy 349.985851 -271.631441) (xy 349.986346 -271.656048) (xy 350.315288 -271.656048) (xy 350.319248 -271.606994)
			(xy 350.331025 -271.55921) (xy 350.350316 -271.513934) (xy 350.376619 -271.472338) (xy 350.409254 -271.435501)
			(xy 350.447375 -271.404376) (xy 350.489996 -271.379769) (xy 350.536012 -271.362317) (xy 350.584231 -271.352473)
			(xy 350.633406 -271.350492) (xy 350.682261 -271.356424) (xy 350.729532 -271.370116) (xy 350.773994 -271.391214)
			(xy 350.814497 -271.41917) (xy 350.84999 -271.453262) (xy 350.879555 -271.492606) (xy 350.902426 -271.536183)
			(xy 350.91801 -271.582864) (xy 350.925905 -271.631441) (xy 350.9264 -271.656048) (xy 351.255342 -271.656048)
			(xy 351.259302 -271.606994) (xy 351.271079 -271.55921) (xy 351.29037 -271.513934) (xy 351.316673 -271.472338)
			(xy 351.349308 -271.435501) (xy 351.387429 -271.404376) (xy 351.43005 -271.379769) (xy 351.476066 -271.362317)
			(xy 351.524285 -271.352473) (xy 351.57346 -271.350492) (xy 351.622315 -271.356424) (xy 351.669586 -271.370116)
			(xy 351.714048 -271.391214) (xy 351.754551 -271.41917) (xy 351.790044 -271.453262) (xy 351.819609 -271.492606)
			(xy 351.84248 -271.536183) (xy 351.858064 -271.582864) (xy 351.865959 -271.631441) (xy 351.866454 -271.656048)
			(xy 352.195396 -271.656048) (xy 352.199356 -271.606994) (xy 352.211133 -271.55921) (xy 352.230424 -271.513934)
			(xy 352.256727 -271.472338) (xy 352.289362 -271.435501) (xy 352.327483 -271.404376) (xy 352.370104 -271.379769)
			(xy 352.41612 -271.362317) (xy 352.464339 -271.352473) (xy 352.513514 -271.350492) (xy 352.562369 -271.356424)
			(xy 352.60964 -271.370116) (xy 352.654102 -271.391214) (xy 352.694605 -271.41917) (xy 352.730098 -271.453262)
			(xy 352.759663 -271.492606) (xy 352.782534 -271.536183) (xy 352.798118 -271.582864) (xy 352.806013 -271.631441)
			(xy 352.806508 -271.656048) (xy 353.135196 -271.656048) (xy 353.139156 -271.606994) (xy 353.150933 -271.55921)
			(xy 353.170224 -271.513934) (xy 353.196527 -271.472338) (xy 353.229162 -271.435501) (xy 353.267283 -271.404376)
			(xy 353.309904 -271.379769) (xy 353.35592 -271.362317) (xy 353.404139 -271.352473) (xy 353.453314 -271.350492)
			(xy 353.502169 -271.356424) (xy 353.54944 -271.370116) (xy 353.593902 -271.391214) (xy 353.634405 -271.41917)
			(xy 353.669898 -271.453262) (xy 353.699463 -271.492606) (xy 353.722334 -271.536183) (xy 353.737918 -271.582864)
			(xy 353.745813 -271.631441) (xy 353.746308 -271.656048) (xy 354.07525 -271.656048) (xy 354.07921 -271.606994)
			(xy 354.090987 -271.55921) (xy 354.110278 -271.513934) (xy 354.136581 -271.472338) (xy 354.169216 -271.435501)
			(xy 354.207337 -271.404376) (xy 354.249958 -271.379769) (xy 354.295974 -271.362317) (xy 354.344193 -271.352473)
			(xy 354.393368 -271.350492) (xy 354.442223 -271.356424) (xy 354.489494 -271.370116) (xy 354.533956 -271.391214)
			(xy 354.574459 -271.41917) (xy 354.609952 -271.453262) (xy 354.639517 -271.492606) (xy 354.662388 -271.536183)
			(xy 354.677972 -271.582864) (xy 354.685867 -271.631441) (xy 354.686362 -271.656048) (xy 355.015304 -271.656048)
			(xy 355.019264 -271.606994) (xy 355.031041 -271.55921) (xy 355.050332 -271.513934) (xy 355.076635 -271.472338)
			(xy 355.10927 -271.435501) (xy 355.147391 -271.404376) (xy 355.190012 -271.379769) (xy 355.236028 -271.362317)
			(xy 355.284247 -271.352473) (xy 355.333422 -271.350492) (xy 355.382277 -271.356424) (xy 355.429548 -271.370116)
			(xy 355.47401 -271.391214) (xy 355.514513 -271.41917) (xy 355.550006 -271.453262) (xy 355.579571 -271.492606)
			(xy 355.602442 -271.536183) (xy 355.618026 -271.582864) (xy 355.625921 -271.631441) (xy 355.626416 -271.656048)
			(xy 355.955358 -271.656048) (xy 355.959318 -271.606994) (xy 355.971095 -271.55921) (xy 355.990386 -271.513934)
			(xy 356.016689 -271.472338) (xy 356.049324 -271.435501) (xy 356.087445 -271.404376) (xy 356.130066 -271.379769)
			(xy 356.176082 -271.362317) (xy 356.224301 -271.352473) (xy 356.273476 -271.350492) (xy 356.322331 -271.356424)
			(xy 356.369602 -271.370116) (xy 356.414064 -271.391214) (xy 356.454567 -271.41917) (xy 356.49006 -271.453262)
			(xy 356.519625 -271.492606) (xy 356.542496 -271.536183) (xy 356.55808 -271.582864) (xy 356.565975 -271.631441)
			(xy 356.56647 -271.656048) (xy 363.468932 -271.656048) (xy 363.472892 -271.606994) (xy 363.484669 -271.55921)
			(xy 363.50396 -271.513934) (xy 363.530263 -271.472338) (xy 363.562898 -271.435501) (xy 363.601019 -271.404376)
			(xy 363.64364 -271.379769) (xy 363.689656 -271.362317) (xy 363.737875 -271.352473) (xy 363.78705 -271.350492)
			(xy 363.835905 -271.356424) (xy 363.883176 -271.370116) (xy 363.927638 -271.391214) (xy 363.968141 -271.41917)
			(xy 364.003634 -271.453262) (xy 364.033199 -271.492606) (xy 364.05607 -271.536183) (xy 364.071654 -271.582864)
			(xy 364.079549 -271.631441) (xy 364.080044 -271.656048) (xy 364.408986 -271.656048) (xy 364.412946 -271.606994)
			(xy 364.424723 -271.55921) (xy 364.444014 -271.513934) (xy 364.470317 -271.472338) (xy 364.502952 -271.435501)
			(xy 364.541073 -271.404376) (xy 364.583694 -271.379769) (xy 364.62971 -271.362317) (xy 364.677929 -271.352473)
			(xy 364.727104 -271.350492) (xy 364.775959 -271.356424) (xy 364.82323 -271.370116) (xy 364.867692 -271.391214)
			(xy 364.908195 -271.41917) (xy 364.943688 -271.453262) (xy 364.973253 -271.492606) (xy 364.996124 -271.536183)
			(xy 365.011708 -271.582864) (xy 365.019603 -271.631441) (xy 365.020098 -271.656048) (xy 365.34904 -271.656048)
			(xy 365.353 -271.606994) (xy 365.364777 -271.55921) (xy 365.384068 -271.513934) (xy 365.410371 -271.472338)
			(xy 365.443006 -271.435501) (xy 365.481127 -271.404376) (xy 365.523748 -271.379769) (xy 365.569764 -271.362317)
			(xy 365.617983 -271.352473) (xy 365.667158 -271.350492) (xy 365.716013 -271.356424) (xy 365.763284 -271.370116)
			(xy 365.807746 -271.391214) (xy 365.848249 -271.41917) (xy 365.883742 -271.453262) (xy 365.913307 -271.492606)
			(xy 365.936178 -271.536183) (xy 365.951762 -271.582864) (xy 365.959657 -271.631441) (xy 365.960152 -271.656048)
			(xy 366.289094 -271.656048) (xy 366.293054 -271.606994) (xy 366.304831 -271.55921) (xy 366.324122 -271.513934)
			(xy 366.350425 -271.472338) (xy 366.38306 -271.435501) (xy 366.421181 -271.404376) (xy 366.463802 -271.379769)
			(xy 366.509818 -271.362317) (xy 366.558037 -271.352473) (xy 366.607212 -271.350492) (xy 366.656067 -271.356424)
			(xy 366.703338 -271.370116) (xy 366.7478 -271.391214) (xy 366.788303 -271.41917) (xy 366.823796 -271.453262)
			(xy 366.853361 -271.492606) (xy 366.876232 -271.536183) (xy 366.891816 -271.582864) (xy 366.899711 -271.631441)
			(xy 366.900206 -271.656048) (xy 367.228894 -271.656048) (xy 367.232854 -271.606994) (xy 367.244631 -271.55921)
			(xy 367.263922 -271.513934) (xy 367.290225 -271.472338) (xy 367.32286 -271.435501) (xy 367.360981 -271.404376)
			(xy 367.403602 -271.379769) (xy 367.449618 -271.362317) (xy 367.497837 -271.352473) (xy 367.547012 -271.350492)
			(xy 367.595867 -271.356424) (xy 367.643138 -271.370116) (xy 367.6876 -271.391214) (xy 367.728103 -271.41917)
			(xy 367.763596 -271.453262) (xy 367.793161 -271.492606) (xy 367.816032 -271.536183) (xy 367.831616 -271.582864)
			(xy 367.839511 -271.631441) (xy 367.840006 -271.656048) (xy 368.168948 -271.656048) (xy 368.172908 -271.606994)
			(xy 368.184685 -271.55921) (xy 368.203976 -271.513934) (xy 368.230279 -271.472338) (xy 368.262914 -271.435501)
			(xy 368.301035 -271.404376) (xy 368.343656 -271.379769) (xy 368.389672 -271.362317) (xy 368.437891 -271.352473)
			(xy 368.487066 -271.350492) (xy 368.535921 -271.356424) (xy 368.583192 -271.370116) (xy 368.627654 -271.391214)
			(xy 368.668157 -271.41917) (xy 368.70365 -271.453262) (xy 368.733215 -271.492606) (xy 368.756086 -271.536183)
			(xy 368.77167 -271.582864) (xy 368.779565 -271.631441) (xy 368.78006 -271.656048) (xy 369.109002 -271.656048)
			(xy 369.112962 -271.606994) (xy 369.124739 -271.55921) (xy 369.14403 -271.513934) (xy 369.170333 -271.472338)
			(xy 369.202968 -271.435501) (xy 369.241089 -271.404376) (xy 369.28371 -271.379769) (xy 369.329726 -271.362317)
			(xy 369.377945 -271.352473) (xy 369.42712 -271.350492) (xy 369.475975 -271.356424) (xy 369.523246 -271.370116)
			(xy 369.567708 -271.391214) (xy 369.608211 -271.41917) (xy 369.643704 -271.453262) (xy 369.673269 -271.492606)
			(xy 369.69614 -271.536183) (xy 369.711724 -271.582864) (xy 369.719619 -271.631441) (xy 369.720114 -271.656048)
			(xy 370.049056 -271.656048) (xy 370.053016 -271.606994) (xy 370.064793 -271.55921) (xy 370.084084 -271.513934)
			(xy 370.110387 -271.472338) (xy 370.143022 -271.435501) (xy 370.181143 -271.404376) (xy 370.223764 -271.379769)
			(xy 370.26978 -271.362317) (xy 370.317999 -271.352473) (xy 370.367174 -271.350492) (xy 370.416029 -271.356424)
			(xy 370.4633 -271.370116) (xy 370.507762 -271.391214) (xy 370.548265 -271.41917) (xy 370.583758 -271.453262)
			(xy 370.613323 -271.492606) (xy 370.636194 -271.536183) (xy 370.651778 -271.582864) (xy 370.659673 -271.631441)
			(xy 370.660168 -271.656048) (xy 370.98911 -271.656048) (xy 370.99307 -271.606994) (xy 371.004847 -271.55921)
			(xy 371.024138 -271.513934) (xy 371.050441 -271.472338) (xy 371.083076 -271.435501) (xy 371.121197 -271.404376)
			(xy 371.163818 -271.379769) (xy 371.209834 -271.362317) (xy 371.258053 -271.352473) (xy 371.307228 -271.350492)
			(xy 371.356083 -271.356424) (xy 371.403354 -271.370116) (xy 371.447816 -271.391214) (xy 371.488319 -271.41917)
			(xy 371.523812 -271.453262) (xy 371.553377 -271.492606) (xy 371.576248 -271.536183) (xy 371.591832 -271.582864)
			(xy 371.599727 -271.631441) (xy 371.600222 -271.656048) (xy 371.92891 -271.656048) (xy 371.93287 -271.606994)
			(xy 371.944647 -271.55921) (xy 371.963938 -271.513934) (xy 371.990241 -271.472338) (xy 372.022876 -271.435501)
			(xy 372.060997 -271.404376) (xy 372.103618 -271.379769) (xy 372.149634 -271.362317) (xy 372.197853 -271.352473)
			(xy 372.247028 -271.350492) (xy 372.295883 -271.356424) (xy 372.343154 -271.370116) (xy 372.387616 -271.391214)
			(xy 372.428119 -271.41917) (xy 372.463612 -271.453262) (xy 372.493177 -271.492606) (xy 372.516048 -271.536183)
			(xy 372.531632 -271.582864) (xy 372.539527 -271.631441) (xy 372.540022 -271.656048) (xy 372.868964 -271.656048)
			(xy 372.872924 -271.606994) (xy 372.884701 -271.55921) (xy 372.903992 -271.513934) (xy 372.930295 -271.472338)
			(xy 372.96293 -271.435501) (xy 373.001051 -271.404376) (xy 373.043672 -271.379769) (xy 373.089688 -271.362317)
			(xy 373.137907 -271.352473) (xy 373.187082 -271.350492) (xy 373.235937 -271.356424) (xy 373.283208 -271.370116)
			(xy 373.32767 -271.391214) (xy 373.368173 -271.41917) (xy 373.403666 -271.453262) (xy 373.433231 -271.492606)
			(xy 373.456102 -271.536183) (xy 373.471686 -271.582864) (xy 373.479581 -271.631441) (xy 373.480076 -271.656048)
			(xy 373.809018 -271.656048) (xy 373.812978 -271.606994) (xy 373.824755 -271.55921) (xy 373.844046 -271.513934)
			(xy 373.870349 -271.472338) (xy 373.902984 -271.435501) (xy 373.941105 -271.404376) (xy 373.983726 -271.379769)
			(xy 374.029742 -271.362317) (xy 374.077961 -271.352473) (xy 374.127136 -271.350492) (xy 374.175991 -271.356424)
			(xy 374.223262 -271.370116) (xy 374.267724 -271.391214) (xy 374.308227 -271.41917) (xy 374.34372 -271.453262)
			(xy 374.373285 -271.492606) (xy 374.396156 -271.536183) (xy 374.41174 -271.582864) (xy 374.419635 -271.631441)
			(xy 374.42013 -271.656048) (xy 374.749072 -271.656048) (xy 374.753032 -271.606994) (xy 374.764809 -271.55921)
			(xy 374.7841 -271.513934) (xy 374.810403 -271.472338) (xy 374.843038 -271.435501) (xy 374.881159 -271.404376)
			(xy 374.92378 -271.379769) (xy 374.969796 -271.362317) (xy 375.018015 -271.352473) (xy 375.06719 -271.350492)
			(xy 375.116045 -271.356424) (xy 375.163316 -271.370116) (xy 375.207778 -271.391214) (xy 375.248281 -271.41917)
			(xy 375.283774 -271.453262) (xy 375.313339 -271.492606) (xy 375.33621 -271.536183) (xy 375.351794 -271.582864)
			(xy 375.359689 -271.631441) (xy 375.360184 -271.656048) (xy 375.678695 -271.656048) (xy 375.68279 -271.60532)
			(xy 375.694969 -271.555906) (xy 375.714917 -271.509086) (xy 375.742118 -271.466072) (xy 375.775866 -271.427978)
			(xy 375.815288 -271.395791) (xy 375.859362 -271.370345) (xy 375.906948 -271.352298) (xy 375.956812 -271.342118)
			(xy 376.007664 -271.340069) (xy 376.058185 -271.346203) (xy 376.107069 -271.360363) (xy 376.153048 -271.38218)
			(xy 376.194932 -271.41109) (xy 376.231636 -271.446345) (xy 376.262209 -271.487031) (xy 376.28586 -271.532094)
			(xy 376.301976 -271.580368) (xy 376.31014 -271.630602) (xy 376.310652 -271.656048) (xy 376.628926 -271.656048)
			(xy 376.632886 -271.606994) (xy 376.644663 -271.55921) (xy 376.663954 -271.513934) (xy 376.690257 -271.472338)
			(xy 376.722892 -271.435501) (xy 376.761013 -271.404376) (xy 376.803634 -271.379769) (xy 376.84965 -271.362317)
			(xy 376.897869 -271.352473) (xy 376.947044 -271.350492) (xy 376.995899 -271.356424) (xy 377.04317 -271.370116)
			(xy 377.087632 -271.391214) (xy 377.128135 -271.41917) (xy 377.163628 -271.453262) (xy 377.193193 -271.492606)
			(xy 377.216064 -271.536183) (xy 377.231648 -271.582864) (xy 377.239543 -271.631441) (xy 377.240038 -271.656048)
			(xy 377.558549 -271.656048) (xy 377.562644 -271.60532) (xy 377.574823 -271.555906) (xy 377.594771 -271.509086)
			(xy 377.621972 -271.466072) (xy 377.65572 -271.427978) (xy 377.695142 -271.395791) (xy 377.739216 -271.370345)
			(xy 377.786802 -271.352298) (xy 377.836666 -271.342118) (xy 377.887518 -271.340069) (xy 377.938039 -271.346203)
			(xy 377.986923 -271.360363) (xy 378.032902 -271.38218) (xy 378.074786 -271.41109) (xy 378.11149 -271.446345)
			(xy 378.142063 -271.487031) (xy 378.165714 -271.532094) (xy 378.18183 -271.580368) (xy 378.189994 -271.630602)
			(xy 378.190506 -271.656048) (xy 378.189994 -271.681494) (xy 378.18183 -271.731728) (xy 378.165714 -271.780002)
			(xy 378.142063 -271.825065) (xy 378.11149 -271.865751) (xy 378.074786 -271.901006) (xy 378.032902 -271.929916)
			(xy 377.986923 -271.951733) (xy 377.938039 -271.965893) (xy 377.887518 -271.972027) (xy 377.836666 -271.969978)
			(xy 377.786802 -271.959798) (xy 377.739216 -271.941751) (xy 377.695142 -271.916305) (xy 377.65572 -271.884118)
			(xy 377.621972 -271.846024) (xy 377.594771 -271.80301) (xy 377.574823 -271.75619) (xy 377.562644 -271.706776)
			(xy 377.558549 -271.656048) (xy 377.240038 -271.656048) (xy 377.239543 -271.680655) (xy 377.231648 -271.729232)
			(xy 377.216064 -271.775913) (xy 377.193193 -271.81949) (xy 377.163628 -271.858834) (xy 377.128135 -271.892926)
			(xy 377.087632 -271.920882) (xy 377.04317 -271.94198) (xy 376.995899 -271.955672) (xy 376.947044 -271.961604)
			(xy 376.897869 -271.959623) (xy 376.84965 -271.949779) (xy 376.803634 -271.932327) (xy 376.761013 -271.90772)
			(xy 376.722892 -271.876595) (xy 376.690257 -271.839758) (xy 376.663954 -271.798162) (xy 376.644663 -271.752886)
			(xy 376.632886 -271.705102) (xy 376.628926 -271.656048) (xy 376.310652 -271.656048) (xy 376.31014 -271.681494)
			(xy 376.301976 -271.731728) (xy 376.28586 -271.780002) (xy 376.262209 -271.825065) (xy 376.231636 -271.865751)
			(xy 376.194932 -271.901006) (xy 376.153048 -271.929916) (xy 376.107069 -271.951733) (xy 376.058185 -271.965893)
			(xy 376.007664 -271.972027) (xy 375.956812 -271.969978) (xy 375.906948 -271.959798) (xy 375.859362 -271.941751)
			(xy 375.815288 -271.916305) (xy 375.775866 -271.884118) (xy 375.742118 -271.846024) (xy 375.714917 -271.80301)
			(xy 375.694969 -271.75619) (xy 375.68279 -271.706776) (xy 375.678695 -271.656048) (xy 375.360184 -271.656048)
			(xy 375.359689 -271.680655) (xy 375.351794 -271.729232) (xy 375.33621 -271.775913) (xy 375.313339 -271.81949)
			(xy 375.283774 -271.858834) (xy 375.248281 -271.892926) (xy 375.207778 -271.920882) (xy 375.163316 -271.94198)
			(xy 375.116045 -271.955672) (xy 375.06719 -271.961604) (xy 375.018015 -271.959623) (xy 374.969796 -271.949779)
			(xy 374.92378 -271.932327) (xy 374.881159 -271.90772) (xy 374.843038 -271.876595) (xy 374.810403 -271.839758)
			(xy 374.7841 -271.798162) (xy 374.764809 -271.752886) (xy 374.753032 -271.705102) (xy 374.749072 -271.656048)
			(xy 374.42013 -271.656048) (xy 374.419635 -271.680655) (xy 374.41174 -271.729232) (xy 374.396156 -271.775913)
			(xy 374.373285 -271.81949) (xy 374.34372 -271.858834) (xy 374.308227 -271.892926) (xy 374.267724 -271.920882)
			(xy 374.223262 -271.94198) (xy 374.175991 -271.955672) (xy 374.127136 -271.961604) (xy 374.077961 -271.959623)
			(xy 374.029742 -271.949779) (xy 373.983726 -271.932327) (xy 373.941105 -271.90772) (xy 373.902984 -271.876595)
			(xy 373.870349 -271.839758) (xy 373.844046 -271.798162) (xy 373.824755 -271.752886) (xy 373.812978 -271.705102)
			(xy 373.809018 -271.656048) (xy 373.480076 -271.656048) (xy 373.479581 -271.680655) (xy 373.471686 -271.729232)
			(xy 373.456102 -271.775913) (xy 373.433231 -271.81949) (xy 373.403666 -271.858834) (xy 373.368173 -271.892926)
			(xy 373.32767 -271.920882) (xy 373.283208 -271.94198) (xy 373.235937 -271.955672) (xy 373.187082 -271.961604)
			(xy 373.137907 -271.959623) (xy 373.089688 -271.949779) (xy 373.043672 -271.932327) (xy 373.001051 -271.90772)
			(xy 372.96293 -271.876595) (xy 372.930295 -271.839758) (xy 372.903992 -271.798162) (xy 372.884701 -271.752886)
			(xy 372.872924 -271.705102) (xy 372.868964 -271.656048) (xy 372.540022 -271.656048) (xy 372.539527 -271.680655)
			(xy 372.531632 -271.729232) (xy 372.516048 -271.775913) (xy 372.493177 -271.81949) (xy 372.463612 -271.858834)
			(xy 372.428119 -271.892926) (xy 372.387616 -271.920882) (xy 372.343154 -271.94198) (xy 372.295883 -271.955672)
			(xy 372.247028 -271.961604) (xy 372.197853 -271.959623) (xy 372.149634 -271.949779) (xy 372.103618 -271.932327)
			(xy 372.060997 -271.90772) (xy 372.022876 -271.876595) (xy 371.990241 -271.839758) (xy 371.963938 -271.798162)
			(xy 371.944647 -271.752886) (xy 371.93287 -271.705102) (xy 371.92891 -271.656048) (xy 371.600222 -271.656048)
			(xy 371.599727 -271.680655) (xy 371.591832 -271.729232) (xy 371.576248 -271.775913) (xy 371.553377 -271.81949)
			(xy 371.523812 -271.858834) (xy 371.488319 -271.892926) (xy 371.447816 -271.920882) (xy 371.403354 -271.94198)
			(xy 371.356083 -271.955672) (xy 371.307228 -271.961604) (xy 371.258053 -271.959623) (xy 371.209834 -271.949779)
			(xy 371.163818 -271.932327) (xy 371.121197 -271.90772) (xy 371.083076 -271.876595) (xy 371.050441 -271.839758)
			(xy 371.024138 -271.798162) (xy 371.004847 -271.752886) (xy 370.99307 -271.705102) (xy 370.98911 -271.656048)
			(xy 370.660168 -271.656048) (xy 370.659673 -271.680655) (xy 370.651778 -271.729232) (xy 370.636194 -271.775913)
			(xy 370.613323 -271.81949) (xy 370.583758 -271.858834) (xy 370.548265 -271.892926) (xy 370.507762 -271.920882)
			(xy 370.4633 -271.94198) (xy 370.416029 -271.955672) (xy 370.367174 -271.961604) (xy 370.317999 -271.959623)
			(xy 370.26978 -271.949779) (xy 370.223764 -271.932327) (xy 370.181143 -271.90772) (xy 370.143022 -271.876595)
			(xy 370.110387 -271.839758) (xy 370.084084 -271.798162) (xy 370.064793 -271.752886) (xy 370.053016 -271.705102)
			(xy 370.049056 -271.656048) (xy 369.720114 -271.656048) (xy 369.719619 -271.680655) (xy 369.711724 -271.729232)
			(xy 369.69614 -271.775913) (xy 369.673269 -271.81949) (xy 369.643704 -271.858834) (xy 369.608211 -271.892926)
			(xy 369.567708 -271.920882) (xy 369.523246 -271.94198) (xy 369.475975 -271.955672) (xy 369.42712 -271.961604)
			(xy 369.377945 -271.959623) (xy 369.329726 -271.949779) (xy 369.28371 -271.932327) (xy 369.241089 -271.90772)
			(xy 369.202968 -271.876595) (xy 369.170333 -271.839758) (xy 369.14403 -271.798162) (xy 369.124739 -271.752886)
			(xy 369.112962 -271.705102) (xy 369.109002 -271.656048) (xy 368.78006 -271.656048) (xy 368.779565 -271.680655)
			(xy 368.77167 -271.729232) (xy 368.756086 -271.775913) (xy 368.733215 -271.81949) (xy 368.70365 -271.858834)
			(xy 368.668157 -271.892926) (xy 368.627654 -271.920882) (xy 368.583192 -271.94198) (xy 368.535921 -271.955672)
			(xy 368.487066 -271.961604) (xy 368.437891 -271.959623) (xy 368.389672 -271.949779) (xy 368.343656 -271.932327)
			(xy 368.301035 -271.90772) (xy 368.262914 -271.876595) (xy 368.230279 -271.839758) (xy 368.203976 -271.798162)
			(xy 368.184685 -271.752886) (xy 368.172908 -271.705102) (xy 368.168948 -271.656048) (xy 367.840006 -271.656048)
			(xy 367.839511 -271.680655) (xy 367.831616 -271.729232) (xy 367.816032 -271.775913) (xy 367.793161 -271.81949)
			(xy 367.763596 -271.858834) (xy 367.728103 -271.892926) (xy 367.6876 -271.920882) (xy 367.643138 -271.94198)
			(xy 367.595867 -271.955672) (xy 367.547012 -271.961604) (xy 367.497837 -271.959623) (xy 367.449618 -271.949779)
			(xy 367.403602 -271.932327) (xy 367.360981 -271.90772) (xy 367.32286 -271.876595) (xy 367.290225 -271.839758)
			(xy 367.263922 -271.798162) (xy 367.244631 -271.752886) (xy 367.232854 -271.705102) (xy 367.228894 -271.656048)
			(xy 366.900206 -271.656048) (xy 366.899711 -271.680655) (xy 366.891816 -271.729232) (xy 366.876232 -271.775913)
			(xy 366.853361 -271.81949) (xy 366.823796 -271.858834) (xy 366.788303 -271.892926) (xy 366.7478 -271.920882)
			(xy 366.703338 -271.94198) (xy 366.656067 -271.955672) (xy 366.607212 -271.961604) (xy 366.558037 -271.959623)
			(xy 366.509818 -271.949779) (xy 366.463802 -271.932327) (xy 366.421181 -271.90772) (xy 366.38306 -271.876595)
			(xy 366.350425 -271.839758) (xy 366.324122 -271.798162) (xy 366.304831 -271.752886) (xy 366.293054 -271.705102)
			(xy 366.289094 -271.656048) (xy 365.960152 -271.656048) (xy 365.959657 -271.680655) (xy 365.951762 -271.729232)
			(xy 365.936178 -271.775913) (xy 365.913307 -271.81949) (xy 365.883742 -271.858834) (xy 365.848249 -271.892926)
			(xy 365.807746 -271.920882) (xy 365.763284 -271.94198) (xy 365.716013 -271.955672) (xy 365.667158 -271.961604)
			(xy 365.617983 -271.959623) (xy 365.569764 -271.949779) (xy 365.523748 -271.932327) (xy 365.481127 -271.90772)
			(xy 365.443006 -271.876595) (xy 365.410371 -271.839758) (xy 365.384068 -271.798162) (xy 365.364777 -271.752886)
			(xy 365.353 -271.705102) (xy 365.34904 -271.656048) (xy 365.020098 -271.656048) (xy 365.019603 -271.680655)
			(xy 365.011708 -271.729232) (xy 364.996124 -271.775913) (xy 364.973253 -271.81949) (xy 364.943688 -271.858834)
			(xy 364.908195 -271.892926) (xy 364.867692 -271.920882) (xy 364.82323 -271.94198) (xy 364.775959 -271.955672)
			(xy 364.727104 -271.961604) (xy 364.677929 -271.959623) (xy 364.62971 -271.949779) (xy 364.583694 -271.932327)
			(xy 364.541073 -271.90772) (xy 364.502952 -271.876595) (xy 364.470317 -271.839758) (xy 364.444014 -271.798162)
			(xy 364.424723 -271.752886) (xy 364.412946 -271.705102) (xy 364.408986 -271.656048) (xy 364.080044 -271.656048)
			(xy 364.079549 -271.680655) (xy 364.071654 -271.729232) (xy 364.05607 -271.775913) (xy 364.033199 -271.81949)
			(xy 364.003634 -271.858834) (xy 363.968141 -271.892926) (xy 363.927638 -271.920882) (xy 363.883176 -271.94198)
			(xy 363.835905 -271.955672) (xy 363.78705 -271.961604) (xy 363.737875 -271.959623) (xy 363.689656 -271.949779)
			(xy 363.64364 -271.932327) (xy 363.601019 -271.90772) (xy 363.562898 -271.876595) (xy 363.530263 -271.839758)
			(xy 363.50396 -271.798162) (xy 363.484669 -271.752886) (xy 363.472892 -271.705102) (xy 363.468932 -271.656048)
			(xy 356.56647 -271.656048) (xy 356.565975 -271.680655) (xy 356.55808 -271.729232) (xy 356.542496 -271.775913)
			(xy 356.519625 -271.81949) (xy 356.49006 -271.858834) (xy 356.454567 -271.892926) (xy 356.414064 -271.920882)
			(xy 356.369602 -271.94198) (xy 356.322331 -271.955672) (xy 356.273476 -271.961604) (xy 356.224301 -271.959623)
			(xy 356.176082 -271.949779) (xy 356.130066 -271.932327) (xy 356.087445 -271.90772) (xy 356.049324 -271.876595)
			(xy 356.016689 -271.839758) (xy 355.990386 -271.798162) (xy 355.971095 -271.752886) (xy 355.959318 -271.705102)
			(xy 355.955358 -271.656048) (xy 355.626416 -271.656048) (xy 355.625921 -271.680655) (xy 355.618026 -271.729232)
			(xy 355.602442 -271.775913) (xy 355.579571 -271.81949) (xy 355.550006 -271.858834) (xy 355.514513 -271.892926)
			(xy 355.47401 -271.920882) (xy 355.429548 -271.94198) (xy 355.382277 -271.955672) (xy 355.333422 -271.961604)
			(xy 355.284247 -271.959623) (xy 355.236028 -271.949779) (xy 355.190012 -271.932327) (xy 355.147391 -271.90772)
			(xy 355.10927 -271.876595) (xy 355.076635 -271.839758) (xy 355.050332 -271.798162) (xy 355.031041 -271.752886)
			(xy 355.019264 -271.705102) (xy 355.015304 -271.656048) (xy 354.686362 -271.656048) (xy 354.685867 -271.680655)
			(xy 354.677972 -271.729232) (xy 354.662388 -271.775913) (xy 354.639517 -271.81949) (xy 354.609952 -271.858834)
			(xy 354.574459 -271.892926) (xy 354.533956 -271.920882) (xy 354.489494 -271.94198) (xy 354.442223 -271.955672)
			(xy 354.393368 -271.961604) (xy 354.344193 -271.959623) (xy 354.295974 -271.949779) (xy 354.249958 -271.932327)
			(xy 354.207337 -271.90772) (xy 354.169216 -271.876595) (xy 354.136581 -271.839758) (xy 354.110278 -271.798162)
			(xy 354.090987 -271.752886) (xy 354.07921 -271.705102) (xy 354.07525 -271.656048) (xy 353.746308 -271.656048)
			(xy 353.745813 -271.680655) (xy 353.737918 -271.729232) (xy 353.722334 -271.775913) (xy 353.699463 -271.81949)
			(xy 353.669898 -271.858834) (xy 353.634405 -271.892926) (xy 353.593902 -271.920882) (xy 353.54944 -271.94198)
			(xy 353.502169 -271.955672) (xy 353.453314 -271.961604) (xy 353.404139 -271.959623) (xy 353.35592 -271.949779)
			(xy 353.309904 -271.932327) (xy 353.267283 -271.90772) (xy 353.229162 -271.876595) (xy 353.196527 -271.839758)
			(xy 353.170224 -271.798162) (xy 353.150933 -271.752886) (xy 353.139156 -271.705102) (xy 353.135196 -271.656048)
			(xy 352.806508 -271.656048) (xy 352.806013 -271.680655) (xy 352.798118 -271.729232) (xy 352.782534 -271.775913)
			(xy 352.759663 -271.81949) (xy 352.730098 -271.858834) (xy 352.694605 -271.892926) (xy 352.654102 -271.920882)
			(xy 352.60964 -271.94198) (xy 352.562369 -271.955672) (xy 352.513514 -271.961604) (xy 352.464339 -271.959623)
			(xy 352.41612 -271.949779) (xy 352.370104 -271.932327) (xy 352.327483 -271.90772) (xy 352.289362 -271.876595)
			(xy 352.256727 -271.839758) (xy 352.230424 -271.798162) (xy 352.211133 -271.752886) (xy 352.199356 -271.705102)
			(xy 352.195396 -271.656048) (xy 351.866454 -271.656048) (xy 351.865959 -271.680655) (xy 351.858064 -271.729232)
			(xy 351.84248 -271.775913) (xy 351.819609 -271.81949) (xy 351.790044 -271.858834) (xy 351.754551 -271.892926)
			(xy 351.714048 -271.920882) (xy 351.669586 -271.94198) (xy 351.622315 -271.955672) (xy 351.57346 -271.961604)
			(xy 351.524285 -271.959623) (xy 351.476066 -271.949779) (xy 351.43005 -271.932327) (xy 351.387429 -271.90772)
			(xy 351.349308 -271.876595) (xy 351.316673 -271.839758) (xy 351.29037 -271.798162) (xy 351.271079 -271.752886)
			(xy 351.259302 -271.705102) (xy 351.255342 -271.656048) (xy 350.9264 -271.656048) (xy 350.925905 -271.680655)
			(xy 350.91801 -271.729232) (xy 350.902426 -271.775913) (xy 350.879555 -271.81949) (xy 350.84999 -271.858834)
			(xy 350.814497 -271.892926) (xy 350.773994 -271.920882) (xy 350.729532 -271.94198) (xy 350.682261 -271.955672)
			(xy 350.633406 -271.961604) (xy 350.584231 -271.959623) (xy 350.536012 -271.949779) (xy 350.489996 -271.932327)
			(xy 350.447375 -271.90772) (xy 350.409254 -271.876595) (xy 350.376619 -271.839758) (xy 350.350316 -271.798162)
			(xy 350.331025 -271.752886) (xy 350.319248 -271.705102) (xy 350.315288 -271.656048) (xy 349.986346 -271.656048)
			(xy 349.985851 -271.680655) (xy 349.977956 -271.729232) (xy 349.962372 -271.775913) (xy 349.939501 -271.81949)
			(xy 349.909936 -271.858834) (xy 349.874443 -271.892926) (xy 349.83394 -271.920882) (xy 349.789478 -271.94198)
			(xy 349.742207 -271.955672) (xy 349.693352 -271.961604) (xy 349.644177 -271.959623) (xy 349.595958 -271.949779)
			(xy 349.549942 -271.932327) (xy 349.507321 -271.90772) (xy 349.4692 -271.876595) (xy 349.436565 -271.839758)
			(xy 349.410262 -271.798162) (xy 349.390971 -271.752886) (xy 349.379194 -271.705102) (xy 349.375234 -271.656048)
			(xy 349.046546 -271.656048) (xy 349.046051 -271.680655) (xy 349.038156 -271.729232) (xy 349.022572 -271.775913)
			(xy 348.999701 -271.81949) (xy 348.970136 -271.858834) (xy 348.934643 -271.892926) (xy 348.89414 -271.920882)
			(xy 348.849678 -271.94198) (xy 348.802407 -271.955672) (xy 348.753552 -271.961604) (xy 348.704377 -271.959623)
			(xy 348.656158 -271.949779) (xy 348.610142 -271.932327) (xy 348.567521 -271.90772) (xy 348.5294 -271.876595)
			(xy 348.496765 -271.839758) (xy 348.470462 -271.798162) (xy 348.451171 -271.752886) (xy 348.439394 -271.705102)
			(xy 348.435434 -271.656048) (xy 348.106492 -271.656048) (xy 348.105997 -271.680655) (xy 348.098102 -271.729232)
			(xy 348.082518 -271.775913) (xy 348.059647 -271.81949) (xy 348.030082 -271.858834) (xy 347.994589 -271.892926)
			(xy 347.954086 -271.920882) (xy 347.909624 -271.94198) (xy 347.862353 -271.955672) (xy 347.813498 -271.961604)
			(xy 347.764323 -271.959623) (xy 347.716104 -271.949779) (xy 347.670088 -271.932327) (xy 347.627467 -271.90772)
			(xy 347.589346 -271.876595) (xy 347.556711 -271.839758) (xy 347.530408 -271.798162) (xy 347.511117 -271.752886)
			(xy 347.49934 -271.705102) (xy 347.49538 -271.656048) (xy 347.166438 -271.656048) (xy 347.165943 -271.680655)
			(xy 347.158048 -271.729232) (xy 347.142464 -271.775913) (xy 347.119593 -271.81949) (xy 347.090028 -271.858834)
			(xy 347.054535 -271.892926) (xy 347.014032 -271.920882) (xy 346.96957 -271.94198) (xy 346.922299 -271.955672)
			(xy 346.873444 -271.961604) (xy 346.824269 -271.959623) (xy 346.77605 -271.949779) (xy 346.730034 -271.932327)
			(xy 346.687413 -271.90772) (xy 346.649292 -271.876595) (xy 346.616657 -271.839758) (xy 346.590354 -271.798162)
			(xy 346.571063 -271.752886) (xy 346.559286 -271.705102) (xy 346.555326 -271.656048) (xy 346.226384 -271.656048)
			(xy 346.225889 -271.680655) (xy 346.217994 -271.729232) (xy 346.20241 -271.775913) (xy 346.179539 -271.81949)
			(xy 346.149974 -271.858834) (xy 346.114481 -271.892926) (xy 346.073978 -271.920882) (xy 346.029516 -271.94198)
			(xy 345.982245 -271.955672) (xy 345.93339 -271.961604) (xy 345.884215 -271.959623) (xy 345.835996 -271.949779)
			(xy 345.78998 -271.932327) (xy 345.747359 -271.90772) (xy 345.709238 -271.876595) (xy 345.676603 -271.839758)
			(xy 345.6503 -271.798162) (xy 345.631009 -271.752886) (xy 345.619232 -271.705102) (xy 345.615272 -271.656048)
			(xy 345.28633 -271.656048) (xy 345.285835 -271.680655) (xy 345.27794 -271.729232) (xy 345.262356 -271.775913)
			(xy 345.239485 -271.81949) (xy 345.20992 -271.858834) (xy 345.174427 -271.892926) (xy 345.133924 -271.920882)
			(xy 345.089462 -271.94198) (xy 345.042191 -271.955672) (xy 344.993336 -271.961604) (xy 344.944161 -271.959623)
			(xy 344.895942 -271.949779) (xy 344.849926 -271.932327) (xy 344.807305 -271.90772) (xy 344.769184 -271.876595)
			(xy 344.736549 -271.839758) (xy 344.710246 -271.798162) (xy 344.690955 -271.752886) (xy 344.679178 -271.705102)
			(xy 344.675218 -271.656048) (xy 344.356944 -271.656048) (xy 344.356432 -271.681494) (xy 344.348268 -271.731728)
			(xy 344.332152 -271.780002) (xy 344.308501 -271.825065) (xy 344.277928 -271.865751) (xy 344.241224 -271.901006)
			(xy 344.19934 -271.929916) (xy 344.153361 -271.951733) (xy 344.104477 -271.965893) (xy 344.053956 -271.972027)
			(xy 344.003104 -271.969978) (xy 343.95324 -271.959798) (xy 343.905654 -271.941751) (xy 343.86158 -271.916305)
			(xy 343.822158 -271.884118) (xy 343.78841 -271.846024) (xy 343.761209 -271.80301) (xy 343.741261 -271.75619)
			(xy 343.729082 -271.706776) (xy 343.724987 -271.656048) (xy 343.406476 -271.656048) (xy 343.405981 -271.680655)
			(xy 343.398086 -271.729232) (xy 343.382502 -271.775913) (xy 343.359631 -271.81949) (xy 343.330066 -271.858834)
			(xy 343.294573 -271.892926) (xy 343.25407 -271.920882) (xy 343.209608 -271.94198) (xy 343.162337 -271.955672)
			(xy 343.113482 -271.961604) (xy 343.064307 -271.959623) (xy 343.016088 -271.949779) (xy 342.970072 -271.932327)
			(xy 342.927451 -271.90772) (xy 342.88933 -271.876595) (xy 342.856695 -271.839758) (xy 342.830392 -271.798162)
			(xy 342.811101 -271.752886) (xy 342.799324 -271.705102) (xy 342.795364 -271.656048) (xy 342.476836 -271.656048)
			(xy 342.476324 -271.681494) (xy 342.46816 -271.731728) (xy 342.452044 -271.780002) (xy 342.428393 -271.825065)
			(xy 342.39782 -271.865751) (xy 342.361116 -271.901006) (xy 342.319232 -271.929916) (xy 342.273253 -271.951733)
			(xy 342.224369 -271.965893) (xy 342.173848 -271.972027) (xy 342.122996 -271.969978) (xy 342.073132 -271.959798)
			(xy 342.025546 -271.941751) (xy 341.981472 -271.916305) (xy 341.94205 -271.884118) (xy 341.908302 -271.846024)
			(xy 341.881101 -271.80301) (xy 341.861153 -271.75619) (xy 341.848974 -271.706776) (xy 341.844879 -271.656048)
			(xy 341.525905 -271.656048) (xy 341.525905 -271.68007) (xy 341.518352 -271.7276) (xy 341.503435 -271.773357)
			(xy 341.481522 -271.816205) (xy 341.453158 -271.855084) (xy 341.419044 -271.889031) (xy 341.380026 -271.917205)
			(xy 341.337071 -271.938907) (xy 341.291242 -271.9536) (xy 341.267542 -271.9578) (xy 341.258652 -271.95907)
			(xy 341.24265 -271.96796) (xy 341.236808 -271.974818) (xy 341.231225 -271.981905) (xy 341.224988 -271.998823)
			(xy 341.224616 -272.007838) (xy 341.224616 -272.160492) (xy 341.224757 -272.165382) (xy 341.226682 -272.174971)
			(xy 341.228426 -272.179542) (xy 341.232236 -272.187162) (xy 341.232998 -272.188432) (xy 341.238996 -272.19901)
			(xy 341.250178 -272.220607) (xy 341.25535 -272.231612) (xy 341.268558 -272.2626) (xy 341.268558 -272.262854)
			(xy 341.271247 -272.269059) (xy 341.279349 -272.279881) (xy 341.28456 -272.28419) (xy 341.28964 -272.288254)
			(xy 341.30234 -272.293588) (xy 341.397844 -272.30578) (xy 341.406973 -272.30658) (xy 341.424802 -272.302399)
			(xy 341.432642 -272.297652) (xy 341.436185 -272.295153) (xy 341.442439 -272.289147) (xy 341.445088 -272.285714)
			(xy 341.445088 -272.28546) (xy 341.459584 -272.266492) (xy 341.493476 -272.232873) (xy 341.532185 -272.204937)
			(xy 341.574769 -272.183364) (xy 341.620192 -272.168678) (xy 341.667345 -272.161238) (xy 341.691214 -272.160746)
			(xy 341.716472 -272.161268) (xy 341.7663 -272.169585) (xy 341.814079 -272.18599) (xy 341.858507 -272.210034)
			(xy 341.898371 -272.241064) (xy 341.932584 -272.278231) (xy 341.960213 -272.320522) (xy 341.980505 -272.366785)
			(xy 341.992906 -272.415756) (xy 341.997074 -272.466054) (xy 342.314779 -272.466054) (xy 342.318874 -272.415326)
			(xy 342.331053 -272.365912) (xy 342.351001 -272.319092) (xy 342.378202 -272.276078) (xy 342.41195 -272.237984)
			(xy 342.451372 -272.205797) (xy 342.495446 -272.180351) (xy 342.543032 -272.162304) (xy 342.592896 -272.152124)
			(xy 342.643748 -272.150075) (xy 342.694269 -272.156209) (xy 342.743153 -272.170369) (xy 342.789132 -272.192186)
			(xy 342.831016 -272.221096) (xy 342.86772 -272.256351) (xy 342.898293 -272.297037) (xy 342.921944 -272.3421)
			(xy 342.93806 -272.390374) (xy 342.946224 -272.440608) (xy 342.946736 -272.466054) (xy 343.254833 -272.466054)
			(xy 343.258928 -272.415326) (xy 343.271107 -272.365912) (xy 343.291055 -272.319092) (xy 343.318256 -272.276078)
			(xy 343.352004 -272.237984) (xy 343.391426 -272.205797) (xy 343.4355 -272.180351) (xy 343.483086 -272.162304)
			(xy 343.53295 -272.152124) (xy 343.583802 -272.150075) (xy 343.634323 -272.156209) (xy 343.683207 -272.170369)
			(xy 343.729186 -272.192186) (xy 343.77107 -272.221096) (xy 343.807774 -272.256351) (xy 343.838347 -272.297037)
			(xy 343.861998 -272.3421) (xy 343.878114 -272.390374) (xy 343.886278 -272.440608) (xy 343.88679 -272.466054)
			(xy 344.205318 -272.466054) (xy 344.209278 -272.417) (xy 344.221055 -272.369216) (xy 344.240346 -272.32394)
			(xy 344.266649 -272.282344) (xy 344.299284 -272.245507) (xy 344.337405 -272.214382) (xy 344.380026 -272.189775)
			(xy 344.426042 -272.172323) (xy 344.474261 -272.162479) (xy 344.523436 -272.160498) (xy 344.572291 -272.16643)
			(xy 344.619562 -272.180122) (xy 344.664024 -272.20122) (xy 344.704527 -272.229176) (xy 344.74002 -272.263268)
			(xy 344.769585 -272.302612) (xy 344.792456 -272.346189) (xy 344.80804 -272.39287) (xy 344.815935 -272.441447)
			(xy 344.81643 -272.466054) (xy 347.025226 -272.466054) (xy 347.029186 -272.417) (xy 347.040963 -272.369216)
			(xy 347.060254 -272.32394) (xy 347.086557 -272.282344) (xy 347.119192 -272.245507) (xy 347.157313 -272.214382)
			(xy 347.199934 -272.189775) (xy 347.24595 -272.172323) (xy 347.294169 -272.162479) (xy 347.343344 -272.160498)
			(xy 347.392199 -272.16643) (xy 347.43947 -272.180122) (xy 347.483932 -272.20122) (xy 347.524435 -272.229176)
			(xy 347.559928 -272.263268) (xy 347.589493 -272.302612) (xy 347.612364 -272.346189) (xy 347.627948 -272.39287)
			(xy 347.635843 -272.441447) (xy 347.636338 -272.466054) (xy 349.845388 -272.466054) (xy 349.849348 -272.417)
			(xy 349.861125 -272.369216) (xy 349.880416 -272.32394) (xy 349.906719 -272.282344) (xy 349.939354 -272.245507)
			(xy 349.977475 -272.214382) (xy 350.020096 -272.189775) (xy 350.066112 -272.172323) (xy 350.114331 -272.162479)
			(xy 350.163506 -272.160498) (xy 350.212361 -272.16643) (xy 350.259632 -272.180122) (xy 350.304094 -272.20122)
			(xy 350.344597 -272.229176) (xy 350.38009 -272.263268) (xy 350.409655 -272.302612) (xy 350.432526 -272.346189)
			(xy 350.44811 -272.39287) (xy 350.456005 -272.441447) (xy 350.4565 -272.466054) (xy 352.665296 -272.466054)
			(xy 352.669256 -272.417) (xy 352.681033 -272.369216) (xy 352.700324 -272.32394) (xy 352.726627 -272.282344)
			(xy 352.759262 -272.245507) (xy 352.797383 -272.214382) (xy 352.840004 -272.189775) (xy 352.88602 -272.172323)
			(xy 352.934239 -272.162479) (xy 352.983414 -272.160498) (xy 353.032269 -272.16643) (xy 353.07954 -272.180122)
			(xy 353.124002 -272.20122) (xy 353.164505 -272.229176) (xy 353.199998 -272.263268) (xy 353.229563 -272.302612)
			(xy 353.252434 -272.346189) (xy 353.268018 -272.39287) (xy 353.275913 -272.441447) (xy 353.276408 -272.466054)
			(xy 355.485204 -272.466054) (xy 355.489164 -272.417) (xy 355.500941 -272.369216) (xy 355.520232 -272.32394)
			(xy 355.546535 -272.282344) (xy 355.57917 -272.245507) (xy 355.617291 -272.214382) (xy 355.659912 -272.189775)
			(xy 355.705928 -272.172323) (xy 355.754147 -272.162479) (xy 355.803322 -272.160498) (xy 355.852177 -272.16643)
			(xy 355.899448 -272.180122) (xy 355.94391 -272.20122) (xy 355.984413 -272.229176) (xy 356.019906 -272.263268)
			(xy 356.049471 -272.302612) (xy 356.072342 -272.346189) (xy 356.087926 -272.39287) (xy 356.095821 -272.441447)
			(xy 356.096316 -272.466054) (xy 356.425258 -272.466054) (xy 356.429218 -272.417) (xy 356.440995 -272.369216)
			(xy 356.460286 -272.32394) (xy 356.486589 -272.282344) (xy 356.519224 -272.245507) (xy 356.557345 -272.214382)
			(xy 356.599966 -272.189775) (xy 356.645982 -272.172323) (xy 356.694201 -272.162479) (xy 356.743376 -272.160498)
			(xy 356.792231 -272.16643) (xy 356.839502 -272.180122) (xy 356.883964 -272.20122) (xy 356.924467 -272.229176)
			(xy 356.95996 -272.263268) (xy 356.989525 -272.302612) (xy 357.012396 -272.346189) (xy 357.02798 -272.39287)
			(xy 357.035875 -272.441447) (xy 357.03637 -272.466054) (xy 357.365312 -272.466054) (xy 357.369272 -272.417)
			(xy 357.381049 -272.369216) (xy 357.40034 -272.32394) (xy 357.426643 -272.282344) (xy 357.459278 -272.245507)
			(xy 357.497399 -272.214382) (xy 357.54002 -272.189775) (xy 357.586036 -272.172323) (xy 357.634255 -272.162479)
			(xy 357.68343 -272.160498) (xy 357.732285 -272.16643) (xy 357.779556 -272.180122) (xy 357.824018 -272.20122)
			(xy 357.864521 -272.229176) (xy 357.900014 -272.263268) (xy 357.929579 -272.302612) (xy 357.95245 -272.346189)
			(xy 357.968034 -272.39287) (xy 357.975929 -272.441447) (xy 357.976424 -272.466054) (xy 358.305366 -272.466054)
			(xy 358.309326 -272.417) (xy 358.321103 -272.369216) (xy 358.340394 -272.32394) (xy 358.366697 -272.282344)
			(xy 358.399332 -272.245507) (xy 358.437453 -272.214382) (xy 358.480074 -272.189775) (xy 358.52609 -272.172323)
			(xy 358.574309 -272.162479) (xy 358.623484 -272.160498) (xy 358.672339 -272.16643) (xy 358.71961 -272.180122)
			(xy 358.764072 -272.20122) (xy 358.804575 -272.229176) (xy 358.840068 -272.263268) (xy 358.869633 -272.302612)
			(xy 358.892504 -272.346189) (xy 358.908088 -272.39287) (xy 358.915983 -272.441447) (xy 358.916478 -272.466054)
			(xy 361.118924 -272.466054) (xy 361.122884 -272.417) (xy 361.134661 -272.369216) (xy 361.153952 -272.32394)
			(xy 361.180255 -272.282344) (xy 361.21289 -272.245507) (xy 361.251011 -272.214382) (xy 361.293632 -272.189775)
			(xy 361.339648 -272.172323) (xy 361.387867 -272.162479) (xy 361.437042 -272.160498) (xy 361.485897 -272.16643)
			(xy 361.533168 -272.180122) (xy 361.57763 -272.20122) (xy 361.618133 -272.229176) (xy 361.653626 -272.263268)
			(xy 361.683191 -272.302612) (xy 361.706062 -272.346189) (xy 361.721646 -272.39287) (xy 361.729541 -272.441447)
			(xy 361.730036 -272.466054) (xy 362.058978 -272.466054) (xy 362.062938 -272.417) (xy 362.074715 -272.369216)
			(xy 362.094006 -272.32394) (xy 362.120309 -272.282344) (xy 362.152944 -272.245507) (xy 362.191065 -272.214382)
			(xy 362.233686 -272.189775) (xy 362.279702 -272.172323) (xy 362.327921 -272.162479) (xy 362.377096 -272.160498)
			(xy 362.425951 -272.16643) (xy 362.473222 -272.180122) (xy 362.517684 -272.20122) (xy 362.558187 -272.229176)
			(xy 362.59368 -272.263268) (xy 362.623245 -272.302612) (xy 362.646116 -272.346189) (xy 362.6617 -272.39287)
			(xy 362.669595 -272.441447) (xy 362.67009 -272.466054) (xy 362.999032 -272.466054) (xy 363.002992 -272.417)
			(xy 363.014769 -272.369216) (xy 363.03406 -272.32394) (xy 363.060363 -272.282344) (xy 363.092998 -272.245507)
			(xy 363.131119 -272.214382) (xy 363.17374 -272.189775) (xy 363.219756 -272.172323) (xy 363.267975 -272.162479)
			(xy 363.31715 -272.160498) (xy 363.366005 -272.16643) (xy 363.413276 -272.180122) (xy 363.457738 -272.20122)
			(xy 363.498241 -272.229176) (xy 363.533734 -272.263268) (xy 363.563299 -272.302612) (xy 363.58617 -272.346189)
			(xy 363.601754 -272.39287) (xy 363.609649 -272.441447) (xy 363.610144 -272.466054) (xy 363.939086 -272.466054)
			(xy 363.943046 -272.417) (xy 363.954823 -272.369216) (xy 363.974114 -272.32394) (xy 364.000417 -272.282344)
			(xy 364.033052 -272.245507) (xy 364.071173 -272.214382) (xy 364.113794 -272.189775) (xy 364.15981 -272.172323)
			(xy 364.208029 -272.162479) (xy 364.257204 -272.160498) (xy 364.306059 -272.16643) (xy 364.35333 -272.180122)
			(xy 364.397792 -272.20122) (xy 364.438295 -272.229176) (xy 364.473788 -272.263268) (xy 364.503353 -272.302612)
			(xy 364.526224 -272.346189) (xy 364.541808 -272.39287) (xy 364.549703 -272.441447) (xy 364.550198 -272.466054)
			(xy 366.758994 -272.466054) (xy 366.762954 -272.417) (xy 366.774731 -272.369216) (xy 366.794022 -272.32394)
			(xy 366.820325 -272.282344) (xy 366.85296 -272.245507) (xy 366.891081 -272.214382) (xy 366.933702 -272.189775)
			(xy 366.979718 -272.172323) (xy 367.027937 -272.162479) (xy 367.077112 -272.160498) (xy 367.125967 -272.16643)
			(xy 367.173238 -272.180122) (xy 367.2177 -272.20122) (xy 367.258203 -272.229176) (xy 367.293696 -272.263268)
			(xy 367.323261 -272.302612) (xy 367.346132 -272.346189) (xy 367.361716 -272.39287) (xy 367.369611 -272.441447)
			(xy 367.370106 -272.466054) (xy 369.578902 -272.466054) (xy 369.582862 -272.417) (xy 369.594639 -272.369216)
			(xy 369.61393 -272.32394) (xy 369.640233 -272.282344) (xy 369.672868 -272.245507) (xy 369.710989 -272.214382)
			(xy 369.75361 -272.189775) (xy 369.799626 -272.172323) (xy 369.847845 -272.162479) (xy 369.89702 -272.160498)
			(xy 369.945875 -272.16643) (xy 369.993146 -272.180122) (xy 370.037608 -272.20122) (xy 370.078111 -272.229176)
			(xy 370.113604 -272.263268) (xy 370.143169 -272.302612) (xy 370.16604 -272.346189) (xy 370.181624 -272.39287)
			(xy 370.189519 -272.441447) (xy 370.190014 -272.466054) (xy 372.399064 -272.466054) (xy 372.403024 -272.417)
			(xy 372.414801 -272.369216) (xy 372.434092 -272.32394) (xy 372.460395 -272.282344) (xy 372.49303 -272.245507)
			(xy 372.531151 -272.214382) (xy 372.573772 -272.189775) (xy 372.619788 -272.172323) (xy 372.668007 -272.162479)
			(xy 372.717182 -272.160498) (xy 372.766037 -272.16643) (xy 372.813308 -272.180122) (xy 372.85777 -272.20122)
			(xy 372.898273 -272.229176) (xy 372.933766 -272.263268) (xy 372.963331 -272.302612) (xy 372.986202 -272.346189)
			(xy 373.001786 -272.39287) (xy 373.009681 -272.441447) (xy 373.010176 -272.466054) (xy 375.218972 -272.466054)
			(xy 375.222932 -272.417) (xy 375.234709 -272.369216) (xy 375.254 -272.32394) (xy 375.280303 -272.282344)
			(xy 375.312938 -272.245507) (xy 375.351059 -272.214382) (xy 375.39368 -272.189775) (xy 375.439696 -272.172323)
			(xy 375.487915 -272.162479) (xy 375.53709 -272.160498) (xy 375.585945 -272.16643) (xy 375.633216 -272.180122)
			(xy 375.677678 -272.20122) (xy 375.718181 -272.229176) (xy 375.753674 -272.263268) (xy 375.783239 -272.302612)
			(xy 375.80611 -272.346189) (xy 375.821694 -272.39287) (xy 375.829589 -272.441447) (xy 375.830084 -272.466054)
			(xy 376.148595 -272.466054) (xy 376.15269 -272.415326) (xy 376.164869 -272.365912) (xy 376.184817 -272.319092)
			(xy 376.212018 -272.276078) (xy 376.245766 -272.237984) (xy 376.285188 -272.205797) (xy 376.329262 -272.180351)
			(xy 376.376848 -272.162304) (xy 376.426712 -272.152124) (xy 376.477564 -272.150075) (xy 376.528085 -272.156209)
			(xy 376.576969 -272.170369) (xy 376.622948 -272.192186) (xy 376.664832 -272.221096) (xy 376.701536 -272.256351)
			(xy 376.732109 -272.297037) (xy 376.75576 -272.3421) (xy 376.771876 -272.390374) (xy 376.78004 -272.440608)
			(xy 376.780552 -272.466054) (xy 377.088649 -272.466054) (xy 377.092744 -272.415326) (xy 377.104923 -272.365912)
			(xy 377.124871 -272.319092) (xy 377.152072 -272.276078) (xy 377.18582 -272.237984) (xy 377.225242 -272.205797)
			(xy 377.269316 -272.180351) (xy 377.316902 -272.162304) (xy 377.366766 -272.152124) (xy 377.417618 -272.150075)
			(xy 377.468139 -272.156209) (xy 377.517023 -272.170369) (xy 377.563002 -272.192186) (xy 377.604886 -272.221096)
			(xy 377.64159 -272.256351) (xy 377.672163 -272.297037) (xy 377.695814 -272.3421) (xy 377.71193 -272.390374)
			(xy 377.720094 -272.440608) (xy 377.720606 -272.466054) (xy 377.720094 -272.4915) (xy 377.71193 -272.541734)
			(xy 377.695814 -272.590008) (xy 377.672163 -272.635071) (xy 377.64159 -272.675757) (xy 377.604886 -272.711012)
			(xy 377.563002 -272.739922) (xy 377.517023 -272.761739) (xy 377.468139 -272.775899) (xy 377.417618 -272.782033)
			(xy 377.366766 -272.779984) (xy 377.316902 -272.769804) (xy 377.269316 -272.751757) (xy 377.225242 -272.726311)
			(xy 377.18582 -272.694124) (xy 377.152072 -272.65603) (xy 377.124871 -272.613016) (xy 377.104923 -272.566196)
			(xy 377.092744 -272.516782) (xy 377.088649 -272.466054) (xy 376.780552 -272.466054) (xy 376.78004 -272.4915)
			(xy 376.771876 -272.541734) (xy 376.75576 -272.590008) (xy 376.732109 -272.635071) (xy 376.701536 -272.675757)
			(xy 376.664832 -272.711012) (xy 376.622948 -272.739922) (xy 376.576969 -272.761739) (xy 376.528085 -272.775899)
			(xy 376.477564 -272.782033) (xy 376.426712 -272.779984) (xy 376.376848 -272.769804) (xy 376.329262 -272.751757)
			(xy 376.285188 -272.726311) (xy 376.245766 -272.694124) (xy 376.212018 -272.65603) (xy 376.184817 -272.613016)
			(xy 376.164869 -272.566196) (xy 376.15269 -272.516782) (xy 376.148595 -272.466054) (xy 375.830084 -272.466054)
			(xy 375.829589 -272.490661) (xy 375.821694 -272.539238) (xy 375.80611 -272.585919) (xy 375.783239 -272.629496)
			(xy 375.753674 -272.66884) (xy 375.718181 -272.702932) (xy 375.677678 -272.730888) (xy 375.633216 -272.751986)
			(xy 375.585945 -272.765678) (xy 375.53709 -272.77161) (xy 375.487915 -272.769629) (xy 375.439696 -272.759785)
			(xy 375.39368 -272.742333) (xy 375.351059 -272.717726) (xy 375.312938 -272.686601) (xy 375.280303 -272.649764)
			(xy 375.254 -272.608168) (xy 375.234709 -272.562892) (xy 375.222932 -272.515108) (xy 375.218972 -272.466054)
			(xy 373.010176 -272.466054) (xy 373.009681 -272.490661) (xy 373.001786 -272.539238) (xy 372.986202 -272.585919)
			(xy 372.963331 -272.629496) (xy 372.933766 -272.66884) (xy 372.898273 -272.702932) (xy 372.85777 -272.730888)
			(xy 372.813308 -272.751986) (xy 372.766037 -272.765678) (xy 372.717182 -272.77161) (xy 372.668007 -272.769629)
			(xy 372.619788 -272.759785) (xy 372.573772 -272.742333) (xy 372.531151 -272.717726) (xy 372.49303 -272.686601)
			(xy 372.460395 -272.649764) (xy 372.434092 -272.608168) (xy 372.414801 -272.562892) (xy 372.403024 -272.515108)
			(xy 372.399064 -272.466054) (xy 370.190014 -272.466054) (xy 370.189519 -272.490661) (xy 370.181624 -272.539238)
			(xy 370.16604 -272.585919) (xy 370.143169 -272.629496) (xy 370.113604 -272.66884) (xy 370.078111 -272.702932)
			(xy 370.037608 -272.730888) (xy 369.993146 -272.751986) (xy 369.945875 -272.765678) (xy 369.89702 -272.77161)
			(xy 369.847845 -272.769629) (xy 369.799626 -272.759785) (xy 369.75361 -272.742333) (xy 369.710989 -272.717726)
			(xy 369.672868 -272.686601) (xy 369.640233 -272.649764) (xy 369.61393 -272.608168) (xy 369.594639 -272.562892)
			(xy 369.582862 -272.515108) (xy 369.578902 -272.466054) (xy 367.370106 -272.466054) (xy 367.369611 -272.490661)
			(xy 367.361716 -272.539238) (xy 367.346132 -272.585919) (xy 367.323261 -272.629496) (xy 367.293696 -272.66884)
			(xy 367.258203 -272.702932) (xy 367.2177 -272.730888) (xy 367.173238 -272.751986) (xy 367.125967 -272.765678)
			(xy 367.077112 -272.77161) (xy 367.027937 -272.769629) (xy 366.979718 -272.759785) (xy 366.933702 -272.742333)
			(xy 366.891081 -272.717726) (xy 366.85296 -272.686601) (xy 366.820325 -272.649764) (xy 366.794022 -272.608168)
			(xy 366.774731 -272.562892) (xy 366.762954 -272.515108) (xy 366.758994 -272.466054) (xy 364.550198 -272.466054)
			(xy 364.549703 -272.490661) (xy 364.541808 -272.539238) (xy 364.526224 -272.585919) (xy 364.503353 -272.629496)
			(xy 364.473788 -272.66884) (xy 364.438295 -272.702932) (xy 364.397792 -272.730888) (xy 364.35333 -272.751986)
			(xy 364.306059 -272.765678) (xy 364.257204 -272.77161) (xy 364.208029 -272.769629) (xy 364.15981 -272.759785)
			(xy 364.113794 -272.742333) (xy 364.071173 -272.717726) (xy 364.033052 -272.686601) (xy 364.000417 -272.649764)
			(xy 363.974114 -272.608168) (xy 363.954823 -272.562892) (xy 363.943046 -272.515108) (xy 363.939086 -272.466054)
			(xy 363.610144 -272.466054) (xy 363.609649 -272.490661) (xy 363.601754 -272.539238) (xy 363.58617 -272.585919)
			(xy 363.563299 -272.629496) (xy 363.533734 -272.66884) (xy 363.498241 -272.702932) (xy 363.457738 -272.730888)
			(xy 363.413276 -272.751986) (xy 363.366005 -272.765678) (xy 363.31715 -272.77161) (xy 363.267975 -272.769629)
			(xy 363.219756 -272.759785) (xy 363.17374 -272.742333) (xy 363.131119 -272.717726) (xy 363.092998 -272.686601)
			(xy 363.060363 -272.649764) (xy 363.03406 -272.608168) (xy 363.014769 -272.562892) (xy 363.002992 -272.515108)
			(xy 362.999032 -272.466054) (xy 362.67009 -272.466054) (xy 362.669595 -272.490661) (xy 362.6617 -272.539238)
			(xy 362.646116 -272.585919) (xy 362.623245 -272.629496) (xy 362.59368 -272.66884) (xy 362.558187 -272.702932)
			(xy 362.517684 -272.730888) (xy 362.473222 -272.751986) (xy 362.425951 -272.765678) (xy 362.377096 -272.77161)
			(xy 362.327921 -272.769629) (xy 362.279702 -272.759785) (xy 362.233686 -272.742333) (xy 362.191065 -272.717726)
			(xy 362.152944 -272.686601) (xy 362.120309 -272.649764) (xy 362.094006 -272.608168) (xy 362.074715 -272.562892)
			(xy 362.062938 -272.515108) (xy 362.058978 -272.466054) (xy 361.730036 -272.466054) (xy 361.729541 -272.490661)
			(xy 361.721646 -272.539238) (xy 361.706062 -272.585919) (xy 361.683191 -272.629496) (xy 361.653626 -272.66884)
			(xy 361.618133 -272.702932) (xy 361.57763 -272.730888) (xy 361.533168 -272.751986) (xy 361.485897 -272.765678)
			(xy 361.437042 -272.77161) (xy 361.387867 -272.769629) (xy 361.339648 -272.759785) (xy 361.293632 -272.742333)
			(xy 361.251011 -272.717726) (xy 361.21289 -272.686601) (xy 361.180255 -272.649764) (xy 361.153952 -272.608168)
			(xy 361.134661 -272.562892) (xy 361.122884 -272.515108) (xy 361.118924 -272.466054) (xy 358.916478 -272.466054)
			(xy 358.915983 -272.490661) (xy 358.908088 -272.539238) (xy 358.892504 -272.585919) (xy 358.869633 -272.629496)
			(xy 358.840068 -272.66884) (xy 358.804575 -272.702932) (xy 358.764072 -272.730888) (xy 358.71961 -272.751986)
			(xy 358.672339 -272.765678) (xy 358.623484 -272.77161) (xy 358.574309 -272.769629) (xy 358.52609 -272.759785)
			(xy 358.480074 -272.742333) (xy 358.437453 -272.717726) (xy 358.399332 -272.686601) (xy 358.366697 -272.649764)
			(xy 358.340394 -272.608168) (xy 358.321103 -272.562892) (xy 358.309326 -272.515108) (xy 358.305366 -272.466054)
			(xy 357.976424 -272.466054) (xy 357.975929 -272.490661) (xy 357.968034 -272.539238) (xy 357.95245 -272.585919)
			(xy 357.929579 -272.629496) (xy 357.900014 -272.66884) (xy 357.864521 -272.702932) (xy 357.824018 -272.730888)
			(xy 357.779556 -272.751986) (xy 357.732285 -272.765678) (xy 357.68343 -272.77161) (xy 357.634255 -272.769629)
			(xy 357.586036 -272.759785) (xy 357.54002 -272.742333) (xy 357.497399 -272.717726) (xy 357.459278 -272.686601)
			(xy 357.426643 -272.649764) (xy 357.40034 -272.608168) (xy 357.381049 -272.562892) (xy 357.369272 -272.515108)
			(xy 357.365312 -272.466054) (xy 357.03637 -272.466054) (xy 357.035875 -272.490661) (xy 357.02798 -272.539238)
			(xy 357.012396 -272.585919) (xy 356.989525 -272.629496) (xy 356.95996 -272.66884) (xy 356.924467 -272.702932)
			(xy 356.883964 -272.730888) (xy 356.839502 -272.751986) (xy 356.792231 -272.765678) (xy 356.743376 -272.77161)
			(xy 356.694201 -272.769629) (xy 356.645982 -272.759785) (xy 356.599966 -272.742333) (xy 356.557345 -272.717726)
			(xy 356.519224 -272.686601) (xy 356.486589 -272.649764) (xy 356.460286 -272.608168) (xy 356.440995 -272.562892)
			(xy 356.429218 -272.515108) (xy 356.425258 -272.466054) (xy 356.096316 -272.466054) (xy 356.095821 -272.490661)
			(xy 356.087926 -272.539238) (xy 356.072342 -272.585919) (xy 356.049471 -272.629496) (xy 356.019906 -272.66884)
			(xy 355.984413 -272.702932) (xy 355.94391 -272.730888) (xy 355.899448 -272.751986) (xy 355.852177 -272.765678)
			(xy 355.803322 -272.77161) (xy 355.754147 -272.769629) (xy 355.705928 -272.759785) (xy 355.659912 -272.742333)
			(xy 355.617291 -272.717726) (xy 355.57917 -272.686601) (xy 355.546535 -272.649764) (xy 355.520232 -272.608168)
			(xy 355.500941 -272.562892) (xy 355.489164 -272.515108) (xy 355.485204 -272.466054) (xy 353.276408 -272.466054)
			(xy 353.275913 -272.490661) (xy 353.268018 -272.539238) (xy 353.252434 -272.585919) (xy 353.229563 -272.629496)
			(xy 353.199998 -272.66884) (xy 353.164505 -272.702932) (xy 353.124002 -272.730888) (xy 353.07954 -272.751986)
			(xy 353.032269 -272.765678) (xy 352.983414 -272.77161) (xy 352.934239 -272.769629) (xy 352.88602 -272.759785)
			(xy 352.840004 -272.742333) (xy 352.797383 -272.717726) (xy 352.759262 -272.686601) (xy 352.726627 -272.649764)
			(xy 352.700324 -272.608168) (xy 352.681033 -272.562892) (xy 352.669256 -272.515108) (xy 352.665296 -272.466054)
			(xy 350.4565 -272.466054) (xy 350.456005 -272.490661) (xy 350.44811 -272.539238) (xy 350.432526 -272.585919)
			(xy 350.409655 -272.629496) (xy 350.38009 -272.66884) (xy 350.344597 -272.702932) (xy 350.304094 -272.730888)
			(xy 350.259632 -272.751986) (xy 350.212361 -272.765678) (xy 350.163506 -272.77161) (xy 350.114331 -272.769629)
			(xy 350.066112 -272.759785) (xy 350.020096 -272.742333) (xy 349.977475 -272.717726) (xy 349.939354 -272.686601)
			(xy 349.906719 -272.649764) (xy 349.880416 -272.608168) (xy 349.861125 -272.562892) (xy 349.849348 -272.515108)
			(xy 349.845388 -272.466054) (xy 347.636338 -272.466054) (xy 347.635843 -272.490661) (xy 347.627948 -272.539238)
			(xy 347.612364 -272.585919) (xy 347.589493 -272.629496) (xy 347.559928 -272.66884) (xy 347.524435 -272.702932)
			(xy 347.483932 -272.730888) (xy 347.43947 -272.751986) (xy 347.392199 -272.765678) (xy 347.343344 -272.77161)
			(xy 347.294169 -272.769629) (xy 347.24595 -272.759785) (xy 347.199934 -272.742333) (xy 347.157313 -272.717726)
			(xy 347.119192 -272.686601) (xy 347.086557 -272.649764) (xy 347.060254 -272.608168) (xy 347.040963 -272.562892)
			(xy 347.029186 -272.515108) (xy 347.025226 -272.466054) (xy 344.81643 -272.466054) (xy 344.815935 -272.490661)
			(xy 344.80804 -272.539238) (xy 344.792456 -272.585919) (xy 344.769585 -272.629496) (xy 344.74002 -272.66884)
			(xy 344.704527 -272.702932) (xy 344.664024 -272.730888) (xy 344.619562 -272.751986) (xy 344.572291 -272.765678)
			(xy 344.523436 -272.77161) (xy 344.474261 -272.769629) (xy 344.426042 -272.759785) (xy 344.380026 -272.742333)
			(xy 344.337405 -272.717726) (xy 344.299284 -272.686601) (xy 344.266649 -272.649764) (xy 344.240346 -272.608168)
			(xy 344.221055 -272.562892) (xy 344.209278 -272.515108) (xy 344.205318 -272.466054) (xy 343.88679 -272.466054)
			(xy 343.886278 -272.4915) (xy 343.878114 -272.541734) (xy 343.861998 -272.590008) (xy 343.838347 -272.635071)
			(xy 343.807774 -272.675757) (xy 343.77107 -272.711012) (xy 343.729186 -272.739922) (xy 343.683207 -272.761739)
			(xy 343.634323 -272.775899) (xy 343.583802 -272.782033) (xy 343.53295 -272.779984) (xy 343.483086 -272.769804)
			(xy 343.4355 -272.751757) (xy 343.391426 -272.726311) (xy 343.352004 -272.694124) (xy 343.318256 -272.65603)
			(xy 343.291055 -272.613016) (xy 343.271107 -272.566196) (xy 343.258928 -272.516782) (xy 343.254833 -272.466054)
			(xy 342.946736 -272.466054) (xy 342.946224 -272.4915) (xy 342.93806 -272.541734) (xy 342.921944 -272.590008)
			(xy 342.898293 -272.635071) (xy 342.86772 -272.675757) (xy 342.831016 -272.711012) (xy 342.789132 -272.739922)
			(xy 342.743153 -272.761739) (xy 342.694269 -272.775899) (xy 342.643748 -272.782033) (xy 342.592896 -272.779984)
			(xy 342.543032 -272.769804) (xy 342.495446 -272.751757) (xy 342.451372 -272.726311) (xy 342.41195 -272.694124)
			(xy 342.378202 -272.65603) (xy 342.351001 -272.613016) (xy 342.331053 -272.566196) (xy 342.318874 -272.516782)
			(xy 342.314779 -272.466054) (xy 341.997074 -272.466054) (xy 341.997078 -272.4661) (xy 341.992906 -272.516444)
			(xy 341.980505 -272.565415) (xy 341.960213 -272.611678) (xy 341.932584 -272.653969) (xy 341.898371 -272.691136)
			(xy 341.858507 -272.722166) (xy 341.814079 -272.74621) (xy 341.7663 -272.762615) (xy 341.716472 -272.770932)
			(xy 341.691214 -272.771362) (xy 341.667343 -272.770901) (xy 341.620184 -272.763469) (xy 341.574757 -272.748783)
			(xy 341.532172 -272.727202) (xy 341.493467 -272.699253) (xy 341.459586 -272.665617) (xy 341.445088 -272.646648)
			(xy 341.445088 -272.646394) (xy 341.442435 -272.642965) (xy 341.436177 -272.636966) (xy 341.432642 -272.634456)
			(xy 341.424815 -272.629677) (xy 341.406975 -272.625493) (xy 341.397844 -272.626328) (xy 341.309198 -272.637758)
			(xy 341.302437 -272.638831) (xy 341.289812 -272.644106) (xy 341.284306 -272.648172) (xy 341.278972 -272.652236)
			(xy 341.271098 -272.662904) (xy 341.268558 -272.669508) (xy 341.260579 -272.689222) (xy 341.242015 -272.72749)
			(xy 341.231474 -272.745962) (xy 341.231474 -272.746216) (xy 341.228357 -272.752035) (xy 341.224883 -272.764766)
			(xy 341.224616 -272.771362) (xy 341.224616 -272.92427) (xy 341.224971 -272.933288) (xy 341.231212 -272.95021)
			(xy 341.236808 -272.95729) (xy 341.24265 -272.964148) (xy 341.258652 -272.973038) (xy 341.267542 -272.974308)
			(xy 341.291263 -272.978416) (xy 341.337105 -272.993113) (xy 341.380072 -273.014821) (xy 341.419101 -273.043003)
			(xy 341.453225 -273.07696) (xy 341.481597 -273.11585) (xy 341.503516 -273.158711) (xy 341.518437 -273.20448)
			(xy 341.525992 -273.252024) (xy 341.525992 -273.27606) (xy 341.844879 -273.27606) (xy 341.848974 -273.225332)
			(xy 341.861153 -273.175918) (xy 341.881101 -273.129098) (xy 341.908302 -273.086084) (xy 341.94205 -273.04799)
			(xy 341.981472 -273.015803) (xy 342.025546 -272.990357) (xy 342.073132 -272.97231) (xy 342.122996 -272.96213)
			(xy 342.173848 -272.960081) (xy 342.224369 -272.966215) (xy 342.273253 -272.980375) (xy 342.319232 -273.002192)
			(xy 342.361116 -273.031102) (xy 342.39782 -273.066357) (xy 342.428393 -273.107043) (xy 342.452044 -273.152106)
			(xy 342.46816 -273.20038) (xy 342.476324 -273.250614) (xy 342.476836 -273.27606) (xy 342.795364 -273.27606)
			(xy 342.799324 -273.227006) (xy 342.811101 -273.179222) (xy 342.830392 -273.133946) (xy 342.856695 -273.09235)
			(xy 342.88933 -273.055513) (xy 342.927451 -273.024388) (xy 342.970072 -272.999781) (xy 343.016088 -272.982329)
			(xy 343.064307 -272.972485) (xy 343.113482 -272.970504) (xy 343.162337 -272.976436) (xy 343.209608 -272.990128)
			(xy 343.25407 -273.011226) (xy 343.294573 -273.039182) (xy 343.330066 -273.073274) (xy 343.359631 -273.112618)
			(xy 343.382502 -273.156195) (xy 343.398086 -273.202876) (xy 343.405981 -273.251453) (xy 343.406476 -273.27606)
			(xy 343.724987 -273.27606) (xy 343.729082 -273.225332) (xy 343.741261 -273.175918) (xy 343.761209 -273.129098)
			(xy 343.78841 -273.086084) (xy 343.822158 -273.04799) (xy 343.86158 -273.015803) (xy 343.905654 -272.990357)
			(xy 343.95324 -272.97231) (xy 344.003104 -272.96213) (xy 344.053956 -272.960081) (xy 344.104477 -272.966215)
			(xy 344.153361 -272.980375) (xy 344.19934 -273.002192) (xy 344.241224 -273.031102) (xy 344.277928 -273.066357)
			(xy 344.308501 -273.107043) (xy 344.332152 -273.152106) (xy 344.348268 -273.20038) (xy 344.356432 -273.250614)
			(xy 344.356944 -273.27606) (xy 344.675218 -273.27606) (xy 344.679178 -273.227006) (xy 344.690955 -273.179222)
			(xy 344.710246 -273.133946) (xy 344.736549 -273.09235) (xy 344.769184 -273.055513) (xy 344.807305 -273.024388)
			(xy 344.849926 -272.999781) (xy 344.895942 -272.982329) (xy 344.944161 -272.972485) (xy 344.993336 -272.970504)
			(xy 345.042191 -272.976436) (xy 345.089462 -272.990128) (xy 345.133924 -273.011226) (xy 345.174427 -273.039182)
			(xy 345.20992 -273.073274) (xy 345.239485 -273.112618) (xy 345.262356 -273.156195) (xy 345.27794 -273.202876)
			(xy 345.285835 -273.251453) (xy 345.28633 -273.27606) (xy 345.615272 -273.27606) (xy 345.619232 -273.227006)
			(xy 345.631009 -273.179222) (xy 345.6503 -273.133946) (xy 345.676603 -273.09235) (xy 345.709238 -273.055513)
			(xy 345.747359 -273.024388) (xy 345.78998 -272.999781) (xy 345.835996 -272.982329) (xy 345.884215 -272.972485)
			(xy 345.93339 -272.970504) (xy 345.982245 -272.976436) (xy 346.029516 -272.990128) (xy 346.073978 -273.011226)
			(xy 346.114481 -273.039182) (xy 346.149974 -273.073274) (xy 346.179539 -273.112618) (xy 346.20241 -273.156195)
			(xy 346.217994 -273.202876) (xy 346.225889 -273.251453) (xy 346.226384 -273.27606) (xy 346.555326 -273.27606)
			(xy 346.559286 -273.227006) (xy 346.571063 -273.179222) (xy 346.590354 -273.133946) (xy 346.616657 -273.09235)
			(xy 346.649292 -273.055513) (xy 346.687413 -273.024388) (xy 346.730034 -272.999781) (xy 346.77605 -272.982329)
			(xy 346.824269 -272.972485) (xy 346.873444 -272.970504) (xy 346.922299 -272.976436) (xy 346.96957 -272.990128)
			(xy 347.014032 -273.011226) (xy 347.054535 -273.039182) (xy 347.090028 -273.073274) (xy 347.119593 -273.112618)
			(xy 347.142464 -273.156195) (xy 347.158048 -273.202876) (xy 347.165943 -273.251453) (xy 347.166438 -273.27606)
			(xy 347.49538 -273.27606) (xy 347.49934 -273.227006) (xy 347.511117 -273.179222) (xy 347.530408 -273.133946)
			(xy 347.556711 -273.09235) (xy 347.589346 -273.055513) (xy 347.627467 -273.024388) (xy 347.670088 -272.999781)
			(xy 347.716104 -272.982329) (xy 347.764323 -272.972485) (xy 347.813498 -272.970504) (xy 347.862353 -272.976436)
			(xy 347.909624 -272.990128) (xy 347.954086 -273.011226) (xy 347.994589 -273.039182) (xy 348.030082 -273.073274)
			(xy 348.059647 -273.112618) (xy 348.082518 -273.156195) (xy 348.098102 -273.202876) (xy 348.105997 -273.251453)
			(xy 348.106492 -273.27606) (xy 348.435434 -273.27606) (xy 348.439394 -273.227006) (xy 348.451171 -273.179222)
			(xy 348.470462 -273.133946) (xy 348.496765 -273.09235) (xy 348.5294 -273.055513) (xy 348.567521 -273.024388)
			(xy 348.610142 -272.999781) (xy 348.656158 -272.982329) (xy 348.704377 -272.972485) (xy 348.753552 -272.970504)
			(xy 348.802407 -272.976436) (xy 348.849678 -272.990128) (xy 348.89414 -273.011226) (xy 348.934643 -273.039182)
			(xy 348.970136 -273.073274) (xy 348.999701 -273.112618) (xy 349.022572 -273.156195) (xy 349.038156 -273.202876)
			(xy 349.046051 -273.251453) (xy 349.046546 -273.27606) (xy 349.375234 -273.27606) (xy 349.379194 -273.227006)
			(xy 349.390971 -273.179222) (xy 349.410262 -273.133946) (xy 349.436565 -273.09235) (xy 349.4692 -273.055513)
			(xy 349.507321 -273.024388) (xy 349.549942 -272.999781) (xy 349.595958 -272.982329) (xy 349.644177 -272.972485)
			(xy 349.693352 -272.970504) (xy 349.742207 -272.976436) (xy 349.789478 -272.990128) (xy 349.83394 -273.011226)
			(xy 349.874443 -273.039182) (xy 349.909936 -273.073274) (xy 349.939501 -273.112618) (xy 349.962372 -273.156195)
			(xy 349.977956 -273.202876) (xy 349.985851 -273.251453) (xy 349.986346 -273.27606) (xy 350.315288 -273.27606)
			(xy 350.319248 -273.227006) (xy 350.331025 -273.179222) (xy 350.350316 -273.133946) (xy 350.376619 -273.09235)
			(xy 350.409254 -273.055513) (xy 350.447375 -273.024388) (xy 350.489996 -272.999781) (xy 350.536012 -272.982329)
			(xy 350.584231 -272.972485) (xy 350.633406 -272.970504) (xy 350.682261 -272.976436) (xy 350.729532 -272.990128)
			(xy 350.773994 -273.011226) (xy 350.814497 -273.039182) (xy 350.84999 -273.073274) (xy 350.879555 -273.112618)
			(xy 350.902426 -273.156195) (xy 350.91801 -273.202876) (xy 350.925905 -273.251453) (xy 350.9264 -273.27606)
			(xy 351.255342 -273.27606) (xy 351.259302 -273.227006) (xy 351.271079 -273.179222) (xy 351.29037 -273.133946)
			(xy 351.316673 -273.09235) (xy 351.349308 -273.055513) (xy 351.387429 -273.024388) (xy 351.43005 -272.999781)
			(xy 351.476066 -272.982329) (xy 351.524285 -272.972485) (xy 351.57346 -272.970504) (xy 351.622315 -272.976436)
			(xy 351.669586 -272.990128) (xy 351.714048 -273.011226) (xy 351.754551 -273.039182) (xy 351.790044 -273.073274)
			(xy 351.819609 -273.112618) (xy 351.84248 -273.156195) (xy 351.858064 -273.202876) (xy 351.865959 -273.251453)
			(xy 351.866454 -273.27606) (xy 352.195396 -273.27606) (xy 352.199356 -273.227006) (xy 352.211133 -273.179222)
			(xy 352.230424 -273.133946) (xy 352.256727 -273.09235) (xy 352.289362 -273.055513) (xy 352.327483 -273.024388)
			(xy 352.370104 -272.999781) (xy 352.41612 -272.982329) (xy 352.464339 -272.972485) (xy 352.513514 -272.970504)
			(xy 352.562369 -272.976436) (xy 352.60964 -272.990128) (xy 352.654102 -273.011226) (xy 352.694605 -273.039182)
			(xy 352.730098 -273.073274) (xy 352.759663 -273.112618) (xy 352.782534 -273.156195) (xy 352.798118 -273.202876)
			(xy 352.806013 -273.251453) (xy 352.806508 -273.27606) (xy 353.135196 -273.27606) (xy 353.139156 -273.227006)
			(xy 353.150933 -273.179222) (xy 353.170224 -273.133946) (xy 353.196527 -273.09235) (xy 353.229162 -273.055513)
			(xy 353.267283 -273.024388) (xy 353.309904 -272.999781) (xy 353.35592 -272.982329) (xy 353.404139 -272.972485)
			(xy 353.453314 -272.970504) (xy 353.502169 -272.976436) (xy 353.54944 -272.990128) (xy 353.593902 -273.011226)
			(xy 353.634405 -273.039182) (xy 353.669898 -273.073274) (xy 353.699463 -273.112618) (xy 353.722334 -273.156195)
			(xy 353.737918 -273.202876) (xy 353.745813 -273.251453) (xy 353.746308 -273.27606) (xy 354.07525 -273.27606)
			(xy 354.07921 -273.227006) (xy 354.090987 -273.179222) (xy 354.110278 -273.133946) (xy 354.136581 -273.09235)
			(xy 354.169216 -273.055513) (xy 354.207337 -273.024388) (xy 354.249958 -272.999781) (xy 354.295974 -272.982329)
			(xy 354.344193 -272.972485) (xy 354.393368 -272.970504) (xy 354.442223 -272.976436) (xy 354.489494 -272.990128)
			(xy 354.533956 -273.011226) (xy 354.574459 -273.039182) (xy 354.609952 -273.073274) (xy 354.639517 -273.112618)
			(xy 354.662388 -273.156195) (xy 354.677972 -273.202876) (xy 354.685867 -273.251453) (xy 354.686362 -273.27606)
			(xy 355.015304 -273.27606) (xy 355.019264 -273.227006) (xy 355.031041 -273.179222) (xy 355.050332 -273.133946)
			(xy 355.076635 -273.09235) (xy 355.10927 -273.055513) (xy 355.147391 -273.024388) (xy 355.190012 -272.999781)
			(xy 355.236028 -272.982329) (xy 355.284247 -272.972485) (xy 355.333422 -272.970504) (xy 355.382277 -272.976436)
			(xy 355.429548 -272.990128) (xy 355.47401 -273.011226) (xy 355.514513 -273.039182) (xy 355.550006 -273.073274)
			(xy 355.579571 -273.112618) (xy 355.602442 -273.156195) (xy 355.618026 -273.202876) (xy 355.625921 -273.251453)
			(xy 355.626416 -273.27606) (xy 355.955358 -273.27606) (xy 355.959318 -273.227006) (xy 355.971095 -273.179222)
			(xy 355.990386 -273.133946) (xy 356.016689 -273.09235) (xy 356.049324 -273.055513) (xy 356.087445 -273.024388)
			(xy 356.130066 -272.999781) (xy 356.176082 -272.982329) (xy 356.224301 -272.972485) (xy 356.273476 -272.970504)
			(xy 356.322331 -272.976436) (xy 356.369602 -272.990128) (xy 356.414064 -273.011226) (xy 356.454567 -273.039182)
			(xy 356.49006 -273.073274) (xy 356.519625 -273.112618) (xy 356.542496 -273.156195) (xy 356.55808 -273.202876)
			(xy 356.565975 -273.251453) (xy 356.56647 -273.27606) (xy 356.895412 -273.27606) (xy 356.899372 -273.227006)
			(xy 356.911149 -273.179222) (xy 356.93044 -273.133946) (xy 356.956743 -273.09235) (xy 356.989378 -273.055513)
			(xy 357.027499 -273.024388) (xy 357.07012 -272.999781) (xy 357.116136 -272.982329) (xy 357.164355 -272.972485)
			(xy 357.21353 -272.970504) (xy 357.262385 -272.976436) (xy 357.309656 -272.990128) (xy 357.354118 -273.011226)
			(xy 357.394621 -273.039182) (xy 357.430114 -273.073274) (xy 357.459679 -273.112618) (xy 357.48255 -273.156195)
			(xy 357.498134 -273.202876) (xy 357.506029 -273.251453) (xy 357.506524 -273.27606) (xy 357.835212 -273.27606)
			(xy 357.839172 -273.227006) (xy 357.850949 -273.179222) (xy 357.87024 -273.133946) (xy 357.896543 -273.09235)
			(xy 357.929178 -273.055513) (xy 357.967299 -273.024388) (xy 358.00992 -272.999781) (xy 358.055936 -272.982329)
			(xy 358.104155 -272.972485) (xy 358.15333 -272.970504) (xy 358.202185 -272.976436) (xy 358.249456 -272.990128)
			(xy 358.293918 -273.011226) (xy 358.334421 -273.039182) (xy 358.369914 -273.073274) (xy 358.399479 -273.112618)
			(xy 358.42235 -273.156195) (xy 358.437934 -273.202876) (xy 358.445829 -273.251453) (xy 358.446324 -273.27606)
			(xy 361.589078 -273.27606) (xy 361.593038 -273.227006) (xy 361.604815 -273.179222) (xy 361.624106 -273.133946)
			(xy 361.650409 -273.09235) (xy 361.683044 -273.055513) (xy 361.721165 -273.024388) (xy 361.763786 -272.999781)
			(xy 361.809802 -272.982329) (xy 361.858021 -272.972485) (xy 361.907196 -272.970504) (xy 361.956051 -272.976436)
			(xy 362.003322 -272.990128) (xy 362.047784 -273.011226) (xy 362.088287 -273.039182) (xy 362.12378 -273.073274)
			(xy 362.153345 -273.112618) (xy 362.176216 -273.156195) (xy 362.1918 -273.202876) (xy 362.199695 -273.251453)
			(xy 362.20019 -273.27606) (xy 362.528878 -273.27606) (xy 362.532838 -273.227006) (xy 362.544615 -273.179222)
			(xy 362.563906 -273.133946) (xy 362.590209 -273.09235) (xy 362.622844 -273.055513) (xy 362.660965 -273.024388)
			(xy 362.703586 -272.999781) (xy 362.749602 -272.982329) (xy 362.797821 -272.972485) (xy 362.846996 -272.970504)
			(xy 362.895851 -272.976436) (xy 362.943122 -272.990128) (xy 362.987584 -273.011226) (xy 363.028087 -273.039182)
			(xy 363.06358 -273.073274) (xy 363.093145 -273.112618) (xy 363.116016 -273.156195) (xy 363.1316 -273.202876)
			(xy 363.139495 -273.251453) (xy 363.13999 -273.27606) (xy 363.468932 -273.27606) (xy 363.472892 -273.227006)
			(xy 363.484669 -273.179222) (xy 363.50396 -273.133946) (xy 363.530263 -273.09235) (xy 363.562898 -273.055513)
			(xy 363.601019 -273.024388) (xy 363.64364 -272.999781) (xy 363.689656 -272.982329) (xy 363.737875 -272.972485)
			(xy 363.78705 -272.970504) (xy 363.835905 -272.976436) (xy 363.883176 -272.990128) (xy 363.927638 -273.011226)
			(xy 363.968141 -273.039182) (xy 364.003634 -273.073274) (xy 364.033199 -273.112618) (xy 364.05607 -273.156195)
			(xy 364.071654 -273.202876) (xy 364.079549 -273.251453) (xy 364.080044 -273.27606) (xy 364.408986 -273.27606)
			(xy 364.412946 -273.227006) (xy 364.424723 -273.179222) (xy 364.444014 -273.133946) (xy 364.470317 -273.09235)
			(xy 364.502952 -273.055513) (xy 364.541073 -273.024388) (xy 364.583694 -272.999781) (xy 364.62971 -272.982329)
			(xy 364.677929 -272.972485) (xy 364.727104 -272.970504) (xy 364.775959 -272.976436) (xy 364.82323 -272.990128)
			(xy 364.867692 -273.011226) (xy 364.908195 -273.039182) (xy 364.943688 -273.073274) (xy 364.973253 -273.112618)
			(xy 364.996124 -273.156195) (xy 365.011708 -273.202876) (xy 365.019603 -273.251453) (xy 365.020098 -273.27606)
			(xy 365.34904 -273.27606) (xy 365.353 -273.227006) (xy 365.364777 -273.179222) (xy 365.384068 -273.133946)
			(xy 365.410371 -273.09235) (xy 365.443006 -273.055513) (xy 365.481127 -273.024388) (xy 365.523748 -272.999781)
			(xy 365.569764 -272.982329) (xy 365.617983 -272.972485) (xy 365.667158 -272.970504) (xy 365.716013 -272.976436)
			(xy 365.763284 -272.990128) (xy 365.807746 -273.011226) (xy 365.848249 -273.039182) (xy 365.883742 -273.073274)
			(xy 365.913307 -273.112618) (xy 365.936178 -273.156195) (xy 365.951762 -273.202876) (xy 365.959657 -273.251453)
			(xy 365.960152 -273.27606) (xy 366.289094 -273.27606) (xy 366.293054 -273.227006) (xy 366.304831 -273.179222)
			(xy 366.324122 -273.133946) (xy 366.350425 -273.09235) (xy 366.38306 -273.055513) (xy 366.421181 -273.024388)
			(xy 366.463802 -272.999781) (xy 366.509818 -272.982329) (xy 366.558037 -272.972485) (xy 366.607212 -272.970504)
			(xy 366.656067 -272.976436) (xy 366.703338 -272.990128) (xy 366.7478 -273.011226) (xy 366.788303 -273.039182)
			(xy 366.823796 -273.073274) (xy 366.853361 -273.112618) (xy 366.876232 -273.156195) (xy 366.891816 -273.202876)
			(xy 366.899711 -273.251453) (xy 366.900206 -273.27606) (xy 367.228894 -273.27606) (xy 367.232854 -273.227006)
			(xy 367.244631 -273.179222) (xy 367.263922 -273.133946) (xy 367.290225 -273.09235) (xy 367.32286 -273.055513)
			(xy 367.360981 -273.024388) (xy 367.403602 -272.999781) (xy 367.449618 -272.982329) (xy 367.497837 -272.972485)
			(xy 367.547012 -272.970504) (xy 367.595867 -272.976436) (xy 367.643138 -272.990128) (xy 367.6876 -273.011226)
			(xy 367.728103 -273.039182) (xy 367.763596 -273.073274) (xy 367.793161 -273.112618) (xy 367.816032 -273.156195)
			(xy 367.831616 -273.202876) (xy 367.839511 -273.251453) (xy 367.840006 -273.27606) (xy 368.168948 -273.27606)
			(xy 368.172908 -273.227006) (xy 368.184685 -273.179222) (xy 368.203976 -273.133946) (xy 368.230279 -273.09235)
			(xy 368.262914 -273.055513) (xy 368.301035 -273.024388) (xy 368.343656 -272.999781) (xy 368.389672 -272.982329)
			(xy 368.437891 -272.972485) (xy 368.487066 -272.970504) (xy 368.535921 -272.976436) (xy 368.583192 -272.990128)
			(xy 368.627654 -273.011226) (xy 368.668157 -273.039182) (xy 368.70365 -273.073274) (xy 368.733215 -273.112618)
			(xy 368.756086 -273.156195) (xy 368.77167 -273.202876) (xy 368.779565 -273.251453) (xy 368.78006 -273.27606)
			(xy 369.109002 -273.27606) (xy 369.112962 -273.227006) (xy 369.124739 -273.179222) (xy 369.14403 -273.133946)
			(xy 369.170333 -273.09235) (xy 369.202968 -273.055513) (xy 369.241089 -273.024388) (xy 369.28371 -272.999781)
			(xy 369.329726 -272.982329) (xy 369.377945 -272.972485) (xy 369.42712 -272.970504) (xy 369.475975 -272.976436)
			(xy 369.523246 -272.990128) (xy 369.567708 -273.011226) (xy 369.608211 -273.039182) (xy 369.643704 -273.073274)
			(xy 369.673269 -273.112618) (xy 369.69614 -273.156195) (xy 369.711724 -273.202876) (xy 369.719619 -273.251453)
			(xy 369.720114 -273.27606) (xy 370.049056 -273.27606) (xy 370.053016 -273.227006) (xy 370.064793 -273.179222)
			(xy 370.084084 -273.133946) (xy 370.110387 -273.09235) (xy 370.143022 -273.055513) (xy 370.181143 -273.024388)
			(xy 370.223764 -272.999781) (xy 370.26978 -272.982329) (xy 370.317999 -272.972485) (xy 370.367174 -272.970504)
			(xy 370.416029 -272.976436) (xy 370.4633 -272.990128) (xy 370.507762 -273.011226) (xy 370.548265 -273.039182)
			(xy 370.583758 -273.073274) (xy 370.613323 -273.112618) (xy 370.636194 -273.156195) (xy 370.651778 -273.202876)
			(xy 370.659673 -273.251453) (xy 370.660168 -273.27606) (xy 370.98911 -273.27606) (xy 370.99307 -273.227006)
			(xy 371.004847 -273.179222) (xy 371.024138 -273.133946) (xy 371.050441 -273.09235) (xy 371.083076 -273.055513)
			(xy 371.121197 -273.024388) (xy 371.163818 -272.999781) (xy 371.209834 -272.982329) (xy 371.258053 -272.972485)
			(xy 371.307228 -272.970504) (xy 371.356083 -272.976436) (xy 371.403354 -272.990128) (xy 371.447816 -273.011226)
			(xy 371.488319 -273.039182) (xy 371.523812 -273.073274) (xy 371.553377 -273.112618) (xy 371.576248 -273.156195)
			(xy 371.591832 -273.202876) (xy 371.599727 -273.251453) (xy 371.600222 -273.27606) (xy 371.92891 -273.27606)
			(xy 371.93287 -273.227006) (xy 371.944647 -273.179222) (xy 371.963938 -273.133946) (xy 371.990241 -273.09235)
			(xy 372.022876 -273.055513) (xy 372.060997 -273.024388) (xy 372.103618 -272.999781) (xy 372.149634 -272.982329)
			(xy 372.197853 -272.972485) (xy 372.247028 -272.970504) (xy 372.295883 -272.976436) (xy 372.343154 -272.990128)
			(xy 372.387616 -273.011226) (xy 372.428119 -273.039182) (xy 372.463612 -273.073274) (xy 372.493177 -273.112618)
			(xy 372.516048 -273.156195) (xy 372.531632 -273.202876) (xy 372.539527 -273.251453) (xy 372.540022 -273.27606)
			(xy 372.868964 -273.27606) (xy 372.872924 -273.227006) (xy 372.884701 -273.179222) (xy 372.903992 -273.133946)
			(xy 372.930295 -273.09235) (xy 372.96293 -273.055513) (xy 373.001051 -273.024388) (xy 373.043672 -272.999781)
			(xy 373.089688 -272.982329) (xy 373.137907 -272.972485) (xy 373.187082 -272.970504) (xy 373.235937 -272.976436)
			(xy 373.283208 -272.990128) (xy 373.32767 -273.011226) (xy 373.368173 -273.039182) (xy 373.403666 -273.073274)
			(xy 373.433231 -273.112618) (xy 373.456102 -273.156195) (xy 373.471686 -273.202876) (xy 373.479581 -273.251453)
			(xy 373.480076 -273.27606) (xy 373.809018 -273.27606) (xy 373.812978 -273.227006) (xy 373.824755 -273.179222)
			(xy 373.844046 -273.133946) (xy 373.870349 -273.09235) (xy 373.902984 -273.055513) (xy 373.941105 -273.024388)
			(xy 373.983726 -272.999781) (xy 374.029742 -272.982329) (xy 374.077961 -272.972485) (xy 374.127136 -272.970504)
			(xy 374.175991 -272.976436) (xy 374.223262 -272.990128) (xy 374.267724 -273.011226) (xy 374.308227 -273.039182)
			(xy 374.34372 -273.073274) (xy 374.373285 -273.112618) (xy 374.396156 -273.156195) (xy 374.41174 -273.202876)
			(xy 374.419635 -273.251453) (xy 374.42013 -273.27606) (xy 374.749072 -273.27606) (xy 374.753032 -273.227006)
			(xy 374.764809 -273.179222) (xy 374.7841 -273.133946) (xy 374.810403 -273.09235) (xy 374.843038 -273.055513)
			(xy 374.881159 -273.024388) (xy 374.92378 -272.999781) (xy 374.969796 -272.982329) (xy 375.018015 -272.972485)
			(xy 375.06719 -272.970504) (xy 375.116045 -272.976436) (xy 375.163316 -272.990128) (xy 375.207778 -273.011226)
			(xy 375.248281 -273.039182) (xy 375.283774 -273.073274) (xy 375.313339 -273.112618) (xy 375.33621 -273.156195)
			(xy 375.351794 -273.202876) (xy 375.359689 -273.251453) (xy 375.360184 -273.27606) (xy 375.678695 -273.27606)
			(xy 375.68279 -273.225332) (xy 375.694969 -273.175918) (xy 375.714917 -273.129098) (xy 375.742118 -273.086084)
			(xy 375.775866 -273.04799) (xy 375.815288 -273.015803) (xy 375.859362 -272.990357) (xy 375.906948 -272.97231)
			(xy 375.956812 -272.96213) (xy 376.007664 -272.960081) (xy 376.058185 -272.966215) (xy 376.107069 -272.980375)
			(xy 376.153048 -273.002192) (xy 376.194932 -273.031102) (xy 376.231636 -273.066357) (xy 376.262209 -273.107043)
			(xy 376.28586 -273.152106) (xy 376.301976 -273.20038) (xy 376.31014 -273.250614) (xy 376.310652 -273.27606)
			(xy 376.628926 -273.27606) (xy 376.632886 -273.227006) (xy 376.644663 -273.179222) (xy 376.663954 -273.133946)
			(xy 376.690257 -273.09235) (xy 376.722892 -273.055513) (xy 376.761013 -273.024388) (xy 376.803634 -272.999781)
			(xy 376.84965 -272.982329) (xy 376.897869 -272.972485) (xy 376.947044 -272.970504) (xy 376.995899 -272.976436)
			(xy 377.04317 -272.990128) (xy 377.087632 -273.011226) (xy 377.128135 -273.039182) (xy 377.163628 -273.073274)
			(xy 377.193193 -273.112618) (xy 377.216064 -273.156195) (xy 377.231648 -273.202876) (xy 377.239543 -273.251453)
			(xy 377.240038 -273.27606) (xy 377.558549 -273.27606) (xy 377.562644 -273.225332) (xy 377.574823 -273.175918)
			(xy 377.594771 -273.129098) (xy 377.621972 -273.086084) (xy 377.65572 -273.04799) (xy 377.695142 -273.015803)
			(xy 377.739216 -272.990357) (xy 377.786802 -272.97231) (xy 377.836666 -272.96213) (xy 377.887518 -272.960081)
			(xy 377.938039 -272.966215) (xy 377.986923 -272.980375) (xy 378.032902 -273.002192) (xy 378.074786 -273.031102)
			(xy 378.11149 -273.066357) (xy 378.142063 -273.107043) (xy 378.165714 -273.152106) (xy 378.18183 -273.20038)
			(xy 378.189994 -273.250614) (xy 378.190506 -273.27606) (xy 378.189994 -273.301506) (xy 378.18183 -273.35174)
			(xy 378.165714 -273.400014) (xy 378.142063 -273.445077) (xy 378.11149 -273.485763) (xy 378.074786 -273.521018)
			(xy 378.032902 -273.549928) (xy 377.986923 -273.571745) (xy 377.938039 -273.585905) (xy 377.887518 -273.592039)
			(xy 377.836666 -273.58999) (xy 377.786802 -273.57981) (xy 377.739216 -273.561763) (xy 377.695142 -273.536317)
			(xy 377.65572 -273.50413) (xy 377.621972 -273.466036) (xy 377.594771 -273.423022) (xy 377.574823 -273.376202)
			(xy 377.562644 -273.326788) (xy 377.558549 -273.27606) (xy 377.240038 -273.27606) (xy 377.239543 -273.300667)
			(xy 377.231648 -273.349244) (xy 377.216064 -273.395925) (xy 377.193193 -273.439502) (xy 377.163628 -273.478846)
			(xy 377.128135 -273.512938) (xy 377.087632 -273.540894) (xy 377.04317 -273.561992) (xy 376.995899 -273.575684)
			(xy 376.947044 -273.581616) (xy 376.897869 -273.579635) (xy 376.84965 -273.569791) (xy 376.803634 -273.552339)
			(xy 376.761013 -273.527732) (xy 376.722892 -273.496607) (xy 376.690257 -273.45977) (xy 376.663954 -273.418174)
			(xy 376.644663 -273.372898) (xy 376.632886 -273.325114) (xy 376.628926 -273.27606) (xy 376.310652 -273.27606)
			(xy 376.31014 -273.301506) (xy 376.301976 -273.35174) (xy 376.28586 -273.400014) (xy 376.262209 -273.445077)
			(xy 376.231636 -273.485763) (xy 376.194932 -273.521018) (xy 376.153048 -273.549928) (xy 376.107069 -273.571745)
			(xy 376.058185 -273.585905) (xy 376.007664 -273.592039) (xy 375.956812 -273.58999) (xy 375.906948 -273.57981)
			(xy 375.859362 -273.561763) (xy 375.815288 -273.536317) (xy 375.775866 -273.50413) (xy 375.742118 -273.466036)
			(xy 375.714917 -273.423022) (xy 375.694969 -273.376202) (xy 375.68279 -273.326788) (xy 375.678695 -273.27606)
			(xy 375.360184 -273.27606) (xy 375.359689 -273.300667) (xy 375.351794 -273.349244) (xy 375.33621 -273.395925)
			(xy 375.313339 -273.439502) (xy 375.283774 -273.478846) (xy 375.248281 -273.512938) (xy 375.207778 -273.540894)
			(xy 375.163316 -273.561992) (xy 375.116045 -273.575684) (xy 375.06719 -273.581616) (xy 375.018015 -273.579635)
			(xy 374.969796 -273.569791) (xy 374.92378 -273.552339) (xy 374.881159 -273.527732) (xy 374.843038 -273.496607)
			(xy 374.810403 -273.45977) (xy 374.7841 -273.418174) (xy 374.764809 -273.372898) (xy 374.753032 -273.325114)
			(xy 374.749072 -273.27606) (xy 374.42013 -273.27606) (xy 374.419635 -273.300667) (xy 374.41174 -273.349244)
			(xy 374.396156 -273.395925) (xy 374.373285 -273.439502) (xy 374.34372 -273.478846) (xy 374.308227 -273.512938)
			(xy 374.267724 -273.540894) (xy 374.223262 -273.561992) (xy 374.175991 -273.575684) (xy 374.127136 -273.581616)
			(xy 374.077961 -273.579635) (xy 374.029742 -273.569791) (xy 373.983726 -273.552339) (xy 373.941105 -273.527732)
			(xy 373.902984 -273.496607) (xy 373.870349 -273.45977) (xy 373.844046 -273.418174) (xy 373.824755 -273.372898)
			(xy 373.812978 -273.325114) (xy 373.809018 -273.27606) (xy 373.480076 -273.27606) (xy 373.479581 -273.300667)
			(xy 373.471686 -273.349244) (xy 373.456102 -273.395925) (xy 373.433231 -273.439502) (xy 373.403666 -273.478846)
			(xy 373.368173 -273.512938) (xy 373.32767 -273.540894) (xy 373.283208 -273.561992) (xy 373.235937 -273.575684)
			(xy 373.187082 -273.581616) (xy 373.137907 -273.579635) (xy 373.089688 -273.569791) (xy 373.043672 -273.552339)
			(xy 373.001051 -273.527732) (xy 372.96293 -273.496607) (xy 372.930295 -273.45977) (xy 372.903992 -273.418174)
			(xy 372.884701 -273.372898) (xy 372.872924 -273.325114) (xy 372.868964 -273.27606) (xy 372.540022 -273.27606)
			(xy 372.539527 -273.300667) (xy 372.531632 -273.349244) (xy 372.516048 -273.395925) (xy 372.493177 -273.439502)
			(xy 372.463612 -273.478846) (xy 372.428119 -273.512938) (xy 372.387616 -273.540894) (xy 372.343154 -273.561992)
			(xy 372.295883 -273.575684) (xy 372.247028 -273.581616) (xy 372.197853 -273.579635) (xy 372.149634 -273.569791)
			(xy 372.103618 -273.552339) (xy 372.060997 -273.527732) (xy 372.022876 -273.496607) (xy 371.990241 -273.45977)
			(xy 371.963938 -273.418174) (xy 371.944647 -273.372898) (xy 371.93287 -273.325114) (xy 371.92891 -273.27606)
			(xy 371.600222 -273.27606) (xy 371.599727 -273.300667) (xy 371.591832 -273.349244) (xy 371.576248 -273.395925)
			(xy 371.553377 -273.439502) (xy 371.523812 -273.478846) (xy 371.488319 -273.512938) (xy 371.447816 -273.540894)
			(xy 371.403354 -273.561992) (xy 371.356083 -273.575684) (xy 371.307228 -273.581616) (xy 371.258053 -273.579635)
			(xy 371.209834 -273.569791) (xy 371.163818 -273.552339) (xy 371.121197 -273.527732) (xy 371.083076 -273.496607)
			(xy 371.050441 -273.45977) (xy 371.024138 -273.418174) (xy 371.004847 -273.372898) (xy 370.99307 -273.325114)
			(xy 370.98911 -273.27606) (xy 370.660168 -273.27606) (xy 370.659673 -273.300667) (xy 370.651778 -273.349244)
			(xy 370.636194 -273.395925) (xy 370.613323 -273.439502) (xy 370.583758 -273.478846) (xy 370.548265 -273.512938)
			(xy 370.507762 -273.540894) (xy 370.4633 -273.561992) (xy 370.416029 -273.575684) (xy 370.367174 -273.581616)
			(xy 370.317999 -273.579635) (xy 370.26978 -273.569791) (xy 370.223764 -273.552339) (xy 370.181143 -273.527732)
			(xy 370.143022 -273.496607) (xy 370.110387 -273.45977) (xy 370.084084 -273.418174) (xy 370.064793 -273.372898)
			(xy 370.053016 -273.325114) (xy 370.049056 -273.27606) (xy 369.720114 -273.27606) (xy 369.719619 -273.300667)
			(xy 369.711724 -273.349244) (xy 369.69614 -273.395925) (xy 369.673269 -273.439502) (xy 369.643704 -273.478846)
			(xy 369.608211 -273.512938) (xy 369.567708 -273.540894) (xy 369.523246 -273.561992) (xy 369.475975 -273.575684)
			(xy 369.42712 -273.581616) (xy 369.377945 -273.579635) (xy 369.329726 -273.569791) (xy 369.28371 -273.552339)
			(xy 369.241089 -273.527732) (xy 369.202968 -273.496607) (xy 369.170333 -273.45977) (xy 369.14403 -273.418174)
			(xy 369.124739 -273.372898) (xy 369.112962 -273.325114) (xy 369.109002 -273.27606) (xy 368.78006 -273.27606)
			(xy 368.779565 -273.300667) (xy 368.77167 -273.349244) (xy 368.756086 -273.395925) (xy 368.733215 -273.439502)
			(xy 368.70365 -273.478846) (xy 368.668157 -273.512938) (xy 368.627654 -273.540894) (xy 368.583192 -273.561992)
			(xy 368.535921 -273.575684) (xy 368.487066 -273.581616) (xy 368.437891 -273.579635) (xy 368.389672 -273.569791)
			(xy 368.343656 -273.552339) (xy 368.301035 -273.527732) (xy 368.262914 -273.496607) (xy 368.230279 -273.45977)
			(xy 368.203976 -273.418174) (xy 368.184685 -273.372898) (xy 368.172908 -273.325114) (xy 368.168948 -273.27606)
			(xy 367.840006 -273.27606) (xy 367.839511 -273.300667) (xy 367.831616 -273.349244) (xy 367.816032 -273.395925)
			(xy 367.793161 -273.439502) (xy 367.763596 -273.478846) (xy 367.728103 -273.512938) (xy 367.6876 -273.540894)
			(xy 367.643138 -273.561992) (xy 367.595867 -273.575684) (xy 367.547012 -273.581616) (xy 367.497837 -273.579635)
			(xy 367.449618 -273.569791) (xy 367.403602 -273.552339) (xy 367.360981 -273.527732) (xy 367.32286 -273.496607)
			(xy 367.290225 -273.45977) (xy 367.263922 -273.418174) (xy 367.244631 -273.372898) (xy 367.232854 -273.325114)
			(xy 367.228894 -273.27606) (xy 366.900206 -273.27606) (xy 366.899711 -273.300667) (xy 366.891816 -273.349244)
			(xy 366.876232 -273.395925) (xy 366.853361 -273.439502) (xy 366.823796 -273.478846) (xy 366.788303 -273.512938)
			(xy 366.7478 -273.540894) (xy 366.703338 -273.561992) (xy 366.656067 -273.575684) (xy 366.607212 -273.581616)
			(xy 366.558037 -273.579635) (xy 366.509818 -273.569791) (xy 366.463802 -273.552339) (xy 366.421181 -273.527732)
			(xy 366.38306 -273.496607) (xy 366.350425 -273.45977) (xy 366.324122 -273.418174) (xy 366.304831 -273.372898)
			(xy 366.293054 -273.325114) (xy 366.289094 -273.27606) (xy 365.960152 -273.27606) (xy 365.959657 -273.300667)
			(xy 365.951762 -273.349244) (xy 365.936178 -273.395925) (xy 365.913307 -273.439502) (xy 365.883742 -273.478846)
			(xy 365.848249 -273.512938) (xy 365.807746 -273.540894) (xy 365.763284 -273.561992) (xy 365.716013 -273.575684)
			(xy 365.667158 -273.581616) (xy 365.617983 -273.579635) (xy 365.569764 -273.569791) (xy 365.523748 -273.552339)
			(xy 365.481127 -273.527732) (xy 365.443006 -273.496607) (xy 365.410371 -273.45977) (xy 365.384068 -273.418174)
			(xy 365.364777 -273.372898) (xy 365.353 -273.325114) (xy 365.34904 -273.27606) (xy 365.020098 -273.27606)
			(xy 365.019603 -273.300667) (xy 365.011708 -273.349244) (xy 364.996124 -273.395925) (xy 364.973253 -273.439502)
			(xy 364.943688 -273.478846) (xy 364.908195 -273.512938) (xy 364.867692 -273.540894) (xy 364.82323 -273.561992)
			(xy 364.775959 -273.575684) (xy 364.727104 -273.581616) (xy 364.677929 -273.579635) (xy 364.62971 -273.569791)
			(xy 364.583694 -273.552339) (xy 364.541073 -273.527732) (xy 364.502952 -273.496607) (xy 364.470317 -273.45977)
			(xy 364.444014 -273.418174) (xy 364.424723 -273.372898) (xy 364.412946 -273.325114) (xy 364.408986 -273.27606)
			(xy 364.080044 -273.27606) (xy 364.079549 -273.300667) (xy 364.071654 -273.349244) (xy 364.05607 -273.395925)
			(xy 364.033199 -273.439502) (xy 364.003634 -273.478846) (xy 363.968141 -273.512938) (xy 363.927638 -273.540894)
			(xy 363.883176 -273.561992) (xy 363.835905 -273.575684) (xy 363.78705 -273.581616) (xy 363.737875 -273.579635)
			(xy 363.689656 -273.569791) (xy 363.64364 -273.552339) (xy 363.601019 -273.527732) (xy 363.562898 -273.496607)
			(xy 363.530263 -273.45977) (xy 363.50396 -273.418174) (xy 363.484669 -273.372898) (xy 363.472892 -273.325114)
			(xy 363.468932 -273.27606) (xy 363.13999 -273.27606) (xy 363.139495 -273.300667) (xy 363.1316 -273.349244)
			(xy 363.116016 -273.395925) (xy 363.093145 -273.439502) (xy 363.06358 -273.478846) (xy 363.028087 -273.512938)
			(xy 362.987584 -273.540894) (xy 362.943122 -273.561992) (xy 362.895851 -273.575684) (xy 362.846996 -273.581616)
			(xy 362.797821 -273.579635) (xy 362.749602 -273.569791) (xy 362.703586 -273.552339) (xy 362.660965 -273.527732)
			(xy 362.622844 -273.496607) (xy 362.590209 -273.45977) (xy 362.563906 -273.418174) (xy 362.544615 -273.372898)
			(xy 362.532838 -273.325114) (xy 362.528878 -273.27606) (xy 362.20019 -273.27606) (xy 362.199695 -273.300667)
			(xy 362.1918 -273.349244) (xy 362.176216 -273.395925) (xy 362.153345 -273.439502) (xy 362.12378 -273.478846)
			(xy 362.088287 -273.512938) (xy 362.047784 -273.540894) (xy 362.003322 -273.561992) (xy 361.956051 -273.575684)
			(xy 361.907196 -273.581616) (xy 361.858021 -273.579635) (xy 361.809802 -273.569791) (xy 361.763786 -273.552339)
			(xy 361.721165 -273.527732) (xy 361.683044 -273.496607) (xy 361.650409 -273.45977) (xy 361.624106 -273.418174)
			(xy 361.604815 -273.372898) (xy 361.593038 -273.325114) (xy 361.589078 -273.27606) (xy 358.446324 -273.27606)
			(xy 358.445829 -273.300667) (xy 358.437934 -273.349244) (xy 358.42235 -273.395925) (xy 358.399479 -273.439502)
			(xy 358.369914 -273.478846) (xy 358.334421 -273.512938) (xy 358.293918 -273.540894) (xy 358.249456 -273.561992)
			(xy 358.202185 -273.575684) (xy 358.15333 -273.581616) (xy 358.104155 -273.579635) (xy 358.055936 -273.569791)
			(xy 358.00992 -273.552339) (xy 357.967299 -273.527732) (xy 357.929178 -273.496607) (xy 357.896543 -273.45977)
			(xy 357.87024 -273.418174) (xy 357.850949 -273.372898) (xy 357.839172 -273.325114) (xy 357.835212 -273.27606)
			(xy 357.506524 -273.27606) (xy 357.506029 -273.300667) (xy 357.498134 -273.349244) (xy 357.48255 -273.395925)
			(xy 357.459679 -273.439502) (xy 357.430114 -273.478846) (xy 357.394621 -273.512938) (xy 357.354118 -273.540894)
			(xy 357.309656 -273.561992) (xy 357.262385 -273.575684) (xy 357.21353 -273.581616) (xy 357.164355 -273.579635)
			(xy 357.116136 -273.569791) (xy 357.07012 -273.552339) (xy 357.027499 -273.527732) (xy 356.989378 -273.496607)
			(xy 356.956743 -273.45977) (xy 356.93044 -273.418174) (xy 356.911149 -273.372898) (xy 356.899372 -273.325114)
			(xy 356.895412 -273.27606) (xy 356.56647 -273.27606) (xy 356.565975 -273.300667) (xy 356.55808 -273.349244)
			(xy 356.542496 -273.395925) (xy 356.519625 -273.439502) (xy 356.49006 -273.478846) (xy 356.454567 -273.512938)
			(xy 356.414064 -273.540894) (xy 356.369602 -273.561992) (xy 356.322331 -273.575684) (xy 356.273476 -273.581616)
			(xy 356.224301 -273.579635) (xy 356.176082 -273.569791) (xy 356.130066 -273.552339) (xy 356.087445 -273.527732)
			(xy 356.049324 -273.496607) (xy 356.016689 -273.45977) (xy 355.990386 -273.418174) (xy 355.971095 -273.372898)
			(xy 355.959318 -273.325114) (xy 355.955358 -273.27606) (xy 355.626416 -273.27606) (xy 355.625921 -273.300667)
			(xy 355.618026 -273.349244) (xy 355.602442 -273.395925) (xy 355.579571 -273.439502) (xy 355.550006 -273.478846)
			(xy 355.514513 -273.512938) (xy 355.47401 -273.540894) (xy 355.429548 -273.561992) (xy 355.382277 -273.575684)
			(xy 355.333422 -273.581616) (xy 355.284247 -273.579635) (xy 355.236028 -273.569791) (xy 355.190012 -273.552339)
			(xy 355.147391 -273.527732) (xy 355.10927 -273.496607) (xy 355.076635 -273.45977) (xy 355.050332 -273.418174)
			(xy 355.031041 -273.372898) (xy 355.019264 -273.325114) (xy 355.015304 -273.27606) (xy 354.686362 -273.27606)
			(xy 354.685867 -273.300667) (xy 354.677972 -273.349244) (xy 354.662388 -273.395925) (xy 354.639517 -273.439502)
			(xy 354.609952 -273.478846) (xy 354.574459 -273.512938) (xy 354.533956 -273.540894) (xy 354.489494 -273.561992)
			(xy 354.442223 -273.575684) (xy 354.393368 -273.581616) (xy 354.344193 -273.579635) (xy 354.295974 -273.569791)
			(xy 354.249958 -273.552339) (xy 354.207337 -273.527732) (xy 354.169216 -273.496607) (xy 354.136581 -273.45977)
			(xy 354.110278 -273.418174) (xy 354.090987 -273.372898) (xy 354.07921 -273.325114) (xy 354.07525 -273.27606)
			(xy 353.746308 -273.27606) (xy 353.745813 -273.300667) (xy 353.737918 -273.349244) (xy 353.722334 -273.395925)
			(xy 353.699463 -273.439502) (xy 353.669898 -273.478846) (xy 353.634405 -273.512938) (xy 353.593902 -273.540894)
			(xy 353.54944 -273.561992) (xy 353.502169 -273.575684) (xy 353.453314 -273.581616) (xy 353.404139 -273.579635)
			(xy 353.35592 -273.569791) (xy 353.309904 -273.552339) (xy 353.267283 -273.527732) (xy 353.229162 -273.496607)
			(xy 353.196527 -273.45977) (xy 353.170224 -273.418174) (xy 353.150933 -273.372898) (xy 353.139156 -273.325114)
			(xy 353.135196 -273.27606) (xy 352.806508 -273.27606) (xy 352.806013 -273.300667) (xy 352.798118 -273.349244)
			(xy 352.782534 -273.395925) (xy 352.759663 -273.439502) (xy 352.730098 -273.478846) (xy 352.694605 -273.512938)
			(xy 352.654102 -273.540894) (xy 352.60964 -273.561992) (xy 352.562369 -273.575684) (xy 352.513514 -273.581616)
			(xy 352.464339 -273.579635) (xy 352.41612 -273.569791) (xy 352.370104 -273.552339) (xy 352.327483 -273.527732)
			(xy 352.289362 -273.496607) (xy 352.256727 -273.45977) (xy 352.230424 -273.418174) (xy 352.211133 -273.372898)
			(xy 352.199356 -273.325114) (xy 352.195396 -273.27606) (xy 351.866454 -273.27606) (xy 351.865959 -273.300667)
			(xy 351.858064 -273.349244) (xy 351.84248 -273.395925) (xy 351.819609 -273.439502) (xy 351.790044 -273.478846)
			(xy 351.754551 -273.512938) (xy 351.714048 -273.540894) (xy 351.669586 -273.561992) (xy 351.622315 -273.575684)
			(xy 351.57346 -273.581616) (xy 351.524285 -273.579635) (xy 351.476066 -273.569791) (xy 351.43005 -273.552339)
			(xy 351.387429 -273.527732) (xy 351.349308 -273.496607) (xy 351.316673 -273.45977) (xy 351.29037 -273.418174)
			(xy 351.271079 -273.372898) (xy 351.259302 -273.325114) (xy 351.255342 -273.27606) (xy 350.9264 -273.27606)
			(xy 350.925905 -273.300667) (xy 350.91801 -273.349244) (xy 350.902426 -273.395925) (xy 350.879555 -273.439502)
			(xy 350.84999 -273.478846) (xy 350.814497 -273.512938) (xy 350.773994 -273.540894) (xy 350.729532 -273.561992)
			(xy 350.682261 -273.575684) (xy 350.633406 -273.581616) (xy 350.584231 -273.579635) (xy 350.536012 -273.569791)
			(xy 350.489996 -273.552339) (xy 350.447375 -273.527732) (xy 350.409254 -273.496607) (xy 350.376619 -273.45977)
			(xy 350.350316 -273.418174) (xy 350.331025 -273.372898) (xy 350.319248 -273.325114) (xy 350.315288 -273.27606)
			(xy 349.986346 -273.27606) (xy 349.985851 -273.300667) (xy 349.977956 -273.349244) (xy 349.962372 -273.395925)
			(xy 349.939501 -273.439502) (xy 349.909936 -273.478846) (xy 349.874443 -273.512938) (xy 349.83394 -273.540894)
			(xy 349.789478 -273.561992) (xy 349.742207 -273.575684) (xy 349.693352 -273.581616) (xy 349.644177 -273.579635)
			(xy 349.595958 -273.569791) (xy 349.549942 -273.552339) (xy 349.507321 -273.527732) (xy 349.4692 -273.496607)
			(xy 349.436565 -273.45977) (xy 349.410262 -273.418174) (xy 349.390971 -273.372898) (xy 349.379194 -273.325114)
			(xy 349.375234 -273.27606) (xy 349.046546 -273.27606) (xy 349.046051 -273.300667) (xy 349.038156 -273.349244)
			(xy 349.022572 -273.395925) (xy 348.999701 -273.439502) (xy 348.970136 -273.478846) (xy 348.934643 -273.512938)
			(xy 348.89414 -273.540894) (xy 348.849678 -273.561992) (xy 348.802407 -273.575684) (xy 348.753552 -273.581616)
			(xy 348.704377 -273.579635) (xy 348.656158 -273.569791) (xy 348.610142 -273.552339) (xy 348.567521 -273.527732)
			(xy 348.5294 -273.496607) (xy 348.496765 -273.45977) (xy 348.470462 -273.418174) (xy 348.451171 -273.372898)
			(xy 348.439394 -273.325114) (xy 348.435434 -273.27606) (xy 348.106492 -273.27606) (xy 348.105997 -273.300667)
			(xy 348.098102 -273.349244) (xy 348.082518 -273.395925) (xy 348.059647 -273.439502) (xy 348.030082 -273.478846)
			(xy 347.994589 -273.512938) (xy 347.954086 -273.540894) (xy 347.909624 -273.561992) (xy 347.862353 -273.575684)
			(xy 347.813498 -273.581616) (xy 347.764323 -273.579635) (xy 347.716104 -273.569791) (xy 347.670088 -273.552339)
			(xy 347.627467 -273.527732) (xy 347.589346 -273.496607) (xy 347.556711 -273.45977) (xy 347.530408 -273.418174)
			(xy 347.511117 -273.372898) (xy 347.49934 -273.325114) (xy 347.49538 -273.27606) (xy 347.166438 -273.27606)
			(xy 347.165943 -273.300667) (xy 347.158048 -273.349244) (xy 347.142464 -273.395925) (xy 347.119593 -273.439502)
			(xy 347.090028 -273.478846) (xy 347.054535 -273.512938) (xy 347.014032 -273.540894) (xy 346.96957 -273.561992)
			(xy 346.922299 -273.575684) (xy 346.873444 -273.581616) (xy 346.824269 -273.579635) (xy 346.77605 -273.569791)
			(xy 346.730034 -273.552339) (xy 346.687413 -273.527732) (xy 346.649292 -273.496607) (xy 346.616657 -273.45977)
			(xy 346.590354 -273.418174) (xy 346.571063 -273.372898) (xy 346.559286 -273.325114) (xy 346.555326 -273.27606)
			(xy 346.226384 -273.27606) (xy 346.225889 -273.300667) (xy 346.217994 -273.349244) (xy 346.20241 -273.395925)
			(xy 346.179539 -273.439502) (xy 346.149974 -273.478846) (xy 346.114481 -273.512938) (xy 346.073978 -273.540894)
			(xy 346.029516 -273.561992) (xy 345.982245 -273.575684) (xy 345.93339 -273.581616) (xy 345.884215 -273.579635)
			(xy 345.835996 -273.569791) (xy 345.78998 -273.552339) (xy 345.747359 -273.527732) (xy 345.709238 -273.496607)
			(xy 345.676603 -273.45977) (xy 345.6503 -273.418174) (xy 345.631009 -273.372898) (xy 345.619232 -273.325114)
			(xy 345.615272 -273.27606) (xy 345.28633 -273.27606) (xy 345.285835 -273.300667) (xy 345.27794 -273.349244)
			(xy 345.262356 -273.395925) (xy 345.239485 -273.439502) (xy 345.20992 -273.478846) (xy 345.174427 -273.512938)
			(xy 345.133924 -273.540894) (xy 345.089462 -273.561992) (xy 345.042191 -273.575684) (xy 344.993336 -273.581616)
			(xy 344.944161 -273.579635) (xy 344.895942 -273.569791) (xy 344.849926 -273.552339) (xy 344.807305 -273.527732)
			(xy 344.769184 -273.496607) (xy 344.736549 -273.45977) (xy 344.710246 -273.418174) (xy 344.690955 -273.372898)
			(xy 344.679178 -273.325114) (xy 344.675218 -273.27606) (xy 344.356944 -273.27606) (xy 344.356432 -273.301506)
			(xy 344.348268 -273.35174) (xy 344.332152 -273.400014) (xy 344.308501 -273.445077) (xy 344.277928 -273.485763)
			(xy 344.241224 -273.521018) (xy 344.19934 -273.549928) (xy 344.153361 -273.571745) (xy 344.104477 -273.585905)
			(xy 344.053956 -273.592039) (xy 344.003104 -273.58999) (xy 343.95324 -273.57981) (xy 343.905654 -273.561763)
			(xy 343.86158 -273.536317) (xy 343.822158 -273.50413) (xy 343.78841 -273.466036) (xy 343.761209 -273.423022)
			(xy 343.741261 -273.376202) (xy 343.729082 -273.326788) (xy 343.724987 -273.27606) (xy 343.406476 -273.27606)
			(xy 343.405981 -273.300667) (xy 343.398086 -273.349244) (xy 343.382502 -273.395925) (xy 343.359631 -273.439502)
			(xy 343.330066 -273.478846) (xy 343.294573 -273.512938) (xy 343.25407 -273.540894) (xy 343.209608 -273.561992)
			(xy 343.162337 -273.575684) (xy 343.113482 -273.581616) (xy 343.064307 -273.579635) (xy 343.016088 -273.569791)
			(xy 342.970072 -273.552339) (xy 342.927451 -273.527732) (xy 342.88933 -273.496607) (xy 342.856695 -273.45977)
			(xy 342.830392 -273.418174) (xy 342.811101 -273.372898) (xy 342.799324 -273.325114) (xy 342.795364 -273.27606)
			(xy 342.476836 -273.27606) (xy 342.476324 -273.301506) (xy 342.46816 -273.35174) (xy 342.452044 -273.400014)
			(xy 342.428393 -273.445077) (xy 342.39782 -273.485763) (xy 342.361116 -273.521018) (xy 342.319232 -273.549928)
			(xy 342.273253 -273.571745) (xy 342.224369 -273.585905) (xy 342.173848 -273.592039) (xy 342.122996 -273.58999)
			(xy 342.073132 -273.57981) (xy 342.025546 -273.561763) (xy 341.981472 -273.536317) (xy 341.94205 -273.50413)
			(xy 341.908302 -273.466036) (xy 341.881101 -273.423022) (xy 341.861153 -273.376202) (xy 341.848974 -273.326788)
			(xy 341.844879 -273.27606) (xy 341.525992 -273.27606) (xy 341.525993 -273.300164) (xy 341.51844 -273.347708)
			(xy 341.50352 -273.393478) (xy 341.481604 -273.436339) (xy 341.453233 -273.475231) (xy 341.419111 -273.509189)
			(xy 341.380083 -273.537372) (xy 341.337116 -273.559082) (xy 341.291275 -273.573781) (xy 341.267542 -273.577812)
			(xy 341.258652 -273.579082) (xy 341.24265 -273.587972) (xy 341.236808 -273.59483) (xy 341.231227 -273.601918)
			(xy 341.224994 -273.618835) (xy 341.224616 -273.62785) (xy 341.224616 -273.787108) (xy 341.224844 -273.793626)
			(xy 341.228175 -273.806233) (xy 341.23122 -273.812) (xy 341.241159 -273.829767) (xy 341.258704 -273.866507)
			(xy 341.266272 -273.885406) (xy 341.266272 -273.88566) (xy 341.268905 -273.891845) (xy 341.276886 -273.902656)
			(xy 341.28202 -273.906996) (xy 341.293196 -273.915632) (xy 341.305642 -273.917156) (xy 341.395812 -273.928586)
			(xy 341.402691 -273.929184) (xy 341.41634 -273.927124) (xy 341.422736 -273.924522) (xy 341.428578 -273.921982)
			(xy 341.438992 -273.9136) (xy 341.44331 -273.907758) (xy 341.457775 -273.888457) (xy 341.491763 -273.854236)
			(xy 341.530701 -273.825775) (xy 341.573625 -273.803779) (xy 341.61947 -273.788796) (xy 341.667099 -273.781195)
			(xy 341.691214 -273.780758) (xy 341.716471 -273.781281) (xy 341.766297 -273.789597) (xy 341.814074 -273.806001)
			(xy 341.8585 -273.830045) (xy 341.898362 -273.861073) (xy 341.932574 -273.898238) (xy 341.960202 -273.940528)
			(xy 341.980493 -273.986789) (xy 341.992894 -274.035758) (xy 341.997062 -274.086066) (xy 342.314779 -274.086066)
			(xy 342.318874 -274.035338) (xy 342.331053 -273.985924) (xy 342.351001 -273.939104) (xy 342.378202 -273.89609)
			(xy 342.41195 -273.857996) (xy 342.451372 -273.825809) (xy 342.495446 -273.800363) (xy 342.543032 -273.782316)
			(xy 342.592896 -273.772136) (xy 342.643748 -273.770087) (xy 342.694269 -273.776221) (xy 342.743153 -273.790381)
			(xy 342.789132 -273.812198) (xy 342.831016 -273.841108) (xy 342.86772 -273.876363) (xy 342.898293 -273.917049)
			(xy 342.921944 -273.962112) (xy 342.93806 -274.010386) (xy 342.946224 -274.06062) (xy 342.946736 -274.086066)
			(xy 343.254833 -274.086066) (xy 343.258928 -274.035338) (xy 343.271107 -273.985924) (xy 343.291055 -273.939104)
			(xy 343.318256 -273.89609) (xy 343.352004 -273.857996) (xy 343.391426 -273.825809) (xy 343.4355 -273.800363)
			(xy 343.483086 -273.782316) (xy 343.53295 -273.772136) (xy 343.583802 -273.770087) (xy 343.634323 -273.776221)
			(xy 343.683207 -273.790381) (xy 343.729186 -273.812198) (xy 343.77107 -273.841108) (xy 343.807774 -273.876363)
			(xy 343.838347 -273.917049) (xy 343.861998 -273.962112) (xy 343.878114 -274.010386) (xy 343.886278 -274.06062)
			(xy 343.88679 -274.086066) (xy 344.205318 -274.086066) (xy 344.209278 -274.037012) (xy 344.221055 -273.989228)
			(xy 344.240346 -273.943952) (xy 344.266649 -273.902356) (xy 344.299284 -273.865519) (xy 344.337405 -273.834394)
			(xy 344.380026 -273.809787) (xy 344.426042 -273.792335) (xy 344.474261 -273.782491) (xy 344.523436 -273.78051)
			(xy 344.572291 -273.786442) (xy 344.619562 -273.800134) (xy 344.664024 -273.821232) (xy 344.704527 -273.849188)
			(xy 344.74002 -273.88328) (xy 344.769585 -273.922624) (xy 344.792456 -273.966201) (xy 344.80804 -274.012882)
			(xy 344.815935 -274.061459) (xy 344.81643 -274.086066) (xy 345.145372 -274.086066) (xy 345.149332 -274.037012)
			(xy 345.161109 -273.989228) (xy 345.1804 -273.943952) (xy 345.206703 -273.902356) (xy 345.239338 -273.865519)
			(xy 345.277459 -273.834394) (xy 345.32008 -273.809787) (xy 345.366096 -273.792335) (xy 345.414315 -273.782491)
			(xy 345.46349 -273.78051) (xy 345.512345 -273.786442) (xy 345.559616 -273.800134) (xy 345.604078 -273.821232)
			(xy 345.644581 -273.849188) (xy 345.680074 -273.88328) (xy 345.709639 -273.922624) (xy 345.73251 -273.966201)
			(xy 345.748094 -274.012882) (xy 345.755989 -274.061459) (xy 345.756484 -274.086066) (xy 346.085426 -274.086066)
			(xy 346.089386 -274.037012) (xy 346.101163 -273.989228) (xy 346.120454 -273.943952) (xy 346.146757 -273.902356)
			(xy 346.179392 -273.865519) (xy 346.217513 -273.834394) (xy 346.260134 -273.809787) (xy 346.30615 -273.792335)
			(xy 346.354369 -273.782491) (xy 346.403544 -273.78051) (xy 346.452399 -273.786442) (xy 346.49967 -273.800134)
			(xy 346.544132 -273.821232) (xy 346.584635 -273.849188) (xy 346.620128 -273.88328) (xy 346.649693 -273.922624)
			(xy 346.672564 -273.966201) (xy 346.688148 -274.012882) (xy 346.696043 -274.061459) (xy 346.696538 -274.086066)
			(xy 347.025226 -274.086066) (xy 347.029186 -274.037012) (xy 347.040963 -273.989228) (xy 347.060254 -273.943952)
			(xy 347.086557 -273.902356) (xy 347.119192 -273.865519) (xy 347.157313 -273.834394) (xy 347.199934 -273.809787)
			(xy 347.24595 -273.792335) (xy 347.294169 -273.782491) (xy 347.343344 -273.78051) (xy 347.392199 -273.786442)
			(xy 347.43947 -273.800134) (xy 347.483932 -273.821232) (xy 347.524435 -273.849188) (xy 347.559928 -273.88328)
			(xy 347.589493 -273.922624) (xy 347.612364 -273.966201) (xy 347.627948 -274.012882) (xy 347.635843 -274.061459)
			(xy 347.636338 -274.086066) (xy 347.96528 -274.086066) (xy 347.96924 -274.037012) (xy 347.981017 -273.989228)
			(xy 348.000308 -273.943952) (xy 348.026611 -273.902356) (xy 348.059246 -273.865519) (xy 348.097367 -273.834394)
			(xy 348.139988 -273.809787) (xy 348.186004 -273.792335) (xy 348.234223 -273.782491) (xy 348.283398 -273.78051)
			(xy 348.332253 -273.786442) (xy 348.379524 -273.800134) (xy 348.423986 -273.821232) (xy 348.464489 -273.849188)
			(xy 348.499982 -273.88328) (xy 348.529547 -273.922624) (xy 348.552418 -273.966201) (xy 348.568002 -274.012882)
			(xy 348.575897 -274.061459) (xy 348.576392 -274.086066) (xy 348.905334 -274.086066) (xy 348.909294 -274.037012)
			(xy 348.921071 -273.989228) (xy 348.940362 -273.943952) (xy 348.966665 -273.902356) (xy 348.9993 -273.865519)
			(xy 349.037421 -273.834394) (xy 349.080042 -273.809787) (xy 349.126058 -273.792335) (xy 349.174277 -273.782491)
			(xy 349.223452 -273.78051) (xy 349.272307 -273.786442) (xy 349.319578 -273.800134) (xy 349.36404 -273.821232)
			(xy 349.404543 -273.849188) (xy 349.440036 -273.88328) (xy 349.469601 -273.922624) (xy 349.492472 -273.966201)
			(xy 349.508056 -274.012882) (xy 349.515951 -274.061459) (xy 349.516446 -274.086066) (xy 349.845388 -274.086066)
			(xy 349.849348 -274.037012) (xy 349.861125 -273.989228) (xy 349.880416 -273.943952) (xy 349.906719 -273.902356)
			(xy 349.939354 -273.865519) (xy 349.977475 -273.834394) (xy 350.020096 -273.809787) (xy 350.066112 -273.792335)
			(xy 350.114331 -273.782491) (xy 350.163506 -273.78051) (xy 350.212361 -273.786442) (xy 350.259632 -273.800134)
			(xy 350.304094 -273.821232) (xy 350.344597 -273.849188) (xy 350.38009 -273.88328) (xy 350.409655 -273.922624)
			(xy 350.432526 -273.966201) (xy 350.44811 -274.012882) (xy 350.456005 -274.061459) (xy 350.4565 -274.086066)
			(xy 350.785442 -274.086066) (xy 350.789402 -274.037012) (xy 350.801179 -273.989228) (xy 350.82047 -273.943952)
			(xy 350.846773 -273.902356) (xy 350.879408 -273.865519) (xy 350.917529 -273.834394) (xy 350.96015 -273.809787)
			(xy 351.006166 -273.792335) (xy 351.054385 -273.782491) (xy 351.10356 -273.78051) (xy 351.152415 -273.786442)
			(xy 351.199686 -273.800134) (xy 351.244148 -273.821232) (xy 351.284651 -273.849188) (xy 351.320144 -273.88328)
			(xy 351.349709 -273.922624) (xy 351.37258 -273.966201) (xy 351.388164 -274.012882) (xy 351.396059 -274.061459)
			(xy 351.396554 -274.086066) (xy 351.725242 -274.086066) (xy 351.729202 -274.037012) (xy 351.740979 -273.989228)
			(xy 351.76027 -273.943952) (xy 351.786573 -273.902356) (xy 351.819208 -273.865519) (xy 351.857329 -273.834394)
			(xy 351.89995 -273.809787) (xy 351.945966 -273.792335) (xy 351.994185 -273.782491) (xy 352.04336 -273.78051)
			(xy 352.092215 -273.786442) (xy 352.139486 -273.800134) (xy 352.183948 -273.821232) (xy 352.224451 -273.849188)
			(xy 352.259944 -273.88328) (xy 352.289509 -273.922624) (xy 352.31238 -273.966201) (xy 352.327964 -274.012882)
			(xy 352.335859 -274.061459) (xy 352.336354 -274.086066) (xy 352.665296 -274.086066) (xy 352.669256 -274.037012)
			(xy 352.681033 -273.989228) (xy 352.700324 -273.943952) (xy 352.726627 -273.902356) (xy 352.759262 -273.865519)
			(xy 352.797383 -273.834394) (xy 352.840004 -273.809787) (xy 352.88602 -273.792335) (xy 352.934239 -273.782491)
			(xy 352.983414 -273.78051) (xy 353.032269 -273.786442) (xy 353.07954 -273.800134) (xy 353.124002 -273.821232)
			(xy 353.164505 -273.849188) (xy 353.199998 -273.88328) (xy 353.229563 -273.922624) (xy 353.252434 -273.966201)
			(xy 353.268018 -274.012882) (xy 353.275913 -274.061459) (xy 353.276408 -274.086066) (xy 353.60535 -274.086066)
			(xy 353.60931 -274.037012) (xy 353.621087 -273.989228) (xy 353.640378 -273.943952) (xy 353.666681 -273.902356)
			(xy 353.699316 -273.865519) (xy 353.737437 -273.834394) (xy 353.780058 -273.809787) (xy 353.826074 -273.792335)
			(xy 353.874293 -273.782491) (xy 353.923468 -273.78051) (xy 353.972323 -273.786442) (xy 354.019594 -273.800134)
			(xy 354.064056 -273.821232) (xy 354.104559 -273.849188) (xy 354.140052 -273.88328) (xy 354.169617 -273.922624)
			(xy 354.192488 -273.966201) (xy 354.208072 -274.012882) (xy 354.215967 -274.061459) (xy 354.216462 -274.086066)
			(xy 354.545404 -274.086066) (xy 354.549364 -274.037012) (xy 354.561141 -273.989228) (xy 354.580432 -273.943952)
			(xy 354.606735 -273.902356) (xy 354.63937 -273.865519) (xy 354.677491 -273.834394) (xy 354.720112 -273.809787)
			(xy 354.766128 -273.792335) (xy 354.814347 -273.782491) (xy 354.863522 -273.78051) (xy 354.912377 -273.786442)
			(xy 354.959648 -273.800134) (xy 355.00411 -273.821232) (xy 355.044613 -273.849188) (xy 355.080106 -273.88328)
			(xy 355.109671 -273.922624) (xy 355.132542 -273.966201) (xy 355.148126 -274.012882) (xy 355.156021 -274.061459)
			(xy 355.156516 -274.086066) (xy 355.485204 -274.086066) (xy 355.489164 -274.037012) (xy 355.500941 -273.989228)
			(xy 355.520232 -273.943952) (xy 355.546535 -273.902356) (xy 355.57917 -273.865519) (xy 355.617291 -273.834394)
			(xy 355.659912 -273.809787) (xy 355.705928 -273.792335) (xy 355.754147 -273.782491) (xy 355.803322 -273.78051)
			(xy 355.852177 -273.786442) (xy 355.899448 -273.800134) (xy 355.94391 -273.821232) (xy 355.984413 -273.849188)
			(xy 356.019906 -273.88328) (xy 356.049471 -273.922624) (xy 356.072342 -273.966201) (xy 356.087926 -274.012882)
			(xy 356.095821 -274.061459) (xy 356.096316 -274.086066) (xy 356.425258 -274.086066) (xy 356.429218 -274.037012)
			(xy 356.440995 -273.989228) (xy 356.460286 -273.943952) (xy 356.486589 -273.902356) (xy 356.519224 -273.865519)
			(xy 356.557345 -273.834394) (xy 356.599966 -273.809787) (xy 356.645982 -273.792335) (xy 356.694201 -273.782491)
			(xy 356.743376 -273.78051) (xy 356.792231 -273.786442) (xy 356.839502 -273.800134) (xy 356.883964 -273.821232)
			(xy 356.924467 -273.849188) (xy 356.95996 -273.88328) (xy 356.989525 -273.922624) (xy 357.012396 -273.966201)
			(xy 357.02798 -274.012882) (xy 357.035875 -274.061459) (xy 357.03637 -274.086066) (xy 357.365312 -274.086066)
			(xy 357.369272 -274.037012) (xy 357.381049 -273.989228) (xy 357.40034 -273.943952) (xy 357.426643 -273.902356)
			(xy 357.459278 -273.865519) (xy 357.497399 -273.834394) (xy 357.54002 -273.809787) (xy 357.586036 -273.792335)
			(xy 357.634255 -273.782491) (xy 357.68343 -273.78051) (xy 357.732285 -273.786442) (xy 357.779556 -273.800134)
			(xy 357.824018 -273.821232) (xy 357.864521 -273.849188) (xy 357.900014 -273.88328) (xy 357.929579 -273.922624)
			(xy 357.95245 -273.966201) (xy 357.968034 -274.012882) (xy 357.975929 -274.061459) (xy 357.976424 -274.086066)
			(xy 358.305366 -274.086066) (xy 358.309326 -274.037012) (xy 358.321103 -273.989228) (xy 358.340394 -273.943952)
			(xy 358.366697 -273.902356) (xy 358.399332 -273.865519) (xy 358.437453 -273.834394) (xy 358.480074 -273.809787)
			(xy 358.52609 -273.792335) (xy 358.574309 -273.782491) (xy 358.623484 -273.78051) (xy 358.672339 -273.786442)
			(xy 358.71961 -273.800134) (xy 358.764072 -273.821232) (xy 358.804575 -273.849188) (xy 358.840068 -273.88328)
			(xy 358.869633 -273.922624) (xy 358.892504 -273.966201) (xy 358.908088 -274.012882) (xy 358.915983 -274.061459)
			(xy 358.916478 -274.086066) (xy 361.118924 -274.086066) (xy 361.122884 -274.037012) (xy 361.134661 -273.989228)
			(xy 361.153952 -273.943952) (xy 361.180255 -273.902356) (xy 361.21289 -273.865519) (xy 361.251011 -273.834394)
			(xy 361.293632 -273.809787) (xy 361.339648 -273.792335) (xy 361.387867 -273.782491) (xy 361.437042 -273.78051)
			(xy 361.485897 -273.786442) (xy 361.533168 -273.800134) (xy 361.57763 -273.821232) (xy 361.618133 -273.849188)
			(xy 361.653626 -273.88328) (xy 361.683191 -273.922624) (xy 361.706062 -273.966201) (xy 361.721646 -274.012882)
			(xy 361.729541 -274.061459) (xy 361.730036 -274.086066) (xy 362.058978 -274.086066) (xy 362.062938 -274.037012)
			(xy 362.074715 -273.989228) (xy 362.094006 -273.943952) (xy 362.120309 -273.902356) (xy 362.152944 -273.865519)
			(xy 362.191065 -273.834394) (xy 362.233686 -273.809787) (xy 362.279702 -273.792335) (xy 362.327921 -273.782491)
			(xy 362.377096 -273.78051) (xy 362.425951 -273.786442) (xy 362.473222 -273.800134) (xy 362.517684 -273.821232)
			(xy 362.558187 -273.849188) (xy 362.59368 -273.88328) (xy 362.623245 -273.922624) (xy 362.646116 -273.966201)
			(xy 362.6617 -274.012882) (xy 362.669595 -274.061459) (xy 362.67009 -274.086066) (xy 362.999032 -274.086066)
			(xy 363.002992 -274.037012) (xy 363.014769 -273.989228) (xy 363.03406 -273.943952) (xy 363.060363 -273.902356)
			(xy 363.092998 -273.865519) (xy 363.131119 -273.834394) (xy 363.17374 -273.809787) (xy 363.219756 -273.792335)
			(xy 363.267975 -273.782491) (xy 363.31715 -273.78051) (xy 363.366005 -273.786442) (xy 363.413276 -273.800134)
			(xy 363.457738 -273.821232) (xy 363.498241 -273.849188) (xy 363.533734 -273.88328) (xy 363.563299 -273.922624)
			(xy 363.58617 -273.966201) (xy 363.601754 -274.012882) (xy 363.609649 -274.061459) (xy 363.610144 -274.086066)
			(xy 363.939086 -274.086066) (xy 363.943046 -274.037012) (xy 363.954823 -273.989228) (xy 363.974114 -273.943952)
			(xy 364.000417 -273.902356) (xy 364.033052 -273.865519) (xy 364.071173 -273.834394) (xy 364.113794 -273.809787)
			(xy 364.15981 -273.792335) (xy 364.208029 -273.782491) (xy 364.257204 -273.78051) (xy 364.306059 -273.786442)
			(xy 364.35333 -273.800134) (xy 364.397792 -273.821232) (xy 364.438295 -273.849188) (xy 364.473788 -273.88328)
			(xy 364.503353 -273.922624) (xy 364.526224 -273.966201) (xy 364.541808 -274.012882) (xy 364.549703 -274.061459)
			(xy 364.550198 -274.086066) (xy 364.878886 -274.086066) (xy 364.882846 -274.037012) (xy 364.894623 -273.989228)
			(xy 364.913914 -273.943952) (xy 364.940217 -273.902356) (xy 364.972852 -273.865519) (xy 365.010973 -273.834394)
			(xy 365.053594 -273.809787) (xy 365.09961 -273.792335) (xy 365.147829 -273.782491) (xy 365.197004 -273.78051)
			(xy 365.245859 -273.786442) (xy 365.29313 -273.800134) (xy 365.337592 -273.821232) (xy 365.378095 -273.849188)
			(xy 365.413588 -273.88328) (xy 365.443153 -273.922624) (xy 365.466024 -273.966201) (xy 365.481608 -274.012882)
			(xy 365.489503 -274.061459) (xy 365.489998 -274.086066) (xy 365.81894 -274.086066) (xy 365.8229 -274.037012)
			(xy 365.834677 -273.989228) (xy 365.853968 -273.943952) (xy 365.880271 -273.902356) (xy 365.912906 -273.865519)
			(xy 365.951027 -273.834394) (xy 365.993648 -273.809787) (xy 366.039664 -273.792335) (xy 366.087883 -273.782491)
			(xy 366.137058 -273.78051) (xy 366.185913 -273.786442) (xy 366.233184 -273.800134) (xy 366.277646 -273.821232)
			(xy 366.318149 -273.849188) (xy 366.353642 -273.88328) (xy 366.383207 -273.922624) (xy 366.406078 -273.966201)
			(xy 366.421662 -274.012882) (xy 366.429557 -274.061459) (xy 366.430052 -274.086066) (xy 366.758994 -274.086066)
			(xy 366.762954 -274.037012) (xy 366.774731 -273.989228) (xy 366.794022 -273.943952) (xy 366.820325 -273.902356)
			(xy 366.85296 -273.865519) (xy 366.891081 -273.834394) (xy 366.933702 -273.809787) (xy 366.979718 -273.792335)
			(xy 367.027937 -273.782491) (xy 367.077112 -273.78051) (xy 367.125967 -273.786442) (xy 367.173238 -273.800134)
			(xy 367.2177 -273.821232) (xy 367.258203 -273.849188) (xy 367.293696 -273.88328) (xy 367.323261 -273.922624)
			(xy 367.346132 -273.966201) (xy 367.361716 -274.012882) (xy 367.369611 -274.061459) (xy 367.370106 -274.086066)
			(xy 367.699048 -274.086066) (xy 367.703008 -274.037012) (xy 367.714785 -273.989228) (xy 367.734076 -273.943952)
			(xy 367.760379 -273.902356) (xy 367.793014 -273.865519) (xy 367.831135 -273.834394) (xy 367.873756 -273.809787)
			(xy 367.919772 -273.792335) (xy 367.967991 -273.782491) (xy 368.017166 -273.78051) (xy 368.066021 -273.786442)
			(xy 368.113292 -273.800134) (xy 368.157754 -273.821232) (xy 368.198257 -273.849188) (xy 368.23375 -273.88328)
			(xy 368.263315 -273.922624) (xy 368.286186 -273.966201) (xy 368.30177 -274.012882) (xy 368.309665 -274.061459)
			(xy 368.31016 -274.086066) (xy 368.639102 -274.086066) (xy 368.643062 -274.037012) (xy 368.654839 -273.989228)
			(xy 368.67413 -273.943952) (xy 368.700433 -273.902356) (xy 368.733068 -273.865519) (xy 368.771189 -273.834394)
			(xy 368.81381 -273.809787) (xy 368.859826 -273.792335) (xy 368.908045 -273.782491) (xy 368.95722 -273.78051)
			(xy 369.006075 -273.786442) (xy 369.053346 -273.800134) (xy 369.097808 -273.821232) (xy 369.138311 -273.849188)
			(xy 369.173804 -273.88328) (xy 369.203369 -273.922624) (xy 369.22624 -273.966201) (xy 369.241824 -274.012882)
			(xy 369.249719 -274.061459) (xy 369.250214 -274.086066) (xy 369.578902 -274.086066) (xy 369.582862 -274.037012)
			(xy 369.594639 -273.989228) (xy 369.61393 -273.943952) (xy 369.640233 -273.902356) (xy 369.672868 -273.865519)
			(xy 369.710989 -273.834394) (xy 369.75361 -273.809787) (xy 369.799626 -273.792335) (xy 369.847845 -273.782491)
			(xy 369.89702 -273.78051) (xy 369.945875 -273.786442) (xy 369.993146 -273.800134) (xy 370.037608 -273.821232)
			(xy 370.078111 -273.849188) (xy 370.113604 -273.88328) (xy 370.143169 -273.922624) (xy 370.16604 -273.966201)
			(xy 370.181624 -274.012882) (xy 370.189519 -274.061459) (xy 370.190014 -274.086066) (xy 370.518956 -274.086066)
			(xy 370.522916 -274.037012) (xy 370.534693 -273.989228) (xy 370.553984 -273.943952) (xy 370.580287 -273.902356)
			(xy 370.612922 -273.865519) (xy 370.651043 -273.834394) (xy 370.693664 -273.809787) (xy 370.73968 -273.792335)
			(xy 370.787899 -273.782491) (xy 370.837074 -273.78051) (xy 370.885929 -273.786442) (xy 370.9332 -273.800134)
			(xy 370.977662 -273.821232) (xy 371.018165 -273.849188) (xy 371.053658 -273.88328) (xy 371.083223 -273.922624)
			(xy 371.106094 -273.966201) (xy 371.121678 -274.012882) (xy 371.129573 -274.061459) (xy 371.130068 -274.086066)
			(xy 371.45901 -274.086066) (xy 371.46297 -274.037012) (xy 371.474747 -273.989228) (xy 371.494038 -273.943952)
			(xy 371.520341 -273.902356) (xy 371.552976 -273.865519) (xy 371.591097 -273.834394) (xy 371.633718 -273.809787)
			(xy 371.679734 -273.792335) (xy 371.727953 -273.782491) (xy 371.777128 -273.78051) (xy 371.825983 -273.786442)
			(xy 371.873254 -273.800134) (xy 371.917716 -273.821232) (xy 371.958219 -273.849188) (xy 371.993712 -273.88328)
			(xy 372.023277 -273.922624) (xy 372.046148 -273.966201) (xy 372.061732 -274.012882) (xy 372.069627 -274.061459)
			(xy 372.070122 -274.086066) (xy 372.399064 -274.086066) (xy 372.403024 -274.037012) (xy 372.414801 -273.989228)
			(xy 372.434092 -273.943952) (xy 372.460395 -273.902356) (xy 372.49303 -273.865519) (xy 372.531151 -273.834394)
			(xy 372.573772 -273.809787) (xy 372.619788 -273.792335) (xy 372.668007 -273.782491) (xy 372.717182 -273.78051)
			(xy 372.766037 -273.786442) (xy 372.813308 -273.800134) (xy 372.85777 -273.821232) (xy 372.898273 -273.849188)
			(xy 372.933766 -273.88328) (xy 372.963331 -273.922624) (xy 372.986202 -273.966201) (xy 373.001786 -274.012882)
			(xy 373.009681 -274.061459) (xy 373.010176 -274.086066) (xy 373.339118 -274.086066) (xy 373.343078 -274.037012)
			(xy 373.354855 -273.989228) (xy 373.374146 -273.943952) (xy 373.400449 -273.902356) (xy 373.433084 -273.865519)
			(xy 373.471205 -273.834394) (xy 373.513826 -273.809787) (xy 373.559842 -273.792335) (xy 373.608061 -273.782491)
			(xy 373.657236 -273.78051) (xy 373.706091 -273.786442) (xy 373.753362 -273.800134) (xy 373.797824 -273.821232)
			(xy 373.838327 -273.849188) (xy 373.87382 -273.88328) (xy 373.903385 -273.922624) (xy 373.926256 -273.966201)
			(xy 373.94184 -274.012882) (xy 373.949735 -274.061459) (xy 373.95023 -274.086066) (xy 374.278918 -274.086066)
			(xy 374.282878 -274.037012) (xy 374.294655 -273.989228) (xy 374.313946 -273.943952) (xy 374.340249 -273.902356)
			(xy 374.372884 -273.865519) (xy 374.411005 -273.834394) (xy 374.453626 -273.809787) (xy 374.499642 -273.792335)
			(xy 374.547861 -273.782491) (xy 374.597036 -273.78051) (xy 374.645891 -273.786442) (xy 374.693162 -273.800134)
			(xy 374.737624 -273.821232) (xy 374.778127 -273.849188) (xy 374.81362 -273.88328) (xy 374.843185 -273.922624)
			(xy 374.866056 -273.966201) (xy 374.88164 -274.012882) (xy 374.889535 -274.061459) (xy 374.89003 -274.086066)
			(xy 375.218972 -274.086066) (xy 375.222932 -274.037012) (xy 375.234709 -273.989228) (xy 375.254 -273.943952)
			(xy 375.280303 -273.902356) (xy 375.312938 -273.865519) (xy 375.351059 -273.834394) (xy 375.39368 -273.809787)
			(xy 375.439696 -273.792335) (xy 375.487915 -273.782491) (xy 375.53709 -273.78051) (xy 375.585945 -273.786442)
			(xy 375.633216 -273.800134) (xy 375.677678 -273.821232) (xy 375.718181 -273.849188) (xy 375.753674 -273.88328)
			(xy 375.783239 -273.922624) (xy 375.80611 -273.966201) (xy 375.821694 -274.012882) (xy 375.829589 -274.061459)
			(xy 375.830084 -274.086066) (xy 376.148595 -274.086066) (xy 376.15269 -274.035338) (xy 376.164869 -273.985924)
			(xy 376.184817 -273.939104) (xy 376.212018 -273.89609) (xy 376.245766 -273.857996) (xy 376.285188 -273.825809)
			(xy 376.329262 -273.800363) (xy 376.376848 -273.782316) (xy 376.426712 -273.772136) (xy 376.477564 -273.770087)
			(xy 376.528085 -273.776221) (xy 376.576969 -273.790381) (xy 376.622948 -273.812198) (xy 376.664832 -273.841108)
			(xy 376.701536 -273.876363) (xy 376.732109 -273.917049) (xy 376.75576 -273.962112) (xy 376.771876 -274.010386)
			(xy 376.78004 -274.06062) (xy 376.780552 -274.086066) (xy 377.088649 -274.086066) (xy 377.092744 -274.035338)
			(xy 377.104923 -273.985924) (xy 377.124871 -273.939104) (xy 377.152072 -273.89609) (xy 377.18582 -273.857996)
			(xy 377.225242 -273.825809) (xy 377.269316 -273.800363) (xy 377.316902 -273.782316) (xy 377.366766 -273.772136)
			(xy 377.417618 -273.770087) (xy 377.468139 -273.776221) (xy 377.517023 -273.790381) (xy 377.563002 -273.812198)
			(xy 377.604886 -273.841108) (xy 377.64159 -273.876363) (xy 377.672163 -273.917049) (xy 377.695814 -273.962112)
			(xy 377.71193 -274.010386) (xy 377.720094 -274.06062) (xy 377.720606 -274.086066) (xy 377.720094 -274.111512)
			(xy 377.71193 -274.161746) (xy 377.695814 -274.21002) (xy 377.672163 -274.255083) (xy 377.64159 -274.295769)
			(xy 377.604886 -274.331024) (xy 377.563002 -274.359934) (xy 377.517023 -274.381751) (xy 377.468139 -274.395911)
			(xy 377.417618 -274.402045) (xy 377.366766 -274.399996) (xy 377.316902 -274.389816) (xy 377.269316 -274.371769)
			(xy 377.225242 -274.346323) (xy 377.18582 -274.314136) (xy 377.152072 -274.276042) (xy 377.124871 -274.233028)
			(xy 377.104923 -274.186208) (xy 377.092744 -274.136794) (xy 377.088649 -274.086066) (xy 376.780552 -274.086066)
			(xy 376.78004 -274.111512) (xy 376.771876 -274.161746) (xy 376.75576 -274.21002) (xy 376.732109 -274.255083)
			(xy 376.701536 -274.295769) (xy 376.664832 -274.331024) (xy 376.622948 -274.359934) (xy 376.576969 -274.381751)
			(xy 376.528085 -274.395911) (xy 376.477564 -274.402045) (xy 376.426712 -274.399996) (xy 376.376848 -274.389816)
			(xy 376.329262 -274.371769) (xy 376.285188 -274.346323) (xy 376.245766 -274.314136) (xy 376.212018 -274.276042)
			(xy 376.184817 -274.233028) (xy 376.164869 -274.186208) (xy 376.15269 -274.136794) (xy 376.148595 -274.086066)
			(xy 375.830084 -274.086066) (xy 375.829589 -274.110673) (xy 375.821694 -274.15925) (xy 375.80611 -274.205931)
			(xy 375.783239 -274.249508) (xy 375.753674 -274.288852) (xy 375.718181 -274.322944) (xy 375.677678 -274.3509)
			(xy 375.633216 -274.371998) (xy 375.585945 -274.38569) (xy 375.53709 -274.391622) (xy 375.487915 -274.389641)
			(xy 375.439696 -274.379797) (xy 375.39368 -274.362345) (xy 375.351059 -274.337738) (xy 375.312938 -274.306613)
			(xy 375.280303 -274.269776) (xy 375.254 -274.22818) (xy 375.234709 -274.182904) (xy 375.222932 -274.13512)
			(xy 375.218972 -274.086066) (xy 374.89003 -274.086066) (xy 374.889535 -274.110673) (xy 374.88164 -274.15925)
			(xy 374.866056 -274.205931) (xy 374.843185 -274.249508) (xy 374.81362 -274.288852) (xy 374.778127 -274.322944)
			(xy 374.737624 -274.3509) (xy 374.693162 -274.371998) (xy 374.645891 -274.38569) (xy 374.597036 -274.391622)
			(xy 374.547861 -274.389641) (xy 374.499642 -274.379797) (xy 374.453626 -274.362345) (xy 374.411005 -274.337738)
			(xy 374.372884 -274.306613) (xy 374.340249 -274.269776) (xy 374.313946 -274.22818) (xy 374.294655 -274.182904)
			(xy 374.282878 -274.13512) (xy 374.278918 -274.086066) (xy 373.95023 -274.086066) (xy 373.949735 -274.110673)
			(xy 373.94184 -274.15925) (xy 373.926256 -274.205931) (xy 373.903385 -274.249508) (xy 373.87382 -274.288852)
			(xy 373.838327 -274.322944) (xy 373.797824 -274.3509) (xy 373.753362 -274.371998) (xy 373.706091 -274.38569)
			(xy 373.657236 -274.391622) (xy 373.608061 -274.389641) (xy 373.559842 -274.379797) (xy 373.513826 -274.362345)
			(xy 373.471205 -274.337738) (xy 373.433084 -274.306613) (xy 373.400449 -274.269776) (xy 373.374146 -274.22818)
			(xy 373.354855 -274.182904) (xy 373.343078 -274.13512) (xy 373.339118 -274.086066) (xy 373.010176 -274.086066)
			(xy 373.009681 -274.110673) (xy 373.001786 -274.15925) (xy 372.986202 -274.205931) (xy 372.963331 -274.249508)
			(xy 372.933766 -274.288852) (xy 372.898273 -274.322944) (xy 372.85777 -274.3509) (xy 372.813308 -274.371998)
			(xy 372.766037 -274.38569) (xy 372.717182 -274.391622) (xy 372.668007 -274.389641) (xy 372.619788 -274.379797)
			(xy 372.573772 -274.362345) (xy 372.531151 -274.337738) (xy 372.49303 -274.306613) (xy 372.460395 -274.269776)
			(xy 372.434092 -274.22818) (xy 372.414801 -274.182904) (xy 372.403024 -274.13512) (xy 372.399064 -274.086066)
			(xy 372.070122 -274.086066) (xy 372.069627 -274.110673) (xy 372.061732 -274.15925) (xy 372.046148 -274.205931)
			(xy 372.023277 -274.249508) (xy 371.993712 -274.288852) (xy 371.958219 -274.322944) (xy 371.917716 -274.3509)
			(xy 371.873254 -274.371998) (xy 371.825983 -274.38569) (xy 371.777128 -274.391622) (xy 371.727953 -274.389641)
			(xy 371.679734 -274.379797) (xy 371.633718 -274.362345) (xy 371.591097 -274.337738) (xy 371.552976 -274.306613)
			(xy 371.520341 -274.269776) (xy 371.494038 -274.22818) (xy 371.474747 -274.182904) (xy 371.46297 -274.13512)
			(xy 371.45901 -274.086066) (xy 371.130068 -274.086066) (xy 371.129573 -274.110673) (xy 371.121678 -274.15925)
			(xy 371.106094 -274.205931) (xy 371.083223 -274.249508) (xy 371.053658 -274.288852) (xy 371.018165 -274.322944)
			(xy 370.977662 -274.3509) (xy 370.9332 -274.371998) (xy 370.885929 -274.38569) (xy 370.837074 -274.391622)
			(xy 370.787899 -274.389641) (xy 370.73968 -274.379797) (xy 370.693664 -274.362345) (xy 370.651043 -274.337738)
			(xy 370.612922 -274.306613) (xy 370.580287 -274.269776) (xy 370.553984 -274.22818) (xy 370.534693 -274.182904)
			(xy 370.522916 -274.13512) (xy 370.518956 -274.086066) (xy 370.190014 -274.086066) (xy 370.189519 -274.110673)
			(xy 370.181624 -274.15925) (xy 370.16604 -274.205931) (xy 370.143169 -274.249508) (xy 370.113604 -274.288852)
			(xy 370.078111 -274.322944) (xy 370.037608 -274.3509) (xy 369.993146 -274.371998) (xy 369.945875 -274.38569)
			(xy 369.89702 -274.391622) (xy 369.847845 -274.389641) (xy 369.799626 -274.379797) (xy 369.75361 -274.362345)
			(xy 369.710989 -274.337738) (xy 369.672868 -274.306613) (xy 369.640233 -274.269776) (xy 369.61393 -274.22818)
			(xy 369.594639 -274.182904) (xy 369.582862 -274.13512) (xy 369.578902 -274.086066) (xy 369.250214 -274.086066)
			(xy 369.249719 -274.110673) (xy 369.241824 -274.15925) (xy 369.22624 -274.205931) (xy 369.203369 -274.249508)
			(xy 369.173804 -274.288852) (xy 369.138311 -274.322944) (xy 369.097808 -274.3509) (xy 369.053346 -274.371998)
			(xy 369.006075 -274.38569) (xy 368.95722 -274.391622) (xy 368.908045 -274.389641) (xy 368.859826 -274.379797)
			(xy 368.81381 -274.362345) (xy 368.771189 -274.337738) (xy 368.733068 -274.306613) (xy 368.700433 -274.269776)
			(xy 368.67413 -274.22818) (xy 368.654839 -274.182904) (xy 368.643062 -274.13512) (xy 368.639102 -274.086066)
			(xy 368.31016 -274.086066) (xy 368.309665 -274.110673) (xy 368.30177 -274.15925) (xy 368.286186 -274.205931)
			(xy 368.263315 -274.249508) (xy 368.23375 -274.288852) (xy 368.198257 -274.322944) (xy 368.157754 -274.3509)
			(xy 368.113292 -274.371998) (xy 368.066021 -274.38569) (xy 368.017166 -274.391622) (xy 367.967991 -274.389641)
			(xy 367.919772 -274.379797) (xy 367.873756 -274.362345) (xy 367.831135 -274.337738) (xy 367.793014 -274.306613)
			(xy 367.760379 -274.269776) (xy 367.734076 -274.22818) (xy 367.714785 -274.182904) (xy 367.703008 -274.13512)
			(xy 367.699048 -274.086066) (xy 367.370106 -274.086066) (xy 367.369611 -274.110673) (xy 367.361716 -274.15925)
			(xy 367.346132 -274.205931) (xy 367.323261 -274.249508) (xy 367.293696 -274.288852) (xy 367.258203 -274.322944)
			(xy 367.2177 -274.3509) (xy 367.173238 -274.371998) (xy 367.125967 -274.38569) (xy 367.077112 -274.391622)
			(xy 367.027937 -274.389641) (xy 366.979718 -274.379797) (xy 366.933702 -274.362345) (xy 366.891081 -274.337738)
			(xy 366.85296 -274.306613) (xy 366.820325 -274.269776) (xy 366.794022 -274.22818) (xy 366.774731 -274.182904)
			(xy 366.762954 -274.13512) (xy 366.758994 -274.086066) (xy 366.430052 -274.086066) (xy 366.429557 -274.110673)
			(xy 366.421662 -274.15925) (xy 366.406078 -274.205931) (xy 366.383207 -274.249508) (xy 366.353642 -274.288852)
			(xy 366.318149 -274.322944) (xy 366.277646 -274.3509) (xy 366.233184 -274.371998) (xy 366.185913 -274.38569)
			(xy 366.137058 -274.391622) (xy 366.087883 -274.389641) (xy 366.039664 -274.379797) (xy 365.993648 -274.362345)
			(xy 365.951027 -274.337738) (xy 365.912906 -274.306613) (xy 365.880271 -274.269776) (xy 365.853968 -274.22818)
			(xy 365.834677 -274.182904) (xy 365.8229 -274.13512) (xy 365.81894 -274.086066) (xy 365.489998 -274.086066)
			(xy 365.489503 -274.110673) (xy 365.481608 -274.15925) (xy 365.466024 -274.205931) (xy 365.443153 -274.249508)
			(xy 365.413588 -274.288852) (xy 365.378095 -274.322944) (xy 365.337592 -274.3509) (xy 365.29313 -274.371998)
			(xy 365.245859 -274.38569) (xy 365.197004 -274.391622) (xy 365.147829 -274.389641) (xy 365.09961 -274.379797)
			(xy 365.053594 -274.362345) (xy 365.010973 -274.337738) (xy 364.972852 -274.306613) (xy 364.940217 -274.269776)
			(xy 364.913914 -274.22818) (xy 364.894623 -274.182904) (xy 364.882846 -274.13512) (xy 364.878886 -274.086066)
			(xy 364.550198 -274.086066) (xy 364.549703 -274.110673) (xy 364.541808 -274.15925) (xy 364.526224 -274.205931)
			(xy 364.503353 -274.249508) (xy 364.473788 -274.288852) (xy 364.438295 -274.322944) (xy 364.397792 -274.3509)
			(xy 364.35333 -274.371998) (xy 364.306059 -274.38569) (xy 364.257204 -274.391622) (xy 364.208029 -274.389641)
			(xy 364.15981 -274.379797) (xy 364.113794 -274.362345) (xy 364.071173 -274.337738) (xy 364.033052 -274.306613)
			(xy 364.000417 -274.269776) (xy 363.974114 -274.22818) (xy 363.954823 -274.182904) (xy 363.943046 -274.13512)
			(xy 363.939086 -274.086066) (xy 363.610144 -274.086066) (xy 363.609649 -274.110673) (xy 363.601754 -274.15925)
			(xy 363.58617 -274.205931) (xy 363.563299 -274.249508) (xy 363.533734 -274.288852) (xy 363.498241 -274.322944)
			(xy 363.457738 -274.3509) (xy 363.413276 -274.371998) (xy 363.366005 -274.38569) (xy 363.31715 -274.391622)
			(xy 363.267975 -274.389641) (xy 363.219756 -274.379797) (xy 363.17374 -274.362345) (xy 363.131119 -274.337738)
			(xy 363.092998 -274.306613) (xy 363.060363 -274.269776) (xy 363.03406 -274.22818) (xy 363.014769 -274.182904)
			(xy 363.002992 -274.13512) (xy 362.999032 -274.086066) (xy 362.67009 -274.086066) (xy 362.669595 -274.110673)
			(xy 362.6617 -274.15925) (xy 362.646116 -274.205931) (xy 362.623245 -274.249508) (xy 362.59368 -274.288852)
			(xy 362.558187 -274.322944) (xy 362.517684 -274.3509) (xy 362.473222 -274.371998) (xy 362.425951 -274.38569)
			(xy 362.377096 -274.391622) (xy 362.327921 -274.389641) (xy 362.279702 -274.379797) (xy 362.233686 -274.362345)
			(xy 362.191065 -274.337738) (xy 362.152944 -274.306613) (xy 362.120309 -274.269776) (xy 362.094006 -274.22818)
			(xy 362.074715 -274.182904) (xy 362.062938 -274.13512) (xy 362.058978 -274.086066) (xy 361.730036 -274.086066)
			(xy 361.729541 -274.110673) (xy 361.721646 -274.15925) (xy 361.706062 -274.205931) (xy 361.683191 -274.249508)
			(xy 361.653626 -274.288852) (xy 361.618133 -274.322944) (xy 361.57763 -274.3509) (xy 361.533168 -274.371998)
			(xy 361.485897 -274.38569) (xy 361.437042 -274.391622) (xy 361.387867 -274.389641) (xy 361.339648 -274.379797)
			(xy 361.293632 -274.362345) (xy 361.251011 -274.337738) (xy 361.21289 -274.306613) (xy 361.180255 -274.269776)
			(xy 361.153952 -274.22818) (xy 361.134661 -274.182904) (xy 361.122884 -274.13512) (xy 361.118924 -274.086066)
			(xy 358.916478 -274.086066) (xy 358.915983 -274.110673) (xy 358.908088 -274.15925) (xy 358.892504 -274.205931)
			(xy 358.869633 -274.249508) (xy 358.840068 -274.288852) (xy 358.804575 -274.322944) (xy 358.764072 -274.3509)
			(xy 358.71961 -274.371998) (xy 358.672339 -274.38569) (xy 358.623484 -274.391622) (xy 358.574309 -274.389641)
			(xy 358.52609 -274.379797) (xy 358.480074 -274.362345) (xy 358.437453 -274.337738) (xy 358.399332 -274.306613)
			(xy 358.366697 -274.269776) (xy 358.340394 -274.22818) (xy 358.321103 -274.182904) (xy 358.309326 -274.13512)
			(xy 358.305366 -274.086066) (xy 357.976424 -274.086066) (xy 357.975929 -274.110673) (xy 357.968034 -274.15925)
			(xy 357.95245 -274.205931) (xy 357.929579 -274.249508) (xy 357.900014 -274.288852) (xy 357.864521 -274.322944)
			(xy 357.824018 -274.3509) (xy 357.779556 -274.371998) (xy 357.732285 -274.38569) (xy 357.68343 -274.391622)
			(xy 357.634255 -274.389641) (xy 357.586036 -274.379797) (xy 357.54002 -274.362345) (xy 357.497399 -274.337738)
			(xy 357.459278 -274.306613) (xy 357.426643 -274.269776) (xy 357.40034 -274.22818) (xy 357.381049 -274.182904)
			(xy 357.369272 -274.13512) (xy 357.365312 -274.086066) (xy 357.03637 -274.086066) (xy 357.035875 -274.110673)
			(xy 357.02798 -274.15925) (xy 357.012396 -274.205931) (xy 356.989525 -274.249508) (xy 356.95996 -274.288852)
			(xy 356.924467 -274.322944) (xy 356.883964 -274.3509) (xy 356.839502 -274.371998) (xy 356.792231 -274.38569)
			(xy 356.743376 -274.391622) (xy 356.694201 -274.389641) (xy 356.645982 -274.379797) (xy 356.599966 -274.362345)
			(xy 356.557345 -274.337738) (xy 356.519224 -274.306613) (xy 356.486589 -274.269776) (xy 356.460286 -274.22818)
			(xy 356.440995 -274.182904) (xy 356.429218 -274.13512) (xy 356.425258 -274.086066) (xy 356.096316 -274.086066)
			(xy 356.095821 -274.110673) (xy 356.087926 -274.15925) (xy 356.072342 -274.205931) (xy 356.049471 -274.249508)
			(xy 356.019906 -274.288852) (xy 355.984413 -274.322944) (xy 355.94391 -274.3509) (xy 355.899448 -274.371998)
			(xy 355.852177 -274.38569) (xy 355.803322 -274.391622) (xy 355.754147 -274.389641) (xy 355.705928 -274.379797)
			(xy 355.659912 -274.362345) (xy 355.617291 -274.337738) (xy 355.57917 -274.306613) (xy 355.546535 -274.269776)
			(xy 355.520232 -274.22818) (xy 355.500941 -274.182904) (xy 355.489164 -274.13512) (xy 355.485204 -274.086066)
			(xy 355.156516 -274.086066) (xy 355.156021 -274.110673) (xy 355.148126 -274.15925) (xy 355.132542 -274.205931)
			(xy 355.109671 -274.249508) (xy 355.080106 -274.288852) (xy 355.044613 -274.322944) (xy 355.00411 -274.3509)
			(xy 354.959648 -274.371998) (xy 354.912377 -274.38569) (xy 354.863522 -274.391622) (xy 354.814347 -274.389641)
			(xy 354.766128 -274.379797) (xy 354.720112 -274.362345) (xy 354.677491 -274.337738) (xy 354.63937 -274.306613)
			(xy 354.606735 -274.269776) (xy 354.580432 -274.22818) (xy 354.561141 -274.182904) (xy 354.549364 -274.13512)
			(xy 354.545404 -274.086066) (xy 354.216462 -274.086066) (xy 354.215967 -274.110673) (xy 354.208072 -274.15925)
			(xy 354.192488 -274.205931) (xy 354.169617 -274.249508) (xy 354.140052 -274.288852) (xy 354.104559 -274.322944)
			(xy 354.064056 -274.3509) (xy 354.019594 -274.371998) (xy 353.972323 -274.38569) (xy 353.923468 -274.391622)
			(xy 353.874293 -274.389641) (xy 353.826074 -274.379797) (xy 353.780058 -274.362345) (xy 353.737437 -274.337738)
			(xy 353.699316 -274.306613) (xy 353.666681 -274.269776) (xy 353.640378 -274.22818) (xy 353.621087 -274.182904)
			(xy 353.60931 -274.13512) (xy 353.60535 -274.086066) (xy 353.276408 -274.086066) (xy 353.275913 -274.110673)
			(xy 353.268018 -274.15925) (xy 353.252434 -274.205931) (xy 353.229563 -274.249508) (xy 353.199998 -274.288852)
			(xy 353.164505 -274.322944) (xy 353.124002 -274.3509) (xy 353.07954 -274.371998) (xy 353.032269 -274.38569)
			(xy 352.983414 -274.391622) (xy 352.934239 -274.389641) (xy 352.88602 -274.379797) (xy 352.840004 -274.362345)
			(xy 352.797383 -274.337738) (xy 352.759262 -274.306613) (xy 352.726627 -274.269776) (xy 352.700324 -274.22818)
			(xy 352.681033 -274.182904) (xy 352.669256 -274.13512) (xy 352.665296 -274.086066) (xy 352.336354 -274.086066)
			(xy 352.335859 -274.110673) (xy 352.327964 -274.15925) (xy 352.31238 -274.205931) (xy 352.289509 -274.249508)
			(xy 352.259944 -274.288852) (xy 352.224451 -274.322944) (xy 352.183948 -274.3509) (xy 352.139486 -274.371998)
			(xy 352.092215 -274.38569) (xy 352.04336 -274.391622) (xy 351.994185 -274.389641) (xy 351.945966 -274.379797)
			(xy 351.89995 -274.362345) (xy 351.857329 -274.337738) (xy 351.819208 -274.306613) (xy 351.786573 -274.269776)
			(xy 351.76027 -274.22818) (xy 351.740979 -274.182904) (xy 351.729202 -274.13512) (xy 351.725242 -274.086066)
			(xy 351.396554 -274.086066) (xy 351.396059 -274.110673) (xy 351.388164 -274.15925) (xy 351.37258 -274.205931)
			(xy 351.349709 -274.249508) (xy 351.320144 -274.288852) (xy 351.284651 -274.322944) (xy 351.244148 -274.3509)
			(xy 351.199686 -274.371998) (xy 351.152415 -274.38569) (xy 351.10356 -274.391622) (xy 351.054385 -274.389641)
			(xy 351.006166 -274.379797) (xy 350.96015 -274.362345) (xy 350.917529 -274.337738) (xy 350.879408 -274.306613)
			(xy 350.846773 -274.269776) (xy 350.82047 -274.22818) (xy 350.801179 -274.182904) (xy 350.789402 -274.13512)
			(xy 350.785442 -274.086066) (xy 350.4565 -274.086066) (xy 350.456005 -274.110673) (xy 350.44811 -274.15925)
			(xy 350.432526 -274.205931) (xy 350.409655 -274.249508) (xy 350.38009 -274.288852) (xy 350.344597 -274.322944)
			(xy 350.304094 -274.3509) (xy 350.259632 -274.371998) (xy 350.212361 -274.38569) (xy 350.163506 -274.391622)
			(xy 350.114331 -274.389641) (xy 350.066112 -274.379797) (xy 350.020096 -274.362345) (xy 349.977475 -274.337738)
			(xy 349.939354 -274.306613) (xy 349.906719 -274.269776) (xy 349.880416 -274.22818) (xy 349.861125 -274.182904)
			(xy 349.849348 -274.13512) (xy 349.845388 -274.086066) (xy 349.516446 -274.086066) (xy 349.515951 -274.110673)
			(xy 349.508056 -274.15925) (xy 349.492472 -274.205931) (xy 349.469601 -274.249508) (xy 349.440036 -274.288852)
			(xy 349.404543 -274.322944) (xy 349.36404 -274.3509) (xy 349.319578 -274.371998) (xy 349.272307 -274.38569)
			(xy 349.223452 -274.391622) (xy 349.174277 -274.389641) (xy 349.126058 -274.379797) (xy 349.080042 -274.362345)
			(xy 349.037421 -274.337738) (xy 348.9993 -274.306613) (xy 348.966665 -274.269776) (xy 348.940362 -274.22818)
			(xy 348.921071 -274.182904) (xy 348.909294 -274.13512) (xy 348.905334 -274.086066) (xy 348.576392 -274.086066)
			(xy 348.575897 -274.110673) (xy 348.568002 -274.15925) (xy 348.552418 -274.205931) (xy 348.529547 -274.249508)
			(xy 348.499982 -274.288852) (xy 348.464489 -274.322944) (xy 348.423986 -274.3509) (xy 348.379524 -274.371998)
			(xy 348.332253 -274.38569) (xy 348.283398 -274.391622) (xy 348.234223 -274.389641) (xy 348.186004 -274.379797)
			(xy 348.139988 -274.362345) (xy 348.097367 -274.337738) (xy 348.059246 -274.306613) (xy 348.026611 -274.269776)
			(xy 348.000308 -274.22818) (xy 347.981017 -274.182904) (xy 347.96924 -274.13512) (xy 347.96528 -274.086066)
			(xy 347.636338 -274.086066) (xy 347.635843 -274.110673) (xy 347.627948 -274.15925) (xy 347.612364 -274.205931)
			(xy 347.589493 -274.249508) (xy 347.559928 -274.288852) (xy 347.524435 -274.322944) (xy 347.483932 -274.3509)
			(xy 347.43947 -274.371998) (xy 347.392199 -274.38569) (xy 347.343344 -274.391622) (xy 347.294169 -274.389641)
			(xy 347.24595 -274.379797) (xy 347.199934 -274.362345) (xy 347.157313 -274.337738) (xy 347.119192 -274.306613)
			(xy 347.086557 -274.269776) (xy 347.060254 -274.22818) (xy 347.040963 -274.182904) (xy 347.029186 -274.13512)
			(xy 347.025226 -274.086066) (xy 346.696538 -274.086066) (xy 346.696043 -274.110673) (xy 346.688148 -274.15925)
			(xy 346.672564 -274.205931) (xy 346.649693 -274.249508) (xy 346.620128 -274.288852) (xy 346.584635 -274.322944)
			(xy 346.544132 -274.3509) (xy 346.49967 -274.371998) (xy 346.452399 -274.38569) (xy 346.403544 -274.391622)
			(xy 346.354369 -274.389641) (xy 346.30615 -274.379797) (xy 346.260134 -274.362345) (xy 346.217513 -274.337738)
			(xy 346.179392 -274.306613) (xy 346.146757 -274.269776) (xy 346.120454 -274.22818) (xy 346.101163 -274.182904)
			(xy 346.089386 -274.13512) (xy 346.085426 -274.086066) (xy 345.756484 -274.086066) (xy 345.755989 -274.110673)
			(xy 345.748094 -274.15925) (xy 345.73251 -274.205931) (xy 345.709639 -274.249508) (xy 345.680074 -274.288852)
			(xy 345.644581 -274.322944) (xy 345.604078 -274.3509) (xy 345.559616 -274.371998) (xy 345.512345 -274.38569)
			(xy 345.46349 -274.391622) (xy 345.414315 -274.389641) (xy 345.366096 -274.379797) (xy 345.32008 -274.362345)
			(xy 345.277459 -274.337738) (xy 345.239338 -274.306613) (xy 345.206703 -274.269776) (xy 345.1804 -274.22818)
			(xy 345.161109 -274.182904) (xy 345.149332 -274.13512) (xy 345.145372 -274.086066) (xy 344.81643 -274.086066)
			(xy 344.815935 -274.110673) (xy 344.80804 -274.15925) (xy 344.792456 -274.205931) (xy 344.769585 -274.249508)
			(xy 344.74002 -274.288852) (xy 344.704527 -274.322944) (xy 344.664024 -274.3509) (xy 344.619562 -274.371998)
			(xy 344.572291 -274.38569) (xy 344.523436 -274.391622) (xy 344.474261 -274.389641) (xy 344.426042 -274.379797)
			(xy 344.380026 -274.362345) (xy 344.337405 -274.337738) (xy 344.299284 -274.306613) (xy 344.266649 -274.269776)
			(xy 344.240346 -274.22818) (xy 344.221055 -274.182904) (xy 344.209278 -274.13512) (xy 344.205318 -274.086066)
			(xy 343.88679 -274.086066) (xy 343.886278 -274.111512) (xy 343.878114 -274.161746) (xy 343.861998 -274.21002)
			(xy 343.838347 -274.255083) (xy 343.807774 -274.295769) (xy 343.77107 -274.331024) (xy 343.729186 -274.359934)
			(xy 343.683207 -274.381751) (xy 343.634323 -274.395911) (xy 343.583802 -274.402045) (xy 343.53295 -274.399996)
			(xy 343.483086 -274.389816) (xy 343.4355 -274.371769) (xy 343.391426 -274.346323) (xy 343.352004 -274.314136)
			(xy 343.318256 -274.276042) (xy 343.291055 -274.233028) (xy 343.271107 -274.186208) (xy 343.258928 -274.136794)
			(xy 343.254833 -274.086066) (xy 342.946736 -274.086066) (xy 342.946224 -274.111512) (xy 342.93806 -274.161746)
			(xy 342.921944 -274.21002) (xy 342.898293 -274.255083) (xy 342.86772 -274.295769) (xy 342.831016 -274.331024)
			(xy 342.789132 -274.359934) (xy 342.743153 -274.381751) (xy 342.694269 -274.395911) (xy 342.643748 -274.402045)
			(xy 342.592896 -274.399996) (xy 342.543032 -274.389816) (xy 342.495446 -274.371769) (xy 342.451372 -274.346323)
			(xy 342.41195 -274.314136) (xy 342.378202 -274.276042) (xy 342.351001 -274.233028) (xy 342.331053 -274.186208)
			(xy 342.318874 -274.136794) (xy 342.314779 -274.086066) (xy 341.997062 -274.086066) (xy 341.997065 -274.0861)
			(xy 341.992894 -274.136442) (xy 341.980493 -274.185411) (xy 341.960202 -274.231672) (xy 341.932574 -274.273962)
			(xy 341.898362 -274.311127) (xy 341.8585 -274.342155) (xy 341.814074 -274.366199) (xy 341.766297 -274.382603)
			(xy 341.716471 -274.390919) (xy 341.691214 -274.391374) (xy 341.678451 -274.391238) (xy 341.653016 -274.38908)
			(xy 341.640414 -274.387056) (xy 341.640414 -274.38731) (xy 341.616961 -274.382883) (xy 341.571707 -274.36772)
			(xy 341.529357 -274.345716) (xy 341.490936 -274.317403) (xy 341.457377 -274.283468) (xy 341.443056 -274.264374)
			(xy 341.438992 -274.258532) (xy 341.428324 -274.249896) (xy 341.422482 -274.247356) (xy 341.416199 -274.244833)
			(xy 341.402805 -274.242893) (xy 341.396066 -274.243546) (xy 341.305642 -274.254976) (xy 341.293196 -274.2565)
			(xy 341.28202 -274.265136) (xy 341.276887 -274.269477) (xy 341.268897 -274.280283) (xy 341.266272 -274.286472)
			(xy 341.266272 -274.286726) (xy 341.258703 -274.305625) (xy 341.241161 -274.342366) (xy 341.23122 -274.360132)
			(xy 341.227918 -274.365974) (xy 341.226394 -274.37207) (xy 341.224616 -274.385024) (xy 341.224616 -274.544282)
			(xy 341.224973 -274.553299) (xy 341.231217 -274.570218) (xy 341.236808 -274.577302) (xy 341.24265 -274.58416)
			(xy 341.258652 -274.59305) (xy 341.267542 -274.59432) (xy 341.291262 -274.598428) (xy 341.337102 -274.613125)
			(xy 341.380068 -274.634833) (xy 341.419095 -274.663013) (xy 341.453217 -274.696969) (xy 341.481588 -274.735858)
			(xy 341.503505 -274.778717) (xy 341.518426 -274.824485) (xy 341.52598 -274.872027) (xy 341.52598 -274.896072)
			(xy 341.844879 -274.896072) (xy 341.848974 -274.845344) (xy 341.861153 -274.79593) (xy 341.881101 -274.74911)
			(xy 341.908302 -274.706096) (xy 341.94205 -274.668002) (xy 341.981472 -274.635815) (xy 342.025546 -274.610369)
			(xy 342.073132 -274.592322) (xy 342.122996 -274.582142) (xy 342.173848 -274.580093) (xy 342.224369 -274.586227)
			(xy 342.273253 -274.600387) (xy 342.319232 -274.622204) (xy 342.361116 -274.651114) (xy 342.39782 -274.686369)
			(xy 342.428393 -274.727055) (xy 342.452044 -274.772118) (xy 342.46816 -274.820392) (xy 342.476324 -274.870626)
			(xy 342.476836 -274.896072) (xy 342.795364 -274.896072) (xy 342.799324 -274.847018) (xy 342.811101 -274.799234)
			(xy 342.830392 -274.753958) (xy 342.856695 -274.712362) (xy 342.88933 -274.675525) (xy 342.927451 -274.6444)
			(xy 342.970072 -274.619793) (xy 343.016088 -274.602341) (xy 343.064307 -274.592497) (xy 343.113482 -274.590516)
			(xy 343.162337 -274.596448) (xy 343.209608 -274.61014) (xy 343.25407 -274.631238) (xy 343.294573 -274.659194)
			(xy 343.330066 -274.693286) (xy 343.359631 -274.73263) (xy 343.382502 -274.776207) (xy 343.398086 -274.822888)
			(xy 343.405981 -274.871465) (xy 343.406476 -274.896072) (xy 343.724987 -274.896072) (xy 343.729082 -274.845344)
			(xy 343.741261 -274.79593) (xy 343.761209 -274.74911) (xy 343.78841 -274.706096) (xy 343.822158 -274.668002)
			(xy 343.86158 -274.635815) (xy 343.905654 -274.610369) (xy 343.95324 -274.592322) (xy 344.003104 -274.582142)
			(xy 344.053956 -274.580093) (xy 344.104477 -274.586227) (xy 344.153361 -274.600387) (xy 344.19934 -274.622204)
			(xy 344.241224 -274.651114) (xy 344.277928 -274.686369) (xy 344.308501 -274.727055) (xy 344.332152 -274.772118)
			(xy 344.348268 -274.820392) (xy 344.356432 -274.870626) (xy 344.356944 -274.896072) (xy 344.675218 -274.896072)
			(xy 344.679178 -274.847018) (xy 344.690955 -274.799234) (xy 344.710246 -274.753958) (xy 344.736549 -274.712362)
			(xy 344.769184 -274.675525) (xy 344.807305 -274.6444) (xy 344.849926 -274.619793) (xy 344.895942 -274.602341)
			(xy 344.944161 -274.592497) (xy 344.993336 -274.590516) (xy 345.042191 -274.596448) (xy 345.089462 -274.61014)
			(xy 345.133924 -274.631238) (xy 345.174427 -274.659194) (xy 345.20992 -274.693286) (xy 345.239485 -274.73263)
			(xy 345.262356 -274.776207) (xy 345.27794 -274.822888) (xy 345.285835 -274.871465) (xy 345.28633 -274.896072)
			(xy 345.615272 -274.896072) (xy 345.619232 -274.847018) (xy 345.631009 -274.799234) (xy 345.6503 -274.753958)
			(xy 345.676603 -274.712362) (xy 345.709238 -274.675525) (xy 345.747359 -274.6444) (xy 345.78998 -274.619793)
			(xy 345.835996 -274.602341) (xy 345.884215 -274.592497) (xy 345.93339 -274.590516) (xy 345.982245 -274.596448)
			(xy 346.029516 -274.61014) (xy 346.073978 -274.631238) (xy 346.114481 -274.659194) (xy 346.149974 -274.693286)
			(xy 346.179539 -274.73263) (xy 346.20241 -274.776207) (xy 346.217994 -274.822888) (xy 346.225889 -274.871465)
			(xy 346.226384 -274.896072) (xy 346.555326 -274.896072) (xy 346.559286 -274.847018) (xy 346.571063 -274.799234)
			(xy 346.590354 -274.753958) (xy 346.616657 -274.712362) (xy 346.649292 -274.675525) (xy 346.687413 -274.6444)
			(xy 346.730034 -274.619793) (xy 346.77605 -274.602341) (xy 346.824269 -274.592497) (xy 346.873444 -274.590516)
			(xy 346.922299 -274.596448) (xy 346.96957 -274.61014) (xy 347.014032 -274.631238) (xy 347.054535 -274.659194)
			(xy 347.090028 -274.693286) (xy 347.119593 -274.73263) (xy 347.142464 -274.776207) (xy 347.158048 -274.822888)
			(xy 347.165943 -274.871465) (xy 347.166438 -274.896072) (xy 347.49538 -274.896072) (xy 347.49934 -274.847018)
			(xy 347.511117 -274.799234) (xy 347.530408 -274.753958) (xy 347.556711 -274.712362) (xy 347.589346 -274.675525)
			(xy 347.627467 -274.6444) (xy 347.670088 -274.619793) (xy 347.716104 -274.602341) (xy 347.764323 -274.592497)
			(xy 347.813498 -274.590516) (xy 347.862353 -274.596448) (xy 347.909624 -274.61014) (xy 347.954086 -274.631238)
			(xy 347.994589 -274.659194) (xy 348.030082 -274.693286) (xy 348.059647 -274.73263) (xy 348.082518 -274.776207)
			(xy 348.098102 -274.822888) (xy 348.105997 -274.871465) (xy 348.106492 -274.896072) (xy 348.435434 -274.896072)
			(xy 348.439394 -274.847018) (xy 348.451171 -274.799234) (xy 348.470462 -274.753958) (xy 348.496765 -274.712362)
			(xy 348.5294 -274.675525) (xy 348.567521 -274.6444) (xy 348.610142 -274.619793) (xy 348.656158 -274.602341)
			(xy 348.704377 -274.592497) (xy 348.753552 -274.590516) (xy 348.802407 -274.596448) (xy 348.849678 -274.61014)
			(xy 348.89414 -274.631238) (xy 348.934643 -274.659194) (xy 348.970136 -274.693286) (xy 348.999701 -274.73263)
			(xy 349.022572 -274.776207) (xy 349.038156 -274.822888) (xy 349.046051 -274.871465) (xy 349.046546 -274.896072)
			(xy 349.375234 -274.896072) (xy 349.379194 -274.847018) (xy 349.390971 -274.799234) (xy 349.410262 -274.753958)
			(xy 349.436565 -274.712362) (xy 349.4692 -274.675525) (xy 349.507321 -274.6444) (xy 349.549942 -274.619793)
			(xy 349.595958 -274.602341) (xy 349.644177 -274.592497) (xy 349.693352 -274.590516) (xy 349.742207 -274.596448)
			(xy 349.789478 -274.61014) (xy 349.83394 -274.631238) (xy 349.874443 -274.659194) (xy 349.909936 -274.693286)
			(xy 349.939501 -274.73263) (xy 349.962372 -274.776207) (xy 349.977956 -274.822888) (xy 349.985851 -274.871465)
			(xy 349.986346 -274.896072) (xy 350.315288 -274.896072) (xy 350.319248 -274.847018) (xy 350.331025 -274.799234)
			(xy 350.350316 -274.753958) (xy 350.376619 -274.712362) (xy 350.409254 -274.675525) (xy 350.447375 -274.6444)
			(xy 350.489996 -274.619793) (xy 350.536012 -274.602341) (xy 350.584231 -274.592497) (xy 350.633406 -274.590516)
			(xy 350.682261 -274.596448) (xy 350.729532 -274.61014) (xy 350.773994 -274.631238) (xy 350.814497 -274.659194)
			(xy 350.84999 -274.693286) (xy 350.879555 -274.73263) (xy 350.902426 -274.776207) (xy 350.91801 -274.822888)
			(xy 350.925905 -274.871465) (xy 350.9264 -274.896072) (xy 351.255342 -274.896072) (xy 351.259302 -274.847018)
			(xy 351.271079 -274.799234) (xy 351.29037 -274.753958) (xy 351.316673 -274.712362) (xy 351.349308 -274.675525)
			(xy 351.387429 -274.6444) (xy 351.43005 -274.619793) (xy 351.476066 -274.602341) (xy 351.524285 -274.592497)
			(xy 351.57346 -274.590516) (xy 351.622315 -274.596448) (xy 351.669586 -274.61014) (xy 351.714048 -274.631238)
			(xy 351.754551 -274.659194) (xy 351.790044 -274.693286) (xy 351.819609 -274.73263) (xy 351.84248 -274.776207)
			(xy 351.858064 -274.822888) (xy 351.865959 -274.871465) (xy 351.866454 -274.896072) (xy 352.195396 -274.896072)
			(xy 352.199356 -274.847018) (xy 352.211133 -274.799234) (xy 352.230424 -274.753958) (xy 352.256727 -274.712362)
			(xy 352.289362 -274.675525) (xy 352.327483 -274.6444) (xy 352.370104 -274.619793) (xy 352.41612 -274.602341)
			(xy 352.464339 -274.592497) (xy 352.513514 -274.590516) (xy 352.562369 -274.596448) (xy 352.60964 -274.61014)
			(xy 352.654102 -274.631238) (xy 352.694605 -274.659194) (xy 352.730098 -274.693286) (xy 352.759663 -274.73263)
			(xy 352.782534 -274.776207) (xy 352.798118 -274.822888) (xy 352.806013 -274.871465) (xy 352.806508 -274.896072)
			(xy 353.135196 -274.896072) (xy 353.139156 -274.847018) (xy 353.150933 -274.799234) (xy 353.170224 -274.753958)
			(xy 353.196527 -274.712362) (xy 353.229162 -274.675525) (xy 353.267283 -274.6444) (xy 353.309904 -274.619793)
			(xy 353.35592 -274.602341) (xy 353.404139 -274.592497) (xy 353.453314 -274.590516) (xy 353.502169 -274.596448)
			(xy 353.54944 -274.61014) (xy 353.593902 -274.631238) (xy 353.634405 -274.659194) (xy 353.669898 -274.693286)
			(xy 353.699463 -274.73263) (xy 353.722334 -274.776207) (xy 353.737918 -274.822888) (xy 353.745813 -274.871465)
			(xy 353.746308 -274.896072) (xy 354.07525 -274.896072) (xy 354.07921 -274.847018) (xy 354.090987 -274.799234)
			(xy 354.110278 -274.753958) (xy 354.136581 -274.712362) (xy 354.169216 -274.675525) (xy 354.207337 -274.6444)
			(xy 354.249958 -274.619793) (xy 354.295974 -274.602341) (xy 354.344193 -274.592497) (xy 354.393368 -274.590516)
			(xy 354.442223 -274.596448) (xy 354.489494 -274.61014) (xy 354.533956 -274.631238) (xy 354.574459 -274.659194)
			(xy 354.609952 -274.693286) (xy 354.639517 -274.73263) (xy 354.662388 -274.776207) (xy 354.677972 -274.822888)
			(xy 354.685867 -274.871465) (xy 354.686362 -274.896072) (xy 355.015304 -274.896072) (xy 355.019264 -274.847018)
			(xy 355.031041 -274.799234) (xy 355.050332 -274.753958) (xy 355.076635 -274.712362) (xy 355.10927 -274.675525)
			(xy 355.147391 -274.6444) (xy 355.190012 -274.619793) (xy 355.236028 -274.602341) (xy 355.284247 -274.592497)
			(xy 355.333422 -274.590516) (xy 355.382277 -274.596448) (xy 355.429548 -274.61014) (xy 355.47401 -274.631238)
			(xy 355.514513 -274.659194) (xy 355.550006 -274.693286) (xy 355.579571 -274.73263) (xy 355.602442 -274.776207)
			(xy 355.618026 -274.822888) (xy 355.625921 -274.871465) (xy 355.626416 -274.896072) (xy 355.955358 -274.896072)
			(xy 355.959318 -274.847018) (xy 355.971095 -274.799234) (xy 355.990386 -274.753958) (xy 356.016689 -274.712362)
			(xy 356.049324 -274.675525) (xy 356.087445 -274.6444) (xy 356.130066 -274.619793) (xy 356.176082 -274.602341)
			(xy 356.224301 -274.592497) (xy 356.273476 -274.590516) (xy 356.322331 -274.596448) (xy 356.369602 -274.61014)
			(xy 356.414064 -274.631238) (xy 356.454567 -274.659194) (xy 356.49006 -274.693286) (xy 356.519625 -274.73263)
			(xy 356.542496 -274.776207) (xy 356.55808 -274.822888) (xy 356.565975 -274.871465) (xy 356.56647 -274.896072)
			(xy 363.468932 -274.896072) (xy 363.472892 -274.847018) (xy 363.484669 -274.799234) (xy 363.50396 -274.753958)
			(xy 363.530263 -274.712362) (xy 363.562898 -274.675525) (xy 363.601019 -274.6444) (xy 363.64364 -274.619793)
			(xy 363.689656 -274.602341) (xy 363.737875 -274.592497) (xy 363.78705 -274.590516) (xy 363.835905 -274.596448)
			(xy 363.883176 -274.61014) (xy 363.927638 -274.631238) (xy 363.968141 -274.659194) (xy 364.003634 -274.693286)
			(xy 364.033199 -274.73263) (xy 364.05607 -274.776207) (xy 364.071654 -274.822888) (xy 364.079549 -274.871465)
			(xy 364.080044 -274.896072) (xy 364.408986 -274.896072) (xy 364.412946 -274.847018) (xy 364.424723 -274.799234)
			(xy 364.444014 -274.753958) (xy 364.470317 -274.712362) (xy 364.502952 -274.675525) (xy 364.541073 -274.6444)
			(xy 364.583694 -274.619793) (xy 364.62971 -274.602341) (xy 364.677929 -274.592497) (xy 364.727104 -274.590516)
			(xy 364.775959 -274.596448) (xy 364.82323 -274.61014) (xy 364.867692 -274.631238) (xy 364.908195 -274.659194)
			(xy 364.943688 -274.693286) (xy 364.973253 -274.73263) (xy 364.996124 -274.776207) (xy 365.011708 -274.822888)
			(xy 365.019603 -274.871465) (xy 365.020098 -274.896072) (xy 365.34904 -274.896072) (xy 365.353 -274.847018)
			(xy 365.364777 -274.799234) (xy 365.384068 -274.753958) (xy 365.410371 -274.712362) (xy 365.443006 -274.675525)
			(xy 365.481127 -274.6444) (xy 365.523748 -274.619793) (xy 365.569764 -274.602341) (xy 365.617983 -274.592497)
			(xy 365.667158 -274.590516) (xy 365.716013 -274.596448) (xy 365.763284 -274.61014) (xy 365.807746 -274.631238)
			(xy 365.848249 -274.659194) (xy 365.883742 -274.693286) (xy 365.913307 -274.73263) (xy 365.936178 -274.776207)
			(xy 365.951762 -274.822888) (xy 365.959657 -274.871465) (xy 365.960152 -274.896072) (xy 366.289094 -274.896072)
			(xy 366.293054 -274.847018) (xy 366.304831 -274.799234) (xy 366.324122 -274.753958) (xy 366.350425 -274.712362)
			(xy 366.38306 -274.675525) (xy 366.421181 -274.6444) (xy 366.463802 -274.619793) (xy 366.509818 -274.602341)
			(xy 366.558037 -274.592497) (xy 366.607212 -274.590516) (xy 366.656067 -274.596448) (xy 366.703338 -274.61014)
			(xy 366.7478 -274.631238) (xy 366.788303 -274.659194) (xy 366.823796 -274.693286) (xy 366.853361 -274.73263)
			(xy 366.876232 -274.776207) (xy 366.891816 -274.822888) (xy 366.899711 -274.871465) (xy 366.900206 -274.896072)
			(xy 367.228894 -274.896072) (xy 367.232854 -274.847018) (xy 367.244631 -274.799234) (xy 367.263922 -274.753958)
			(xy 367.290225 -274.712362) (xy 367.32286 -274.675525) (xy 367.360981 -274.6444) (xy 367.403602 -274.619793)
			(xy 367.449618 -274.602341) (xy 367.497837 -274.592497) (xy 367.547012 -274.590516) (xy 367.595867 -274.596448)
			(xy 367.643138 -274.61014) (xy 367.6876 -274.631238) (xy 367.728103 -274.659194) (xy 367.763596 -274.693286)
			(xy 367.793161 -274.73263) (xy 367.816032 -274.776207) (xy 367.831616 -274.822888) (xy 367.839511 -274.871465)
			(xy 367.840006 -274.896072) (xy 368.168948 -274.896072) (xy 368.172908 -274.847018) (xy 368.184685 -274.799234)
			(xy 368.203976 -274.753958) (xy 368.230279 -274.712362) (xy 368.262914 -274.675525) (xy 368.301035 -274.6444)
			(xy 368.343656 -274.619793) (xy 368.389672 -274.602341) (xy 368.437891 -274.592497) (xy 368.487066 -274.590516)
			(xy 368.535921 -274.596448) (xy 368.583192 -274.61014) (xy 368.627654 -274.631238) (xy 368.668157 -274.659194)
			(xy 368.70365 -274.693286) (xy 368.733215 -274.73263) (xy 368.756086 -274.776207) (xy 368.77167 -274.822888)
			(xy 368.779565 -274.871465) (xy 368.78006 -274.896072) (xy 369.109002 -274.896072) (xy 369.112962 -274.847018)
			(xy 369.124739 -274.799234) (xy 369.14403 -274.753958) (xy 369.170333 -274.712362) (xy 369.202968 -274.675525)
			(xy 369.241089 -274.6444) (xy 369.28371 -274.619793) (xy 369.329726 -274.602341) (xy 369.377945 -274.592497)
			(xy 369.42712 -274.590516) (xy 369.475975 -274.596448) (xy 369.523246 -274.61014) (xy 369.567708 -274.631238)
			(xy 369.608211 -274.659194) (xy 369.643704 -274.693286) (xy 369.673269 -274.73263) (xy 369.69614 -274.776207)
			(xy 369.711724 -274.822888) (xy 369.719619 -274.871465) (xy 369.720114 -274.896072) (xy 370.049056 -274.896072)
			(xy 370.053016 -274.847018) (xy 370.064793 -274.799234) (xy 370.084084 -274.753958) (xy 370.110387 -274.712362)
			(xy 370.143022 -274.675525) (xy 370.181143 -274.6444) (xy 370.223764 -274.619793) (xy 370.26978 -274.602341)
			(xy 370.317999 -274.592497) (xy 370.367174 -274.590516) (xy 370.416029 -274.596448) (xy 370.4633 -274.61014)
			(xy 370.507762 -274.631238) (xy 370.548265 -274.659194) (xy 370.583758 -274.693286) (xy 370.613323 -274.73263)
			(xy 370.636194 -274.776207) (xy 370.651778 -274.822888) (xy 370.659673 -274.871465) (xy 370.660168 -274.896072)
			(xy 370.98911 -274.896072) (xy 370.99307 -274.847018) (xy 371.004847 -274.799234) (xy 371.024138 -274.753958)
			(xy 371.050441 -274.712362) (xy 371.083076 -274.675525) (xy 371.121197 -274.6444) (xy 371.163818 -274.619793)
			(xy 371.209834 -274.602341) (xy 371.258053 -274.592497) (xy 371.307228 -274.590516) (xy 371.356083 -274.596448)
			(xy 371.403354 -274.61014) (xy 371.447816 -274.631238) (xy 371.488319 -274.659194) (xy 371.523812 -274.693286)
			(xy 371.553377 -274.73263) (xy 371.576248 -274.776207) (xy 371.591832 -274.822888) (xy 371.599727 -274.871465)
			(xy 371.600222 -274.896072) (xy 371.92891 -274.896072) (xy 371.93287 -274.847018) (xy 371.944647 -274.799234)
			(xy 371.963938 -274.753958) (xy 371.990241 -274.712362) (xy 372.022876 -274.675525) (xy 372.060997 -274.6444)
			(xy 372.103618 -274.619793) (xy 372.149634 -274.602341) (xy 372.197853 -274.592497) (xy 372.247028 -274.590516)
			(xy 372.295883 -274.596448) (xy 372.343154 -274.61014) (xy 372.387616 -274.631238) (xy 372.428119 -274.659194)
			(xy 372.463612 -274.693286) (xy 372.493177 -274.73263) (xy 372.516048 -274.776207) (xy 372.531632 -274.822888)
			(xy 372.539527 -274.871465) (xy 372.540022 -274.896072) (xy 372.868964 -274.896072) (xy 372.872924 -274.847018)
			(xy 372.884701 -274.799234) (xy 372.903992 -274.753958) (xy 372.930295 -274.712362) (xy 372.96293 -274.675525)
			(xy 373.001051 -274.6444) (xy 373.043672 -274.619793) (xy 373.089688 -274.602341) (xy 373.137907 -274.592497)
			(xy 373.187082 -274.590516) (xy 373.235937 -274.596448) (xy 373.283208 -274.61014) (xy 373.32767 -274.631238)
			(xy 373.368173 -274.659194) (xy 373.403666 -274.693286) (xy 373.433231 -274.73263) (xy 373.456102 -274.776207)
			(xy 373.471686 -274.822888) (xy 373.479581 -274.871465) (xy 373.480076 -274.896072) (xy 373.809018 -274.896072)
			(xy 373.812978 -274.847018) (xy 373.824755 -274.799234) (xy 373.844046 -274.753958) (xy 373.870349 -274.712362)
			(xy 373.902984 -274.675525) (xy 373.941105 -274.6444) (xy 373.983726 -274.619793) (xy 374.029742 -274.602341)
			(xy 374.077961 -274.592497) (xy 374.127136 -274.590516) (xy 374.175991 -274.596448) (xy 374.223262 -274.61014)
			(xy 374.267724 -274.631238) (xy 374.308227 -274.659194) (xy 374.34372 -274.693286) (xy 374.373285 -274.73263)
			(xy 374.396156 -274.776207) (xy 374.41174 -274.822888) (xy 374.419635 -274.871465) (xy 374.42013 -274.896072)
			(xy 374.749072 -274.896072) (xy 374.753032 -274.847018) (xy 374.764809 -274.799234) (xy 374.7841 -274.753958)
			(xy 374.810403 -274.712362) (xy 374.843038 -274.675525) (xy 374.881159 -274.6444) (xy 374.92378 -274.619793)
			(xy 374.969796 -274.602341) (xy 375.018015 -274.592497) (xy 375.06719 -274.590516) (xy 375.116045 -274.596448)
			(xy 375.163316 -274.61014) (xy 375.207778 -274.631238) (xy 375.248281 -274.659194) (xy 375.283774 -274.693286)
			(xy 375.313339 -274.73263) (xy 375.33621 -274.776207) (xy 375.351794 -274.822888) (xy 375.359689 -274.871465)
			(xy 375.360184 -274.896072) (xy 375.678695 -274.896072) (xy 375.68279 -274.845344) (xy 375.694969 -274.79593)
			(xy 375.714917 -274.74911) (xy 375.742118 -274.706096) (xy 375.775866 -274.668002) (xy 375.815288 -274.635815)
			(xy 375.859362 -274.610369) (xy 375.906948 -274.592322) (xy 375.956812 -274.582142) (xy 376.007664 -274.580093)
			(xy 376.058185 -274.586227) (xy 376.107069 -274.600387) (xy 376.153048 -274.622204) (xy 376.194932 -274.651114)
			(xy 376.231636 -274.686369) (xy 376.262209 -274.727055) (xy 376.28586 -274.772118) (xy 376.301976 -274.820392)
			(xy 376.31014 -274.870626) (xy 376.310652 -274.896072) (xy 376.628926 -274.896072) (xy 376.632886 -274.847018)
			(xy 376.644663 -274.799234) (xy 376.663954 -274.753958) (xy 376.690257 -274.712362) (xy 376.722892 -274.675525)
			(xy 376.761013 -274.6444) (xy 376.803634 -274.619793) (xy 376.84965 -274.602341) (xy 376.897869 -274.592497)
			(xy 376.947044 -274.590516) (xy 376.995899 -274.596448) (xy 377.04317 -274.61014) (xy 377.087632 -274.631238)
			(xy 377.128135 -274.659194) (xy 377.163628 -274.693286) (xy 377.193193 -274.73263) (xy 377.216064 -274.776207)
			(xy 377.231648 -274.822888) (xy 377.239543 -274.871465) (xy 377.240038 -274.896072) (xy 377.558549 -274.896072)
			(xy 377.562644 -274.845344) (xy 377.574823 -274.79593) (xy 377.594771 -274.74911) (xy 377.621972 -274.706096)
			(xy 377.65572 -274.668002) (xy 377.695142 -274.635815) (xy 377.739216 -274.610369) (xy 377.786802 -274.592322)
			(xy 377.836666 -274.582142) (xy 377.887518 -274.580093) (xy 377.938039 -274.586227) (xy 377.986923 -274.600387)
			(xy 378.032902 -274.622204) (xy 378.074786 -274.651114) (xy 378.11149 -274.686369) (xy 378.142063 -274.727055)
			(xy 378.165714 -274.772118) (xy 378.18183 -274.820392) (xy 378.189994 -274.870626) (xy 378.190506 -274.896072)
			(xy 378.189994 -274.921518) (xy 378.18183 -274.971752) (xy 378.165714 -275.020026) (xy 378.142063 -275.065089)
			(xy 378.11149 -275.105775) (xy 378.074786 -275.14103) (xy 378.032902 -275.16994) (xy 377.986923 -275.191757)
			(xy 377.938039 -275.205917) (xy 377.887518 -275.212051) (xy 377.836666 -275.210002) (xy 377.786802 -275.199822)
			(xy 377.739216 -275.181775) (xy 377.695142 -275.156329) (xy 377.65572 -275.124142) (xy 377.621972 -275.086048)
			(xy 377.594771 -275.043034) (xy 377.574823 -274.996214) (xy 377.562644 -274.9468) (xy 377.558549 -274.896072)
			(xy 377.240038 -274.896072) (xy 377.239543 -274.920679) (xy 377.231648 -274.969256) (xy 377.216064 -275.015937)
			(xy 377.193193 -275.059514) (xy 377.163628 -275.098858) (xy 377.128135 -275.13295) (xy 377.087632 -275.160906)
			(xy 377.04317 -275.182004) (xy 376.995899 -275.195696) (xy 376.947044 -275.201628) (xy 376.897869 -275.199647)
			(xy 376.84965 -275.189803) (xy 376.803634 -275.172351) (xy 376.761013 -275.147744) (xy 376.722892 -275.116619)
			(xy 376.690257 -275.079782) (xy 376.663954 -275.038186) (xy 376.644663 -274.99291) (xy 376.632886 -274.945126)
			(xy 376.628926 -274.896072) (xy 376.310652 -274.896072) (xy 376.31014 -274.921518) (xy 376.301976 -274.971752)
			(xy 376.28586 -275.020026) (xy 376.262209 -275.065089) (xy 376.231636 -275.105775) (xy 376.194932 -275.14103)
			(xy 376.153048 -275.16994) (xy 376.107069 -275.191757) (xy 376.058185 -275.205917) (xy 376.007664 -275.212051)
			(xy 375.956812 -275.210002) (xy 375.906948 -275.199822) (xy 375.859362 -275.181775) (xy 375.815288 -275.156329)
			(xy 375.775866 -275.124142) (xy 375.742118 -275.086048) (xy 375.714917 -275.043034) (xy 375.694969 -274.996214)
			(xy 375.68279 -274.9468) (xy 375.678695 -274.896072) (xy 375.360184 -274.896072) (xy 375.359689 -274.920679)
			(xy 375.351794 -274.969256) (xy 375.33621 -275.015937) (xy 375.313339 -275.059514) (xy 375.283774 -275.098858)
			(xy 375.248281 -275.13295) (xy 375.207778 -275.160906) (xy 375.163316 -275.182004) (xy 375.116045 -275.195696)
			(xy 375.06719 -275.201628) (xy 375.018015 -275.199647) (xy 374.969796 -275.189803) (xy 374.92378 -275.172351)
			(xy 374.881159 -275.147744) (xy 374.843038 -275.116619) (xy 374.810403 -275.079782) (xy 374.7841 -275.038186)
			(xy 374.764809 -274.99291) (xy 374.753032 -274.945126) (xy 374.749072 -274.896072) (xy 374.42013 -274.896072)
			(xy 374.419635 -274.920679) (xy 374.41174 -274.969256) (xy 374.396156 -275.015937) (xy 374.373285 -275.059514)
			(xy 374.34372 -275.098858) (xy 374.308227 -275.13295) (xy 374.267724 -275.160906) (xy 374.223262 -275.182004)
			(xy 374.175991 -275.195696) (xy 374.127136 -275.201628) (xy 374.077961 -275.199647) (xy 374.029742 -275.189803)
			(xy 373.983726 -275.172351) (xy 373.941105 -275.147744) (xy 373.902984 -275.116619) (xy 373.870349 -275.079782)
			(xy 373.844046 -275.038186) (xy 373.824755 -274.99291) (xy 373.812978 -274.945126) (xy 373.809018 -274.896072)
			(xy 373.480076 -274.896072) (xy 373.479581 -274.920679) (xy 373.471686 -274.969256) (xy 373.456102 -275.015937)
			(xy 373.433231 -275.059514) (xy 373.403666 -275.098858) (xy 373.368173 -275.13295) (xy 373.32767 -275.160906)
			(xy 373.283208 -275.182004) (xy 373.235937 -275.195696) (xy 373.187082 -275.201628) (xy 373.137907 -275.199647)
			(xy 373.089688 -275.189803) (xy 373.043672 -275.172351) (xy 373.001051 -275.147744) (xy 372.96293 -275.116619)
			(xy 372.930295 -275.079782) (xy 372.903992 -275.038186) (xy 372.884701 -274.99291) (xy 372.872924 -274.945126)
			(xy 372.868964 -274.896072) (xy 372.540022 -274.896072) (xy 372.539527 -274.920679) (xy 372.531632 -274.969256)
			(xy 372.516048 -275.015937) (xy 372.493177 -275.059514) (xy 372.463612 -275.098858) (xy 372.428119 -275.13295)
			(xy 372.387616 -275.160906) (xy 372.343154 -275.182004) (xy 372.295883 -275.195696) (xy 372.247028 -275.201628)
			(xy 372.197853 -275.199647) (xy 372.149634 -275.189803) (xy 372.103618 -275.172351) (xy 372.060997 -275.147744)
			(xy 372.022876 -275.116619) (xy 371.990241 -275.079782) (xy 371.963938 -275.038186) (xy 371.944647 -274.99291)
			(xy 371.93287 -274.945126) (xy 371.92891 -274.896072) (xy 371.600222 -274.896072) (xy 371.599727 -274.920679)
			(xy 371.591832 -274.969256) (xy 371.576248 -275.015937) (xy 371.553377 -275.059514) (xy 371.523812 -275.098858)
			(xy 371.488319 -275.13295) (xy 371.447816 -275.160906) (xy 371.403354 -275.182004) (xy 371.356083 -275.195696)
			(xy 371.307228 -275.201628) (xy 371.258053 -275.199647) (xy 371.209834 -275.189803) (xy 371.163818 -275.172351)
			(xy 371.121197 -275.147744) (xy 371.083076 -275.116619) (xy 371.050441 -275.079782) (xy 371.024138 -275.038186)
			(xy 371.004847 -274.99291) (xy 370.99307 -274.945126) (xy 370.98911 -274.896072) (xy 370.660168 -274.896072)
			(xy 370.659673 -274.920679) (xy 370.651778 -274.969256) (xy 370.636194 -275.015937) (xy 370.613323 -275.059514)
			(xy 370.583758 -275.098858) (xy 370.548265 -275.13295) (xy 370.507762 -275.160906) (xy 370.4633 -275.182004)
			(xy 370.416029 -275.195696) (xy 370.367174 -275.201628) (xy 370.317999 -275.199647) (xy 370.26978 -275.189803)
			(xy 370.223764 -275.172351) (xy 370.181143 -275.147744) (xy 370.143022 -275.116619) (xy 370.110387 -275.079782)
			(xy 370.084084 -275.038186) (xy 370.064793 -274.99291) (xy 370.053016 -274.945126) (xy 370.049056 -274.896072)
			(xy 369.720114 -274.896072) (xy 369.719619 -274.920679) (xy 369.711724 -274.969256) (xy 369.69614 -275.015937)
			(xy 369.673269 -275.059514) (xy 369.643704 -275.098858) (xy 369.608211 -275.13295) (xy 369.567708 -275.160906)
			(xy 369.523246 -275.182004) (xy 369.475975 -275.195696) (xy 369.42712 -275.201628) (xy 369.377945 -275.199647)
			(xy 369.329726 -275.189803) (xy 369.28371 -275.172351) (xy 369.241089 -275.147744) (xy 369.202968 -275.116619)
			(xy 369.170333 -275.079782) (xy 369.14403 -275.038186) (xy 369.124739 -274.99291) (xy 369.112962 -274.945126)
			(xy 369.109002 -274.896072) (xy 368.78006 -274.896072) (xy 368.779565 -274.920679) (xy 368.77167 -274.969256)
			(xy 368.756086 -275.015937) (xy 368.733215 -275.059514) (xy 368.70365 -275.098858) (xy 368.668157 -275.13295)
			(xy 368.627654 -275.160906) (xy 368.583192 -275.182004) (xy 368.535921 -275.195696) (xy 368.487066 -275.201628)
			(xy 368.437891 -275.199647) (xy 368.389672 -275.189803) (xy 368.343656 -275.172351) (xy 368.301035 -275.147744)
			(xy 368.262914 -275.116619) (xy 368.230279 -275.079782) (xy 368.203976 -275.038186) (xy 368.184685 -274.99291)
			(xy 368.172908 -274.945126) (xy 368.168948 -274.896072) (xy 367.840006 -274.896072) (xy 367.839511 -274.920679)
			(xy 367.831616 -274.969256) (xy 367.816032 -275.015937) (xy 367.793161 -275.059514) (xy 367.763596 -275.098858)
			(xy 367.728103 -275.13295) (xy 367.6876 -275.160906) (xy 367.643138 -275.182004) (xy 367.595867 -275.195696)
			(xy 367.547012 -275.201628) (xy 367.497837 -275.199647) (xy 367.449618 -275.189803) (xy 367.403602 -275.172351)
			(xy 367.360981 -275.147744) (xy 367.32286 -275.116619) (xy 367.290225 -275.079782) (xy 367.263922 -275.038186)
			(xy 367.244631 -274.99291) (xy 367.232854 -274.945126) (xy 367.228894 -274.896072) (xy 366.900206 -274.896072)
			(xy 366.899711 -274.920679) (xy 366.891816 -274.969256) (xy 366.876232 -275.015937) (xy 366.853361 -275.059514)
			(xy 366.823796 -275.098858) (xy 366.788303 -275.13295) (xy 366.7478 -275.160906) (xy 366.703338 -275.182004)
			(xy 366.656067 -275.195696) (xy 366.607212 -275.201628) (xy 366.558037 -275.199647) (xy 366.509818 -275.189803)
			(xy 366.463802 -275.172351) (xy 366.421181 -275.147744) (xy 366.38306 -275.116619) (xy 366.350425 -275.079782)
			(xy 366.324122 -275.038186) (xy 366.304831 -274.99291) (xy 366.293054 -274.945126) (xy 366.289094 -274.896072)
			(xy 365.960152 -274.896072) (xy 365.959657 -274.920679) (xy 365.951762 -274.969256) (xy 365.936178 -275.015937)
			(xy 365.913307 -275.059514) (xy 365.883742 -275.098858) (xy 365.848249 -275.13295) (xy 365.807746 -275.160906)
			(xy 365.763284 -275.182004) (xy 365.716013 -275.195696) (xy 365.667158 -275.201628) (xy 365.617983 -275.199647)
			(xy 365.569764 -275.189803) (xy 365.523748 -275.172351) (xy 365.481127 -275.147744) (xy 365.443006 -275.116619)
			(xy 365.410371 -275.079782) (xy 365.384068 -275.038186) (xy 365.364777 -274.99291) (xy 365.353 -274.945126)
			(xy 365.34904 -274.896072) (xy 365.020098 -274.896072) (xy 365.019603 -274.920679) (xy 365.011708 -274.969256)
			(xy 364.996124 -275.015937) (xy 364.973253 -275.059514) (xy 364.943688 -275.098858) (xy 364.908195 -275.13295)
			(xy 364.867692 -275.160906) (xy 364.82323 -275.182004) (xy 364.775959 -275.195696) (xy 364.727104 -275.201628)
			(xy 364.677929 -275.199647) (xy 364.62971 -275.189803) (xy 364.583694 -275.172351) (xy 364.541073 -275.147744)
			(xy 364.502952 -275.116619) (xy 364.470317 -275.079782) (xy 364.444014 -275.038186) (xy 364.424723 -274.99291)
			(xy 364.412946 -274.945126) (xy 364.408986 -274.896072) (xy 364.080044 -274.896072) (xy 364.079549 -274.920679)
			(xy 364.071654 -274.969256) (xy 364.05607 -275.015937) (xy 364.033199 -275.059514) (xy 364.003634 -275.098858)
			(xy 363.968141 -275.13295) (xy 363.927638 -275.160906) (xy 363.883176 -275.182004) (xy 363.835905 -275.195696)
			(xy 363.78705 -275.201628) (xy 363.737875 -275.199647) (xy 363.689656 -275.189803) (xy 363.64364 -275.172351)
			(xy 363.601019 -275.147744) (xy 363.562898 -275.116619) (xy 363.530263 -275.079782) (xy 363.50396 -275.038186)
			(xy 363.484669 -274.99291) (xy 363.472892 -274.945126) (xy 363.468932 -274.896072) (xy 356.56647 -274.896072)
			(xy 356.565975 -274.920679) (xy 356.55808 -274.969256) (xy 356.542496 -275.015937) (xy 356.519625 -275.059514)
			(xy 356.49006 -275.098858) (xy 356.454567 -275.13295) (xy 356.414064 -275.160906) (xy 356.369602 -275.182004)
			(xy 356.322331 -275.195696) (xy 356.273476 -275.201628) (xy 356.224301 -275.199647) (xy 356.176082 -275.189803)
			(xy 356.130066 -275.172351) (xy 356.087445 -275.147744) (xy 356.049324 -275.116619) (xy 356.016689 -275.079782)
			(xy 355.990386 -275.038186) (xy 355.971095 -274.99291) (xy 355.959318 -274.945126) (xy 355.955358 -274.896072)
			(xy 355.626416 -274.896072) (xy 355.625921 -274.920679) (xy 355.618026 -274.969256) (xy 355.602442 -275.015937)
			(xy 355.579571 -275.059514) (xy 355.550006 -275.098858) (xy 355.514513 -275.13295) (xy 355.47401 -275.160906)
			(xy 355.429548 -275.182004) (xy 355.382277 -275.195696) (xy 355.333422 -275.201628) (xy 355.284247 -275.199647)
			(xy 355.236028 -275.189803) (xy 355.190012 -275.172351) (xy 355.147391 -275.147744) (xy 355.10927 -275.116619)
			(xy 355.076635 -275.079782) (xy 355.050332 -275.038186) (xy 355.031041 -274.99291) (xy 355.019264 -274.945126)
			(xy 355.015304 -274.896072) (xy 354.686362 -274.896072) (xy 354.685867 -274.920679) (xy 354.677972 -274.969256)
			(xy 354.662388 -275.015937) (xy 354.639517 -275.059514) (xy 354.609952 -275.098858) (xy 354.574459 -275.13295)
			(xy 354.533956 -275.160906) (xy 354.489494 -275.182004) (xy 354.442223 -275.195696) (xy 354.393368 -275.201628)
			(xy 354.344193 -275.199647) (xy 354.295974 -275.189803) (xy 354.249958 -275.172351) (xy 354.207337 -275.147744)
			(xy 354.169216 -275.116619) (xy 354.136581 -275.079782) (xy 354.110278 -275.038186) (xy 354.090987 -274.99291)
			(xy 354.07921 -274.945126) (xy 354.07525 -274.896072) (xy 353.746308 -274.896072) (xy 353.745813 -274.920679)
			(xy 353.737918 -274.969256) (xy 353.722334 -275.015937) (xy 353.699463 -275.059514) (xy 353.669898 -275.098858)
			(xy 353.634405 -275.13295) (xy 353.593902 -275.160906) (xy 353.54944 -275.182004) (xy 353.502169 -275.195696)
			(xy 353.453314 -275.201628) (xy 353.404139 -275.199647) (xy 353.35592 -275.189803) (xy 353.309904 -275.172351)
			(xy 353.267283 -275.147744) (xy 353.229162 -275.116619) (xy 353.196527 -275.079782) (xy 353.170224 -275.038186)
			(xy 353.150933 -274.99291) (xy 353.139156 -274.945126) (xy 353.135196 -274.896072) (xy 352.806508 -274.896072)
			(xy 352.806013 -274.920679) (xy 352.798118 -274.969256) (xy 352.782534 -275.015937) (xy 352.759663 -275.059514)
			(xy 352.730098 -275.098858) (xy 352.694605 -275.13295) (xy 352.654102 -275.160906) (xy 352.60964 -275.182004)
			(xy 352.562369 -275.195696) (xy 352.513514 -275.201628) (xy 352.464339 -275.199647) (xy 352.41612 -275.189803)
			(xy 352.370104 -275.172351) (xy 352.327483 -275.147744) (xy 352.289362 -275.116619) (xy 352.256727 -275.079782)
			(xy 352.230424 -275.038186) (xy 352.211133 -274.99291) (xy 352.199356 -274.945126) (xy 352.195396 -274.896072)
			(xy 351.866454 -274.896072) (xy 351.865959 -274.920679) (xy 351.858064 -274.969256) (xy 351.84248 -275.015937)
			(xy 351.819609 -275.059514) (xy 351.790044 -275.098858) (xy 351.754551 -275.13295) (xy 351.714048 -275.160906)
			(xy 351.669586 -275.182004) (xy 351.622315 -275.195696) (xy 351.57346 -275.201628) (xy 351.524285 -275.199647)
			(xy 351.476066 -275.189803) (xy 351.43005 -275.172351) (xy 351.387429 -275.147744) (xy 351.349308 -275.116619)
			(xy 351.316673 -275.079782) (xy 351.29037 -275.038186) (xy 351.271079 -274.99291) (xy 351.259302 -274.945126)
			(xy 351.255342 -274.896072) (xy 350.9264 -274.896072) (xy 350.925905 -274.920679) (xy 350.91801 -274.969256)
			(xy 350.902426 -275.015937) (xy 350.879555 -275.059514) (xy 350.84999 -275.098858) (xy 350.814497 -275.13295)
			(xy 350.773994 -275.160906) (xy 350.729532 -275.182004) (xy 350.682261 -275.195696) (xy 350.633406 -275.201628)
			(xy 350.584231 -275.199647) (xy 350.536012 -275.189803) (xy 350.489996 -275.172351) (xy 350.447375 -275.147744)
			(xy 350.409254 -275.116619) (xy 350.376619 -275.079782) (xy 350.350316 -275.038186) (xy 350.331025 -274.99291)
			(xy 350.319248 -274.945126) (xy 350.315288 -274.896072) (xy 349.986346 -274.896072) (xy 349.985851 -274.920679)
			(xy 349.977956 -274.969256) (xy 349.962372 -275.015937) (xy 349.939501 -275.059514) (xy 349.909936 -275.098858)
			(xy 349.874443 -275.13295) (xy 349.83394 -275.160906) (xy 349.789478 -275.182004) (xy 349.742207 -275.195696)
			(xy 349.693352 -275.201628) (xy 349.644177 -275.199647) (xy 349.595958 -275.189803) (xy 349.549942 -275.172351)
			(xy 349.507321 -275.147744) (xy 349.4692 -275.116619) (xy 349.436565 -275.079782) (xy 349.410262 -275.038186)
			(xy 349.390971 -274.99291) (xy 349.379194 -274.945126) (xy 349.375234 -274.896072) (xy 349.046546 -274.896072)
			(xy 349.046051 -274.920679) (xy 349.038156 -274.969256) (xy 349.022572 -275.015937) (xy 348.999701 -275.059514)
			(xy 348.970136 -275.098858) (xy 348.934643 -275.13295) (xy 348.89414 -275.160906) (xy 348.849678 -275.182004)
			(xy 348.802407 -275.195696) (xy 348.753552 -275.201628) (xy 348.704377 -275.199647) (xy 348.656158 -275.189803)
			(xy 348.610142 -275.172351) (xy 348.567521 -275.147744) (xy 348.5294 -275.116619) (xy 348.496765 -275.079782)
			(xy 348.470462 -275.038186) (xy 348.451171 -274.99291) (xy 348.439394 -274.945126) (xy 348.435434 -274.896072)
			(xy 348.106492 -274.896072) (xy 348.105997 -274.920679) (xy 348.098102 -274.969256) (xy 348.082518 -275.015937)
			(xy 348.059647 -275.059514) (xy 348.030082 -275.098858) (xy 347.994589 -275.13295) (xy 347.954086 -275.160906)
			(xy 347.909624 -275.182004) (xy 347.862353 -275.195696) (xy 347.813498 -275.201628) (xy 347.764323 -275.199647)
			(xy 347.716104 -275.189803) (xy 347.670088 -275.172351) (xy 347.627467 -275.147744) (xy 347.589346 -275.116619)
			(xy 347.556711 -275.079782) (xy 347.530408 -275.038186) (xy 347.511117 -274.99291) (xy 347.49934 -274.945126)
			(xy 347.49538 -274.896072) (xy 347.166438 -274.896072) (xy 347.165943 -274.920679) (xy 347.158048 -274.969256)
			(xy 347.142464 -275.015937) (xy 347.119593 -275.059514) (xy 347.090028 -275.098858) (xy 347.054535 -275.13295)
			(xy 347.014032 -275.160906) (xy 346.96957 -275.182004) (xy 346.922299 -275.195696) (xy 346.873444 -275.201628)
			(xy 346.824269 -275.199647) (xy 346.77605 -275.189803) (xy 346.730034 -275.172351) (xy 346.687413 -275.147744)
			(xy 346.649292 -275.116619) (xy 346.616657 -275.079782) (xy 346.590354 -275.038186) (xy 346.571063 -274.99291)
			(xy 346.559286 -274.945126) (xy 346.555326 -274.896072) (xy 346.226384 -274.896072) (xy 346.225889 -274.920679)
			(xy 346.217994 -274.969256) (xy 346.20241 -275.015937) (xy 346.179539 -275.059514) (xy 346.149974 -275.098858)
			(xy 346.114481 -275.13295) (xy 346.073978 -275.160906) (xy 346.029516 -275.182004) (xy 345.982245 -275.195696)
			(xy 345.93339 -275.201628) (xy 345.884215 -275.199647) (xy 345.835996 -275.189803) (xy 345.78998 -275.172351)
			(xy 345.747359 -275.147744) (xy 345.709238 -275.116619) (xy 345.676603 -275.079782) (xy 345.6503 -275.038186)
			(xy 345.631009 -274.99291) (xy 345.619232 -274.945126) (xy 345.615272 -274.896072) (xy 345.28633 -274.896072)
			(xy 345.285835 -274.920679) (xy 345.27794 -274.969256) (xy 345.262356 -275.015937) (xy 345.239485 -275.059514)
			(xy 345.20992 -275.098858) (xy 345.174427 -275.13295) (xy 345.133924 -275.160906) (xy 345.089462 -275.182004)
			(xy 345.042191 -275.195696) (xy 344.993336 -275.201628) (xy 344.944161 -275.199647) (xy 344.895942 -275.189803)
			(xy 344.849926 -275.172351) (xy 344.807305 -275.147744) (xy 344.769184 -275.116619) (xy 344.736549 -275.079782)
			(xy 344.710246 -275.038186) (xy 344.690955 -274.99291) (xy 344.679178 -274.945126) (xy 344.675218 -274.896072)
			(xy 344.356944 -274.896072) (xy 344.356432 -274.921518) (xy 344.348268 -274.971752) (xy 344.332152 -275.020026)
			(xy 344.308501 -275.065089) (xy 344.277928 -275.105775) (xy 344.241224 -275.14103) (xy 344.19934 -275.16994)
			(xy 344.153361 -275.191757) (xy 344.104477 -275.205917) (xy 344.053956 -275.212051) (xy 344.003104 -275.210002)
			(xy 343.95324 -275.199822) (xy 343.905654 -275.181775) (xy 343.86158 -275.156329) (xy 343.822158 -275.124142)
			(xy 343.78841 -275.086048) (xy 343.761209 -275.043034) (xy 343.741261 -274.996214) (xy 343.729082 -274.9468)
			(xy 343.724987 -274.896072) (xy 343.406476 -274.896072) (xy 343.405981 -274.920679) (xy 343.398086 -274.969256)
			(xy 343.382502 -275.015937) (xy 343.359631 -275.059514) (xy 343.330066 -275.098858) (xy 343.294573 -275.13295)
			(xy 343.25407 -275.160906) (xy 343.209608 -275.182004) (xy 343.162337 -275.195696) (xy 343.113482 -275.201628)
			(xy 343.064307 -275.199647) (xy 343.016088 -275.189803) (xy 342.970072 -275.172351) (xy 342.927451 -275.147744)
			(xy 342.88933 -275.116619) (xy 342.856695 -275.079782) (xy 342.830392 -275.038186) (xy 342.811101 -274.99291)
			(xy 342.799324 -274.945126) (xy 342.795364 -274.896072) (xy 342.476836 -274.896072) (xy 342.476324 -274.921518)
			(xy 342.46816 -274.971752) (xy 342.452044 -275.020026) (xy 342.428393 -275.065089) (xy 342.39782 -275.105775)
			(xy 342.361116 -275.14103) (xy 342.319232 -275.16994) (xy 342.273253 -275.191757) (xy 342.224369 -275.205917)
			(xy 342.173848 -275.212051) (xy 342.122996 -275.210002) (xy 342.073132 -275.199822) (xy 342.025546 -275.181775)
			(xy 341.981472 -275.156329) (xy 341.94205 -275.124142) (xy 341.908302 -275.086048) (xy 341.881101 -275.043034)
			(xy 341.861153 -274.996214) (xy 341.848974 -274.9468) (xy 341.844879 -274.896072) (xy 341.52598 -274.896072)
			(xy 341.525981 -274.920165) (xy 341.518428 -274.967707) (xy 341.503509 -275.013475) (xy 341.481593 -275.056335)
			(xy 341.453223 -275.095225) (xy 341.419102 -275.129181) (xy 341.380075 -275.157363) (xy 341.33711 -275.179072)
			(xy 341.291271 -275.19377) (xy 341.267542 -275.197824) (xy 341.258652 -275.199094) (xy 341.24265 -275.207984)
			(xy 341.236808 -275.214842) (xy 341.231214 -275.221926) (xy 341.224951 -275.238843) (xy 341.224616 -275.247862)
			(xy 341.224616 -275.40712) (xy 341.224846 -275.413638) (xy 341.228179 -275.426243) (xy 341.23122 -275.432012)
			(xy 341.241159 -275.449779) (xy 341.258702 -275.48652) (xy 341.266272 -275.505418) (xy 341.266272 -275.505672)
			(xy 341.268906 -275.511856) (xy 341.276889 -275.522665) (xy 341.28202 -275.527008) (xy 341.293196 -275.535644)
			(xy 341.305642 -275.537168) (xy 341.395812 -275.548598) (xy 341.402691 -275.549196) (xy 341.41634 -275.547136)
			(xy 341.422736 -275.544534) (xy 341.428578 -275.541994) (xy 341.438992 -275.533612) (xy 341.44331 -275.52777)
			(xy 341.457774 -275.508468) (xy 341.491762 -275.474246) (xy 341.5307 -275.445783) (xy 341.573624 -275.423787)
			(xy 341.619469 -275.408803) (xy 341.667098 -275.401202) (xy 341.691214 -275.40077) (xy 341.71647 -275.401293)
			(xy 341.766294 -275.409609) (xy 341.814069 -275.426012) (xy 341.858493 -275.450055) (xy 341.898354 -275.481082)
			(xy 341.932565 -275.518246) (xy 341.960192 -275.560534) (xy 341.980482 -275.606792) (xy 341.992882 -275.65576)
			(xy 341.997051 -275.706078) (xy 342.314779 -275.706078) (xy 342.318874 -275.65535) (xy 342.331053 -275.605936)
			(xy 342.351001 -275.559116) (xy 342.378202 -275.516102) (xy 342.41195 -275.478008) (xy 342.451372 -275.445821)
			(xy 342.495446 -275.420375) (xy 342.543032 -275.402328) (xy 342.592896 -275.392148) (xy 342.643748 -275.390099)
			(xy 342.694269 -275.396233) (xy 342.743153 -275.410393) (xy 342.789132 -275.43221) (xy 342.831016 -275.46112)
			(xy 342.86772 -275.496375) (xy 342.898293 -275.537061) (xy 342.921944 -275.582124) (xy 342.93806 -275.630398)
			(xy 342.946224 -275.680632) (xy 342.946736 -275.706078) (xy 343.254833 -275.706078) (xy 343.258928 -275.65535)
			(xy 343.271107 -275.605936) (xy 343.291055 -275.559116) (xy 343.318256 -275.516102) (xy 343.352004 -275.478008)
			(xy 343.391426 -275.445821) (xy 343.4355 -275.420375) (xy 343.483086 -275.402328) (xy 343.53295 -275.392148)
			(xy 343.583802 -275.390099) (xy 343.634323 -275.396233) (xy 343.683207 -275.410393) (xy 343.729186 -275.43221)
			(xy 343.77107 -275.46112) (xy 343.807774 -275.496375) (xy 343.838347 -275.537061) (xy 343.861998 -275.582124)
			(xy 343.878114 -275.630398) (xy 343.886278 -275.680632) (xy 343.88679 -275.706078) (xy 344.205318 -275.706078)
			(xy 344.209278 -275.657024) (xy 344.221055 -275.60924) (xy 344.240346 -275.563964) (xy 344.266649 -275.522368)
			(xy 344.299284 -275.485531) (xy 344.337405 -275.454406) (xy 344.380026 -275.429799) (xy 344.426042 -275.412347)
			(xy 344.474261 -275.402503) (xy 344.523436 -275.400522) (xy 344.572291 -275.406454) (xy 344.619562 -275.420146)
			(xy 344.664024 -275.441244) (xy 344.704527 -275.4692) (xy 344.74002 -275.503292) (xy 344.769585 -275.542636)
			(xy 344.792456 -275.586213) (xy 344.80804 -275.632894) (xy 344.815935 -275.681471) (xy 344.81643 -275.706078)
			(xy 347.025226 -275.706078) (xy 347.029186 -275.657024) (xy 347.040963 -275.60924) (xy 347.060254 -275.563964)
			(xy 347.086557 -275.522368) (xy 347.119192 -275.485531) (xy 347.157313 -275.454406) (xy 347.199934 -275.429799)
			(xy 347.24595 -275.412347) (xy 347.294169 -275.402503) (xy 347.343344 -275.400522) (xy 347.392199 -275.406454)
			(xy 347.43947 -275.420146) (xy 347.483932 -275.441244) (xy 347.524435 -275.4692) (xy 347.559928 -275.503292)
			(xy 347.589493 -275.542636) (xy 347.612364 -275.586213) (xy 347.627948 -275.632894) (xy 347.635843 -275.681471)
			(xy 347.636338 -275.706078) (xy 349.845388 -275.706078) (xy 349.849348 -275.657024) (xy 349.861125 -275.60924)
			(xy 349.880416 -275.563964) (xy 349.906719 -275.522368) (xy 349.939354 -275.485531) (xy 349.977475 -275.454406)
			(xy 350.020096 -275.429799) (xy 350.066112 -275.412347) (xy 350.114331 -275.402503) (xy 350.163506 -275.400522)
			(xy 350.212361 -275.406454) (xy 350.259632 -275.420146) (xy 350.304094 -275.441244) (xy 350.344597 -275.4692)
			(xy 350.38009 -275.503292) (xy 350.409655 -275.542636) (xy 350.432526 -275.586213) (xy 350.44811 -275.632894)
			(xy 350.456005 -275.681471) (xy 350.4565 -275.706078) (xy 352.665296 -275.706078) (xy 352.669256 -275.657024)
			(xy 352.681033 -275.60924) (xy 352.700324 -275.563964) (xy 352.726627 -275.522368) (xy 352.759262 -275.485531)
			(xy 352.797383 -275.454406) (xy 352.840004 -275.429799) (xy 352.88602 -275.412347) (xy 352.934239 -275.402503)
			(xy 352.983414 -275.400522) (xy 353.032269 -275.406454) (xy 353.07954 -275.420146) (xy 353.124002 -275.441244)
			(xy 353.164505 -275.4692) (xy 353.199998 -275.503292) (xy 353.229563 -275.542636) (xy 353.252434 -275.586213)
			(xy 353.268018 -275.632894) (xy 353.275913 -275.681471) (xy 353.276408 -275.706078) (xy 355.485204 -275.706078)
			(xy 355.489164 -275.657024) (xy 355.500941 -275.60924) (xy 355.520232 -275.563964) (xy 355.546535 -275.522368)
			(xy 355.57917 -275.485531) (xy 355.617291 -275.454406) (xy 355.659912 -275.429799) (xy 355.705928 -275.412347)
			(xy 355.754147 -275.402503) (xy 355.803322 -275.400522) (xy 355.852177 -275.406454) (xy 355.899448 -275.420146)
			(xy 355.94391 -275.441244) (xy 355.984413 -275.4692) (xy 356.019906 -275.503292) (xy 356.049471 -275.542636)
			(xy 356.072342 -275.586213) (xy 356.087926 -275.632894) (xy 356.095821 -275.681471) (xy 356.096316 -275.706078)
			(xy 356.425258 -275.706078) (xy 356.429218 -275.657024) (xy 356.440995 -275.60924) (xy 356.460286 -275.563964)
			(xy 356.486589 -275.522368) (xy 356.519224 -275.485531) (xy 356.557345 -275.454406) (xy 356.599966 -275.429799)
			(xy 356.645982 -275.412347) (xy 356.694201 -275.402503) (xy 356.743376 -275.400522) (xy 356.792231 -275.406454)
			(xy 356.839502 -275.420146) (xy 356.883964 -275.441244) (xy 356.924467 -275.4692) (xy 356.95996 -275.503292)
			(xy 356.989525 -275.542636) (xy 357.012396 -275.586213) (xy 357.02798 -275.632894) (xy 357.035875 -275.681471)
			(xy 357.03637 -275.706078) (xy 357.365312 -275.706078) (xy 357.369272 -275.657024) (xy 357.381049 -275.60924)
			(xy 357.40034 -275.563964) (xy 357.426643 -275.522368) (xy 357.459278 -275.485531) (xy 357.497399 -275.454406)
			(xy 357.54002 -275.429799) (xy 357.586036 -275.412347) (xy 357.634255 -275.402503) (xy 357.68343 -275.400522)
			(xy 357.732285 -275.406454) (xy 357.779556 -275.420146) (xy 357.824018 -275.441244) (xy 357.864521 -275.4692)
			(xy 357.900014 -275.503292) (xy 357.929579 -275.542636) (xy 357.95245 -275.586213) (xy 357.968034 -275.632894)
			(xy 357.975929 -275.681471) (xy 357.976424 -275.706078) (xy 358.305366 -275.706078) (xy 358.309326 -275.657024)
			(xy 358.321103 -275.60924) (xy 358.340394 -275.563964) (xy 358.366697 -275.522368) (xy 358.399332 -275.485531)
			(xy 358.437453 -275.454406) (xy 358.480074 -275.429799) (xy 358.52609 -275.412347) (xy 358.574309 -275.402503)
			(xy 358.623484 -275.400522) (xy 358.672339 -275.406454) (xy 358.71961 -275.420146) (xy 358.764072 -275.441244)
			(xy 358.804575 -275.4692) (xy 358.840068 -275.503292) (xy 358.869633 -275.542636) (xy 358.892504 -275.586213)
			(xy 358.908088 -275.632894) (xy 358.915983 -275.681471) (xy 358.916478 -275.706078) (xy 361.118924 -275.706078)
			(xy 361.122884 -275.657024) (xy 361.134661 -275.60924) (xy 361.153952 -275.563964) (xy 361.180255 -275.522368)
			(xy 361.21289 -275.485531) (xy 361.251011 -275.454406) (xy 361.293632 -275.429799) (xy 361.339648 -275.412347)
			(xy 361.387867 -275.402503) (xy 361.437042 -275.400522) (xy 361.485897 -275.406454) (xy 361.533168 -275.420146)
			(xy 361.57763 -275.441244) (xy 361.618133 -275.4692) (xy 361.653626 -275.503292) (xy 361.683191 -275.542636)
			(xy 361.706062 -275.586213) (xy 361.721646 -275.632894) (xy 361.729541 -275.681471) (xy 361.730036 -275.706078)
			(xy 362.058978 -275.706078) (xy 362.062938 -275.657024) (xy 362.074715 -275.60924) (xy 362.094006 -275.563964)
			(xy 362.120309 -275.522368) (xy 362.152944 -275.485531) (xy 362.191065 -275.454406) (xy 362.233686 -275.429799)
			(xy 362.279702 -275.412347) (xy 362.327921 -275.402503) (xy 362.377096 -275.400522) (xy 362.425951 -275.406454)
			(xy 362.473222 -275.420146) (xy 362.517684 -275.441244) (xy 362.558187 -275.4692) (xy 362.59368 -275.503292)
			(xy 362.623245 -275.542636) (xy 362.646116 -275.586213) (xy 362.6617 -275.632894) (xy 362.669595 -275.681471)
			(xy 362.67009 -275.706078) (xy 362.999032 -275.706078) (xy 363.002992 -275.657024) (xy 363.014769 -275.60924)
			(xy 363.03406 -275.563964) (xy 363.060363 -275.522368) (xy 363.092998 -275.485531) (xy 363.131119 -275.454406)
			(xy 363.17374 -275.429799) (xy 363.219756 -275.412347) (xy 363.267975 -275.402503) (xy 363.31715 -275.400522)
			(xy 363.366005 -275.406454) (xy 363.413276 -275.420146) (xy 363.457738 -275.441244) (xy 363.498241 -275.4692)
			(xy 363.533734 -275.503292) (xy 363.563299 -275.542636) (xy 363.58617 -275.586213) (xy 363.601754 -275.632894)
			(xy 363.609649 -275.681471) (xy 363.610144 -275.706078) (xy 363.939086 -275.706078) (xy 363.943046 -275.657024)
			(xy 363.954823 -275.60924) (xy 363.974114 -275.563964) (xy 364.000417 -275.522368) (xy 364.033052 -275.485531)
			(xy 364.071173 -275.454406) (xy 364.113794 -275.429799) (xy 364.15981 -275.412347) (xy 364.208029 -275.402503)
			(xy 364.257204 -275.400522) (xy 364.306059 -275.406454) (xy 364.35333 -275.420146) (xy 364.397792 -275.441244)
			(xy 364.438295 -275.4692) (xy 364.473788 -275.503292) (xy 364.503353 -275.542636) (xy 364.526224 -275.586213)
			(xy 364.541808 -275.632894) (xy 364.549703 -275.681471) (xy 364.550198 -275.706078) (xy 366.758994 -275.706078)
			(xy 366.762954 -275.657024) (xy 366.774731 -275.60924) (xy 366.794022 -275.563964) (xy 366.820325 -275.522368)
			(xy 366.85296 -275.485531) (xy 366.891081 -275.454406) (xy 366.933702 -275.429799) (xy 366.979718 -275.412347)
			(xy 367.027937 -275.402503) (xy 367.077112 -275.400522) (xy 367.125967 -275.406454) (xy 367.173238 -275.420146)
			(xy 367.2177 -275.441244) (xy 367.258203 -275.4692) (xy 367.293696 -275.503292) (xy 367.323261 -275.542636)
			(xy 367.346132 -275.586213) (xy 367.361716 -275.632894) (xy 367.369611 -275.681471) (xy 367.370106 -275.706078)
			(xy 369.578902 -275.706078) (xy 369.582862 -275.657024) (xy 369.594639 -275.60924) (xy 369.61393 -275.563964)
			(xy 369.640233 -275.522368) (xy 369.672868 -275.485531) (xy 369.710989 -275.454406) (xy 369.75361 -275.429799)
			(xy 369.799626 -275.412347) (xy 369.847845 -275.402503) (xy 369.89702 -275.400522) (xy 369.945875 -275.406454)
			(xy 369.993146 -275.420146) (xy 370.037608 -275.441244) (xy 370.078111 -275.4692) (xy 370.113604 -275.503292)
			(xy 370.143169 -275.542636) (xy 370.16604 -275.586213) (xy 370.181624 -275.632894) (xy 370.189519 -275.681471)
			(xy 370.190014 -275.706078) (xy 372.399064 -275.706078) (xy 372.403024 -275.657024) (xy 372.414801 -275.60924)
			(xy 372.434092 -275.563964) (xy 372.460395 -275.522368) (xy 372.49303 -275.485531) (xy 372.531151 -275.454406)
			(xy 372.573772 -275.429799) (xy 372.619788 -275.412347) (xy 372.668007 -275.402503) (xy 372.717182 -275.400522)
			(xy 372.766037 -275.406454) (xy 372.813308 -275.420146) (xy 372.85777 -275.441244) (xy 372.898273 -275.4692)
			(xy 372.933766 -275.503292) (xy 372.963331 -275.542636) (xy 372.986202 -275.586213) (xy 373.001786 -275.632894)
			(xy 373.009681 -275.681471) (xy 373.010176 -275.706078) (xy 375.218972 -275.706078) (xy 375.222932 -275.657024)
			(xy 375.234709 -275.60924) (xy 375.254 -275.563964) (xy 375.280303 -275.522368) (xy 375.312938 -275.485531)
			(xy 375.351059 -275.454406) (xy 375.39368 -275.429799) (xy 375.439696 -275.412347) (xy 375.487915 -275.402503)
			(xy 375.53709 -275.400522) (xy 375.585945 -275.406454) (xy 375.633216 -275.420146) (xy 375.677678 -275.441244)
			(xy 375.718181 -275.4692) (xy 375.753674 -275.503292) (xy 375.783239 -275.542636) (xy 375.80611 -275.586213)
			(xy 375.821694 -275.632894) (xy 375.829589 -275.681471) (xy 375.830084 -275.706078) (xy 376.148595 -275.706078)
			(xy 376.15269 -275.65535) (xy 376.164869 -275.605936) (xy 376.184817 -275.559116) (xy 376.212018 -275.516102)
			(xy 376.245766 -275.478008) (xy 376.285188 -275.445821) (xy 376.329262 -275.420375) (xy 376.376848 -275.402328)
			(xy 376.426712 -275.392148) (xy 376.477564 -275.390099) (xy 376.528085 -275.396233) (xy 376.576969 -275.410393)
			(xy 376.622948 -275.43221) (xy 376.664832 -275.46112) (xy 376.701536 -275.496375) (xy 376.732109 -275.537061)
			(xy 376.75576 -275.582124) (xy 376.771876 -275.630398) (xy 376.78004 -275.680632) (xy 376.780552 -275.706078)
			(xy 377.088649 -275.706078) (xy 377.092744 -275.65535) (xy 377.104923 -275.605936) (xy 377.124871 -275.559116)
			(xy 377.152072 -275.516102) (xy 377.18582 -275.478008) (xy 377.225242 -275.445821) (xy 377.269316 -275.420375)
			(xy 377.316902 -275.402328) (xy 377.366766 -275.392148) (xy 377.417618 -275.390099) (xy 377.468139 -275.396233)
			(xy 377.517023 -275.410393) (xy 377.563002 -275.43221) (xy 377.604886 -275.46112) (xy 377.64159 -275.496375)
			(xy 377.672163 -275.537061) (xy 377.695814 -275.582124) (xy 377.71193 -275.630398) (xy 377.720094 -275.680632)
			(xy 377.720606 -275.706078) (xy 377.720094 -275.731524) (xy 377.71193 -275.781758) (xy 377.695814 -275.830032)
			(xy 377.672163 -275.875095) (xy 377.64159 -275.915781) (xy 377.604886 -275.951036) (xy 377.563002 -275.979946)
			(xy 377.517023 -276.001763) (xy 377.468139 -276.015923) (xy 377.417618 -276.022057) (xy 377.366766 -276.020008)
			(xy 377.316902 -276.009828) (xy 377.269316 -275.991781) (xy 377.225242 -275.966335) (xy 377.18582 -275.934148)
			(xy 377.152072 -275.896054) (xy 377.124871 -275.85304) (xy 377.104923 -275.80622) (xy 377.092744 -275.756806)
			(xy 377.088649 -275.706078) (xy 376.780552 -275.706078) (xy 376.78004 -275.731524) (xy 376.771876 -275.781758)
			(xy 376.75576 -275.830032) (xy 376.732109 -275.875095) (xy 376.701536 -275.915781) (xy 376.664832 -275.951036)
			(xy 376.622948 -275.979946) (xy 376.576969 -276.001763) (xy 376.528085 -276.015923) (xy 376.477564 -276.022057)
			(xy 376.426712 -276.020008) (xy 376.376848 -276.009828) (xy 376.329262 -275.991781) (xy 376.285188 -275.966335)
			(xy 376.245766 -275.934148) (xy 376.212018 -275.896054) (xy 376.184817 -275.85304) (xy 376.164869 -275.80622)
			(xy 376.15269 -275.756806) (xy 376.148595 -275.706078) (xy 375.830084 -275.706078) (xy 375.829589 -275.730685)
			(xy 375.821694 -275.779262) (xy 375.80611 -275.825943) (xy 375.783239 -275.86952) (xy 375.753674 -275.908864)
			(xy 375.718181 -275.942956) (xy 375.677678 -275.970912) (xy 375.633216 -275.99201) (xy 375.585945 -276.005702)
			(xy 375.53709 -276.011634) (xy 375.487915 -276.009653) (xy 375.439696 -275.999809) (xy 375.39368 -275.982357)
			(xy 375.351059 -275.95775) (xy 375.312938 -275.926625) (xy 375.280303 -275.889788) (xy 375.254 -275.848192)
			(xy 375.234709 -275.802916) (xy 375.222932 -275.755132) (xy 375.218972 -275.706078) (xy 373.010176 -275.706078)
			(xy 373.009681 -275.730685) (xy 373.001786 -275.779262) (xy 372.986202 -275.825943) (xy 372.963331 -275.86952)
			(xy 372.933766 -275.908864) (xy 372.898273 -275.942956) (xy 372.85777 -275.970912) (xy 372.813308 -275.99201)
			(xy 372.766037 -276.005702) (xy 372.717182 -276.011634) (xy 372.668007 -276.009653) (xy 372.619788 -275.999809)
			(xy 372.573772 -275.982357) (xy 372.531151 -275.95775) (xy 372.49303 -275.926625) (xy 372.460395 -275.889788)
			(xy 372.434092 -275.848192) (xy 372.414801 -275.802916) (xy 372.403024 -275.755132) (xy 372.399064 -275.706078)
			(xy 370.190014 -275.706078) (xy 370.189519 -275.730685) (xy 370.181624 -275.779262) (xy 370.16604 -275.825943)
			(xy 370.143169 -275.86952) (xy 370.113604 -275.908864) (xy 370.078111 -275.942956) (xy 370.037608 -275.970912)
			(xy 369.993146 -275.99201) (xy 369.945875 -276.005702) (xy 369.89702 -276.011634) (xy 369.847845 -276.009653)
			(xy 369.799626 -275.999809) (xy 369.75361 -275.982357) (xy 369.710989 -275.95775) (xy 369.672868 -275.926625)
			(xy 369.640233 -275.889788) (xy 369.61393 -275.848192) (xy 369.594639 -275.802916) (xy 369.582862 -275.755132)
			(xy 369.578902 -275.706078) (xy 367.370106 -275.706078) (xy 367.369611 -275.730685) (xy 367.361716 -275.779262)
			(xy 367.346132 -275.825943) (xy 367.323261 -275.86952) (xy 367.293696 -275.908864) (xy 367.258203 -275.942956)
			(xy 367.2177 -275.970912) (xy 367.173238 -275.99201) (xy 367.125967 -276.005702) (xy 367.077112 -276.011634)
			(xy 367.027937 -276.009653) (xy 366.979718 -275.999809) (xy 366.933702 -275.982357) (xy 366.891081 -275.95775)
			(xy 366.85296 -275.926625) (xy 366.820325 -275.889788) (xy 366.794022 -275.848192) (xy 366.774731 -275.802916)
			(xy 366.762954 -275.755132) (xy 366.758994 -275.706078) (xy 364.550198 -275.706078) (xy 364.549703 -275.730685)
			(xy 364.541808 -275.779262) (xy 364.526224 -275.825943) (xy 364.503353 -275.86952) (xy 364.473788 -275.908864)
			(xy 364.438295 -275.942956) (xy 364.397792 -275.970912) (xy 364.35333 -275.99201) (xy 364.306059 -276.005702)
			(xy 364.257204 -276.011634) (xy 364.208029 -276.009653) (xy 364.15981 -275.999809) (xy 364.113794 -275.982357)
			(xy 364.071173 -275.95775) (xy 364.033052 -275.926625) (xy 364.000417 -275.889788) (xy 363.974114 -275.848192)
			(xy 363.954823 -275.802916) (xy 363.943046 -275.755132) (xy 363.939086 -275.706078) (xy 363.610144 -275.706078)
			(xy 363.609649 -275.730685) (xy 363.601754 -275.779262) (xy 363.58617 -275.825943) (xy 363.563299 -275.86952)
			(xy 363.533734 -275.908864) (xy 363.498241 -275.942956) (xy 363.457738 -275.970912) (xy 363.413276 -275.99201)
			(xy 363.366005 -276.005702) (xy 363.31715 -276.011634) (xy 363.267975 -276.009653) (xy 363.219756 -275.999809)
			(xy 363.17374 -275.982357) (xy 363.131119 -275.95775) (xy 363.092998 -275.926625) (xy 363.060363 -275.889788)
			(xy 363.03406 -275.848192) (xy 363.014769 -275.802916) (xy 363.002992 -275.755132) (xy 362.999032 -275.706078)
			(xy 362.67009 -275.706078) (xy 362.669595 -275.730685) (xy 362.6617 -275.779262) (xy 362.646116 -275.825943)
			(xy 362.623245 -275.86952) (xy 362.59368 -275.908864) (xy 362.558187 -275.942956) (xy 362.517684 -275.970912)
			(xy 362.473222 -275.99201) (xy 362.425951 -276.005702) (xy 362.377096 -276.011634) (xy 362.327921 -276.009653)
			(xy 362.279702 -275.999809) (xy 362.233686 -275.982357) (xy 362.191065 -275.95775) (xy 362.152944 -275.926625)
			(xy 362.120309 -275.889788) (xy 362.094006 -275.848192) (xy 362.074715 -275.802916) (xy 362.062938 -275.755132)
			(xy 362.058978 -275.706078) (xy 361.730036 -275.706078) (xy 361.729541 -275.730685) (xy 361.721646 -275.779262)
			(xy 361.706062 -275.825943) (xy 361.683191 -275.86952) (xy 361.653626 -275.908864) (xy 361.618133 -275.942956)
			(xy 361.57763 -275.970912) (xy 361.533168 -275.99201) (xy 361.485897 -276.005702) (xy 361.437042 -276.011634)
			(xy 361.387867 -276.009653) (xy 361.339648 -275.999809) (xy 361.293632 -275.982357) (xy 361.251011 -275.95775)
			(xy 361.21289 -275.926625) (xy 361.180255 -275.889788) (xy 361.153952 -275.848192) (xy 361.134661 -275.802916)
			(xy 361.122884 -275.755132) (xy 361.118924 -275.706078) (xy 358.916478 -275.706078) (xy 358.915983 -275.730685)
			(xy 358.908088 -275.779262) (xy 358.892504 -275.825943) (xy 358.869633 -275.86952) (xy 358.840068 -275.908864)
			(xy 358.804575 -275.942956) (xy 358.764072 -275.970912) (xy 358.71961 -275.99201) (xy 358.672339 -276.005702)
			(xy 358.623484 -276.011634) (xy 358.574309 -276.009653) (xy 358.52609 -275.999809) (xy 358.480074 -275.982357)
			(xy 358.437453 -275.95775) (xy 358.399332 -275.926625) (xy 358.366697 -275.889788) (xy 358.340394 -275.848192)
			(xy 358.321103 -275.802916) (xy 358.309326 -275.755132) (xy 358.305366 -275.706078) (xy 357.976424 -275.706078)
			(xy 357.975929 -275.730685) (xy 357.968034 -275.779262) (xy 357.95245 -275.825943) (xy 357.929579 -275.86952)
			(xy 357.900014 -275.908864) (xy 357.864521 -275.942956) (xy 357.824018 -275.970912) (xy 357.779556 -275.99201)
			(xy 357.732285 -276.005702) (xy 357.68343 -276.011634) (xy 357.634255 -276.009653) (xy 357.586036 -275.999809)
			(xy 357.54002 -275.982357) (xy 357.497399 -275.95775) (xy 357.459278 -275.926625) (xy 357.426643 -275.889788)
			(xy 357.40034 -275.848192) (xy 357.381049 -275.802916) (xy 357.369272 -275.755132) (xy 357.365312 -275.706078)
			(xy 357.03637 -275.706078) (xy 357.035875 -275.730685) (xy 357.02798 -275.779262) (xy 357.012396 -275.825943)
			(xy 356.989525 -275.86952) (xy 356.95996 -275.908864) (xy 356.924467 -275.942956) (xy 356.883964 -275.970912)
			(xy 356.839502 -275.99201) (xy 356.792231 -276.005702) (xy 356.743376 -276.011634) (xy 356.694201 -276.009653)
			(xy 356.645982 -275.999809) (xy 356.599966 -275.982357) (xy 356.557345 -275.95775) (xy 356.519224 -275.926625)
			(xy 356.486589 -275.889788) (xy 356.460286 -275.848192) (xy 356.440995 -275.802916) (xy 356.429218 -275.755132)
			(xy 356.425258 -275.706078) (xy 356.096316 -275.706078) (xy 356.095821 -275.730685) (xy 356.087926 -275.779262)
			(xy 356.072342 -275.825943) (xy 356.049471 -275.86952) (xy 356.019906 -275.908864) (xy 355.984413 -275.942956)
			(xy 355.94391 -275.970912) (xy 355.899448 -275.99201) (xy 355.852177 -276.005702) (xy 355.803322 -276.011634)
			(xy 355.754147 -276.009653) (xy 355.705928 -275.999809) (xy 355.659912 -275.982357) (xy 355.617291 -275.95775)
			(xy 355.57917 -275.926625) (xy 355.546535 -275.889788) (xy 355.520232 -275.848192) (xy 355.500941 -275.802916)
			(xy 355.489164 -275.755132) (xy 355.485204 -275.706078) (xy 353.276408 -275.706078) (xy 353.275913 -275.730685)
			(xy 353.268018 -275.779262) (xy 353.252434 -275.825943) (xy 353.229563 -275.86952) (xy 353.199998 -275.908864)
			(xy 353.164505 -275.942956) (xy 353.124002 -275.970912) (xy 353.07954 -275.99201) (xy 353.032269 -276.005702)
			(xy 352.983414 -276.011634) (xy 352.934239 -276.009653) (xy 352.88602 -275.999809) (xy 352.840004 -275.982357)
			(xy 352.797383 -275.95775) (xy 352.759262 -275.926625) (xy 352.726627 -275.889788) (xy 352.700324 -275.848192)
			(xy 352.681033 -275.802916) (xy 352.669256 -275.755132) (xy 352.665296 -275.706078) (xy 350.4565 -275.706078)
			(xy 350.456005 -275.730685) (xy 350.44811 -275.779262) (xy 350.432526 -275.825943) (xy 350.409655 -275.86952)
			(xy 350.38009 -275.908864) (xy 350.344597 -275.942956) (xy 350.304094 -275.970912) (xy 350.259632 -275.99201)
			(xy 350.212361 -276.005702) (xy 350.163506 -276.011634) (xy 350.114331 -276.009653) (xy 350.066112 -275.999809)
			(xy 350.020096 -275.982357) (xy 349.977475 -275.95775) (xy 349.939354 -275.926625) (xy 349.906719 -275.889788)
			(xy 349.880416 -275.848192) (xy 349.861125 -275.802916) (xy 349.849348 -275.755132) (xy 349.845388 -275.706078)
			(xy 347.636338 -275.706078) (xy 347.635843 -275.730685) (xy 347.627948 -275.779262) (xy 347.612364 -275.825943)
			(xy 347.589493 -275.86952) (xy 347.559928 -275.908864) (xy 347.524435 -275.942956) (xy 347.483932 -275.970912)
			(xy 347.43947 -275.99201) (xy 347.392199 -276.005702) (xy 347.343344 -276.011634) (xy 347.294169 -276.009653)
			(xy 347.24595 -275.999809) (xy 347.199934 -275.982357) (xy 347.157313 -275.95775) (xy 347.119192 -275.926625)
			(xy 347.086557 -275.889788) (xy 347.060254 -275.848192) (xy 347.040963 -275.802916) (xy 347.029186 -275.755132)
			(xy 347.025226 -275.706078) (xy 344.81643 -275.706078) (xy 344.815935 -275.730685) (xy 344.80804 -275.779262)
			(xy 344.792456 -275.825943) (xy 344.769585 -275.86952) (xy 344.74002 -275.908864) (xy 344.704527 -275.942956)
			(xy 344.664024 -275.970912) (xy 344.619562 -275.99201) (xy 344.572291 -276.005702) (xy 344.523436 -276.011634)
			(xy 344.474261 -276.009653) (xy 344.426042 -275.999809) (xy 344.380026 -275.982357) (xy 344.337405 -275.95775)
			(xy 344.299284 -275.926625) (xy 344.266649 -275.889788) (xy 344.240346 -275.848192) (xy 344.221055 -275.802916)
			(xy 344.209278 -275.755132) (xy 344.205318 -275.706078) (xy 343.88679 -275.706078) (xy 343.886278 -275.731524)
			(xy 343.878114 -275.781758) (xy 343.861998 -275.830032) (xy 343.838347 -275.875095) (xy 343.807774 -275.915781)
			(xy 343.77107 -275.951036) (xy 343.729186 -275.979946) (xy 343.683207 -276.001763) (xy 343.634323 -276.015923)
			(xy 343.583802 -276.022057) (xy 343.53295 -276.020008) (xy 343.483086 -276.009828) (xy 343.4355 -275.991781)
			(xy 343.391426 -275.966335) (xy 343.352004 -275.934148) (xy 343.318256 -275.896054) (xy 343.291055 -275.85304)
			(xy 343.271107 -275.80622) (xy 343.258928 -275.756806) (xy 343.254833 -275.706078) (xy 342.946736 -275.706078)
			(xy 342.946224 -275.731524) (xy 342.93806 -275.781758) (xy 342.921944 -275.830032) (xy 342.898293 -275.875095)
			(xy 342.86772 -275.915781) (xy 342.831016 -275.951036) (xy 342.789132 -275.979946) (xy 342.743153 -276.001763)
			(xy 342.694269 -276.015923) (xy 342.643748 -276.022057) (xy 342.592896 -276.020008) (xy 342.543032 -276.009828)
			(xy 342.495446 -275.991781) (xy 342.451372 -275.966335) (xy 342.41195 -275.934148) (xy 342.378202 -275.896054)
			(xy 342.351001 -275.85304) (xy 342.331053 -275.80622) (xy 342.318874 -275.756806) (xy 342.314779 -275.706078)
			(xy 341.997051 -275.706078) (xy 341.997053 -275.7061) (xy 341.992882 -275.75644) (xy 341.980482 -275.805408)
			(xy 341.960192 -275.851666) (xy 341.932565 -275.893954) (xy 341.898354 -275.931118) (xy 341.858493 -275.962145)
			(xy 341.814069 -275.986188) (xy 341.766294 -276.002591) (xy 341.71647 -276.010907) (xy 341.691214 -276.011386)
			(xy 341.678451 -276.01125) (xy 341.653016 -276.009092) (xy 341.640414 -276.007068) (xy 341.640414 -276.007322)
			(xy 341.616961 -276.002895) (xy 341.571707 -275.987733) (xy 341.529355 -275.965729) (xy 341.490934 -275.937416)
			(xy 341.457374 -275.903482) (xy 341.443056 -275.884386) (xy 341.438992 -275.878544) (xy 341.428324 -275.869908)
			(xy 341.422482 -275.867368) (xy 341.416199 -275.864844) (xy 341.402805 -275.862904) (xy 341.396066 -275.863558)
			(xy 341.305642 -275.874988) (xy 341.293196 -275.876512) (xy 341.28202 -275.885148) (xy 341.276887 -275.889489)
			(xy 341.2689 -275.900297) (xy 341.266272 -275.906484) (xy 341.266272 -275.906738) (xy 341.258702 -275.925636)
			(xy 341.24116 -275.962378) (xy 341.23122 -275.980144) (xy 341.227918 -275.985986) (xy 341.226394 -275.992082)
			(xy 341.224616 -276.005036) (xy 341.224616 -276.164294) (xy 341.224975 -276.173311) (xy 341.231222 -276.190227)
			(xy 341.236808 -276.197314) (xy 341.24265 -276.204172) (xy 341.258652 -276.213062) (xy 341.267542 -276.214332)
			(xy 341.291261 -276.21844) (xy 341.337099 -276.233136) (xy 341.380063 -276.254844) (xy 341.419089 -276.283024)
			(xy 341.453209 -276.316978) (xy 341.481579 -276.355866) (xy 341.503495 -276.398724) (xy 341.518415 -276.444489)
			(xy 341.525969 -276.492029) (xy 341.525969 -276.516084) (xy 341.844879 -276.516084) (xy 341.848974 -276.465356)
			(xy 341.861153 -276.415942) (xy 341.881101 -276.369122) (xy 341.908302 -276.326108) (xy 341.94205 -276.288014)
			(xy 341.981472 -276.255827) (xy 342.025546 -276.230381) (xy 342.073132 -276.212334) (xy 342.122996 -276.202154)
			(xy 342.173848 -276.200105) (xy 342.224369 -276.206239) (xy 342.273253 -276.220399) (xy 342.319232 -276.242216)
			(xy 342.361116 -276.271126) (xy 342.39782 -276.306381) (xy 342.428393 -276.347067) (xy 342.452044 -276.39213)
			(xy 342.46816 -276.440404) (xy 342.476324 -276.490638) (xy 342.476836 -276.516084) (xy 342.795364 -276.516084)
			(xy 342.799324 -276.46703) (xy 342.811101 -276.419246) (xy 342.830392 -276.37397) (xy 342.856695 -276.332374)
			(xy 342.88933 -276.295537) (xy 342.927451 -276.264412) (xy 342.970072 -276.239805) (xy 343.016088 -276.222353)
			(xy 343.064307 -276.212509) (xy 343.113482 -276.210528) (xy 343.162337 -276.21646) (xy 343.209608 -276.230152)
			(xy 343.25407 -276.25125) (xy 343.294573 -276.279206) (xy 343.330066 -276.313298) (xy 343.359631 -276.352642)
			(xy 343.382502 -276.396219) (xy 343.398086 -276.4429) (xy 343.405981 -276.491477) (xy 343.406476 -276.516084)
			(xy 343.724987 -276.516084) (xy 343.729082 -276.465356) (xy 343.741261 -276.415942) (xy 343.761209 -276.369122)
			(xy 343.78841 -276.326108) (xy 343.822158 -276.288014) (xy 343.86158 -276.255827) (xy 343.905654 -276.230381)
			(xy 343.95324 -276.212334) (xy 344.003104 -276.202154) (xy 344.053956 -276.200105) (xy 344.104477 -276.206239)
			(xy 344.153361 -276.220399) (xy 344.19934 -276.242216) (xy 344.241224 -276.271126) (xy 344.277928 -276.306381)
			(xy 344.308501 -276.347067) (xy 344.332152 -276.39213) (xy 344.348268 -276.440404) (xy 344.356432 -276.490638)
			(xy 344.356944 -276.516084) (xy 344.675218 -276.516084) (xy 344.679178 -276.46703) (xy 344.690955 -276.419246)
			(xy 344.710246 -276.37397) (xy 344.736549 -276.332374) (xy 344.769184 -276.295537) (xy 344.807305 -276.264412)
			(xy 344.849926 -276.239805) (xy 344.895942 -276.222353) (xy 344.944161 -276.212509) (xy 344.993336 -276.210528)
			(xy 345.042191 -276.21646) (xy 345.089462 -276.230152) (xy 345.133924 -276.25125) (xy 345.174427 -276.279206)
			(xy 345.20992 -276.313298) (xy 345.239485 -276.352642) (xy 345.262356 -276.396219) (xy 345.27794 -276.4429)
			(xy 345.285835 -276.491477) (xy 345.28633 -276.516084) (xy 345.615272 -276.516084) (xy 345.619232 -276.46703)
			(xy 345.631009 -276.419246) (xy 345.6503 -276.37397) (xy 345.676603 -276.332374) (xy 345.709238 -276.295537)
			(xy 345.747359 -276.264412) (xy 345.78998 -276.239805) (xy 345.835996 -276.222353) (xy 345.884215 -276.212509)
			(xy 345.93339 -276.210528) (xy 345.982245 -276.21646) (xy 346.029516 -276.230152) (xy 346.073978 -276.25125)
			(xy 346.114481 -276.279206) (xy 346.149974 -276.313298) (xy 346.179539 -276.352642) (xy 346.20241 -276.396219)
			(xy 346.217994 -276.4429) (xy 346.225889 -276.491477) (xy 346.226384 -276.516084) (xy 346.555326 -276.516084)
			(xy 346.559286 -276.46703) (xy 346.571063 -276.419246) (xy 346.590354 -276.37397) (xy 346.616657 -276.332374)
			(xy 346.649292 -276.295537) (xy 346.687413 -276.264412) (xy 346.730034 -276.239805) (xy 346.77605 -276.222353)
			(xy 346.824269 -276.212509) (xy 346.873444 -276.210528) (xy 346.922299 -276.21646) (xy 346.96957 -276.230152)
			(xy 347.014032 -276.25125) (xy 347.054535 -276.279206) (xy 347.090028 -276.313298) (xy 347.119593 -276.352642)
			(xy 347.142464 -276.396219) (xy 347.158048 -276.4429) (xy 347.165943 -276.491477) (xy 347.166438 -276.516084)
			(xy 347.49538 -276.516084) (xy 347.49934 -276.46703) (xy 347.511117 -276.419246) (xy 347.530408 -276.37397)
			(xy 347.556711 -276.332374) (xy 347.589346 -276.295537) (xy 347.627467 -276.264412) (xy 347.670088 -276.239805)
			(xy 347.716104 -276.222353) (xy 347.764323 -276.212509) (xy 347.813498 -276.210528) (xy 347.862353 -276.21646)
			(xy 347.909624 -276.230152) (xy 347.954086 -276.25125) (xy 347.994589 -276.279206) (xy 348.030082 -276.313298)
			(xy 348.059647 -276.352642) (xy 348.082518 -276.396219) (xy 348.098102 -276.4429) (xy 348.105997 -276.491477)
			(xy 348.106492 -276.516084) (xy 348.435434 -276.516084) (xy 348.439394 -276.46703) (xy 348.451171 -276.419246)
			(xy 348.470462 -276.37397) (xy 348.496765 -276.332374) (xy 348.5294 -276.295537) (xy 348.567521 -276.264412)
			(xy 348.610142 -276.239805) (xy 348.656158 -276.222353) (xy 348.704377 -276.212509) (xy 348.753552 -276.210528)
			(xy 348.802407 -276.21646) (xy 348.849678 -276.230152) (xy 348.89414 -276.25125) (xy 348.934643 -276.279206)
			(xy 348.970136 -276.313298) (xy 348.999701 -276.352642) (xy 349.022572 -276.396219) (xy 349.038156 -276.4429)
			(xy 349.046051 -276.491477) (xy 349.046546 -276.516084) (xy 349.375234 -276.516084) (xy 349.379194 -276.46703)
			(xy 349.390971 -276.419246) (xy 349.410262 -276.37397) (xy 349.436565 -276.332374) (xy 349.4692 -276.295537)
			(xy 349.507321 -276.264412) (xy 349.549942 -276.239805) (xy 349.595958 -276.222353) (xy 349.644177 -276.212509)
			(xy 349.693352 -276.210528) (xy 349.742207 -276.21646) (xy 349.789478 -276.230152) (xy 349.83394 -276.25125)
			(xy 349.874443 -276.279206) (xy 349.909936 -276.313298) (xy 349.939501 -276.352642) (xy 349.962372 -276.396219)
			(xy 349.977956 -276.4429) (xy 349.985851 -276.491477) (xy 349.986346 -276.516084) (xy 350.315288 -276.516084)
			(xy 350.319248 -276.46703) (xy 350.331025 -276.419246) (xy 350.350316 -276.37397) (xy 350.376619 -276.332374)
			(xy 350.409254 -276.295537) (xy 350.447375 -276.264412) (xy 350.489996 -276.239805) (xy 350.536012 -276.222353)
			(xy 350.584231 -276.212509) (xy 350.633406 -276.210528) (xy 350.682261 -276.21646) (xy 350.729532 -276.230152)
			(xy 350.773994 -276.25125) (xy 350.814497 -276.279206) (xy 350.84999 -276.313298) (xy 350.879555 -276.352642)
			(xy 350.902426 -276.396219) (xy 350.91801 -276.4429) (xy 350.925905 -276.491477) (xy 350.9264 -276.516084)
			(xy 351.255342 -276.516084) (xy 351.259302 -276.46703) (xy 351.271079 -276.419246) (xy 351.29037 -276.37397)
			(xy 351.316673 -276.332374) (xy 351.349308 -276.295537) (xy 351.387429 -276.264412) (xy 351.43005 -276.239805)
			(xy 351.476066 -276.222353) (xy 351.524285 -276.212509) (xy 351.57346 -276.210528) (xy 351.622315 -276.21646)
			(xy 351.669586 -276.230152) (xy 351.714048 -276.25125) (xy 351.754551 -276.279206) (xy 351.790044 -276.313298)
			(xy 351.819609 -276.352642) (xy 351.84248 -276.396219) (xy 351.858064 -276.4429) (xy 351.865959 -276.491477)
			(xy 351.866454 -276.516084) (xy 352.195396 -276.516084) (xy 352.199356 -276.46703) (xy 352.211133 -276.419246)
			(xy 352.230424 -276.37397) (xy 352.256727 -276.332374) (xy 352.289362 -276.295537) (xy 352.327483 -276.264412)
			(xy 352.370104 -276.239805) (xy 352.41612 -276.222353) (xy 352.464339 -276.212509) (xy 352.513514 -276.210528)
			(xy 352.562369 -276.21646) (xy 352.60964 -276.230152) (xy 352.654102 -276.25125) (xy 352.694605 -276.279206)
			(xy 352.730098 -276.313298) (xy 352.759663 -276.352642) (xy 352.782534 -276.396219) (xy 352.798118 -276.4429)
			(xy 352.806013 -276.491477) (xy 352.806508 -276.516084) (xy 353.135196 -276.516084) (xy 353.139156 -276.46703)
			(xy 353.150933 -276.419246) (xy 353.170224 -276.37397) (xy 353.196527 -276.332374) (xy 353.229162 -276.295537)
			(xy 353.267283 -276.264412) (xy 353.309904 -276.239805) (xy 353.35592 -276.222353) (xy 353.404139 -276.212509)
			(xy 353.453314 -276.210528) (xy 353.502169 -276.21646) (xy 353.54944 -276.230152) (xy 353.593902 -276.25125)
			(xy 353.634405 -276.279206) (xy 353.669898 -276.313298) (xy 353.699463 -276.352642) (xy 353.722334 -276.396219)
			(xy 353.737918 -276.4429) (xy 353.745813 -276.491477) (xy 353.746308 -276.516084) (xy 354.07525 -276.516084)
			(xy 354.07921 -276.46703) (xy 354.090987 -276.419246) (xy 354.110278 -276.37397) (xy 354.136581 -276.332374)
			(xy 354.169216 -276.295537) (xy 354.207337 -276.264412) (xy 354.249958 -276.239805) (xy 354.295974 -276.222353)
			(xy 354.344193 -276.212509) (xy 354.393368 -276.210528) (xy 354.442223 -276.21646) (xy 354.489494 -276.230152)
			(xy 354.533956 -276.25125) (xy 354.574459 -276.279206) (xy 354.609952 -276.313298) (xy 354.639517 -276.352642)
			(xy 354.662388 -276.396219) (xy 354.677972 -276.4429) (xy 354.685867 -276.491477) (xy 354.686362 -276.516084)
			(xy 355.015304 -276.516084) (xy 355.019264 -276.46703) (xy 355.031041 -276.419246) (xy 355.050332 -276.37397)
			(xy 355.076635 -276.332374) (xy 355.10927 -276.295537) (xy 355.147391 -276.264412) (xy 355.190012 -276.239805)
			(xy 355.236028 -276.222353) (xy 355.284247 -276.212509) (xy 355.333422 -276.210528) (xy 355.382277 -276.21646)
			(xy 355.429548 -276.230152) (xy 355.47401 -276.25125) (xy 355.514513 -276.279206) (xy 355.550006 -276.313298)
			(xy 355.579571 -276.352642) (xy 355.602442 -276.396219) (xy 355.618026 -276.4429) (xy 355.625921 -276.491477)
			(xy 355.626416 -276.516084) (xy 355.955358 -276.516084) (xy 355.959318 -276.46703) (xy 355.971095 -276.419246)
			(xy 355.990386 -276.37397) (xy 356.016689 -276.332374) (xy 356.049324 -276.295537) (xy 356.087445 -276.264412)
			(xy 356.130066 -276.239805) (xy 356.176082 -276.222353) (xy 356.224301 -276.212509) (xy 356.273476 -276.210528)
			(xy 356.322331 -276.21646) (xy 356.369602 -276.230152) (xy 356.414064 -276.25125) (xy 356.454567 -276.279206)
			(xy 356.49006 -276.313298) (xy 356.519625 -276.352642) (xy 356.542496 -276.396219) (xy 356.55808 -276.4429)
			(xy 356.565975 -276.491477) (xy 356.56647 -276.516084) (xy 356.895412 -276.516084) (xy 356.899372 -276.46703)
			(xy 356.911149 -276.419246) (xy 356.93044 -276.37397) (xy 356.956743 -276.332374) (xy 356.989378 -276.295537)
			(xy 357.027499 -276.264412) (xy 357.07012 -276.239805) (xy 357.116136 -276.222353) (xy 357.164355 -276.212509)
			(xy 357.21353 -276.210528) (xy 357.262385 -276.21646) (xy 357.309656 -276.230152) (xy 357.354118 -276.25125)
			(xy 357.394621 -276.279206) (xy 357.430114 -276.313298) (xy 357.459679 -276.352642) (xy 357.48255 -276.396219)
			(xy 357.498134 -276.4429) (xy 357.506029 -276.491477) (xy 357.506524 -276.516084) (xy 357.835212 -276.516084)
			(xy 357.839172 -276.46703) (xy 357.850949 -276.419246) (xy 357.87024 -276.37397) (xy 357.896543 -276.332374)
			(xy 357.929178 -276.295537) (xy 357.967299 -276.264412) (xy 358.00992 -276.239805) (xy 358.055936 -276.222353)
			(xy 358.104155 -276.212509) (xy 358.15333 -276.210528) (xy 358.202185 -276.21646) (xy 358.249456 -276.230152)
			(xy 358.293918 -276.25125) (xy 358.334421 -276.279206) (xy 358.369914 -276.313298) (xy 358.399479 -276.352642)
			(xy 358.42235 -276.396219) (xy 358.437934 -276.4429) (xy 358.445829 -276.491477) (xy 358.446324 -276.516084)
			(xy 361.589078 -276.516084) (xy 361.593038 -276.46703) (xy 361.604815 -276.419246) (xy 361.624106 -276.37397)
			(xy 361.650409 -276.332374) (xy 361.683044 -276.295537) (xy 361.721165 -276.264412) (xy 361.763786 -276.239805)
			(xy 361.809802 -276.222353) (xy 361.858021 -276.212509) (xy 361.907196 -276.210528) (xy 361.956051 -276.21646)
			(xy 362.003322 -276.230152) (xy 362.047784 -276.25125) (xy 362.088287 -276.279206) (xy 362.12378 -276.313298)
			(xy 362.153345 -276.352642) (xy 362.176216 -276.396219) (xy 362.1918 -276.4429) (xy 362.199695 -276.491477)
			(xy 362.20019 -276.516084) (xy 362.528878 -276.516084) (xy 362.532838 -276.46703) (xy 362.544615 -276.419246)
			(xy 362.563906 -276.37397) (xy 362.590209 -276.332374) (xy 362.622844 -276.295537) (xy 362.660965 -276.264412)
			(xy 362.703586 -276.239805) (xy 362.749602 -276.222353) (xy 362.797821 -276.212509) (xy 362.846996 -276.210528)
			(xy 362.895851 -276.21646) (xy 362.943122 -276.230152) (xy 362.987584 -276.25125) (xy 363.028087 -276.279206)
			(xy 363.06358 -276.313298) (xy 363.093145 -276.352642) (xy 363.116016 -276.396219) (xy 363.1316 -276.4429)
			(xy 363.139495 -276.491477) (xy 363.13999 -276.516084) (xy 363.468932 -276.516084) (xy 363.472892 -276.46703)
			(xy 363.484669 -276.419246) (xy 363.50396 -276.37397) (xy 363.530263 -276.332374) (xy 363.562898 -276.295537)
			(xy 363.601019 -276.264412) (xy 363.64364 -276.239805) (xy 363.689656 -276.222353) (xy 363.737875 -276.212509)
			(xy 363.78705 -276.210528) (xy 363.835905 -276.21646) (xy 363.883176 -276.230152) (xy 363.927638 -276.25125)
			(xy 363.968141 -276.279206) (xy 364.003634 -276.313298) (xy 364.033199 -276.352642) (xy 364.05607 -276.396219)
			(xy 364.071654 -276.4429) (xy 364.079549 -276.491477) (xy 364.080044 -276.516084) (xy 364.408986 -276.516084)
			(xy 364.412946 -276.46703) (xy 364.424723 -276.419246) (xy 364.444014 -276.37397) (xy 364.470317 -276.332374)
			(xy 364.502952 -276.295537) (xy 364.541073 -276.264412) (xy 364.583694 -276.239805) (xy 364.62971 -276.222353)
			(xy 364.677929 -276.212509) (xy 364.727104 -276.210528) (xy 364.775959 -276.21646) (xy 364.82323 -276.230152)
			(xy 364.867692 -276.25125) (xy 364.908195 -276.279206) (xy 364.943688 -276.313298) (xy 364.973253 -276.352642)
			(xy 364.996124 -276.396219) (xy 365.011708 -276.4429) (xy 365.019603 -276.491477) (xy 365.020098 -276.516084)
			(xy 365.34904 -276.516084) (xy 365.353 -276.46703) (xy 365.364777 -276.419246) (xy 365.384068 -276.37397)
			(xy 365.410371 -276.332374) (xy 365.443006 -276.295537) (xy 365.481127 -276.264412) (xy 365.523748 -276.239805)
			(xy 365.569764 -276.222353) (xy 365.617983 -276.212509) (xy 365.667158 -276.210528) (xy 365.716013 -276.21646)
			(xy 365.763284 -276.230152) (xy 365.807746 -276.25125) (xy 365.848249 -276.279206) (xy 365.883742 -276.313298)
			(xy 365.913307 -276.352642) (xy 365.936178 -276.396219) (xy 365.951762 -276.4429) (xy 365.959657 -276.491477)
			(xy 365.960152 -276.516084) (xy 366.289094 -276.516084) (xy 366.293054 -276.46703) (xy 366.304831 -276.419246)
			(xy 366.324122 -276.37397) (xy 366.350425 -276.332374) (xy 366.38306 -276.295537) (xy 366.421181 -276.264412)
			(xy 366.463802 -276.239805) (xy 366.509818 -276.222353) (xy 366.558037 -276.212509) (xy 366.607212 -276.210528)
			(xy 366.656067 -276.21646) (xy 366.703338 -276.230152) (xy 366.7478 -276.25125) (xy 366.788303 -276.279206)
			(xy 366.823796 -276.313298) (xy 366.853361 -276.352642) (xy 366.876232 -276.396219) (xy 366.891816 -276.4429)
			(xy 366.899711 -276.491477) (xy 366.900206 -276.516084) (xy 367.228894 -276.516084) (xy 367.232854 -276.46703)
			(xy 367.244631 -276.419246) (xy 367.263922 -276.37397) (xy 367.290225 -276.332374) (xy 367.32286 -276.295537)
			(xy 367.360981 -276.264412) (xy 367.403602 -276.239805) (xy 367.449618 -276.222353) (xy 367.497837 -276.212509)
			(xy 367.547012 -276.210528) (xy 367.595867 -276.21646) (xy 367.643138 -276.230152) (xy 367.6876 -276.25125)
			(xy 367.728103 -276.279206) (xy 367.763596 -276.313298) (xy 367.793161 -276.352642) (xy 367.816032 -276.396219)
			(xy 367.831616 -276.4429) (xy 367.839511 -276.491477) (xy 367.840006 -276.516084) (xy 368.168948 -276.516084)
			(xy 368.172908 -276.46703) (xy 368.184685 -276.419246) (xy 368.203976 -276.37397) (xy 368.230279 -276.332374)
			(xy 368.262914 -276.295537) (xy 368.301035 -276.264412) (xy 368.343656 -276.239805) (xy 368.389672 -276.222353)
			(xy 368.437891 -276.212509) (xy 368.487066 -276.210528) (xy 368.535921 -276.21646) (xy 368.583192 -276.230152)
			(xy 368.627654 -276.25125) (xy 368.668157 -276.279206) (xy 368.70365 -276.313298) (xy 368.733215 -276.352642)
			(xy 368.756086 -276.396219) (xy 368.77167 -276.4429) (xy 368.779565 -276.491477) (xy 368.78006 -276.516084)
			(xy 369.109002 -276.516084) (xy 369.112962 -276.46703) (xy 369.124739 -276.419246) (xy 369.14403 -276.37397)
			(xy 369.170333 -276.332374) (xy 369.202968 -276.295537) (xy 369.241089 -276.264412) (xy 369.28371 -276.239805)
			(xy 369.329726 -276.222353) (xy 369.377945 -276.212509) (xy 369.42712 -276.210528) (xy 369.475975 -276.21646)
			(xy 369.523246 -276.230152) (xy 369.567708 -276.25125) (xy 369.608211 -276.279206) (xy 369.643704 -276.313298)
			(xy 369.673269 -276.352642) (xy 369.69614 -276.396219) (xy 369.711724 -276.4429) (xy 369.719619 -276.491477)
			(xy 369.720114 -276.516084) (xy 370.049056 -276.516084) (xy 370.053016 -276.46703) (xy 370.064793 -276.419246)
			(xy 370.084084 -276.37397) (xy 370.110387 -276.332374) (xy 370.143022 -276.295537) (xy 370.181143 -276.264412)
			(xy 370.223764 -276.239805) (xy 370.26978 -276.222353) (xy 370.317999 -276.212509) (xy 370.367174 -276.210528)
			(xy 370.416029 -276.21646) (xy 370.4633 -276.230152) (xy 370.507762 -276.25125) (xy 370.548265 -276.279206)
			(xy 370.583758 -276.313298) (xy 370.613323 -276.352642) (xy 370.636194 -276.396219) (xy 370.651778 -276.4429)
			(xy 370.659673 -276.491477) (xy 370.660168 -276.516084) (xy 370.98911 -276.516084) (xy 370.99307 -276.46703)
			(xy 371.004847 -276.419246) (xy 371.024138 -276.37397) (xy 371.050441 -276.332374) (xy 371.083076 -276.295537)
			(xy 371.121197 -276.264412) (xy 371.163818 -276.239805) (xy 371.209834 -276.222353) (xy 371.258053 -276.212509)
			(xy 371.307228 -276.210528) (xy 371.356083 -276.21646) (xy 371.403354 -276.230152) (xy 371.447816 -276.25125)
			(xy 371.488319 -276.279206) (xy 371.523812 -276.313298) (xy 371.553377 -276.352642) (xy 371.576248 -276.396219)
			(xy 371.591832 -276.4429) (xy 371.599727 -276.491477) (xy 371.600222 -276.516084) (xy 371.92891 -276.516084)
			(xy 371.93287 -276.46703) (xy 371.944647 -276.419246) (xy 371.963938 -276.37397) (xy 371.990241 -276.332374)
			(xy 372.022876 -276.295537) (xy 372.060997 -276.264412) (xy 372.103618 -276.239805) (xy 372.149634 -276.222353)
			(xy 372.197853 -276.212509) (xy 372.247028 -276.210528) (xy 372.295883 -276.21646) (xy 372.343154 -276.230152)
			(xy 372.387616 -276.25125) (xy 372.428119 -276.279206) (xy 372.463612 -276.313298) (xy 372.493177 -276.352642)
			(xy 372.516048 -276.396219) (xy 372.531632 -276.4429) (xy 372.539527 -276.491477) (xy 372.540022 -276.516084)
			(xy 372.868964 -276.516084) (xy 372.872924 -276.46703) (xy 372.884701 -276.419246) (xy 372.903992 -276.37397)
			(xy 372.930295 -276.332374) (xy 372.96293 -276.295537) (xy 373.001051 -276.264412) (xy 373.043672 -276.239805)
			(xy 373.089688 -276.222353) (xy 373.137907 -276.212509) (xy 373.187082 -276.210528) (xy 373.235937 -276.21646)
			(xy 373.283208 -276.230152) (xy 373.32767 -276.25125) (xy 373.368173 -276.279206) (xy 373.403666 -276.313298)
			(xy 373.433231 -276.352642) (xy 373.456102 -276.396219) (xy 373.471686 -276.4429) (xy 373.479581 -276.491477)
			(xy 373.480076 -276.516084) (xy 373.809018 -276.516084) (xy 373.812978 -276.46703) (xy 373.824755 -276.419246)
			(xy 373.844046 -276.37397) (xy 373.870349 -276.332374) (xy 373.902984 -276.295537) (xy 373.941105 -276.264412)
			(xy 373.983726 -276.239805) (xy 374.029742 -276.222353) (xy 374.077961 -276.212509) (xy 374.127136 -276.210528)
			(xy 374.175991 -276.21646) (xy 374.223262 -276.230152) (xy 374.267724 -276.25125) (xy 374.308227 -276.279206)
			(xy 374.34372 -276.313298) (xy 374.373285 -276.352642) (xy 374.396156 -276.396219) (xy 374.41174 -276.4429)
			(xy 374.419635 -276.491477) (xy 374.42013 -276.516084) (xy 374.749072 -276.516084) (xy 374.753032 -276.46703)
			(xy 374.764809 -276.419246) (xy 374.7841 -276.37397) (xy 374.810403 -276.332374) (xy 374.843038 -276.295537)
			(xy 374.881159 -276.264412) (xy 374.92378 -276.239805) (xy 374.969796 -276.222353) (xy 375.018015 -276.212509)
			(xy 375.06719 -276.210528) (xy 375.116045 -276.21646) (xy 375.163316 -276.230152) (xy 375.207778 -276.25125)
			(xy 375.248281 -276.279206) (xy 375.283774 -276.313298) (xy 375.313339 -276.352642) (xy 375.33621 -276.396219)
			(xy 375.351794 -276.4429) (xy 375.359689 -276.491477) (xy 375.360184 -276.516084) (xy 375.678695 -276.516084)
			(xy 375.68279 -276.465356) (xy 375.694969 -276.415942) (xy 375.714917 -276.369122) (xy 375.742118 -276.326108)
			(xy 375.775866 -276.288014) (xy 375.815288 -276.255827) (xy 375.859362 -276.230381) (xy 375.906948 -276.212334)
			(xy 375.956812 -276.202154) (xy 376.007664 -276.200105) (xy 376.058185 -276.206239) (xy 376.107069 -276.220399)
			(xy 376.153048 -276.242216) (xy 376.194932 -276.271126) (xy 376.231636 -276.306381) (xy 376.262209 -276.347067)
			(xy 376.28586 -276.39213) (xy 376.301976 -276.440404) (xy 376.31014 -276.490638) (xy 376.310652 -276.516084)
			(xy 376.628926 -276.516084) (xy 376.632886 -276.46703) (xy 376.644663 -276.419246) (xy 376.663954 -276.37397)
			(xy 376.690257 -276.332374) (xy 376.722892 -276.295537) (xy 376.761013 -276.264412) (xy 376.803634 -276.239805)
			(xy 376.84965 -276.222353) (xy 376.897869 -276.212509) (xy 376.947044 -276.210528) (xy 376.995899 -276.21646)
			(xy 377.04317 -276.230152) (xy 377.087632 -276.25125) (xy 377.128135 -276.279206) (xy 377.163628 -276.313298)
			(xy 377.193193 -276.352642) (xy 377.216064 -276.396219) (xy 377.231648 -276.4429) (xy 377.239543 -276.491477)
			(xy 377.240038 -276.516084) (xy 377.558549 -276.516084) (xy 377.562644 -276.465356) (xy 377.574823 -276.415942)
			(xy 377.594771 -276.369122) (xy 377.621972 -276.326108) (xy 377.65572 -276.288014) (xy 377.695142 -276.255827)
			(xy 377.739216 -276.230381) (xy 377.786802 -276.212334) (xy 377.836666 -276.202154) (xy 377.887518 -276.200105)
			(xy 377.938039 -276.206239) (xy 377.986923 -276.220399) (xy 378.032902 -276.242216) (xy 378.074786 -276.271126)
			(xy 378.11149 -276.306381) (xy 378.142063 -276.347067) (xy 378.165714 -276.39213) (xy 378.18183 -276.440404)
			(xy 378.189994 -276.490638) (xy 378.190506 -276.516084) (xy 378.189994 -276.54153) (xy 378.18183 -276.591764)
			(xy 378.165714 -276.640038) (xy 378.142063 -276.685101) (xy 378.11149 -276.725787) (xy 378.074786 -276.761042)
			(xy 378.032902 -276.789952) (xy 377.986923 -276.811769) (xy 377.938039 -276.825929) (xy 377.887518 -276.832063)
			(xy 377.836666 -276.830014) (xy 377.786802 -276.819834) (xy 377.739216 -276.801787) (xy 377.695142 -276.776341)
			(xy 377.65572 -276.744154) (xy 377.621972 -276.70606) (xy 377.594771 -276.663046) (xy 377.574823 -276.616226)
			(xy 377.562644 -276.566812) (xy 377.558549 -276.516084) (xy 377.240038 -276.516084) (xy 377.239543 -276.540691)
			(xy 377.231648 -276.589268) (xy 377.216064 -276.635949) (xy 377.193193 -276.679526) (xy 377.163628 -276.71887)
			(xy 377.128135 -276.752962) (xy 377.087632 -276.780918) (xy 377.04317 -276.802016) (xy 376.995899 -276.815708)
			(xy 376.947044 -276.82164) (xy 376.897869 -276.819659) (xy 376.84965 -276.809815) (xy 376.803634 -276.792363)
			(xy 376.761013 -276.767756) (xy 376.722892 -276.736631) (xy 376.690257 -276.699794) (xy 376.663954 -276.658198)
			(xy 376.644663 -276.612922) (xy 376.632886 -276.565138) (xy 376.628926 -276.516084) (xy 376.310652 -276.516084)
			(xy 376.31014 -276.54153) (xy 376.301976 -276.591764) (xy 376.28586 -276.640038) (xy 376.262209 -276.685101)
			(xy 376.231636 -276.725787) (xy 376.194932 -276.761042) (xy 376.153048 -276.789952) (xy 376.107069 -276.811769)
			(xy 376.058185 -276.825929) (xy 376.007664 -276.832063) (xy 375.956812 -276.830014) (xy 375.906948 -276.819834)
			(xy 375.859362 -276.801787) (xy 375.815288 -276.776341) (xy 375.775866 -276.744154) (xy 375.742118 -276.70606)
			(xy 375.714917 -276.663046) (xy 375.694969 -276.616226) (xy 375.68279 -276.566812) (xy 375.678695 -276.516084)
			(xy 375.360184 -276.516084) (xy 375.359689 -276.540691) (xy 375.351794 -276.589268) (xy 375.33621 -276.635949)
			(xy 375.313339 -276.679526) (xy 375.283774 -276.71887) (xy 375.248281 -276.752962) (xy 375.207778 -276.780918)
			(xy 375.163316 -276.802016) (xy 375.116045 -276.815708) (xy 375.06719 -276.82164) (xy 375.018015 -276.819659)
			(xy 374.969796 -276.809815) (xy 374.92378 -276.792363) (xy 374.881159 -276.767756) (xy 374.843038 -276.736631)
			(xy 374.810403 -276.699794) (xy 374.7841 -276.658198) (xy 374.764809 -276.612922) (xy 374.753032 -276.565138)
			(xy 374.749072 -276.516084) (xy 374.42013 -276.516084) (xy 374.419635 -276.540691) (xy 374.41174 -276.589268)
			(xy 374.396156 -276.635949) (xy 374.373285 -276.679526) (xy 374.34372 -276.71887) (xy 374.308227 -276.752962)
			(xy 374.267724 -276.780918) (xy 374.223262 -276.802016) (xy 374.175991 -276.815708) (xy 374.127136 -276.82164)
			(xy 374.077961 -276.819659) (xy 374.029742 -276.809815) (xy 373.983726 -276.792363) (xy 373.941105 -276.767756)
			(xy 373.902984 -276.736631) (xy 373.870349 -276.699794) (xy 373.844046 -276.658198) (xy 373.824755 -276.612922)
			(xy 373.812978 -276.565138) (xy 373.809018 -276.516084) (xy 373.480076 -276.516084) (xy 373.479581 -276.540691)
			(xy 373.471686 -276.589268) (xy 373.456102 -276.635949) (xy 373.433231 -276.679526) (xy 373.403666 -276.71887)
			(xy 373.368173 -276.752962) (xy 373.32767 -276.780918) (xy 373.283208 -276.802016) (xy 373.235937 -276.815708)
			(xy 373.187082 -276.82164) (xy 373.137907 -276.819659) (xy 373.089688 -276.809815) (xy 373.043672 -276.792363)
			(xy 373.001051 -276.767756) (xy 372.96293 -276.736631) (xy 372.930295 -276.699794) (xy 372.903992 -276.658198)
			(xy 372.884701 -276.612922) (xy 372.872924 -276.565138) (xy 372.868964 -276.516084) (xy 372.540022 -276.516084)
			(xy 372.539527 -276.540691) (xy 372.531632 -276.589268) (xy 372.516048 -276.635949) (xy 372.493177 -276.679526)
			(xy 372.463612 -276.71887) (xy 372.428119 -276.752962) (xy 372.387616 -276.780918) (xy 372.343154 -276.802016)
			(xy 372.295883 -276.815708) (xy 372.247028 -276.82164) (xy 372.197853 -276.819659) (xy 372.149634 -276.809815)
			(xy 372.103618 -276.792363) (xy 372.060997 -276.767756) (xy 372.022876 -276.736631) (xy 371.990241 -276.699794)
			(xy 371.963938 -276.658198) (xy 371.944647 -276.612922) (xy 371.93287 -276.565138) (xy 371.92891 -276.516084)
			(xy 371.600222 -276.516084) (xy 371.599727 -276.540691) (xy 371.591832 -276.589268) (xy 371.576248 -276.635949)
			(xy 371.553377 -276.679526) (xy 371.523812 -276.71887) (xy 371.488319 -276.752962) (xy 371.447816 -276.780918)
			(xy 371.403354 -276.802016) (xy 371.356083 -276.815708) (xy 371.307228 -276.82164) (xy 371.258053 -276.819659)
			(xy 371.209834 -276.809815) (xy 371.163818 -276.792363) (xy 371.121197 -276.767756) (xy 371.083076 -276.736631)
			(xy 371.050441 -276.699794) (xy 371.024138 -276.658198) (xy 371.004847 -276.612922) (xy 370.99307 -276.565138)
			(xy 370.98911 -276.516084) (xy 370.660168 -276.516084) (xy 370.659673 -276.540691) (xy 370.651778 -276.589268)
			(xy 370.636194 -276.635949) (xy 370.613323 -276.679526) (xy 370.583758 -276.71887) (xy 370.548265 -276.752962)
			(xy 370.507762 -276.780918) (xy 370.4633 -276.802016) (xy 370.416029 -276.815708) (xy 370.367174 -276.82164)
			(xy 370.317999 -276.819659) (xy 370.26978 -276.809815) (xy 370.223764 -276.792363) (xy 370.181143 -276.767756)
			(xy 370.143022 -276.736631) (xy 370.110387 -276.699794) (xy 370.084084 -276.658198) (xy 370.064793 -276.612922)
			(xy 370.053016 -276.565138) (xy 370.049056 -276.516084) (xy 369.720114 -276.516084) (xy 369.719619 -276.540691)
			(xy 369.711724 -276.589268) (xy 369.69614 -276.635949) (xy 369.673269 -276.679526) (xy 369.643704 -276.71887)
			(xy 369.608211 -276.752962) (xy 369.567708 -276.780918) (xy 369.523246 -276.802016) (xy 369.475975 -276.815708)
			(xy 369.42712 -276.82164) (xy 369.377945 -276.819659) (xy 369.329726 -276.809815) (xy 369.28371 -276.792363)
			(xy 369.241089 -276.767756) (xy 369.202968 -276.736631) (xy 369.170333 -276.699794) (xy 369.14403 -276.658198)
			(xy 369.124739 -276.612922) (xy 369.112962 -276.565138) (xy 369.109002 -276.516084) (xy 368.78006 -276.516084)
			(xy 368.779565 -276.540691) (xy 368.77167 -276.589268) (xy 368.756086 -276.635949) (xy 368.733215 -276.679526)
			(xy 368.70365 -276.71887) (xy 368.668157 -276.752962) (xy 368.627654 -276.780918) (xy 368.583192 -276.802016)
			(xy 368.535921 -276.815708) (xy 368.487066 -276.82164) (xy 368.437891 -276.819659) (xy 368.389672 -276.809815)
			(xy 368.343656 -276.792363) (xy 368.301035 -276.767756) (xy 368.262914 -276.736631) (xy 368.230279 -276.699794)
			(xy 368.203976 -276.658198) (xy 368.184685 -276.612922) (xy 368.172908 -276.565138) (xy 368.168948 -276.516084)
			(xy 367.840006 -276.516084) (xy 367.839511 -276.540691) (xy 367.831616 -276.589268) (xy 367.816032 -276.635949)
			(xy 367.793161 -276.679526) (xy 367.763596 -276.71887) (xy 367.728103 -276.752962) (xy 367.6876 -276.780918)
			(xy 367.643138 -276.802016) (xy 367.595867 -276.815708) (xy 367.547012 -276.82164) (xy 367.497837 -276.819659)
			(xy 367.449618 -276.809815) (xy 367.403602 -276.792363) (xy 367.360981 -276.767756) (xy 367.32286 -276.736631)
			(xy 367.290225 -276.699794) (xy 367.263922 -276.658198) (xy 367.244631 -276.612922) (xy 367.232854 -276.565138)
			(xy 367.228894 -276.516084) (xy 366.900206 -276.516084) (xy 366.899711 -276.540691) (xy 366.891816 -276.589268)
			(xy 366.876232 -276.635949) (xy 366.853361 -276.679526) (xy 366.823796 -276.71887) (xy 366.788303 -276.752962)
			(xy 366.7478 -276.780918) (xy 366.703338 -276.802016) (xy 366.656067 -276.815708) (xy 366.607212 -276.82164)
			(xy 366.558037 -276.819659) (xy 366.509818 -276.809815) (xy 366.463802 -276.792363) (xy 366.421181 -276.767756)
			(xy 366.38306 -276.736631) (xy 366.350425 -276.699794) (xy 366.324122 -276.658198) (xy 366.304831 -276.612922)
			(xy 366.293054 -276.565138) (xy 366.289094 -276.516084) (xy 365.960152 -276.516084) (xy 365.959657 -276.540691)
			(xy 365.951762 -276.589268) (xy 365.936178 -276.635949) (xy 365.913307 -276.679526) (xy 365.883742 -276.71887)
			(xy 365.848249 -276.752962) (xy 365.807746 -276.780918) (xy 365.763284 -276.802016) (xy 365.716013 -276.815708)
			(xy 365.667158 -276.82164) (xy 365.617983 -276.819659) (xy 365.569764 -276.809815) (xy 365.523748 -276.792363)
			(xy 365.481127 -276.767756) (xy 365.443006 -276.736631) (xy 365.410371 -276.699794) (xy 365.384068 -276.658198)
			(xy 365.364777 -276.612922) (xy 365.353 -276.565138) (xy 365.34904 -276.516084) (xy 365.020098 -276.516084)
			(xy 365.019603 -276.540691) (xy 365.011708 -276.589268) (xy 364.996124 -276.635949) (xy 364.973253 -276.679526)
			(xy 364.943688 -276.71887) (xy 364.908195 -276.752962) (xy 364.867692 -276.780918) (xy 364.82323 -276.802016)
			(xy 364.775959 -276.815708) (xy 364.727104 -276.82164) (xy 364.677929 -276.819659) (xy 364.62971 -276.809815)
			(xy 364.583694 -276.792363) (xy 364.541073 -276.767756) (xy 364.502952 -276.736631) (xy 364.470317 -276.699794)
			(xy 364.444014 -276.658198) (xy 364.424723 -276.612922) (xy 364.412946 -276.565138) (xy 364.408986 -276.516084)
			(xy 364.080044 -276.516084) (xy 364.079549 -276.540691) (xy 364.071654 -276.589268) (xy 364.05607 -276.635949)
			(xy 364.033199 -276.679526) (xy 364.003634 -276.71887) (xy 363.968141 -276.752962) (xy 363.927638 -276.780918)
			(xy 363.883176 -276.802016) (xy 363.835905 -276.815708) (xy 363.78705 -276.82164) (xy 363.737875 -276.819659)
			(xy 363.689656 -276.809815) (xy 363.64364 -276.792363) (xy 363.601019 -276.767756) (xy 363.562898 -276.736631)
			(xy 363.530263 -276.699794) (xy 363.50396 -276.658198) (xy 363.484669 -276.612922) (xy 363.472892 -276.565138)
			(xy 363.468932 -276.516084) (xy 363.13999 -276.516084) (xy 363.139495 -276.540691) (xy 363.1316 -276.589268)
			(xy 363.116016 -276.635949) (xy 363.093145 -276.679526) (xy 363.06358 -276.71887) (xy 363.028087 -276.752962)
			(xy 362.987584 -276.780918) (xy 362.943122 -276.802016) (xy 362.895851 -276.815708) (xy 362.846996 -276.82164)
			(xy 362.797821 -276.819659) (xy 362.749602 -276.809815) (xy 362.703586 -276.792363) (xy 362.660965 -276.767756)
			(xy 362.622844 -276.736631) (xy 362.590209 -276.699794) (xy 362.563906 -276.658198) (xy 362.544615 -276.612922)
			(xy 362.532838 -276.565138) (xy 362.528878 -276.516084) (xy 362.20019 -276.516084) (xy 362.199695 -276.540691)
			(xy 362.1918 -276.589268) (xy 362.176216 -276.635949) (xy 362.153345 -276.679526) (xy 362.12378 -276.71887)
			(xy 362.088287 -276.752962) (xy 362.047784 -276.780918) (xy 362.003322 -276.802016) (xy 361.956051 -276.815708)
			(xy 361.907196 -276.82164) (xy 361.858021 -276.819659) (xy 361.809802 -276.809815) (xy 361.763786 -276.792363)
			(xy 361.721165 -276.767756) (xy 361.683044 -276.736631) (xy 361.650409 -276.699794) (xy 361.624106 -276.658198)
			(xy 361.604815 -276.612922) (xy 361.593038 -276.565138) (xy 361.589078 -276.516084) (xy 358.446324 -276.516084)
			(xy 358.445829 -276.540691) (xy 358.437934 -276.589268) (xy 358.42235 -276.635949) (xy 358.399479 -276.679526)
			(xy 358.369914 -276.71887) (xy 358.334421 -276.752962) (xy 358.293918 -276.780918) (xy 358.249456 -276.802016)
			(xy 358.202185 -276.815708) (xy 358.15333 -276.82164) (xy 358.104155 -276.819659) (xy 358.055936 -276.809815)
			(xy 358.00992 -276.792363) (xy 357.967299 -276.767756) (xy 357.929178 -276.736631) (xy 357.896543 -276.699794)
			(xy 357.87024 -276.658198) (xy 357.850949 -276.612922) (xy 357.839172 -276.565138) (xy 357.835212 -276.516084)
			(xy 357.506524 -276.516084) (xy 357.506029 -276.540691) (xy 357.498134 -276.589268) (xy 357.48255 -276.635949)
			(xy 357.459679 -276.679526) (xy 357.430114 -276.71887) (xy 357.394621 -276.752962) (xy 357.354118 -276.780918)
			(xy 357.309656 -276.802016) (xy 357.262385 -276.815708) (xy 357.21353 -276.82164) (xy 357.164355 -276.819659)
			(xy 357.116136 -276.809815) (xy 357.07012 -276.792363) (xy 357.027499 -276.767756) (xy 356.989378 -276.736631)
			(xy 356.956743 -276.699794) (xy 356.93044 -276.658198) (xy 356.911149 -276.612922) (xy 356.899372 -276.565138)
			(xy 356.895412 -276.516084) (xy 356.56647 -276.516084) (xy 356.565975 -276.540691) (xy 356.55808 -276.589268)
			(xy 356.542496 -276.635949) (xy 356.519625 -276.679526) (xy 356.49006 -276.71887) (xy 356.454567 -276.752962)
			(xy 356.414064 -276.780918) (xy 356.369602 -276.802016) (xy 356.322331 -276.815708) (xy 356.273476 -276.82164)
			(xy 356.224301 -276.819659) (xy 356.176082 -276.809815) (xy 356.130066 -276.792363) (xy 356.087445 -276.767756)
			(xy 356.049324 -276.736631) (xy 356.016689 -276.699794) (xy 355.990386 -276.658198) (xy 355.971095 -276.612922)
			(xy 355.959318 -276.565138) (xy 355.955358 -276.516084) (xy 355.626416 -276.516084) (xy 355.625921 -276.540691)
			(xy 355.618026 -276.589268) (xy 355.602442 -276.635949) (xy 355.579571 -276.679526) (xy 355.550006 -276.71887)
			(xy 355.514513 -276.752962) (xy 355.47401 -276.780918) (xy 355.429548 -276.802016) (xy 355.382277 -276.815708)
			(xy 355.333422 -276.82164) (xy 355.284247 -276.819659) (xy 355.236028 -276.809815) (xy 355.190012 -276.792363)
			(xy 355.147391 -276.767756) (xy 355.10927 -276.736631) (xy 355.076635 -276.699794) (xy 355.050332 -276.658198)
			(xy 355.031041 -276.612922) (xy 355.019264 -276.565138) (xy 355.015304 -276.516084) (xy 354.686362 -276.516084)
			(xy 354.685867 -276.540691) (xy 354.677972 -276.589268) (xy 354.662388 -276.635949) (xy 354.639517 -276.679526)
			(xy 354.609952 -276.71887) (xy 354.574459 -276.752962) (xy 354.533956 -276.780918) (xy 354.489494 -276.802016)
			(xy 354.442223 -276.815708) (xy 354.393368 -276.82164) (xy 354.344193 -276.819659) (xy 354.295974 -276.809815)
			(xy 354.249958 -276.792363) (xy 354.207337 -276.767756) (xy 354.169216 -276.736631) (xy 354.136581 -276.699794)
			(xy 354.110278 -276.658198) (xy 354.090987 -276.612922) (xy 354.07921 -276.565138) (xy 354.07525 -276.516084)
			(xy 353.746308 -276.516084) (xy 353.745813 -276.540691) (xy 353.737918 -276.589268) (xy 353.722334 -276.635949)
			(xy 353.699463 -276.679526) (xy 353.669898 -276.71887) (xy 353.634405 -276.752962) (xy 353.593902 -276.780918)
			(xy 353.54944 -276.802016) (xy 353.502169 -276.815708) (xy 353.453314 -276.82164) (xy 353.404139 -276.819659)
			(xy 353.35592 -276.809815) (xy 353.309904 -276.792363) (xy 353.267283 -276.767756) (xy 353.229162 -276.736631)
			(xy 353.196527 -276.699794) (xy 353.170224 -276.658198) (xy 353.150933 -276.612922) (xy 353.139156 -276.565138)
			(xy 353.135196 -276.516084) (xy 352.806508 -276.516084) (xy 352.806013 -276.540691) (xy 352.798118 -276.589268)
			(xy 352.782534 -276.635949) (xy 352.759663 -276.679526) (xy 352.730098 -276.71887) (xy 352.694605 -276.752962)
			(xy 352.654102 -276.780918) (xy 352.60964 -276.802016) (xy 352.562369 -276.815708) (xy 352.513514 -276.82164)
			(xy 352.464339 -276.819659) (xy 352.41612 -276.809815) (xy 352.370104 -276.792363) (xy 352.327483 -276.767756)
			(xy 352.289362 -276.736631) (xy 352.256727 -276.699794) (xy 352.230424 -276.658198) (xy 352.211133 -276.612922)
			(xy 352.199356 -276.565138) (xy 352.195396 -276.516084) (xy 351.866454 -276.516084) (xy 351.865959 -276.540691)
			(xy 351.858064 -276.589268) (xy 351.84248 -276.635949) (xy 351.819609 -276.679526) (xy 351.790044 -276.71887)
			(xy 351.754551 -276.752962) (xy 351.714048 -276.780918) (xy 351.669586 -276.802016) (xy 351.622315 -276.815708)
			(xy 351.57346 -276.82164) (xy 351.524285 -276.819659) (xy 351.476066 -276.809815) (xy 351.43005 -276.792363)
			(xy 351.387429 -276.767756) (xy 351.349308 -276.736631) (xy 351.316673 -276.699794) (xy 351.29037 -276.658198)
			(xy 351.271079 -276.612922) (xy 351.259302 -276.565138) (xy 351.255342 -276.516084) (xy 350.9264 -276.516084)
			(xy 350.925905 -276.540691) (xy 350.91801 -276.589268) (xy 350.902426 -276.635949) (xy 350.879555 -276.679526)
			(xy 350.84999 -276.71887) (xy 350.814497 -276.752962) (xy 350.773994 -276.780918) (xy 350.729532 -276.802016)
			(xy 350.682261 -276.815708) (xy 350.633406 -276.82164) (xy 350.584231 -276.819659) (xy 350.536012 -276.809815)
			(xy 350.489996 -276.792363) (xy 350.447375 -276.767756) (xy 350.409254 -276.736631) (xy 350.376619 -276.699794)
			(xy 350.350316 -276.658198) (xy 350.331025 -276.612922) (xy 350.319248 -276.565138) (xy 350.315288 -276.516084)
			(xy 349.986346 -276.516084) (xy 349.985851 -276.540691) (xy 349.977956 -276.589268) (xy 349.962372 -276.635949)
			(xy 349.939501 -276.679526) (xy 349.909936 -276.71887) (xy 349.874443 -276.752962) (xy 349.83394 -276.780918)
			(xy 349.789478 -276.802016) (xy 349.742207 -276.815708) (xy 349.693352 -276.82164) (xy 349.644177 -276.819659)
			(xy 349.595958 -276.809815) (xy 349.549942 -276.792363) (xy 349.507321 -276.767756) (xy 349.4692 -276.736631)
			(xy 349.436565 -276.699794) (xy 349.410262 -276.658198) (xy 349.390971 -276.612922) (xy 349.379194 -276.565138)
			(xy 349.375234 -276.516084) (xy 349.046546 -276.516084) (xy 349.046051 -276.540691) (xy 349.038156 -276.589268)
			(xy 349.022572 -276.635949) (xy 348.999701 -276.679526) (xy 348.970136 -276.71887) (xy 348.934643 -276.752962)
			(xy 348.89414 -276.780918) (xy 348.849678 -276.802016) (xy 348.802407 -276.815708) (xy 348.753552 -276.82164)
			(xy 348.704377 -276.819659) (xy 348.656158 -276.809815) (xy 348.610142 -276.792363) (xy 348.567521 -276.767756)
			(xy 348.5294 -276.736631) (xy 348.496765 -276.699794) (xy 348.470462 -276.658198) (xy 348.451171 -276.612922)
			(xy 348.439394 -276.565138) (xy 348.435434 -276.516084) (xy 348.106492 -276.516084) (xy 348.105997 -276.540691)
			(xy 348.098102 -276.589268) (xy 348.082518 -276.635949) (xy 348.059647 -276.679526) (xy 348.030082 -276.71887)
			(xy 347.994589 -276.752962) (xy 347.954086 -276.780918) (xy 347.909624 -276.802016) (xy 347.862353 -276.815708)
			(xy 347.813498 -276.82164) (xy 347.764323 -276.819659) (xy 347.716104 -276.809815) (xy 347.670088 -276.792363)
			(xy 347.627467 -276.767756) (xy 347.589346 -276.736631) (xy 347.556711 -276.699794) (xy 347.530408 -276.658198)
			(xy 347.511117 -276.612922) (xy 347.49934 -276.565138) (xy 347.49538 -276.516084) (xy 347.166438 -276.516084)
			(xy 347.165943 -276.540691) (xy 347.158048 -276.589268) (xy 347.142464 -276.635949) (xy 347.119593 -276.679526)
			(xy 347.090028 -276.71887) (xy 347.054535 -276.752962) (xy 347.014032 -276.780918) (xy 346.96957 -276.802016)
			(xy 346.922299 -276.815708) (xy 346.873444 -276.82164) (xy 346.824269 -276.819659) (xy 346.77605 -276.809815)
			(xy 346.730034 -276.792363) (xy 346.687413 -276.767756) (xy 346.649292 -276.736631) (xy 346.616657 -276.699794)
			(xy 346.590354 -276.658198) (xy 346.571063 -276.612922) (xy 346.559286 -276.565138) (xy 346.555326 -276.516084)
			(xy 346.226384 -276.516084) (xy 346.225889 -276.540691) (xy 346.217994 -276.589268) (xy 346.20241 -276.635949)
			(xy 346.179539 -276.679526) (xy 346.149974 -276.71887) (xy 346.114481 -276.752962) (xy 346.073978 -276.780918)
			(xy 346.029516 -276.802016) (xy 345.982245 -276.815708) (xy 345.93339 -276.82164) (xy 345.884215 -276.819659)
			(xy 345.835996 -276.809815) (xy 345.78998 -276.792363) (xy 345.747359 -276.767756) (xy 345.709238 -276.736631)
			(xy 345.676603 -276.699794) (xy 345.6503 -276.658198) (xy 345.631009 -276.612922) (xy 345.619232 -276.565138)
			(xy 345.615272 -276.516084) (xy 345.28633 -276.516084) (xy 345.285835 -276.540691) (xy 345.27794 -276.589268)
			(xy 345.262356 -276.635949) (xy 345.239485 -276.679526) (xy 345.20992 -276.71887) (xy 345.174427 -276.752962)
			(xy 345.133924 -276.780918) (xy 345.089462 -276.802016) (xy 345.042191 -276.815708) (xy 344.993336 -276.82164)
			(xy 344.944161 -276.819659) (xy 344.895942 -276.809815) (xy 344.849926 -276.792363) (xy 344.807305 -276.767756)
			(xy 344.769184 -276.736631) (xy 344.736549 -276.699794) (xy 344.710246 -276.658198) (xy 344.690955 -276.612922)
			(xy 344.679178 -276.565138) (xy 344.675218 -276.516084) (xy 344.356944 -276.516084) (xy 344.356432 -276.54153)
			(xy 344.348268 -276.591764) (xy 344.332152 -276.640038) (xy 344.308501 -276.685101) (xy 344.277928 -276.725787)
			(xy 344.241224 -276.761042) (xy 344.19934 -276.789952) (xy 344.153361 -276.811769) (xy 344.104477 -276.825929)
			(xy 344.053956 -276.832063) (xy 344.003104 -276.830014) (xy 343.95324 -276.819834) (xy 343.905654 -276.801787)
			(xy 343.86158 -276.776341) (xy 343.822158 -276.744154) (xy 343.78841 -276.70606) (xy 343.761209 -276.663046)
			(xy 343.741261 -276.616226) (xy 343.729082 -276.566812) (xy 343.724987 -276.516084) (xy 343.406476 -276.516084)
			(xy 343.405981 -276.540691) (xy 343.398086 -276.589268) (xy 343.382502 -276.635949) (xy 343.359631 -276.679526)
			(xy 343.330066 -276.71887) (xy 343.294573 -276.752962) (xy 343.25407 -276.780918) (xy 343.209608 -276.802016)
			(xy 343.162337 -276.815708) (xy 343.113482 -276.82164) (xy 343.064307 -276.819659) (xy 343.016088 -276.809815)
			(xy 342.970072 -276.792363) (xy 342.927451 -276.767756) (xy 342.88933 -276.736631) (xy 342.856695 -276.699794)
			(xy 342.830392 -276.658198) (xy 342.811101 -276.612922) (xy 342.799324 -276.565138) (xy 342.795364 -276.516084)
			(xy 342.476836 -276.516084) (xy 342.476324 -276.54153) (xy 342.46816 -276.591764) (xy 342.452044 -276.640038)
			(xy 342.428393 -276.685101) (xy 342.39782 -276.725787) (xy 342.361116 -276.761042) (xy 342.319232 -276.789952)
			(xy 342.273253 -276.811769) (xy 342.224369 -276.825929) (xy 342.173848 -276.832063) (xy 342.122996 -276.830014)
			(xy 342.073132 -276.819834) (xy 342.025546 -276.801787) (xy 341.981472 -276.776341) (xy 341.94205 -276.744154)
			(xy 341.908302 -276.70606) (xy 341.881101 -276.663046) (xy 341.861153 -276.616226) (xy 341.848974 -276.566812)
			(xy 341.844879 -276.516084) (xy 341.525969 -276.516084) (xy 341.525969 -276.540166) (xy 341.518416 -276.587706)
			(xy 341.503497 -276.633472) (xy 341.481581 -276.67633) (xy 341.453212 -276.715218) (xy 341.419093 -276.749173)
			(xy 341.380067 -276.777354) (xy 341.337104 -276.799062) (xy 341.291266 -276.813759) (xy 341.267542 -276.817836)
			(xy 341.258652 -276.819106) (xy 341.24265 -276.827996) (xy 341.236808 -276.834854) (xy 341.231215 -276.841938)
			(xy 341.224957 -276.858855) (xy 341.224616 -276.867874) (xy 341.224616 -277.020528) (xy 341.224751 -277.025419)
			(xy 341.226665 -277.035013) (xy 341.228426 -277.039578) (xy 341.232236 -277.047198) (xy 341.232998 -277.048468)
			(xy 341.238996 -277.059046) (xy 341.250176 -277.080644) (xy 341.25535 -277.091648) (xy 341.268558 -277.122636)
			(xy 341.268558 -277.12289) (xy 341.27125 -277.129092) (xy 341.279357 -277.139908) (xy 341.28456 -277.144226)
			(xy 341.28964 -277.14829) (xy 341.30234 -277.153624) (xy 341.397844 -277.165816) (xy 341.406973 -277.166616)
			(xy 341.424803 -277.162438) (xy 341.432642 -277.157688) (xy 341.436187 -277.15519) (xy 341.442443 -277.149187)
			(xy 341.445088 -277.14575) (xy 341.445088 -277.145496) (xy 341.459582 -277.126526) (xy 341.493473 -277.092904)
			(xy 341.532182 -277.064964) (xy 341.574766 -277.043388) (xy 341.620189 -277.0287) (xy 341.667345 -277.021259)
			(xy 341.691214 -277.020782) (xy 341.716469 -277.021305) (xy 341.766291 -277.029621) (xy 341.814064 -277.046023)
			(xy 341.858487 -277.070065) (xy 341.898346 -277.10109) (xy 341.932555 -277.138253) (xy 341.960181 -277.18054)
			(xy 341.980471 -277.226796) (xy 341.99287 -277.275762) (xy 341.99704 -277.32609) (xy 342.314779 -277.32609)
			(xy 342.318874 -277.275362) (xy 342.331053 -277.225948) (xy 342.351001 -277.179128) (xy 342.378202 -277.136114)
			(xy 342.41195 -277.09802) (xy 342.451372 -277.065833) (xy 342.495446 -277.040387) (xy 342.543032 -277.02234)
			(xy 342.592896 -277.01216) (xy 342.643748 -277.010111) (xy 342.694269 -277.016245) (xy 342.743153 -277.030405)
			(xy 342.789132 -277.052222) (xy 342.831016 -277.081132) (xy 342.86772 -277.116387) (xy 342.898293 -277.157073)
			(xy 342.921944 -277.202136) (xy 342.93806 -277.25041) (xy 342.946224 -277.300644) (xy 342.946736 -277.32609)
			(xy 343.254833 -277.32609) (xy 343.258928 -277.275362) (xy 343.271107 -277.225948) (xy 343.291055 -277.179128)
			(xy 343.318256 -277.136114) (xy 343.352004 -277.09802) (xy 343.391426 -277.065833) (xy 343.4355 -277.040387)
			(xy 343.483086 -277.02234) (xy 343.53295 -277.01216) (xy 343.583802 -277.010111) (xy 343.634323 -277.016245)
			(xy 343.683207 -277.030405) (xy 343.729186 -277.052222) (xy 343.77107 -277.081132) (xy 343.807774 -277.116387)
			(xy 343.838347 -277.157073) (xy 343.861998 -277.202136) (xy 343.878114 -277.25041) (xy 343.886278 -277.300644)
			(xy 343.88679 -277.32609) (xy 344.205318 -277.32609) (xy 344.209278 -277.277036) (xy 344.221055 -277.229252)
			(xy 344.240346 -277.183976) (xy 344.266649 -277.14238) (xy 344.299284 -277.105543) (xy 344.337405 -277.074418)
			(xy 344.380026 -277.049811) (xy 344.426042 -277.032359) (xy 344.474261 -277.022515) (xy 344.523436 -277.020534)
			(xy 344.572291 -277.026466) (xy 344.619562 -277.040158) (xy 344.664024 -277.061256) (xy 344.704527 -277.089212)
			(xy 344.74002 -277.123304) (xy 344.769585 -277.162648) (xy 344.792456 -277.206225) (xy 344.80804 -277.252906)
			(xy 344.815935 -277.301483) (xy 344.81643 -277.32609) (xy 345.145372 -277.32609) (xy 345.149332 -277.277036)
			(xy 345.161109 -277.229252) (xy 345.1804 -277.183976) (xy 345.206703 -277.14238) (xy 345.239338 -277.105543)
			(xy 345.277459 -277.074418) (xy 345.32008 -277.049811) (xy 345.366096 -277.032359) (xy 345.414315 -277.022515)
			(xy 345.46349 -277.020534) (xy 345.512345 -277.026466) (xy 345.559616 -277.040158) (xy 345.604078 -277.061256)
			(xy 345.644581 -277.089212) (xy 345.680074 -277.123304) (xy 345.709639 -277.162648) (xy 345.73251 -277.206225)
			(xy 345.748094 -277.252906) (xy 345.755989 -277.301483) (xy 345.756484 -277.32609) (xy 346.085426 -277.32609)
			(xy 346.089386 -277.277036) (xy 346.101163 -277.229252) (xy 346.120454 -277.183976) (xy 346.146757 -277.14238)
			(xy 346.179392 -277.105543) (xy 346.217513 -277.074418) (xy 346.260134 -277.049811) (xy 346.30615 -277.032359)
			(xy 346.354369 -277.022515) (xy 346.403544 -277.020534) (xy 346.452399 -277.026466) (xy 346.49967 -277.040158)
			(xy 346.544132 -277.061256) (xy 346.584635 -277.089212) (xy 346.620128 -277.123304) (xy 346.649693 -277.162648)
			(xy 346.672564 -277.206225) (xy 346.688148 -277.252906) (xy 346.696043 -277.301483) (xy 346.696538 -277.32609)
			(xy 347.025226 -277.32609) (xy 347.029186 -277.277036) (xy 347.040963 -277.229252) (xy 347.060254 -277.183976)
			(xy 347.086557 -277.14238) (xy 347.119192 -277.105543) (xy 347.157313 -277.074418) (xy 347.199934 -277.049811)
			(xy 347.24595 -277.032359) (xy 347.294169 -277.022515) (xy 347.343344 -277.020534) (xy 347.392199 -277.026466)
			(xy 347.43947 -277.040158) (xy 347.483932 -277.061256) (xy 347.524435 -277.089212) (xy 347.559928 -277.123304)
			(xy 347.589493 -277.162648) (xy 347.612364 -277.206225) (xy 347.627948 -277.252906) (xy 347.635843 -277.301483)
			(xy 347.636338 -277.32609) (xy 347.96528 -277.32609) (xy 347.96924 -277.277036) (xy 347.981017 -277.229252)
			(xy 348.000308 -277.183976) (xy 348.026611 -277.14238) (xy 348.059246 -277.105543) (xy 348.097367 -277.074418)
			(xy 348.139988 -277.049811) (xy 348.186004 -277.032359) (xy 348.234223 -277.022515) (xy 348.283398 -277.020534)
			(xy 348.332253 -277.026466) (xy 348.379524 -277.040158) (xy 348.423986 -277.061256) (xy 348.464489 -277.089212)
			(xy 348.499982 -277.123304) (xy 348.529547 -277.162648) (xy 348.552418 -277.206225) (xy 348.568002 -277.252906)
			(xy 348.575897 -277.301483) (xy 348.576392 -277.32609) (xy 348.905334 -277.32609) (xy 348.909294 -277.277036)
			(xy 348.921071 -277.229252) (xy 348.940362 -277.183976) (xy 348.966665 -277.14238) (xy 348.9993 -277.105543)
			(xy 349.037421 -277.074418) (xy 349.080042 -277.049811) (xy 349.126058 -277.032359) (xy 349.174277 -277.022515)
			(xy 349.223452 -277.020534) (xy 349.272307 -277.026466) (xy 349.319578 -277.040158) (xy 349.36404 -277.061256)
			(xy 349.404543 -277.089212) (xy 349.440036 -277.123304) (xy 349.469601 -277.162648) (xy 349.492472 -277.206225)
			(xy 349.508056 -277.252906) (xy 349.515951 -277.301483) (xy 349.516446 -277.32609) (xy 349.845388 -277.32609)
			(xy 349.849348 -277.277036) (xy 349.861125 -277.229252) (xy 349.880416 -277.183976) (xy 349.906719 -277.14238)
			(xy 349.939354 -277.105543) (xy 349.977475 -277.074418) (xy 350.020096 -277.049811) (xy 350.066112 -277.032359)
			(xy 350.114331 -277.022515) (xy 350.163506 -277.020534) (xy 350.212361 -277.026466) (xy 350.259632 -277.040158)
			(xy 350.304094 -277.061256) (xy 350.344597 -277.089212) (xy 350.38009 -277.123304) (xy 350.409655 -277.162648)
			(xy 350.432526 -277.206225) (xy 350.44811 -277.252906) (xy 350.456005 -277.301483) (xy 350.4565 -277.32609)
			(xy 350.785442 -277.32609) (xy 350.789402 -277.277036) (xy 350.801179 -277.229252) (xy 350.82047 -277.183976)
			(xy 350.846773 -277.14238) (xy 350.879408 -277.105543) (xy 350.917529 -277.074418) (xy 350.96015 -277.049811)
			(xy 351.006166 -277.032359) (xy 351.054385 -277.022515) (xy 351.10356 -277.020534) (xy 351.152415 -277.026466)
			(xy 351.199686 -277.040158) (xy 351.244148 -277.061256) (xy 351.284651 -277.089212) (xy 351.320144 -277.123304)
			(xy 351.349709 -277.162648) (xy 351.37258 -277.206225) (xy 351.388164 -277.252906) (xy 351.396059 -277.301483)
			(xy 351.396554 -277.32609) (xy 351.725242 -277.32609) (xy 351.729202 -277.277036) (xy 351.740979 -277.229252)
			(xy 351.76027 -277.183976) (xy 351.786573 -277.14238) (xy 351.819208 -277.105543) (xy 351.857329 -277.074418)
			(xy 351.89995 -277.049811) (xy 351.945966 -277.032359) (xy 351.994185 -277.022515) (xy 352.04336 -277.020534)
			(xy 352.092215 -277.026466) (xy 352.139486 -277.040158) (xy 352.183948 -277.061256) (xy 352.224451 -277.089212)
			(xy 352.259944 -277.123304) (xy 352.289509 -277.162648) (xy 352.31238 -277.206225) (xy 352.327964 -277.252906)
			(xy 352.335859 -277.301483) (xy 352.336354 -277.32609) (xy 352.665296 -277.32609) (xy 352.669256 -277.277036)
			(xy 352.681033 -277.229252) (xy 352.700324 -277.183976) (xy 352.726627 -277.14238) (xy 352.759262 -277.105543)
			(xy 352.797383 -277.074418) (xy 352.840004 -277.049811) (xy 352.88602 -277.032359) (xy 352.934239 -277.022515)
			(xy 352.983414 -277.020534) (xy 353.032269 -277.026466) (xy 353.07954 -277.040158) (xy 353.124002 -277.061256)
			(xy 353.164505 -277.089212) (xy 353.199998 -277.123304) (xy 353.229563 -277.162648) (xy 353.252434 -277.206225)
			(xy 353.268018 -277.252906) (xy 353.275913 -277.301483) (xy 353.276408 -277.32609) (xy 353.60535 -277.32609)
			(xy 353.60931 -277.277036) (xy 353.621087 -277.229252) (xy 353.640378 -277.183976) (xy 353.666681 -277.14238)
			(xy 353.699316 -277.105543) (xy 353.737437 -277.074418) (xy 353.780058 -277.049811) (xy 353.826074 -277.032359)
			(xy 353.874293 -277.022515) (xy 353.923468 -277.020534) (xy 353.972323 -277.026466) (xy 354.019594 -277.040158)
			(xy 354.064056 -277.061256) (xy 354.104559 -277.089212) (xy 354.140052 -277.123304) (xy 354.169617 -277.162648)
			(xy 354.192488 -277.206225) (xy 354.208072 -277.252906) (xy 354.215967 -277.301483) (xy 354.216462 -277.32609)
			(xy 354.545404 -277.32609) (xy 354.549364 -277.277036) (xy 354.561141 -277.229252) (xy 354.580432 -277.183976)
			(xy 354.606735 -277.14238) (xy 354.63937 -277.105543) (xy 354.677491 -277.074418) (xy 354.720112 -277.049811)
			(xy 354.766128 -277.032359) (xy 354.814347 -277.022515) (xy 354.863522 -277.020534) (xy 354.912377 -277.026466)
			(xy 354.959648 -277.040158) (xy 355.00411 -277.061256) (xy 355.044613 -277.089212) (xy 355.080106 -277.123304)
			(xy 355.109671 -277.162648) (xy 355.132542 -277.206225) (xy 355.148126 -277.252906) (xy 355.156021 -277.301483)
			(xy 355.156516 -277.32609) (xy 355.485204 -277.32609) (xy 355.489164 -277.277036) (xy 355.500941 -277.229252)
			(xy 355.520232 -277.183976) (xy 355.546535 -277.14238) (xy 355.57917 -277.105543) (xy 355.617291 -277.074418)
			(xy 355.659912 -277.049811) (xy 355.705928 -277.032359) (xy 355.754147 -277.022515) (xy 355.803322 -277.020534)
			(xy 355.852177 -277.026466) (xy 355.899448 -277.040158) (xy 355.94391 -277.061256) (xy 355.984413 -277.089212)
			(xy 356.019906 -277.123304) (xy 356.049471 -277.162648) (xy 356.072342 -277.206225) (xy 356.087926 -277.252906)
			(xy 356.095821 -277.301483) (xy 356.096316 -277.32609) (xy 356.425258 -277.32609) (xy 356.429218 -277.277036)
			(xy 356.440995 -277.229252) (xy 356.460286 -277.183976) (xy 356.486589 -277.14238) (xy 356.519224 -277.105543)
			(xy 356.557345 -277.074418) (xy 356.599966 -277.049811) (xy 356.645982 -277.032359) (xy 356.694201 -277.022515)
			(xy 356.743376 -277.020534) (xy 356.792231 -277.026466) (xy 356.839502 -277.040158) (xy 356.883964 -277.061256)
			(xy 356.924467 -277.089212) (xy 356.95996 -277.123304) (xy 356.989525 -277.162648) (xy 357.012396 -277.206225)
			(xy 357.02798 -277.252906) (xy 357.035875 -277.301483) (xy 357.03637 -277.32609) (xy 357.365312 -277.32609)
			(xy 357.369272 -277.277036) (xy 357.381049 -277.229252) (xy 357.40034 -277.183976) (xy 357.426643 -277.14238)
			(xy 357.459278 -277.105543) (xy 357.497399 -277.074418) (xy 357.54002 -277.049811) (xy 357.586036 -277.032359)
			(xy 357.634255 -277.022515) (xy 357.68343 -277.020534) (xy 357.732285 -277.026466) (xy 357.779556 -277.040158)
			(xy 357.824018 -277.061256) (xy 357.864521 -277.089212) (xy 357.900014 -277.123304) (xy 357.929579 -277.162648)
			(xy 357.95245 -277.206225) (xy 357.968034 -277.252906) (xy 357.975929 -277.301483) (xy 357.976424 -277.32609)
			(xy 358.305366 -277.32609) (xy 358.309326 -277.277036) (xy 358.321103 -277.229252) (xy 358.340394 -277.183976)
			(xy 358.366697 -277.14238) (xy 358.399332 -277.105543) (xy 358.437453 -277.074418) (xy 358.480074 -277.049811)
			(xy 358.52609 -277.032359) (xy 358.574309 -277.022515) (xy 358.623484 -277.020534) (xy 358.672339 -277.026466)
			(xy 358.71961 -277.040158) (xy 358.764072 -277.061256) (xy 358.804575 -277.089212) (xy 358.840068 -277.123304)
			(xy 358.869633 -277.162648) (xy 358.892504 -277.206225) (xy 358.908088 -277.252906) (xy 358.915983 -277.301483)
			(xy 358.916478 -277.32609) (xy 361.118924 -277.32609) (xy 361.122884 -277.277036) (xy 361.134661 -277.229252)
			(xy 361.153952 -277.183976) (xy 361.180255 -277.14238) (xy 361.21289 -277.105543) (xy 361.251011 -277.074418)
			(xy 361.293632 -277.049811) (xy 361.339648 -277.032359) (xy 361.387867 -277.022515) (xy 361.437042 -277.020534)
			(xy 361.485897 -277.026466) (xy 361.533168 -277.040158) (xy 361.57763 -277.061256) (xy 361.618133 -277.089212)
			(xy 361.653626 -277.123304) (xy 361.683191 -277.162648) (xy 361.706062 -277.206225) (xy 361.721646 -277.252906)
			(xy 361.729541 -277.301483) (xy 361.730036 -277.32609) (xy 362.058978 -277.32609) (xy 362.062938 -277.277036)
			(xy 362.074715 -277.229252) (xy 362.094006 -277.183976) (xy 362.120309 -277.14238) (xy 362.152944 -277.105543)
			(xy 362.191065 -277.074418) (xy 362.233686 -277.049811) (xy 362.279702 -277.032359) (xy 362.327921 -277.022515)
			(xy 362.377096 -277.020534) (xy 362.425951 -277.026466) (xy 362.473222 -277.040158) (xy 362.517684 -277.061256)
			(xy 362.558187 -277.089212) (xy 362.59368 -277.123304) (xy 362.623245 -277.162648) (xy 362.646116 -277.206225)
			(xy 362.6617 -277.252906) (xy 362.669595 -277.301483) (xy 362.67009 -277.32609) (xy 362.999032 -277.32609)
			(xy 363.002992 -277.277036) (xy 363.014769 -277.229252) (xy 363.03406 -277.183976) (xy 363.060363 -277.14238)
			(xy 363.092998 -277.105543) (xy 363.131119 -277.074418) (xy 363.17374 -277.049811) (xy 363.219756 -277.032359)
			(xy 363.267975 -277.022515) (xy 363.31715 -277.020534) (xy 363.366005 -277.026466) (xy 363.413276 -277.040158)
			(xy 363.457738 -277.061256) (xy 363.498241 -277.089212) (xy 363.533734 -277.123304) (xy 363.563299 -277.162648)
			(xy 363.58617 -277.206225) (xy 363.601754 -277.252906) (xy 363.609649 -277.301483) (xy 363.610144 -277.32609)
			(xy 363.939086 -277.32609) (xy 363.943046 -277.277036) (xy 363.954823 -277.229252) (xy 363.974114 -277.183976)
			(xy 364.000417 -277.14238) (xy 364.033052 -277.105543) (xy 364.071173 -277.074418) (xy 364.113794 -277.049811)
			(xy 364.15981 -277.032359) (xy 364.208029 -277.022515) (xy 364.257204 -277.020534) (xy 364.306059 -277.026466)
			(xy 364.35333 -277.040158) (xy 364.397792 -277.061256) (xy 364.438295 -277.089212) (xy 364.473788 -277.123304)
			(xy 364.503353 -277.162648) (xy 364.526224 -277.206225) (xy 364.541808 -277.252906) (xy 364.549703 -277.301483)
			(xy 364.550198 -277.32609) (xy 364.878886 -277.32609) (xy 364.882846 -277.277036) (xy 364.894623 -277.229252)
			(xy 364.913914 -277.183976) (xy 364.940217 -277.14238) (xy 364.972852 -277.105543) (xy 365.010973 -277.074418)
			(xy 365.053594 -277.049811) (xy 365.09961 -277.032359) (xy 365.147829 -277.022515) (xy 365.197004 -277.020534)
			(xy 365.245859 -277.026466) (xy 365.29313 -277.040158) (xy 365.337592 -277.061256) (xy 365.378095 -277.089212)
			(xy 365.413588 -277.123304) (xy 365.443153 -277.162648) (xy 365.466024 -277.206225) (xy 365.481608 -277.252906)
			(xy 365.489503 -277.301483) (xy 365.489998 -277.32609) (xy 365.81894 -277.32609) (xy 365.8229 -277.277036)
			(xy 365.834677 -277.229252) (xy 365.853968 -277.183976) (xy 365.880271 -277.14238) (xy 365.912906 -277.105543)
			(xy 365.951027 -277.074418) (xy 365.993648 -277.049811) (xy 366.039664 -277.032359) (xy 366.087883 -277.022515)
			(xy 366.137058 -277.020534) (xy 366.185913 -277.026466) (xy 366.233184 -277.040158) (xy 366.277646 -277.061256)
			(xy 366.318149 -277.089212) (xy 366.353642 -277.123304) (xy 366.383207 -277.162648) (xy 366.406078 -277.206225)
			(xy 366.421662 -277.252906) (xy 366.429557 -277.301483) (xy 366.430052 -277.32609) (xy 366.758994 -277.32609)
			(xy 366.762954 -277.277036) (xy 366.774731 -277.229252) (xy 366.794022 -277.183976) (xy 366.820325 -277.14238)
			(xy 366.85296 -277.105543) (xy 366.891081 -277.074418) (xy 366.933702 -277.049811) (xy 366.979718 -277.032359)
			(xy 367.027937 -277.022515) (xy 367.077112 -277.020534) (xy 367.125967 -277.026466) (xy 367.173238 -277.040158)
			(xy 367.2177 -277.061256) (xy 367.258203 -277.089212) (xy 367.293696 -277.123304) (xy 367.323261 -277.162648)
			(xy 367.346132 -277.206225) (xy 367.361716 -277.252906) (xy 367.369611 -277.301483) (xy 367.370106 -277.32609)
			(xy 367.699048 -277.32609) (xy 367.703008 -277.277036) (xy 367.714785 -277.229252) (xy 367.734076 -277.183976)
			(xy 367.760379 -277.14238) (xy 367.793014 -277.105543) (xy 367.831135 -277.074418) (xy 367.873756 -277.049811)
			(xy 367.919772 -277.032359) (xy 367.967991 -277.022515) (xy 368.017166 -277.020534) (xy 368.066021 -277.026466)
			(xy 368.113292 -277.040158) (xy 368.157754 -277.061256) (xy 368.198257 -277.089212) (xy 368.23375 -277.123304)
			(xy 368.263315 -277.162648) (xy 368.286186 -277.206225) (xy 368.30177 -277.252906) (xy 368.309665 -277.301483)
			(xy 368.31016 -277.32609) (xy 368.639102 -277.32609) (xy 368.643062 -277.277036) (xy 368.654839 -277.229252)
			(xy 368.67413 -277.183976) (xy 368.700433 -277.14238) (xy 368.733068 -277.105543) (xy 368.771189 -277.074418)
			(xy 368.81381 -277.049811) (xy 368.859826 -277.032359) (xy 368.908045 -277.022515) (xy 368.95722 -277.020534)
			(xy 369.006075 -277.026466) (xy 369.053346 -277.040158) (xy 369.097808 -277.061256) (xy 369.138311 -277.089212)
			(xy 369.173804 -277.123304) (xy 369.203369 -277.162648) (xy 369.22624 -277.206225) (xy 369.241824 -277.252906)
			(xy 369.249719 -277.301483) (xy 369.250214 -277.32609) (xy 369.578902 -277.32609) (xy 369.582862 -277.277036)
			(xy 369.594639 -277.229252) (xy 369.61393 -277.183976) (xy 369.640233 -277.14238) (xy 369.672868 -277.105543)
			(xy 369.710989 -277.074418) (xy 369.75361 -277.049811) (xy 369.799626 -277.032359) (xy 369.847845 -277.022515)
			(xy 369.89702 -277.020534) (xy 369.945875 -277.026466) (xy 369.993146 -277.040158) (xy 370.037608 -277.061256)
			(xy 370.078111 -277.089212) (xy 370.113604 -277.123304) (xy 370.143169 -277.162648) (xy 370.16604 -277.206225)
			(xy 370.181624 -277.252906) (xy 370.189519 -277.301483) (xy 370.190014 -277.32609) (xy 370.518956 -277.32609)
			(xy 370.522916 -277.277036) (xy 370.534693 -277.229252) (xy 370.553984 -277.183976) (xy 370.580287 -277.14238)
			(xy 370.612922 -277.105543) (xy 370.651043 -277.074418) (xy 370.693664 -277.049811) (xy 370.73968 -277.032359)
			(xy 370.787899 -277.022515) (xy 370.837074 -277.020534) (xy 370.885929 -277.026466) (xy 370.9332 -277.040158)
			(xy 370.977662 -277.061256) (xy 371.018165 -277.089212) (xy 371.053658 -277.123304) (xy 371.083223 -277.162648)
			(xy 371.106094 -277.206225) (xy 371.121678 -277.252906) (xy 371.129573 -277.301483) (xy 371.130068 -277.32609)
			(xy 371.45901 -277.32609) (xy 371.46297 -277.277036) (xy 371.474747 -277.229252) (xy 371.494038 -277.183976)
			(xy 371.520341 -277.14238) (xy 371.552976 -277.105543) (xy 371.591097 -277.074418) (xy 371.633718 -277.049811)
			(xy 371.679734 -277.032359) (xy 371.727953 -277.022515) (xy 371.777128 -277.020534) (xy 371.825983 -277.026466)
			(xy 371.873254 -277.040158) (xy 371.917716 -277.061256) (xy 371.958219 -277.089212) (xy 371.993712 -277.123304)
			(xy 372.023277 -277.162648) (xy 372.046148 -277.206225) (xy 372.061732 -277.252906) (xy 372.069627 -277.301483)
			(xy 372.070122 -277.32609) (xy 372.399064 -277.32609) (xy 372.403024 -277.277036) (xy 372.414801 -277.229252)
			(xy 372.434092 -277.183976) (xy 372.460395 -277.14238) (xy 372.49303 -277.105543) (xy 372.531151 -277.074418)
			(xy 372.573772 -277.049811) (xy 372.619788 -277.032359) (xy 372.668007 -277.022515) (xy 372.717182 -277.020534)
			(xy 372.766037 -277.026466) (xy 372.813308 -277.040158) (xy 372.85777 -277.061256) (xy 372.898273 -277.089212)
			(xy 372.933766 -277.123304) (xy 372.963331 -277.162648) (xy 372.986202 -277.206225) (xy 373.001786 -277.252906)
			(xy 373.009681 -277.301483) (xy 373.010176 -277.32609) (xy 373.339118 -277.32609) (xy 373.343078 -277.277036)
			(xy 373.354855 -277.229252) (xy 373.374146 -277.183976) (xy 373.400449 -277.14238) (xy 373.433084 -277.105543)
			(xy 373.471205 -277.074418) (xy 373.513826 -277.049811) (xy 373.559842 -277.032359) (xy 373.608061 -277.022515)
			(xy 373.657236 -277.020534) (xy 373.706091 -277.026466) (xy 373.753362 -277.040158) (xy 373.797824 -277.061256)
			(xy 373.838327 -277.089212) (xy 373.87382 -277.123304) (xy 373.903385 -277.162648) (xy 373.926256 -277.206225)
			(xy 373.94184 -277.252906) (xy 373.949735 -277.301483) (xy 373.95023 -277.32609) (xy 374.278918 -277.32609)
			(xy 374.282878 -277.277036) (xy 374.294655 -277.229252) (xy 374.313946 -277.183976) (xy 374.340249 -277.14238)
			(xy 374.372884 -277.105543) (xy 374.411005 -277.074418) (xy 374.453626 -277.049811) (xy 374.499642 -277.032359)
			(xy 374.547861 -277.022515) (xy 374.597036 -277.020534) (xy 374.645891 -277.026466) (xy 374.693162 -277.040158)
			(xy 374.737624 -277.061256) (xy 374.778127 -277.089212) (xy 374.81362 -277.123304) (xy 374.843185 -277.162648)
			(xy 374.866056 -277.206225) (xy 374.88164 -277.252906) (xy 374.889535 -277.301483) (xy 374.89003 -277.32609)
			(xy 375.218972 -277.32609) (xy 375.222932 -277.277036) (xy 375.234709 -277.229252) (xy 375.254 -277.183976)
			(xy 375.280303 -277.14238) (xy 375.312938 -277.105543) (xy 375.351059 -277.074418) (xy 375.39368 -277.049811)
			(xy 375.439696 -277.032359) (xy 375.487915 -277.022515) (xy 375.53709 -277.020534) (xy 375.585945 -277.026466)
			(xy 375.633216 -277.040158) (xy 375.677678 -277.061256) (xy 375.718181 -277.089212) (xy 375.753674 -277.123304)
			(xy 375.783239 -277.162648) (xy 375.80611 -277.206225) (xy 375.821694 -277.252906) (xy 375.829589 -277.301483)
			(xy 375.830084 -277.32609) (xy 376.148595 -277.32609) (xy 376.15269 -277.275362) (xy 376.164869 -277.225948)
			(xy 376.184817 -277.179128) (xy 376.212018 -277.136114) (xy 376.245766 -277.09802) (xy 376.285188 -277.065833)
			(xy 376.329262 -277.040387) (xy 376.376848 -277.02234) (xy 376.426712 -277.01216) (xy 376.477564 -277.010111)
			(xy 376.528085 -277.016245) (xy 376.576969 -277.030405) (xy 376.622948 -277.052222) (xy 376.664832 -277.081132)
			(xy 376.701536 -277.116387) (xy 376.732109 -277.157073) (xy 376.75576 -277.202136) (xy 376.771876 -277.25041)
			(xy 376.78004 -277.300644) (xy 376.780552 -277.32609) (xy 377.088649 -277.32609) (xy 377.092744 -277.275362)
			(xy 377.104923 -277.225948) (xy 377.124871 -277.179128) (xy 377.152072 -277.136114) (xy 377.18582 -277.09802)
			(xy 377.225242 -277.065833) (xy 377.269316 -277.040387) (xy 377.316902 -277.02234) (xy 377.366766 -277.01216)
			(xy 377.417618 -277.010111) (xy 377.468139 -277.016245) (xy 377.517023 -277.030405) (xy 377.563002 -277.052222)
			(xy 377.604886 -277.081132) (xy 377.64159 -277.116387) (xy 377.672163 -277.157073) (xy 377.695814 -277.202136)
			(xy 377.71193 -277.25041) (xy 377.720094 -277.300644) (xy 377.720606 -277.32609) (xy 377.720094 -277.351536)
			(xy 377.71193 -277.40177) (xy 377.695814 -277.450044) (xy 377.672163 -277.495107) (xy 377.64159 -277.535793)
			(xy 377.604886 -277.571048) (xy 377.563002 -277.599958) (xy 377.517023 -277.621775) (xy 377.468139 -277.635935)
			(xy 377.417618 -277.642069) (xy 377.366766 -277.64002) (xy 377.316902 -277.62984) (xy 377.269316 -277.611793)
			(xy 377.225242 -277.586347) (xy 377.18582 -277.55416) (xy 377.152072 -277.516066) (xy 377.124871 -277.473052)
			(xy 377.104923 -277.426232) (xy 377.092744 -277.376818) (xy 377.088649 -277.32609) (xy 376.780552 -277.32609)
			(xy 376.78004 -277.351536) (xy 376.771876 -277.40177) (xy 376.75576 -277.450044) (xy 376.732109 -277.495107)
			(xy 376.701536 -277.535793) (xy 376.664832 -277.571048) (xy 376.622948 -277.599958) (xy 376.576969 -277.621775)
			(xy 376.528085 -277.635935) (xy 376.477564 -277.642069) (xy 376.426712 -277.64002) (xy 376.376848 -277.62984)
			(xy 376.329262 -277.611793) (xy 376.285188 -277.586347) (xy 376.245766 -277.55416) (xy 376.212018 -277.516066)
			(xy 376.184817 -277.473052) (xy 376.164869 -277.426232) (xy 376.15269 -277.376818) (xy 376.148595 -277.32609)
			(xy 375.830084 -277.32609) (xy 375.829589 -277.350697) (xy 375.821694 -277.399274) (xy 375.80611 -277.445955)
			(xy 375.783239 -277.489532) (xy 375.753674 -277.528876) (xy 375.718181 -277.562968) (xy 375.677678 -277.590924)
			(xy 375.633216 -277.612022) (xy 375.585945 -277.625714) (xy 375.53709 -277.631646) (xy 375.487915 -277.629665)
			(xy 375.439696 -277.619821) (xy 375.39368 -277.602369) (xy 375.351059 -277.577762) (xy 375.312938 -277.546637)
			(xy 375.280303 -277.5098) (xy 375.254 -277.468204) (xy 375.234709 -277.422928) (xy 375.222932 -277.375144)
			(xy 375.218972 -277.32609) (xy 374.89003 -277.32609) (xy 374.889535 -277.350697) (xy 374.88164 -277.399274)
			(xy 374.866056 -277.445955) (xy 374.843185 -277.489532) (xy 374.81362 -277.528876) (xy 374.778127 -277.562968)
			(xy 374.737624 -277.590924) (xy 374.693162 -277.612022) (xy 374.645891 -277.625714) (xy 374.597036 -277.631646)
			(xy 374.547861 -277.629665) (xy 374.499642 -277.619821) (xy 374.453626 -277.602369) (xy 374.411005 -277.577762)
			(xy 374.372884 -277.546637) (xy 374.340249 -277.5098) (xy 374.313946 -277.468204) (xy 374.294655 -277.422928)
			(xy 374.282878 -277.375144) (xy 374.278918 -277.32609) (xy 373.95023 -277.32609) (xy 373.949735 -277.350697)
			(xy 373.94184 -277.399274) (xy 373.926256 -277.445955) (xy 373.903385 -277.489532) (xy 373.87382 -277.528876)
			(xy 373.838327 -277.562968) (xy 373.797824 -277.590924) (xy 373.753362 -277.612022) (xy 373.706091 -277.625714)
			(xy 373.657236 -277.631646) (xy 373.608061 -277.629665) (xy 373.559842 -277.619821) (xy 373.513826 -277.602369)
			(xy 373.471205 -277.577762) (xy 373.433084 -277.546637) (xy 373.400449 -277.5098) (xy 373.374146 -277.468204)
			(xy 373.354855 -277.422928) (xy 373.343078 -277.375144) (xy 373.339118 -277.32609) (xy 373.010176 -277.32609)
			(xy 373.009681 -277.350697) (xy 373.001786 -277.399274) (xy 372.986202 -277.445955) (xy 372.963331 -277.489532)
			(xy 372.933766 -277.528876) (xy 372.898273 -277.562968) (xy 372.85777 -277.590924) (xy 372.813308 -277.612022)
			(xy 372.766037 -277.625714) (xy 372.717182 -277.631646) (xy 372.668007 -277.629665) (xy 372.619788 -277.619821)
			(xy 372.573772 -277.602369) (xy 372.531151 -277.577762) (xy 372.49303 -277.546637) (xy 372.460395 -277.5098)
			(xy 372.434092 -277.468204) (xy 372.414801 -277.422928) (xy 372.403024 -277.375144) (xy 372.399064 -277.32609)
			(xy 372.070122 -277.32609) (xy 372.069627 -277.350697) (xy 372.061732 -277.399274) (xy 372.046148 -277.445955)
			(xy 372.023277 -277.489532) (xy 371.993712 -277.528876) (xy 371.958219 -277.562968) (xy 371.917716 -277.590924)
			(xy 371.873254 -277.612022) (xy 371.825983 -277.625714) (xy 371.777128 -277.631646) (xy 371.727953 -277.629665)
			(xy 371.679734 -277.619821) (xy 371.633718 -277.602369) (xy 371.591097 -277.577762) (xy 371.552976 -277.546637)
			(xy 371.520341 -277.5098) (xy 371.494038 -277.468204) (xy 371.474747 -277.422928) (xy 371.46297 -277.375144)
			(xy 371.45901 -277.32609) (xy 371.130068 -277.32609) (xy 371.129573 -277.350697) (xy 371.121678 -277.399274)
			(xy 371.106094 -277.445955) (xy 371.083223 -277.489532) (xy 371.053658 -277.528876) (xy 371.018165 -277.562968)
			(xy 370.977662 -277.590924) (xy 370.9332 -277.612022) (xy 370.885929 -277.625714) (xy 370.837074 -277.631646)
			(xy 370.787899 -277.629665) (xy 370.73968 -277.619821) (xy 370.693664 -277.602369) (xy 370.651043 -277.577762)
			(xy 370.612922 -277.546637) (xy 370.580287 -277.5098) (xy 370.553984 -277.468204) (xy 370.534693 -277.422928)
			(xy 370.522916 -277.375144) (xy 370.518956 -277.32609) (xy 370.190014 -277.32609) (xy 370.189519 -277.350697)
			(xy 370.181624 -277.399274) (xy 370.16604 -277.445955) (xy 370.143169 -277.489532) (xy 370.113604 -277.528876)
			(xy 370.078111 -277.562968) (xy 370.037608 -277.590924) (xy 369.993146 -277.612022) (xy 369.945875 -277.625714)
			(xy 369.89702 -277.631646) (xy 369.847845 -277.629665) (xy 369.799626 -277.619821) (xy 369.75361 -277.602369)
			(xy 369.710989 -277.577762) (xy 369.672868 -277.546637) (xy 369.640233 -277.5098) (xy 369.61393 -277.468204)
			(xy 369.594639 -277.422928) (xy 369.582862 -277.375144) (xy 369.578902 -277.32609) (xy 369.250214 -277.32609)
			(xy 369.249719 -277.350697) (xy 369.241824 -277.399274) (xy 369.22624 -277.445955) (xy 369.203369 -277.489532)
			(xy 369.173804 -277.528876) (xy 369.138311 -277.562968) (xy 369.097808 -277.590924) (xy 369.053346 -277.612022)
			(xy 369.006075 -277.625714) (xy 368.95722 -277.631646) (xy 368.908045 -277.629665) (xy 368.859826 -277.619821)
			(xy 368.81381 -277.602369) (xy 368.771189 -277.577762) (xy 368.733068 -277.546637) (xy 368.700433 -277.5098)
			(xy 368.67413 -277.468204) (xy 368.654839 -277.422928) (xy 368.643062 -277.375144) (xy 368.639102 -277.32609)
			(xy 368.31016 -277.32609) (xy 368.309665 -277.350697) (xy 368.30177 -277.399274) (xy 368.286186 -277.445955)
			(xy 368.263315 -277.489532) (xy 368.23375 -277.528876) (xy 368.198257 -277.562968) (xy 368.157754 -277.590924)
			(xy 368.113292 -277.612022) (xy 368.066021 -277.625714) (xy 368.017166 -277.631646) (xy 367.967991 -277.629665)
			(xy 367.919772 -277.619821) (xy 367.873756 -277.602369) (xy 367.831135 -277.577762) (xy 367.793014 -277.546637)
			(xy 367.760379 -277.5098) (xy 367.734076 -277.468204) (xy 367.714785 -277.422928) (xy 367.703008 -277.375144)
			(xy 367.699048 -277.32609) (xy 367.370106 -277.32609) (xy 367.369611 -277.350697) (xy 367.361716 -277.399274)
			(xy 367.346132 -277.445955) (xy 367.323261 -277.489532) (xy 367.293696 -277.528876) (xy 367.258203 -277.562968)
			(xy 367.2177 -277.590924) (xy 367.173238 -277.612022) (xy 367.125967 -277.625714) (xy 367.077112 -277.631646)
			(xy 367.027937 -277.629665) (xy 366.979718 -277.619821) (xy 366.933702 -277.602369) (xy 366.891081 -277.577762)
			(xy 366.85296 -277.546637) (xy 366.820325 -277.5098) (xy 366.794022 -277.468204) (xy 366.774731 -277.422928)
			(xy 366.762954 -277.375144) (xy 366.758994 -277.32609) (xy 366.430052 -277.32609) (xy 366.429557 -277.350697)
			(xy 366.421662 -277.399274) (xy 366.406078 -277.445955) (xy 366.383207 -277.489532) (xy 366.353642 -277.528876)
			(xy 366.318149 -277.562968) (xy 366.277646 -277.590924) (xy 366.233184 -277.612022) (xy 366.185913 -277.625714)
			(xy 366.137058 -277.631646) (xy 366.087883 -277.629665) (xy 366.039664 -277.619821) (xy 365.993648 -277.602369)
			(xy 365.951027 -277.577762) (xy 365.912906 -277.546637) (xy 365.880271 -277.5098) (xy 365.853968 -277.468204)
			(xy 365.834677 -277.422928) (xy 365.8229 -277.375144) (xy 365.81894 -277.32609) (xy 365.489998 -277.32609)
			(xy 365.489503 -277.350697) (xy 365.481608 -277.399274) (xy 365.466024 -277.445955) (xy 365.443153 -277.489532)
			(xy 365.413588 -277.528876) (xy 365.378095 -277.562968) (xy 365.337592 -277.590924) (xy 365.29313 -277.612022)
			(xy 365.245859 -277.625714) (xy 365.197004 -277.631646) (xy 365.147829 -277.629665) (xy 365.09961 -277.619821)
			(xy 365.053594 -277.602369) (xy 365.010973 -277.577762) (xy 364.972852 -277.546637) (xy 364.940217 -277.5098)
			(xy 364.913914 -277.468204) (xy 364.894623 -277.422928) (xy 364.882846 -277.375144) (xy 364.878886 -277.32609)
			(xy 364.550198 -277.32609) (xy 364.549703 -277.350697) (xy 364.541808 -277.399274) (xy 364.526224 -277.445955)
			(xy 364.503353 -277.489532) (xy 364.473788 -277.528876) (xy 364.438295 -277.562968) (xy 364.397792 -277.590924)
			(xy 364.35333 -277.612022) (xy 364.306059 -277.625714) (xy 364.257204 -277.631646) (xy 364.208029 -277.629665)
			(xy 364.15981 -277.619821) (xy 364.113794 -277.602369) (xy 364.071173 -277.577762) (xy 364.033052 -277.546637)
			(xy 364.000417 -277.5098) (xy 363.974114 -277.468204) (xy 363.954823 -277.422928) (xy 363.943046 -277.375144)
			(xy 363.939086 -277.32609) (xy 363.610144 -277.32609) (xy 363.609649 -277.350697) (xy 363.601754 -277.399274)
			(xy 363.58617 -277.445955) (xy 363.563299 -277.489532) (xy 363.533734 -277.528876) (xy 363.498241 -277.562968)
			(xy 363.457738 -277.590924) (xy 363.413276 -277.612022) (xy 363.366005 -277.625714) (xy 363.31715 -277.631646)
			(xy 363.267975 -277.629665) (xy 363.219756 -277.619821) (xy 363.17374 -277.602369) (xy 363.131119 -277.577762)
			(xy 363.092998 -277.546637) (xy 363.060363 -277.5098) (xy 363.03406 -277.468204) (xy 363.014769 -277.422928)
			(xy 363.002992 -277.375144) (xy 362.999032 -277.32609) (xy 362.67009 -277.32609) (xy 362.669595 -277.350697)
			(xy 362.6617 -277.399274) (xy 362.646116 -277.445955) (xy 362.623245 -277.489532) (xy 362.59368 -277.528876)
			(xy 362.558187 -277.562968) (xy 362.517684 -277.590924) (xy 362.473222 -277.612022) (xy 362.425951 -277.625714)
			(xy 362.377096 -277.631646) (xy 362.327921 -277.629665) (xy 362.279702 -277.619821) (xy 362.233686 -277.602369)
			(xy 362.191065 -277.577762) (xy 362.152944 -277.546637) (xy 362.120309 -277.5098) (xy 362.094006 -277.468204)
			(xy 362.074715 -277.422928) (xy 362.062938 -277.375144) (xy 362.058978 -277.32609) (xy 361.730036 -277.32609)
			(xy 361.729541 -277.350697) (xy 361.721646 -277.399274) (xy 361.706062 -277.445955) (xy 361.683191 -277.489532)
			(xy 361.653626 -277.528876) (xy 361.618133 -277.562968) (xy 361.57763 -277.590924) (xy 361.533168 -277.612022)
			(xy 361.485897 -277.625714) (xy 361.437042 -277.631646) (xy 361.387867 -277.629665) (xy 361.339648 -277.619821)
			(xy 361.293632 -277.602369) (xy 361.251011 -277.577762) (xy 361.21289 -277.546637) (xy 361.180255 -277.5098)
			(xy 361.153952 -277.468204) (xy 361.134661 -277.422928) (xy 361.122884 -277.375144) (xy 361.118924 -277.32609)
			(xy 358.916478 -277.32609) (xy 358.915983 -277.350697) (xy 358.908088 -277.399274) (xy 358.892504 -277.445955)
			(xy 358.869633 -277.489532) (xy 358.840068 -277.528876) (xy 358.804575 -277.562968) (xy 358.764072 -277.590924)
			(xy 358.71961 -277.612022) (xy 358.672339 -277.625714) (xy 358.623484 -277.631646) (xy 358.574309 -277.629665)
			(xy 358.52609 -277.619821) (xy 358.480074 -277.602369) (xy 358.437453 -277.577762) (xy 358.399332 -277.546637)
			(xy 358.366697 -277.5098) (xy 358.340394 -277.468204) (xy 358.321103 -277.422928) (xy 358.309326 -277.375144)
			(xy 358.305366 -277.32609) (xy 357.976424 -277.32609) (xy 357.975929 -277.350697) (xy 357.968034 -277.399274)
			(xy 357.95245 -277.445955) (xy 357.929579 -277.489532) (xy 357.900014 -277.528876) (xy 357.864521 -277.562968)
			(xy 357.824018 -277.590924) (xy 357.779556 -277.612022) (xy 357.732285 -277.625714) (xy 357.68343 -277.631646)
			(xy 357.634255 -277.629665) (xy 357.586036 -277.619821) (xy 357.54002 -277.602369) (xy 357.497399 -277.577762)
			(xy 357.459278 -277.546637) (xy 357.426643 -277.5098) (xy 357.40034 -277.468204) (xy 357.381049 -277.422928)
			(xy 357.369272 -277.375144) (xy 357.365312 -277.32609) (xy 357.03637 -277.32609) (xy 357.035875 -277.350697)
			(xy 357.02798 -277.399274) (xy 357.012396 -277.445955) (xy 356.989525 -277.489532) (xy 356.95996 -277.528876)
			(xy 356.924467 -277.562968) (xy 356.883964 -277.590924) (xy 356.839502 -277.612022) (xy 356.792231 -277.625714)
			(xy 356.743376 -277.631646) (xy 356.694201 -277.629665) (xy 356.645982 -277.619821) (xy 356.599966 -277.602369)
			(xy 356.557345 -277.577762) (xy 356.519224 -277.546637) (xy 356.486589 -277.5098) (xy 356.460286 -277.468204)
			(xy 356.440995 -277.422928) (xy 356.429218 -277.375144) (xy 356.425258 -277.32609) (xy 356.096316 -277.32609)
			(xy 356.095821 -277.350697) (xy 356.087926 -277.399274) (xy 356.072342 -277.445955) (xy 356.049471 -277.489532)
			(xy 356.019906 -277.528876) (xy 355.984413 -277.562968) (xy 355.94391 -277.590924) (xy 355.899448 -277.612022)
			(xy 355.852177 -277.625714) (xy 355.803322 -277.631646) (xy 355.754147 -277.629665) (xy 355.705928 -277.619821)
			(xy 355.659912 -277.602369) (xy 355.617291 -277.577762) (xy 355.57917 -277.546637) (xy 355.546535 -277.5098)
			(xy 355.520232 -277.468204) (xy 355.500941 -277.422928) (xy 355.489164 -277.375144) (xy 355.485204 -277.32609)
			(xy 355.156516 -277.32609) (xy 355.156021 -277.350697) (xy 355.148126 -277.399274) (xy 355.132542 -277.445955)
			(xy 355.109671 -277.489532) (xy 355.080106 -277.528876) (xy 355.044613 -277.562968) (xy 355.00411 -277.590924)
			(xy 354.959648 -277.612022) (xy 354.912377 -277.625714) (xy 354.863522 -277.631646) (xy 354.814347 -277.629665)
			(xy 354.766128 -277.619821) (xy 354.720112 -277.602369) (xy 354.677491 -277.577762) (xy 354.63937 -277.546637)
			(xy 354.606735 -277.5098) (xy 354.580432 -277.468204) (xy 354.561141 -277.422928) (xy 354.549364 -277.375144)
			(xy 354.545404 -277.32609) (xy 354.216462 -277.32609) (xy 354.215967 -277.350697) (xy 354.208072 -277.399274)
			(xy 354.192488 -277.445955) (xy 354.169617 -277.489532) (xy 354.140052 -277.528876) (xy 354.104559 -277.562968)
			(xy 354.064056 -277.590924) (xy 354.019594 -277.612022) (xy 353.972323 -277.625714) (xy 353.923468 -277.631646)
			(xy 353.874293 -277.629665) (xy 353.826074 -277.619821) (xy 353.780058 -277.602369) (xy 353.737437 -277.577762)
			(xy 353.699316 -277.546637) (xy 353.666681 -277.5098) (xy 353.640378 -277.468204) (xy 353.621087 -277.422928)
			(xy 353.60931 -277.375144) (xy 353.60535 -277.32609) (xy 353.276408 -277.32609) (xy 353.275913 -277.350697)
			(xy 353.268018 -277.399274) (xy 353.252434 -277.445955) (xy 353.229563 -277.489532) (xy 353.199998 -277.528876)
			(xy 353.164505 -277.562968) (xy 353.124002 -277.590924) (xy 353.07954 -277.612022) (xy 353.032269 -277.625714)
			(xy 352.983414 -277.631646) (xy 352.934239 -277.629665) (xy 352.88602 -277.619821) (xy 352.840004 -277.602369)
			(xy 352.797383 -277.577762) (xy 352.759262 -277.546637) (xy 352.726627 -277.5098) (xy 352.700324 -277.468204)
			(xy 352.681033 -277.422928) (xy 352.669256 -277.375144) (xy 352.665296 -277.32609) (xy 352.336354 -277.32609)
			(xy 352.335859 -277.350697) (xy 352.327964 -277.399274) (xy 352.31238 -277.445955) (xy 352.289509 -277.489532)
			(xy 352.259944 -277.528876) (xy 352.224451 -277.562968) (xy 352.183948 -277.590924) (xy 352.139486 -277.612022)
			(xy 352.092215 -277.625714) (xy 352.04336 -277.631646) (xy 351.994185 -277.629665) (xy 351.945966 -277.619821)
			(xy 351.89995 -277.602369) (xy 351.857329 -277.577762) (xy 351.819208 -277.546637) (xy 351.786573 -277.5098)
			(xy 351.76027 -277.468204) (xy 351.740979 -277.422928) (xy 351.729202 -277.375144) (xy 351.725242 -277.32609)
			(xy 351.396554 -277.32609) (xy 351.396059 -277.350697) (xy 351.388164 -277.399274) (xy 351.37258 -277.445955)
			(xy 351.349709 -277.489532) (xy 351.320144 -277.528876) (xy 351.284651 -277.562968) (xy 351.244148 -277.590924)
			(xy 351.199686 -277.612022) (xy 351.152415 -277.625714) (xy 351.10356 -277.631646) (xy 351.054385 -277.629665)
			(xy 351.006166 -277.619821) (xy 350.96015 -277.602369) (xy 350.917529 -277.577762) (xy 350.879408 -277.546637)
			(xy 350.846773 -277.5098) (xy 350.82047 -277.468204) (xy 350.801179 -277.422928) (xy 350.789402 -277.375144)
			(xy 350.785442 -277.32609) (xy 350.4565 -277.32609) (xy 350.456005 -277.350697) (xy 350.44811 -277.399274)
			(xy 350.432526 -277.445955) (xy 350.409655 -277.489532) (xy 350.38009 -277.528876) (xy 350.344597 -277.562968)
			(xy 350.304094 -277.590924) (xy 350.259632 -277.612022) (xy 350.212361 -277.625714) (xy 350.163506 -277.631646)
			(xy 350.114331 -277.629665) (xy 350.066112 -277.619821) (xy 350.020096 -277.602369) (xy 349.977475 -277.577762)
			(xy 349.939354 -277.546637) (xy 349.906719 -277.5098) (xy 349.880416 -277.468204) (xy 349.861125 -277.422928)
			(xy 349.849348 -277.375144) (xy 349.845388 -277.32609) (xy 349.516446 -277.32609) (xy 349.515951 -277.350697)
			(xy 349.508056 -277.399274) (xy 349.492472 -277.445955) (xy 349.469601 -277.489532) (xy 349.440036 -277.528876)
			(xy 349.404543 -277.562968) (xy 349.36404 -277.590924) (xy 349.319578 -277.612022) (xy 349.272307 -277.625714)
			(xy 349.223452 -277.631646) (xy 349.174277 -277.629665) (xy 349.126058 -277.619821) (xy 349.080042 -277.602369)
			(xy 349.037421 -277.577762) (xy 348.9993 -277.546637) (xy 348.966665 -277.5098) (xy 348.940362 -277.468204)
			(xy 348.921071 -277.422928) (xy 348.909294 -277.375144) (xy 348.905334 -277.32609) (xy 348.576392 -277.32609)
			(xy 348.575897 -277.350697) (xy 348.568002 -277.399274) (xy 348.552418 -277.445955) (xy 348.529547 -277.489532)
			(xy 348.499982 -277.528876) (xy 348.464489 -277.562968) (xy 348.423986 -277.590924) (xy 348.379524 -277.612022)
			(xy 348.332253 -277.625714) (xy 348.283398 -277.631646) (xy 348.234223 -277.629665) (xy 348.186004 -277.619821)
			(xy 348.139988 -277.602369) (xy 348.097367 -277.577762) (xy 348.059246 -277.546637) (xy 348.026611 -277.5098)
			(xy 348.000308 -277.468204) (xy 347.981017 -277.422928) (xy 347.96924 -277.375144) (xy 347.96528 -277.32609)
			(xy 347.636338 -277.32609) (xy 347.635843 -277.350697) (xy 347.627948 -277.399274) (xy 347.612364 -277.445955)
			(xy 347.589493 -277.489532) (xy 347.559928 -277.528876) (xy 347.524435 -277.562968) (xy 347.483932 -277.590924)
			(xy 347.43947 -277.612022) (xy 347.392199 -277.625714) (xy 347.343344 -277.631646) (xy 347.294169 -277.629665)
			(xy 347.24595 -277.619821) (xy 347.199934 -277.602369) (xy 347.157313 -277.577762) (xy 347.119192 -277.546637)
			(xy 347.086557 -277.5098) (xy 347.060254 -277.468204) (xy 347.040963 -277.422928) (xy 347.029186 -277.375144)
			(xy 347.025226 -277.32609) (xy 346.696538 -277.32609) (xy 346.696043 -277.350697) (xy 346.688148 -277.399274)
			(xy 346.672564 -277.445955) (xy 346.649693 -277.489532) (xy 346.620128 -277.528876) (xy 346.584635 -277.562968)
			(xy 346.544132 -277.590924) (xy 346.49967 -277.612022) (xy 346.452399 -277.625714) (xy 346.403544 -277.631646)
			(xy 346.354369 -277.629665) (xy 346.30615 -277.619821) (xy 346.260134 -277.602369) (xy 346.217513 -277.577762)
			(xy 346.179392 -277.546637) (xy 346.146757 -277.5098) (xy 346.120454 -277.468204) (xy 346.101163 -277.422928)
			(xy 346.089386 -277.375144) (xy 346.085426 -277.32609) (xy 345.756484 -277.32609) (xy 345.755989 -277.350697)
			(xy 345.748094 -277.399274) (xy 345.73251 -277.445955) (xy 345.709639 -277.489532) (xy 345.680074 -277.528876)
			(xy 345.644581 -277.562968) (xy 345.604078 -277.590924) (xy 345.559616 -277.612022) (xy 345.512345 -277.625714)
			(xy 345.46349 -277.631646) (xy 345.414315 -277.629665) (xy 345.366096 -277.619821) (xy 345.32008 -277.602369)
			(xy 345.277459 -277.577762) (xy 345.239338 -277.546637) (xy 345.206703 -277.5098) (xy 345.1804 -277.468204)
			(xy 345.161109 -277.422928) (xy 345.149332 -277.375144) (xy 345.145372 -277.32609) (xy 344.81643 -277.32609)
			(xy 344.815935 -277.350697) (xy 344.80804 -277.399274) (xy 344.792456 -277.445955) (xy 344.769585 -277.489532)
			(xy 344.74002 -277.528876) (xy 344.704527 -277.562968) (xy 344.664024 -277.590924) (xy 344.619562 -277.612022)
			(xy 344.572291 -277.625714) (xy 344.523436 -277.631646) (xy 344.474261 -277.629665) (xy 344.426042 -277.619821)
			(xy 344.380026 -277.602369) (xy 344.337405 -277.577762) (xy 344.299284 -277.546637) (xy 344.266649 -277.5098)
			(xy 344.240346 -277.468204) (xy 344.221055 -277.422928) (xy 344.209278 -277.375144) (xy 344.205318 -277.32609)
			(xy 343.88679 -277.32609) (xy 343.886278 -277.351536) (xy 343.878114 -277.40177) (xy 343.861998 -277.450044)
			(xy 343.838347 -277.495107) (xy 343.807774 -277.535793) (xy 343.77107 -277.571048) (xy 343.729186 -277.599958)
			(xy 343.683207 -277.621775) (xy 343.634323 -277.635935) (xy 343.583802 -277.642069) (xy 343.53295 -277.64002)
			(xy 343.483086 -277.62984) (xy 343.4355 -277.611793) (xy 343.391426 -277.586347) (xy 343.352004 -277.55416)
			(xy 343.318256 -277.516066) (xy 343.291055 -277.473052) (xy 343.271107 -277.426232) (xy 343.258928 -277.376818)
			(xy 343.254833 -277.32609) (xy 342.946736 -277.32609) (xy 342.946224 -277.351536) (xy 342.93806 -277.40177)
			(xy 342.921944 -277.450044) (xy 342.898293 -277.495107) (xy 342.86772 -277.535793) (xy 342.831016 -277.571048)
			(xy 342.789132 -277.599958) (xy 342.743153 -277.621775) (xy 342.694269 -277.635935) (xy 342.643748 -277.642069)
			(xy 342.592896 -277.64002) (xy 342.543032 -277.62984) (xy 342.495446 -277.611793) (xy 342.451372 -277.586347)
			(xy 342.41195 -277.55416) (xy 342.378202 -277.516066) (xy 342.351001 -277.473052) (xy 342.331053 -277.426232)
			(xy 342.318874 -277.376818) (xy 342.314779 -277.32609) (xy 341.99704 -277.32609) (xy 341.997041 -277.3261)
			(xy 341.99287 -277.376438) (xy 341.980471 -277.425404) (xy 341.960181 -277.47166) (xy 341.932555 -277.513947)
			(xy 341.898346 -277.55111) (xy 341.858487 -277.582135) (xy 341.814064 -277.606177) (xy 341.766291 -277.622579)
			(xy 341.716469 -277.630895) (xy 341.691214 -277.631398) (xy 341.667343 -277.630938) (xy 341.620183 -277.623506)
			(xy 341.574755 -277.608821) (xy 341.532168 -277.587242) (xy 341.49346 -277.559295) (xy 341.459576 -277.525661)
			(xy 341.445088 -277.506684) (xy 341.445088 -277.50643) (xy 341.442437 -277.502999) (xy 341.436181 -277.496997)
			(xy 341.432642 -277.494492) (xy 341.424814 -277.489718) (xy 341.406975 -277.48554) (xy 341.397844 -277.486364)
			(xy 341.309198 -277.497794) (xy 341.302436 -277.498865) (xy 341.289807 -277.504135) (xy 341.284306 -277.508208)
			(xy 341.278972 -277.512272) (xy 341.271098 -277.52294) (xy 341.268558 -277.529544) (xy 341.260578 -277.549257)
			(xy 341.242012 -277.587525) (xy 341.231474 -277.605998) (xy 341.231474 -277.606252) (xy 341.228361 -277.612072)
			(xy 341.224896 -277.624803) (xy 341.224616 -277.631398) (xy 341.224616 -277.784306) (xy 341.224977 -277.793322)
			(xy 341.231227 -277.810236) (xy 341.236808 -277.817326) (xy 341.24265 -277.824184) (xy 341.258652 -277.833074)
			(xy 341.267542 -277.834344) (xy 341.29126 -277.838452) (xy 341.337096 -277.853148) (xy 341.380059 -277.874855)
			(xy 341.419083 -277.903034) (xy 341.453201 -277.936987) (xy 341.48157 -277.975874) (xy 341.503485 -278.01873)
			(xy 341.518404 -278.064494) (xy 341.525957 -278.112032) (xy 341.525957 -278.136096) (xy 341.844879 -278.136096)
			(xy 341.848974 -278.085368) (xy 341.861153 -278.035954) (xy 341.881101 -277.989134) (xy 341.908302 -277.94612)
			(xy 341.94205 -277.908026) (xy 341.981472 -277.875839) (xy 342.025546 -277.850393) (xy 342.073132 -277.832346)
			(xy 342.122996 -277.822166) (xy 342.173848 -277.820117) (xy 342.224369 -277.826251) (xy 342.273253 -277.840411)
			(xy 342.319232 -277.862228) (xy 342.361116 -277.891138) (xy 342.39782 -277.926393) (xy 342.428393 -277.967079)
			(xy 342.452044 -278.012142) (xy 342.46816 -278.060416) (xy 342.476324 -278.11065) (xy 342.476836 -278.136096)
			(xy 342.795364 -278.136096) (xy 342.799324 -278.087042) (xy 342.811101 -278.039258) (xy 342.830392 -277.993982)
			(xy 342.856695 -277.952386) (xy 342.88933 -277.915549) (xy 342.927451 -277.884424) (xy 342.970072 -277.859817)
			(xy 343.016088 -277.842365) (xy 343.064307 -277.832521) (xy 343.113482 -277.83054) (xy 343.162337 -277.836472)
			(xy 343.209608 -277.850164) (xy 343.25407 -277.871262) (xy 343.294573 -277.899218) (xy 343.330066 -277.93331)
			(xy 343.359631 -277.972654) (xy 343.382502 -278.016231) (xy 343.398086 -278.062912) (xy 343.405981 -278.111489)
			(xy 343.406476 -278.136096) (xy 343.724987 -278.136096) (xy 343.729082 -278.085368) (xy 343.741261 -278.035954)
			(xy 343.761209 -277.989134) (xy 343.78841 -277.94612) (xy 343.822158 -277.908026) (xy 343.86158 -277.875839)
			(xy 343.905654 -277.850393) (xy 343.95324 -277.832346) (xy 344.003104 -277.822166) (xy 344.053956 -277.820117)
			(xy 344.104477 -277.826251) (xy 344.153361 -277.840411) (xy 344.19934 -277.862228) (xy 344.241224 -277.891138)
			(xy 344.277928 -277.926393) (xy 344.308501 -277.967079) (xy 344.332152 -278.012142) (xy 344.348268 -278.060416)
			(xy 344.356432 -278.11065) (xy 344.356944 -278.136096) (xy 344.675218 -278.136096) (xy 344.679178 -278.087042)
			(xy 344.690955 -278.039258) (xy 344.710246 -277.993982) (xy 344.736549 -277.952386) (xy 344.769184 -277.915549)
			(xy 344.807305 -277.884424) (xy 344.849926 -277.859817) (xy 344.895942 -277.842365) (xy 344.944161 -277.832521)
			(xy 344.993336 -277.83054) (xy 345.042191 -277.836472) (xy 345.089462 -277.850164) (xy 345.133924 -277.871262)
			(xy 345.174427 -277.899218) (xy 345.20992 -277.93331) (xy 345.239485 -277.972654) (xy 345.262356 -278.016231)
			(xy 345.27794 -278.062912) (xy 345.285835 -278.111489) (xy 345.28633 -278.136096) (xy 345.615272 -278.136096)
			(xy 345.619232 -278.087042) (xy 345.631009 -278.039258) (xy 345.6503 -277.993982) (xy 345.676603 -277.952386)
			(xy 345.709238 -277.915549) (xy 345.747359 -277.884424) (xy 345.78998 -277.859817) (xy 345.835996 -277.842365)
			(xy 345.884215 -277.832521) (xy 345.93339 -277.83054) (xy 345.982245 -277.836472) (xy 346.029516 -277.850164)
			(xy 346.073978 -277.871262) (xy 346.114481 -277.899218) (xy 346.149974 -277.93331) (xy 346.179539 -277.972654)
			(xy 346.20241 -278.016231) (xy 346.217994 -278.062912) (xy 346.225889 -278.111489) (xy 346.226384 -278.136096)
			(xy 346.555326 -278.136096) (xy 346.559286 -278.087042) (xy 346.571063 -278.039258) (xy 346.590354 -277.993982)
			(xy 346.616657 -277.952386) (xy 346.649292 -277.915549) (xy 346.687413 -277.884424) (xy 346.730034 -277.859817)
			(xy 346.77605 -277.842365) (xy 346.824269 -277.832521) (xy 346.873444 -277.83054) (xy 346.922299 -277.836472)
			(xy 346.96957 -277.850164) (xy 347.014032 -277.871262) (xy 347.054535 -277.899218) (xy 347.090028 -277.93331)
			(xy 347.119593 -277.972654) (xy 347.142464 -278.016231) (xy 347.158048 -278.062912) (xy 347.165943 -278.111489)
			(xy 347.166438 -278.136096) (xy 347.49538 -278.136096) (xy 347.49934 -278.087042) (xy 347.511117 -278.039258)
			(xy 347.530408 -277.993982) (xy 347.556711 -277.952386) (xy 347.589346 -277.915549) (xy 347.627467 -277.884424)
			(xy 347.670088 -277.859817) (xy 347.716104 -277.842365) (xy 347.764323 -277.832521) (xy 347.813498 -277.83054)
			(xy 347.862353 -277.836472) (xy 347.909624 -277.850164) (xy 347.954086 -277.871262) (xy 347.994589 -277.899218)
			(xy 348.030082 -277.93331) (xy 348.059647 -277.972654) (xy 348.082518 -278.016231) (xy 348.098102 -278.062912)
			(xy 348.105997 -278.111489) (xy 348.106492 -278.136096) (xy 348.435434 -278.136096) (xy 348.439394 -278.087042)
			(xy 348.451171 -278.039258) (xy 348.470462 -277.993982) (xy 348.496765 -277.952386) (xy 348.5294 -277.915549)
			(xy 348.567521 -277.884424) (xy 348.610142 -277.859817) (xy 348.656158 -277.842365) (xy 348.704377 -277.832521)
			(xy 348.753552 -277.83054) (xy 348.802407 -277.836472) (xy 348.849678 -277.850164) (xy 348.89414 -277.871262)
			(xy 348.934643 -277.899218) (xy 348.970136 -277.93331) (xy 348.999701 -277.972654) (xy 349.022572 -278.016231)
			(xy 349.038156 -278.062912) (xy 349.046051 -278.111489) (xy 349.046546 -278.136096) (xy 349.375234 -278.136096)
			(xy 349.379194 -278.087042) (xy 349.390971 -278.039258) (xy 349.410262 -277.993982) (xy 349.436565 -277.952386)
			(xy 349.4692 -277.915549) (xy 349.507321 -277.884424) (xy 349.549942 -277.859817) (xy 349.595958 -277.842365)
			(xy 349.644177 -277.832521) (xy 349.693352 -277.83054) (xy 349.742207 -277.836472) (xy 349.789478 -277.850164)
			(xy 349.83394 -277.871262) (xy 349.874443 -277.899218) (xy 349.909936 -277.93331) (xy 349.939501 -277.972654)
			(xy 349.962372 -278.016231) (xy 349.977956 -278.062912) (xy 349.985851 -278.111489) (xy 349.986346 -278.136096)
			(xy 350.315288 -278.136096) (xy 350.319248 -278.087042) (xy 350.331025 -278.039258) (xy 350.350316 -277.993982)
			(xy 350.376619 -277.952386) (xy 350.409254 -277.915549) (xy 350.447375 -277.884424) (xy 350.489996 -277.859817)
			(xy 350.536012 -277.842365) (xy 350.584231 -277.832521) (xy 350.633406 -277.83054) (xy 350.682261 -277.836472)
			(xy 350.729532 -277.850164) (xy 350.773994 -277.871262) (xy 350.814497 -277.899218) (xy 350.84999 -277.93331)
			(xy 350.879555 -277.972654) (xy 350.902426 -278.016231) (xy 350.91801 -278.062912) (xy 350.925905 -278.111489)
			(xy 350.9264 -278.136096) (xy 351.255342 -278.136096) (xy 351.259302 -278.087042) (xy 351.271079 -278.039258)
			(xy 351.29037 -277.993982) (xy 351.316673 -277.952386) (xy 351.349308 -277.915549) (xy 351.387429 -277.884424)
			(xy 351.43005 -277.859817) (xy 351.476066 -277.842365) (xy 351.524285 -277.832521) (xy 351.57346 -277.83054)
			(xy 351.622315 -277.836472) (xy 351.669586 -277.850164) (xy 351.714048 -277.871262) (xy 351.754551 -277.899218)
			(xy 351.790044 -277.93331) (xy 351.819609 -277.972654) (xy 351.84248 -278.016231) (xy 351.858064 -278.062912)
			(xy 351.865959 -278.111489) (xy 351.866454 -278.136096) (xy 352.195396 -278.136096) (xy 352.199356 -278.087042)
			(xy 352.211133 -278.039258) (xy 352.230424 -277.993982) (xy 352.256727 -277.952386) (xy 352.289362 -277.915549)
			(xy 352.327483 -277.884424) (xy 352.370104 -277.859817) (xy 352.41612 -277.842365) (xy 352.464339 -277.832521)
			(xy 352.513514 -277.83054) (xy 352.562369 -277.836472) (xy 352.60964 -277.850164) (xy 352.654102 -277.871262)
			(xy 352.694605 -277.899218) (xy 352.730098 -277.93331) (xy 352.759663 -277.972654) (xy 352.782534 -278.016231)
			(xy 352.798118 -278.062912) (xy 352.806013 -278.111489) (xy 352.806508 -278.136096) (xy 353.135196 -278.136096)
			(xy 353.139156 -278.087042) (xy 353.150933 -278.039258) (xy 353.170224 -277.993982) (xy 353.196527 -277.952386)
			(xy 353.229162 -277.915549) (xy 353.267283 -277.884424) (xy 353.309904 -277.859817) (xy 353.35592 -277.842365)
			(xy 353.404139 -277.832521) (xy 353.453314 -277.83054) (xy 353.502169 -277.836472) (xy 353.54944 -277.850164)
			(xy 353.593902 -277.871262) (xy 353.634405 -277.899218) (xy 353.669898 -277.93331) (xy 353.699463 -277.972654)
			(xy 353.722334 -278.016231) (xy 353.737918 -278.062912) (xy 353.745813 -278.111489) (xy 353.746308 -278.136096)
			(xy 354.07525 -278.136096) (xy 354.07921 -278.087042) (xy 354.090987 -278.039258) (xy 354.110278 -277.993982)
			(xy 354.136581 -277.952386) (xy 354.169216 -277.915549) (xy 354.207337 -277.884424) (xy 354.249958 -277.859817)
			(xy 354.295974 -277.842365) (xy 354.344193 -277.832521) (xy 354.393368 -277.83054) (xy 354.442223 -277.836472)
			(xy 354.489494 -277.850164) (xy 354.533956 -277.871262) (xy 354.574459 -277.899218) (xy 354.609952 -277.93331)
			(xy 354.639517 -277.972654) (xy 354.662388 -278.016231) (xy 354.677972 -278.062912) (xy 354.685867 -278.111489)
			(xy 354.686362 -278.136096) (xy 355.015304 -278.136096) (xy 355.019264 -278.087042) (xy 355.031041 -278.039258)
			(xy 355.050332 -277.993982) (xy 355.076635 -277.952386) (xy 355.10927 -277.915549) (xy 355.147391 -277.884424)
			(xy 355.190012 -277.859817) (xy 355.236028 -277.842365) (xy 355.284247 -277.832521) (xy 355.333422 -277.83054)
			(xy 355.382277 -277.836472) (xy 355.429548 -277.850164) (xy 355.47401 -277.871262) (xy 355.514513 -277.899218)
			(xy 355.550006 -277.93331) (xy 355.579571 -277.972654) (xy 355.602442 -278.016231) (xy 355.618026 -278.062912)
			(xy 355.625921 -278.111489) (xy 355.626416 -278.136096) (xy 355.955358 -278.136096) (xy 355.959318 -278.087042)
			(xy 355.971095 -278.039258) (xy 355.990386 -277.993982) (xy 356.016689 -277.952386) (xy 356.049324 -277.915549)
			(xy 356.087445 -277.884424) (xy 356.130066 -277.859817) (xy 356.176082 -277.842365) (xy 356.224301 -277.832521)
			(xy 356.273476 -277.83054) (xy 356.322331 -277.836472) (xy 356.369602 -277.850164) (xy 356.414064 -277.871262)
			(xy 356.454567 -277.899218) (xy 356.49006 -277.93331) (xy 356.519625 -277.972654) (xy 356.542496 -278.016231)
			(xy 356.55808 -278.062912) (xy 356.565975 -278.111489) (xy 356.56647 -278.136096) (xy 363.468932 -278.136096)
			(xy 363.472892 -278.087042) (xy 363.484669 -278.039258) (xy 363.50396 -277.993982) (xy 363.530263 -277.952386)
			(xy 363.562898 -277.915549) (xy 363.601019 -277.884424) (xy 363.64364 -277.859817) (xy 363.689656 -277.842365)
			(xy 363.737875 -277.832521) (xy 363.78705 -277.83054) (xy 363.835905 -277.836472) (xy 363.883176 -277.850164)
			(xy 363.927638 -277.871262) (xy 363.968141 -277.899218) (xy 364.003634 -277.93331) (xy 364.033199 -277.972654)
			(xy 364.05607 -278.016231) (xy 364.071654 -278.062912) (xy 364.079549 -278.111489) (xy 364.080044 -278.136096)
			(xy 364.408986 -278.136096) (xy 364.412946 -278.087042) (xy 364.424723 -278.039258) (xy 364.444014 -277.993982)
			(xy 364.470317 -277.952386) (xy 364.502952 -277.915549) (xy 364.541073 -277.884424) (xy 364.583694 -277.859817)
			(xy 364.62971 -277.842365) (xy 364.677929 -277.832521) (xy 364.727104 -277.83054) (xy 364.775959 -277.836472)
			(xy 364.82323 -277.850164) (xy 364.867692 -277.871262) (xy 364.908195 -277.899218) (xy 364.943688 -277.93331)
			(xy 364.973253 -277.972654) (xy 364.996124 -278.016231) (xy 365.011708 -278.062912) (xy 365.019603 -278.111489)
			(xy 365.020098 -278.136096) (xy 365.34904 -278.136096) (xy 365.353 -278.087042) (xy 365.364777 -278.039258)
			(xy 365.384068 -277.993982) (xy 365.410371 -277.952386) (xy 365.443006 -277.915549) (xy 365.481127 -277.884424)
			(xy 365.523748 -277.859817) (xy 365.569764 -277.842365) (xy 365.617983 -277.832521) (xy 365.667158 -277.83054)
			(xy 365.716013 -277.836472) (xy 365.763284 -277.850164) (xy 365.807746 -277.871262) (xy 365.848249 -277.899218)
			(xy 365.883742 -277.93331) (xy 365.913307 -277.972654) (xy 365.936178 -278.016231) (xy 365.951762 -278.062912)
			(xy 365.959657 -278.111489) (xy 365.960152 -278.136096) (xy 366.289094 -278.136096) (xy 366.293054 -278.087042)
			(xy 366.304831 -278.039258) (xy 366.324122 -277.993982) (xy 366.350425 -277.952386) (xy 366.38306 -277.915549)
			(xy 366.421181 -277.884424) (xy 366.463802 -277.859817) (xy 366.509818 -277.842365) (xy 366.558037 -277.832521)
			(xy 366.607212 -277.83054) (xy 366.656067 -277.836472) (xy 366.703338 -277.850164) (xy 366.7478 -277.871262)
			(xy 366.788303 -277.899218) (xy 366.823796 -277.93331) (xy 366.853361 -277.972654) (xy 366.876232 -278.016231)
			(xy 366.891816 -278.062912) (xy 366.899711 -278.111489) (xy 366.900206 -278.136096) (xy 367.228894 -278.136096)
			(xy 367.232854 -278.087042) (xy 367.244631 -278.039258) (xy 367.263922 -277.993982) (xy 367.290225 -277.952386)
			(xy 367.32286 -277.915549) (xy 367.360981 -277.884424) (xy 367.403602 -277.859817) (xy 367.449618 -277.842365)
			(xy 367.497837 -277.832521) (xy 367.547012 -277.83054) (xy 367.595867 -277.836472) (xy 367.643138 -277.850164)
			(xy 367.6876 -277.871262) (xy 367.728103 -277.899218) (xy 367.763596 -277.93331) (xy 367.793161 -277.972654)
			(xy 367.816032 -278.016231) (xy 367.831616 -278.062912) (xy 367.839511 -278.111489) (xy 367.840006 -278.136096)
			(xy 368.168948 -278.136096) (xy 368.172908 -278.087042) (xy 368.184685 -278.039258) (xy 368.203976 -277.993982)
			(xy 368.230279 -277.952386) (xy 368.262914 -277.915549) (xy 368.301035 -277.884424) (xy 368.343656 -277.859817)
			(xy 368.389672 -277.842365) (xy 368.437891 -277.832521) (xy 368.487066 -277.83054) (xy 368.535921 -277.836472)
			(xy 368.583192 -277.850164) (xy 368.627654 -277.871262) (xy 368.668157 -277.899218) (xy 368.70365 -277.93331)
			(xy 368.733215 -277.972654) (xy 368.756086 -278.016231) (xy 368.77167 -278.062912) (xy 368.779565 -278.111489)
			(xy 368.78006 -278.136096) (xy 369.109002 -278.136096) (xy 369.112962 -278.087042) (xy 369.124739 -278.039258)
			(xy 369.14403 -277.993982) (xy 369.170333 -277.952386) (xy 369.202968 -277.915549) (xy 369.241089 -277.884424)
			(xy 369.28371 -277.859817) (xy 369.329726 -277.842365) (xy 369.377945 -277.832521) (xy 369.42712 -277.83054)
			(xy 369.475975 -277.836472) (xy 369.523246 -277.850164) (xy 369.567708 -277.871262) (xy 369.608211 -277.899218)
			(xy 369.643704 -277.93331) (xy 369.673269 -277.972654) (xy 369.69614 -278.016231) (xy 369.711724 -278.062912)
			(xy 369.719619 -278.111489) (xy 369.720114 -278.136096) (xy 370.049056 -278.136096) (xy 370.053016 -278.087042)
			(xy 370.064793 -278.039258) (xy 370.084084 -277.993982) (xy 370.110387 -277.952386) (xy 370.143022 -277.915549)
			(xy 370.181143 -277.884424) (xy 370.223764 -277.859817) (xy 370.26978 -277.842365) (xy 370.317999 -277.832521)
			(xy 370.367174 -277.83054) (xy 370.416029 -277.836472) (xy 370.4633 -277.850164) (xy 370.507762 -277.871262)
			(xy 370.548265 -277.899218) (xy 370.583758 -277.93331) (xy 370.613323 -277.972654) (xy 370.636194 -278.016231)
			(xy 370.651778 -278.062912) (xy 370.659673 -278.111489) (xy 370.660168 -278.136096) (xy 370.98911 -278.136096)
			(xy 370.99307 -278.087042) (xy 371.004847 -278.039258) (xy 371.024138 -277.993982) (xy 371.050441 -277.952386)
			(xy 371.083076 -277.915549) (xy 371.121197 -277.884424) (xy 371.163818 -277.859817) (xy 371.209834 -277.842365)
			(xy 371.258053 -277.832521) (xy 371.307228 -277.83054) (xy 371.356083 -277.836472) (xy 371.403354 -277.850164)
			(xy 371.447816 -277.871262) (xy 371.488319 -277.899218) (xy 371.523812 -277.93331) (xy 371.553377 -277.972654)
			(xy 371.576248 -278.016231) (xy 371.591832 -278.062912) (xy 371.599727 -278.111489) (xy 371.600222 -278.136096)
			(xy 371.92891 -278.136096) (xy 371.93287 -278.087042) (xy 371.944647 -278.039258) (xy 371.963938 -277.993982)
			(xy 371.990241 -277.952386) (xy 372.022876 -277.915549) (xy 372.060997 -277.884424) (xy 372.103618 -277.859817)
			(xy 372.149634 -277.842365) (xy 372.197853 -277.832521) (xy 372.247028 -277.83054) (xy 372.295883 -277.836472)
			(xy 372.343154 -277.850164) (xy 372.387616 -277.871262) (xy 372.428119 -277.899218) (xy 372.463612 -277.93331)
			(xy 372.493177 -277.972654) (xy 372.516048 -278.016231) (xy 372.531632 -278.062912) (xy 372.539527 -278.111489)
			(xy 372.540022 -278.136096) (xy 372.868964 -278.136096) (xy 372.872924 -278.087042) (xy 372.884701 -278.039258)
			(xy 372.903992 -277.993982) (xy 372.930295 -277.952386) (xy 372.96293 -277.915549) (xy 373.001051 -277.884424)
			(xy 373.043672 -277.859817) (xy 373.089688 -277.842365) (xy 373.137907 -277.832521) (xy 373.187082 -277.83054)
			(xy 373.235937 -277.836472) (xy 373.283208 -277.850164) (xy 373.32767 -277.871262) (xy 373.368173 -277.899218)
			(xy 373.403666 -277.93331) (xy 373.433231 -277.972654) (xy 373.456102 -278.016231) (xy 373.471686 -278.062912)
			(xy 373.479581 -278.111489) (xy 373.480076 -278.136096) (xy 373.809018 -278.136096) (xy 373.812978 -278.087042)
			(xy 373.824755 -278.039258) (xy 373.844046 -277.993982) (xy 373.870349 -277.952386) (xy 373.902984 -277.915549)
			(xy 373.941105 -277.884424) (xy 373.983726 -277.859817) (xy 374.029742 -277.842365) (xy 374.077961 -277.832521)
			(xy 374.127136 -277.83054) (xy 374.175991 -277.836472) (xy 374.223262 -277.850164) (xy 374.267724 -277.871262)
			(xy 374.308227 -277.899218) (xy 374.34372 -277.93331) (xy 374.373285 -277.972654) (xy 374.396156 -278.016231)
			(xy 374.41174 -278.062912) (xy 374.419635 -278.111489) (xy 374.42013 -278.136096) (xy 374.749072 -278.136096)
			(xy 374.753032 -278.087042) (xy 374.764809 -278.039258) (xy 374.7841 -277.993982) (xy 374.810403 -277.952386)
			(xy 374.843038 -277.915549) (xy 374.881159 -277.884424) (xy 374.92378 -277.859817) (xy 374.969796 -277.842365)
			(xy 375.018015 -277.832521) (xy 375.06719 -277.83054) (xy 375.116045 -277.836472) (xy 375.163316 -277.850164)
			(xy 375.207778 -277.871262) (xy 375.248281 -277.899218) (xy 375.283774 -277.93331) (xy 375.313339 -277.972654)
			(xy 375.33621 -278.016231) (xy 375.351794 -278.062912) (xy 375.359689 -278.111489) (xy 375.360184 -278.136096)
			(xy 375.678695 -278.136096) (xy 375.68279 -278.085368) (xy 375.694969 -278.035954) (xy 375.714917 -277.989134)
			(xy 375.742118 -277.94612) (xy 375.775866 -277.908026) (xy 375.815288 -277.875839) (xy 375.859362 -277.850393)
			(xy 375.906948 -277.832346) (xy 375.956812 -277.822166) (xy 376.007664 -277.820117) (xy 376.058185 -277.826251)
			(xy 376.107069 -277.840411) (xy 376.153048 -277.862228) (xy 376.194932 -277.891138) (xy 376.231636 -277.926393)
			(xy 376.262209 -277.967079) (xy 376.28586 -278.012142) (xy 376.301976 -278.060416) (xy 376.31014 -278.11065)
			(xy 376.310652 -278.136096) (xy 376.628926 -278.136096) (xy 376.632886 -278.087042) (xy 376.644663 -278.039258)
			(xy 376.663954 -277.993982) (xy 376.690257 -277.952386) (xy 376.722892 -277.915549) (xy 376.761013 -277.884424)
			(xy 376.803634 -277.859817) (xy 376.84965 -277.842365) (xy 376.897869 -277.832521) (xy 376.947044 -277.83054)
			(xy 376.995899 -277.836472) (xy 377.04317 -277.850164) (xy 377.087632 -277.871262) (xy 377.128135 -277.899218)
			(xy 377.163628 -277.93331) (xy 377.193193 -277.972654) (xy 377.216064 -278.016231) (xy 377.231648 -278.062912)
			(xy 377.239543 -278.111489) (xy 377.240038 -278.136096) (xy 377.558549 -278.136096) (xy 377.562644 -278.085368)
			(xy 377.574823 -278.035954) (xy 377.594771 -277.989134) (xy 377.621972 -277.94612) (xy 377.65572 -277.908026)
			(xy 377.695142 -277.875839) (xy 377.739216 -277.850393) (xy 377.786802 -277.832346) (xy 377.836666 -277.822166)
			(xy 377.887518 -277.820117) (xy 377.938039 -277.826251) (xy 377.986923 -277.840411) (xy 378.032902 -277.862228)
			(xy 378.074786 -277.891138) (xy 378.11149 -277.926393) (xy 378.142063 -277.967079) (xy 378.165714 -278.012142)
			(xy 378.18183 -278.060416) (xy 378.189994 -278.11065) (xy 378.190506 -278.136096) (xy 378.189994 -278.161542)
			(xy 378.18183 -278.211776) (xy 378.165714 -278.26005) (xy 378.142063 -278.305113) (xy 378.11149 -278.345799)
			(xy 378.074786 -278.381054) (xy 378.032902 -278.409964) (xy 377.986923 -278.431781) (xy 377.938039 -278.445941)
			(xy 377.887518 -278.452075) (xy 377.836666 -278.450026) (xy 377.786802 -278.439846) (xy 377.739216 -278.421799)
			(xy 377.695142 -278.396353) (xy 377.65572 -278.364166) (xy 377.621972 -278.326072) (xy 377.594771 -278.283058)
			(xy 377.574823 -278.236238) (xy 377.562644 -278.186824) (xy 377.558549 -278.136096) (xy 377.240038 -278.136096)
			(xy 377.239543 -278.160703) (xy 377.231648 -278.20928) (xy 377.216064 -278.255961) (xy 377.193193 -278.299538)
			(xy 377.163628 -278.338882) (xy 377.128135 -278.372974) (xy 377.087632 -278.40093) (xy 377.04317 -278.422028)
			(xy 376.995899 -278.43572) (xy 376.947044 -278.441652) (xy 376.897869 -278.439671) (xy 376.84965 -278.429827)
			(xy 376.803634 -278.412375) (xy 376.761013 -278.387768) (xy 376.722892 -278.356643) (xy 376.690257 -278.319806)
			(xy 376.663954 -278.27821) (xy 376.644663 -278.232934) (xy 376.632886 -278.18515) (xy 376.628926 -278.136096)
			(xy 376.310652 -278.136096) (xy 376.31014 -278.161542) (xy 376.301976 -278.211776) (xy 376.28586 -278.26005)
			(xy 376.262209 -278.305113) (xy 376.231636 -278.345799) (xy 376.194932 -278.381054) (xy 376.153048 -278.409964)
			(xy 376.107069 -278.431781) (xy 376.058185 -278.445941) (xy 376.007664 -278.452075) (xy 375.956812 -278.450026)
			(xy 375.906948 -278.439846) (xy 375.859362 -278.421799) (xy 375.815288 -278.396353) (xy 375.775866 -278.364166)
			(xy 375.742118 -278.326072) (xy 375.714917 -278.283058) (xy 375.694969 -278.236238) (xy 375.68279 -278.186824)
			(xy 375.678695 -278.136096) (xy 375.360184 -278.136096) (xy 375.359689 -278.160703) (xy 375.351794 -278.20928)
			(xy 375.33621 -278.255961) (xy 375.313339 -278.299538) (xy 375.283774 -278.338882) (xy 375.248281 -278.372974)
			(xy 375.207778 -278.40093) (xy 375.163316 -278.422028) (xy 375.116045 -278.43572) (xy 375.06719 -278.441652)
			(xy 375.018015 -278.439671) (xy 374.969796 -278.429827) (xy 374.92378 -278.412375) (xy 374.881159 -278.387768)
			(xy 374.843038 -278.356643) (xy 374.810403 -278.319806) (xy 374.7841 -278.27821) (xy 374.764809 -278.232934)
			(xy 374.753032 -278.18515) (xy 374.749072 -278.136096) (xy 374.42013 -278.136096) (xy 374.419635 -278.160703)
			(xy 374.41174 -278.20928) (xy 374.396156 -278.255961) (xy 374.373285 -278.299538) (xy 374.34372 -278.338882)
			(xy 374.308227 -278.372974) (xy 374.267724 -278.40093) (xy 374.223262 -278.422028) (xy 374.175991 -278.43572)
			(xy 374.127136 -278.441652) (xy 374.077961 -278.439671) (xy 374.029742 -278.429827) (xy 373.983726 -278.412375)
			(xy 373.941105 -278.387768) (xy 373.902984 -278.356643) (xy 373.870349 -278.319806) (xy 373.844046 -278.27821)
			(xy 373.824755 -278.232934) (xy 373.812978 -278.18515) (xy 373.809018 -278.136096) (xy 373.480076 -278.136096)
			(xy 373.479581 -278.160703) (xy 373.471686 -278.20928) (xy 373.456102 -278.255961) (xy 373.433231 -278.299538)
			(xy 373.403666 -278.338882) (xy 373.368173 -278.372974) (xy 373.32767 -278.40093) (xy 373.283208 -278.422028)
			(xy 373.235937 -278.43572) (xy 373.187082 -278.441652) (xy 373.137907 -278.439671) (xy 373.089688 -278.429827)
			(xy 373.043672 -278.412375) (xy 373.001051 -278.387768) (xy 372.96293 -278.356643) (xy 372.930295 -278.319806)
			(xy 372.903992 -278.27821) (xy 372.884701 -278.232934) (xy 372.872924 -278.18515) (xy 372.868964 -278.136096)
			(xy 372.540022 -278.136096) (xy 372.539527 -278.160703) (xy 372.531632 -278.20928) (xy 372.516048 -278.255961)
			(xy 372.493177 -278.299538) (xy 372.463612 -278.338882) (xy 372.428119 -278.372974) (xy 372.387616 -278.40093)
			(xy 372.343154 -278.422028) (xy 372.295883 -278.43572) (xy 372.247028 -278.441652) (xy 372.197853 -278.439671)
			(xy 372.149634 -278.429827) (xy 372.103618 -278.412375) (xy 372.060997 -278.387768) (xy 372.022876 -278.356643)
			(xy 371.990241 -278.319806) (xy 371.963938 -278.27821) (xy 371.944647 -278.232934) (xy 371.93287 -278.18515)
			(xy 371.92891 -278.136096) (xy 371.600222 -278.136096) (xy 371.599727 -278.160703) (xy 371.591832 -278.20928)
			(xy 371.576248 -278.255961) (xy 371.553377 -278.299538) (xy 371.523812 -278.338882) (xy 371.488319 -278.372974)
			(xy 371.447816 -278.40093) (xy 371.403354 -278.422028) (xy 371.356083 -278.43572) (xy 371.307228 -278.441652)
			(xy 371.258053 -278.439671) (xy 371.209834 -278.429827) (xy 371.163818 -278.412375) (xy 371.121197 -278.387768)
			(xy 371.083076 -278.356643) (xy 371.050441 -278.319806) (xy 371.024138 -278.27821) (xy 371.004847 -278.232934)
			(xy 370.99307 -278.18515) (xy 370.98911 -278.136096) (xy 370.660168 -278.136096) (xy 370.659673 -278.160703)
			(xy 370.651778 -278.20928) (xy 370.636194 -278.255961) (xy 370.613323 -278.299538) (xy 370.583758 -278.338882)
			(xy 370.548265 -278.372974) (xy 370.507762 -278.40093) (xy 370.4633 -278.422028) (xy 370.416029 -278.43572)
			(xy 370.367174 -278.441652) (xy 370.317999 -278.439671) (xy 370.26978 -278.429827) (xy 370.223764 -278.412375)
			(xy 370.181143 -278.387768) (xy 370.143022 -278.356643) (xy 370.110387 -278.319806) (xy 370.084084 -278.27821)
			(xy 370.064793 -278.232934) (xy 370.053016 -278.18515) (xy 370.049056 -278.136096) (xy 369.720114 -278.136096)
			(xy 369.719619 -278.160703) (xy 369.711724 -278.20928) (xy 369.69614 -278.255961) (xy 369.673269 -278.299538)
			(xy 369.643704 -278.338882) (xy 369.608211 -278.372974) (xy 369.567708 -278.40093) (xy 369.523246 -278.422028)
			(xy 369.475975 -278.43572) (xy 369.42712 -278.441652) (xy 369.377945 -278.439671) (xy 369.329726 -278.429827)
			(xy 369.28371 -278.412375) (xy 369.241089 -278.387768) (xy 369.202968 -278.356643) (xy 369.170333 -278.319806)
			(xy 369.14403 -278.27821) (xy 369.124739 -278.232934) (xy 369.112962 -278.18515) (xy 369.109002 -278.136096)
			(xy 368.78006 -278.136096) (xy 368.779565 -278.160703) (xy 368.77167 -278.20928) (xy 368.756086 -278.255961)
			(xy 368.733215 -278.299538) (xy 368.70365 -278.338882) (xy 368.668157 -278.372974) (xy 368.627654 -278.40093)
			(xy 368.583192 -278.422028) (xy 368.535921 -278.43572) (xy 368.487066 -278.441652) (xy 368.437891 -278.439671)
			(xy 368.389672 -278.429827) (xy 368.343656 -278.412375) (xy 368.301035 -278.387768) (xy 368.262914 -278.356643)
			(xy 368.230279 -278.319806) (xy 368.203976 -278.27821) (xy 368.184685 -278.232934) (xy 368.172908 -278.18515)
			(xy 368.168948 -278.136096) (xy 367.840006 -278.136096) (xy 367.839511 -278.160703) (xy 367.831616 -278.20928)
			(xy 367.816032 -278.255961) (xy 367.793161 -278.299538) (xy 367.763596 -278.338882) (xy 367.728103 -278.372974)
			(xy 367.6876 -278.40093) (xy 367.643138 -278.422028) (xy 367.595867 -278.43572) (xy 367.547012 -278.441652)
			(xy 367.497837 -278.439671) (xy 367.449618 -278.429827) (xy 367.403602 -278.412375) (xy 367.360981 -278.387768)
			(xy 367.32286 -278.356643) (xy 367.290225 -278.319806) (xy 367.263922 -278.27821) (xy 367.244631 -278.232934)
			(xy 367.232854 -278.18515) (xy 367.228894 -278.136096) (xy 366.900206 -278.136096) (xy 366.899711 -278.160703)
			(xy 366.891816 -278.20928) (xy 366.876232 -278.255961) (xy 366.853361 -278.299538) (xy 366.823796 -278.338882)
			(xy 366.788303 -278.372974) (xy 366.7478 -278.40093) (xy 366.703338 -278.422028) (xy 366.656067 -278.43572)
			(xy 366.607212 -278.441652) (xy 366.558037 -278.439671) (xy 366.509818 -278.429827) (xy 366.463802 -278.412375)
			(xy 366.421181 -278.387768) (xy 366.38306 -278.356643) (xy 366.350425 -278.319806) (xy 366.324122 -278.27821)
			(xy 366.304831 -278.232934) (xy 366.293054 -278.18515) (xy 366.289094 -278.136096) (xy 365.960152 -278.136096)
			(xy 365.959657 -278.160703) (xy 365.951762 -278.20928) (xy 365.936178 -278.255961) (xy 365.913307 -278.299538)
			(xy 365.883742 -278.338882) (xy 365.848249 -278.372974) (xy 365.807746 -278.40093) (xy 365.763284 -278.422028)
			(xy 365.716013 -278.43572) (xy 365.667158 -278.441652) (xy 365.617983 -278.439671) (xy 365.569764 -278.429827)
			(xy 365.523748 -278.412375) (xy 365.481127 -278.387768) (xy 365.443006 -278.356643) (xy 365.410371 -278.319806)
			(xy 365.384068 -278.27821) (xy 365.364777 -278.232934) (xy 365.353 -278.18515) (xy 365.34904 -278.136096)
			(xy 365.020098 -278.136096) (xy 365.019603 -278.160703) (xy 365.011708 -278.20928) (xy 364.996124 -278.255961)
			(xy 364.973253 -278.299538) (xy 364.943688 -278.338882) (xy 364.908195 -278.372974) (xy 364.867692 -278.40093)
			(xy 364.82323 -278.422028) (xy 364.775959 -278.43572) (xy 364.727104 -278.441652) (xy 364.677929 -278.439671)
			(xy 364.62971 -278.429827) (xy 364.583694 -278.412375) (xy 364.541073 -278.387768) (xy 364.502952 -278.356643)
			(xy 364.470317 -278.319806) (xy 364.444014 -278.27821) (xy 364.424723 -278.232934) (xy 364.412946 -278.18515)
			(xy 364.408986 -278.136096) (xy 364.080044 -278.136096) (xy 364.079549 -278.160703) (xy 364.071654 -278.20928)
			(xy 364.05607 -278.255961) (xy 364.033199 -278.299538) (xy 364.003634 -278.338882) (xy 363.968141 -278.372974)
			(xy 363.927638 -278.40093) (xy 363.883176 -278.422028) (xy 363.835905 -278.43572) (xy 363.78705 -278.441652)
			(xy 363.737875 -278.439671) (xy 363.689656 -278.429827) (xy 363.64364 -278.412375) (xy 363.601019 -278.387768)
			(xy 363.562898 -278.356643) (xy 363.530263 -278.319806) (xy 363.50396 -278.27821) (xy 363.484669 -278.232934)
			(xy 363.472892 -278.18515) (xy 363.468932 -278.136096) (xy 356.56647 -278.136096) (xy 356.565975 -278.160703)
			(xy 356.55808 -278.20928) (xy 356.542496 -278.255961) (xy 356.519625 -278.299538) (xy 356.49006 -278.338882)
			(xy 356.454567 -278.372974) (xy 356.414064 -278.40093) (xy 356.369602 -278.422028) (xy 356.322331 -278.43572)
			(xy 356.273476 -278.441652) (xy 356.224301 -278.439671) (xy 356.176082 -278.429827) (xy 356.130066 -278.412375)
			(xy 356.087445 -278.387768) (xy 356.049324 -278.356643) (xy 356.016689 -278.319806) (xy 355.990386 -278.27821)
			(xy 355.971095 -278.232934) (xy 355.959318 -278.18515) (xy 355.955358 -278.136096) (xy 355.626416 -278.136096)
			(xy 355.625921 -278.160703) (xy 355.618026 -278.20928) (xy 355.602442 -278.255961) (xy 355.579571 -278.299538)
			(xy 355.550006 -278.338882) (xy 355.514513 -278.372974) (xy 355.47401 -278.40093) (xy 355.429548 -278.422028)
			(xy 355.382277 -278.43572) (xy 355.333422 -278.441652) (xy 355.284247 -278.439671) (xy 355.236028 -278.429827)
			(xy 355.190012 -278.412375) (xy 355.147391 -278.387768) (xy 355.10927 -278.356643) (xy 355.076635 -278.319806)
			(xy 355.050332 -278.27821) (xy 355.031041 -278.232934) (xy 355.019264 -278.18515) (xy 355.015304 -278.136096)
			(xy 354.686362 -278.136096) (xy 354.685867 -278.160703) (xy 354.677972 -278.20928) (xy 354.662388 -278.255961)
			(xy 354.639517 -278.299538) (xy 354.609952 -278.338882) (xy 354.574459 -278.372974) (xy 354.533956 -278.40093)
			(xy 354.489494 -278.422028) (xy 354.442223 -278.43572) (xy 354.393368 -278.441652) (xy 354.344193 -278.439671)
			(xy 354.295974 -278.429827) (xy 354.249958 -278.412375) (xy 354.207337 -278.387768) (xy 354.169216 -278.356643)
			(xy 354.136581 -278.319806) (xy 354.110278 -278.27821) (xy 354.090987 -278.232934) (xy 354.07921 -278.18515)
			(xy 354.07525 -278.136096) (xy 353.746308 -278.136096) (xy 353.745813 -278.160703) (xy 353.737918 -278.20928)
			(xy 353.722334 -278.255961) (xy 353.699463 -278.299538) (xy 353.669898 -278.338882) (xy 353.634405 -278.372974)
			(xy 353.593902 -278.40093) (xy 353.54944 -278.422028) (xy 353.502169 -278.43572) (xy 353.453314 -278.441652)
			(xy 353.404139 -278.439671) (xy 353.35592 -278.429827) (xy 353.309904 -278.412375) (xy 353.267283 -278.387768)
			(xy 353.229162 -278.356643) (xy 353.196527 -278.319806) (xy 353.170224 -278.27821) (xy 353.150933 -278.232934)
			(xy 353.139156 -278.18515) (xy 353.135196 -278.136096) (xy 352.806508 -278.136096) (xy 352.806013 -278.160703)
			(xy 352.798118 -278.20928) (xy 352.782534 -278.255961) (xy 352.759663 -278.299538) (xy 352.730098 -278.338882)
			(xy 352.694605 -278.372974) (xy 352.654102 -278.40093) (xy 352.60964 -278.422028) (xy 352.562369 -278.43572)
			(xy 352.513514 -278.441652) (xy 352.464339 -278.439671) (xy 352.41612 -278.429827) (xy 352.370104 -278.412375)
			(xy 352.327483 -278.387768) (xy 352.289362 -278.356643) (xy 352.256727 -278.319806) (xy 352.230424 -278.27821)
			(xy 352.211133 -278.232934) (xy 352.199356 -278.18515) (xy 352.195396 -278.136096) (xy 351.866454 -278.136096)
			(xy 351.865959 -278.160703) (xy 351.858064 -278.20928) (xy 351.84248 -278.255961) (xy 351.819609 -278.299538)
			(xy 351.790044 -278.338882) (xy 351.754551 -278.372974) (xy 351.714048 -278.40093) (xy 351.669586 -278.422028)
			(xy 351.622315 -278.43572) (xy 351.57346 -278.441652) (xy 351.524285 -278.439671) (xy 351.476066 -278.429827)
			(xy 351.43005 -278.412375) (xy 351.387429 -278.387768) (xy 351.349308 -278.356643) (xy 351.316673 -278.319806)
			(xy 351.29037 -278.27821) (xy 351.271079 -278.232934) (xy 351.259302 -278.18515) (xy 351.255342 -278.136096)
			(xy 350.9264 -278.136096) (xy 350.925905 -278.160703) (xy 350.91801 -278.20928) (xy 350.902426 -278.255961)
			(xy 350.879555 -278.299538) (xy 350.84999 -278.338882) (xy 350.814497 -278.372974) (xy 350.773994 -278.40093)
			(xy 350.729532 -278.422028) (xy 350.682261 -278.43572) (xy 350.633406 -278.441652) (xy 350.584231 -278.439671)
			(xy 350.536012 -278.429827) (xy 350.489996 -278.412375) (xy 350.447375 -278.387768) (xy 350.409254 -278.356643)
			(xy 350.376619 -278.319806) (xy 350.350316 -278.27821) (xy 350.331025 -278.232934) (xy 350.319248 -278.18515)
			(xy 350.315288 -278.136096) (xy 349.986346 -278.136096) (xy 349.985851 -278.160703) (xy 349.977956 -278.20928)
			(xy 349.962372 -278.255961) (xy 349.939501 -278.299538) (xy 349.909936 -278.338882) (xy 349.874443 -278.372974)
			(xy 349.83394 -278.40093) (xy 349.789478 -278.422028) (xy 349.742207 -278.43572) (xy 349.693352 -278.441652)
			(xy 349.644177 -278.439671) (xy 349.595958 -278.429827) (xy 349.549942 -278.412375) (xy 349.507321 -278.387768)
			(xy 349.4692 -278.356643) (xy 349.436565 -278.319806) (xy 349.410262 -278.27821) (xy 349.390971 -278.232934)
			(xy 349.379194 -278.18515) (xy 349.375234 -278.136096) (xy 349.046546 -278.136096) (xy 349.046051 -278.160703)
			(xy 349.038156 -278.20928) (xy 349.022572 -278.255961) (xy 348.999701 -278.299538) (xy 348.970136 -278.338882)
			(xy 348.934643 -278.372974) (xy 348.89414 -278.40093) (xy 348.849678 -278.422028) (xy 348.802407 -278.43572)
			(xy 348.753552 -278.441652) (xy 348.704377 -278.439671) (xy 348.656158 -278.429827) (xy 348.610142 -278.412375)
			(xy 348.567521 -278.387768) (xy 348.5294 -278.356643) (xy 348.496765 -278.319806) (xy 348.470462 -278.27821)
			(xy 348.451171 -278.232934) (xy 348.439394 -278.18515) (xy 348.435434 -278.136096) (xy 348.106492 -278.136096)
			(xy 348.105997 -278.160703) (xy 348.098102 -278.20928) (xy 348.082518 -278.255961) (xy 348.059647 -278.299538)
			(xy 348.030082 -278.338882) (xy 347.994589 -278.372974) (xy 347.954086 -278.40093) (xy 347.909624 -278.422028)
			(xy 347.862353 -278.43572) (xy 347.813498 -278.441652) (xy 347.764323 -278.439671) (xy 347.716104 -278.429827)
			(xy 347.670088 -278.412375) (xy 347.627467 -278.387768) (xy 347.589346 -278.356643) (xy 347.556711 -278.319806)
			(xy 347.530408 -278.27821) (xy 347.511117 -278.232934) (xy 347.49934 -278.18515) (xy 347.49538 -278.136096)
			(xy 347.166438 -278.136096) (xy 347.165943 -278.160703) (xy 347.158048 -278.20928) (xy 347.142464 -278.255961)
			(xy 347.119593 -278.299538) (xy 347.090028 -278.338882) (xy 347.054535 -278.372974) (xy 347.014032 -278.40093)
			(xy 346.96957 -278.422028) (xy 346.922299 -278.43572) (xy 346.873444 -278.441652) (xy 346.824269 -278.439671)
			(xy 346.77605 -278.429827) (xy 346.730034 -278.412375) (xy 346.687413 -278.387768) (xy 346.649292 -278.356643)
			(xy 346.616657 -278.319806) (xy 346.590354 -278.27821) (xy 346.571063 -278.232934) (xy 346.559286 -278.18515)
			(xy 346.555326 -278.136096) (xy 346.226384 -278.136096) (xy 346.225889 -278.160703) (xy 346.217994 -278.20928)
			(xy 346.20241 -278.255961) (xy 346.179539 -278.299538) (xy 346.149974 -278.338882) (xy 346.114481 -278.372974)
			(xy 346.073978 -278.40093) (xy 346.029516 -278.422028) (xy 345.982245 -278.43572) (xy 345.93339 -278.441652)
			(xy 345.884215 -278.439671) (xy 345.835996 -278.429827) (xy 345.78998 -278.412375) (xy 345.747359 -278.387768)
			(xy 345.709238 -278.356643) (xy 345.676603 -278.319806) (xy 345.6503 -278.27821) (xy 345.631009 -278.232934)
			(xy 345.619232 -278.18515) (xy 345.615272 -278.136096) (xy 345.28633 -278.136096) (xy 345.285835 -278.160703)
			(xy 345.27794 -278.20928) (xy 345.262356 -278.255961) (xy 345.239485 -278.299538) (xy 345.20992 -278.338882)
			(xy 345.174427 -278.372974) (xy 345.133924 -278.40093) (xy 345.089462 -278.422028) (xy 345.042191 -278.43572)
			(xy 344.993336 -278.441652) (xy 344.944161 -278.439671) (xy 344.895942 -278.429827) (xy 344.849926 -278.412375)
			(xy 344.807305 -278.387768) (xy 344.769184 -278.356643) (xy 344.736549 -278.319806) (xy 344.710246 -278.27821)
			(xy 344.690955 -278.232934) (xy 344.679178 -278.18515) (xy 344.675218 -278.136096) (xy 344.356944 -278.136096)
			(xy 344.356432 -278.161542) (xy 344.348268 -278.211776) (xy 344.332152 -278.26005) (xy 344.308501 -278.305113)
			(xy 344.277928 -278.345799) (xy 344.241224 -278.381054) (xy 344.19934 -278.409964) (xy 344.153361 -278.431781)
			(xy 344.104477 -278.445941) (xy 344.053956 -278.452075) (xy 344.003104 -278.450026) (xy 343.95324 -278.439846)
			(xy 343.905654 -278.421799) (xy 343.86158 -278.396353) (xy 343.822158 -278.364166) (xy 343.78841 -278.326072)
			(xy 343.761209 -278.283058) (xy 343.741261 -278.236238) (xy 343.729082 -278.186824) (xy 343.724987 -278.136096)
			(xy 343.406476 -278.136096) (xy 343.405981 -278.160703) (xy 343.398086 -278.20928) (xy 343.382502 -278.255961)
			(xy 343.359631 -278.299538) (xy 343.330066 -278.338882) (xy 343.294573 -278.372974) (xy 343.25407 -278.40093)
			(xy 343.209608 -278.422028) (xy 343.162337 -278.43572) (xy 343.113482 -278.441652) (xy 343.064307 -278.439671)
			(xy 343.016088 -278.429827) (xy 342.970072 -278.412375) (xy 342.927451 -278.387768) (xy 342.88933 -278.356643)
			(xy 342.856695 -278.319806) (xy 342.830392 -278.27821) (xy 342.811101 -278.232934) (xy 342.799324 -278.18515)
			(xy 342.795364 -278.136096) (xy 342.476836 -278.136096) (xy 342.476324 -278.161542) (xy 342.46816 -278.211776)
			(xy 342.452044 -278.26005) (xy 342.428393 -278.305113) (xy 342.39782 -278.345799) (xy 342.361116 -278.381054)
			(xy 342.319232 -278.409964) (xy 342.273253 -278.431781) (xy 342.224369 -278.445941) (xy 342.173848 -278.452075)
			(xy 342.122996 -278.450026) (xy 342.073132 -278.439846) (xy 342.025546 -278.421799) (xy 341.981472 -278.396353)
			(xy 341.94205 -278.364166) (xy 341.908302 -278.326072) (xy 341.881101 -278.283058) (xy 341.861153 -278.236238)
			(xy 341.848974 -278.186824) (xy 341.844879 -278.136096) (xy 341.525957 -278.136096) (xy 341.525957 -278.160167)
			(xy 341.518404 -278.207705) (xy 341.503485 -278.253469) (xy 341.48157 -278.296325) (xy 341.453202 -278.335212)
			(xy 341.419083 -278.369165) (xy 341.38006 -278.397345) (xy 341.337098 -278.419051) (xy 341.291262 -278.433748)
			(xy 341.267542 -278.437848) (xy 341.258652 -278.439118) (xy 341.24265 -278.448008) (xy 341.236808 -278.454866)
			(xy 341.231217 -278.461951) (xy 341.224963 -278.478868) (xy 341.224616 -278.487886) (xy 341.224616 -278.647144)
			(xy 341.224849 -278.653661) (xy 341.228187 -278.666263) (xy 341.23122 -278.672036) (xy 341.241158 -278.689803)
			(xy 341.2587 -278.726545) (xy 341.266272 -278.745442) (xy 341.266272 -278.745696) (xy 341.268899 -278.751886)
			(xy 341.276872 -278.762707) (xy 341.28202 -278.767032) (xy 341.293196 -278.775668) (xy 341.305642 -278.777192)
			(xy 341.395812 -278.788622) (xy 341.402691 -278.78922) (xy 341.41634 -278.787161) (xy 341.422736 -278.784558)
			(xy 341.428578 -278.782018) (xy 341.438992 -278.773636) (xy 341.44331 -278.767794) (xy 341.457774 -278.748491)
			(xy 341.49176 -278.714266) (xy 341.530698 -278.685801) (xy 341.573622 -278.663803) (xy 341.619468 -278.648818)
			(xy 341.667098 -278.641216) (xy 341.691214 -278.640794) (xy 341.716468 -278.641317) (xy 341.766288 -278.649632)
			(xy 341.81406 -278.666034) (xy 341.85848 -278.690075) (xy 341.898338 -278.721099) (xy 341.932546 -278.758261)
			(xy 341.960171 -278.800545) (xy 341.980459 -278.8468) (xy 341.992858 -278.895764) (xy 341.997029 -278.9461)
			(xy 341.997029 -278.946102) (xy 342.314779 -278.946102) (xy 342.318874 -278.895374) (xy 342.331053 -278.84596)
			(xy 342.351001 -278.79914) (xy 342.378202 -278.756126) (xy 342.41195 -278.718032) (xy 342.451372 -278.685845)
			(xy 342.495446 -278.660399) (xy 342.543032 -278.642352) (xy 342.592896 -278.632172) (xy 342.643748 -278.630123)
			(xy 342.694269 -278.636257) (xy 342.743153 -278.650417) (xy 342.789132 -278.672234) (xy 342.831016 -278.701144)
			(xy 342.86772 -278.736399) (xy 342.898293 -278.777085) (xy 342.921944 -278.822148) (xy 342.93806 -278.870422)
			(xy 342.946224 -278.920656) (xy 342.946736 -278.946102) (xy 343.254833 -278.946102) (xy 343.258928 -278.895374)
			(xy 343.271107 -278.84596) (xy 343.291055 -278.79914) (xy 343.318256 -278.756126) (xy 343.352004 -278.718032)
			(xy 343.391426 -278.685845) (xy 343.4355 -278.660399) (xy 343.483086 -278.642352) (xy 343.53295 -278.632172)
			(xy 343.583802 -278.630123) (xy 343.634323 -278.636257) (xy 343.683207 -278.650417) (xy 343.729186 -278.672234)
			(xy 343.77107 -278.701144) (xy 343.807774 -278.736399) (xy 343.838347 -278.777085) (xy 343.861998 -278.822148)
			(xy 343.878114 -278.870422) (xy 343.886278 -278.920656) (xy 343.88679 -278.946102) (xy 344.205318 -278.946102)
			(xy 344.209278 -278.897048) (xy 344.221055 -278.849264) (xy 344.240346 -278.803988) (xy 344.266649 -278.762392)
			(xy 344.299284 -278.725555) (xy 344.337405 -278.69443) (xy 344.380026 -278.669823) (xy 344.426042 -278.652371)
			(xy 344.474261 -278.642527) (xy 344.523436 -278.640546) (xy 344.572291 -278.646478) (xy 344.619562 -278.66017)
			(xy 344.664024 -278.681268) (xy 344.704527 -278.709224) (xy 344.74002 -278.743316) (xy 344.769585 -278.78266)
			(xy 344.792456 -278.826237) (xy 344.80804 -278.872918) (xy 344.815935 -278.921495) (xy 344.81643 -278.946102)
			(xy 347.025226 -278.946102) (xy 347.029186 -278.897048) (xy 347.040963 -278.849264) (xy 347.060254 -278.803988)
			(xy 347.086557 -278.762392) (xy 347.119192 -278.725555) (xy 347.157313 -278.69443) (xy 347.199934 -278.669823)
			(xy 347.24595 -278.652371) (xy 347.294169 -278.642527) (xy 347.343344 -278.640546) (xy 347.392199 -278.646478)
			(xy 347.43947 -278.66017) (xy 347.483932 -278.681268) (xy 347.524435 -278.709224) (xy 347.559928 -278.743316)
			(xy 347.589493 -278.78266) (xy 347.612364 -278.826237) (xy 347.627948 -278.872918) (xy 347.635843 -278.921495)
			(xy 347.636338 -278.946102) (xy 349.845388 -278.946102) (xy 349.849348 -278.897048) (xy 349.861125 -278.849264)
			(xy 349.880416 -278.803988) (xy 349.906719 -278.762392) (xy 349.939354 -278.725555) (xy 349.977475 -278.69443)
			(xy 350.020096 -278.669823) (xy 350.066112 -278.652371) (xy 350.114331 -278.642527) (xy 350.163506 -278.640546)
			(xy 350.212361 -278.646478) (xy 350.259632 -278.66017) (xy 350.304094 -278.681268) (xy 350.344597 -278.709224)
			(xy 350.38009 -278.743316) (xy 350.409655 -278.78266) (xy 350.432526 -278.826237) (xy 350.44811 -278.872918)
			(xy 350.456005 -278.921495) (xy 350.4565 -278.946102) (xy 352.665296 -278.946102) (xy 352.669256 -278.897048)
			(xy 352.681033 -278.849264) (xy 352.700324 -278.803988) (xy 352.726627 -278.762392) (xy 352.759262 -278.725555)
			(xy 352.797383 -278.69443) (xy 352.840004 -278.669823) (xy 352.88602 -278.652371) (xy 352.934239 -278.642527)
			(xy 352.983414 -278.640546) (xy 353.032269 -278.646478) (xy 353.07954 -278.66017) (xy 353.124002 -278.681268)
			(xy 353.164505 -278.709224) (xy 353.199998 -278.743316) (xy 353.229563 -278.78266) (xy 353.252434 -278.826237)
			(xy 353.268018 -278.872918) (xy 353.275913 -278.921495) (xy 353.276408 -278.946102) (xy 355.485204 -278.946102)
			(xy 355.489164 -278.897048) (xy 355.500941 -278.849264) (xy 355.520232 -278.803988) (xy 355.546535 -278.762392)
			(xy 355.57917 -278.725555) (xy 355.617291 -278.69443) (xy 355.659912 -278.669823) (xy 355.705928 -278.652371)
			(xy 355.754147 -278.642527) (xy 355.803322 -278.640546) (xy 355.852177 -278.646478) (xy 355.899448 -278.66017)
			(xy 355.94391 -278.681268) (xy 355.984413 -278.709224) (xy 356.019906 -278.743316) (xy 356.049471 -278.78266)
			(xy 356.072342 -278.826237) (xy 356.087926 -278.872918) (xy 356.095821 -278.921495) (xy 356.096316 -278.946102)
			(xy 356.425258 -278.946102) (xy 356.429218 -278.897048) (xy 356.440995 -278.849264) (xy 356.460286 -278.803988)
			(xy 356.486589 -278.762392) (xy 356.519224 -278.725555) (xy 356.557345 -278.69443) (xy 356.599966 -278.669823)
			(xy 356.645982 -278.652371) (xy 356.694201 -278.642527) (xy 356.743376 -278.640546) (xy 356.792231 -278.646478)
			(xy 356.839502 -278.66017) (xy 356.883964 -278.681268) (xy 356.924467 -278.709224) (xy 356.95996 -278.743316)
			(xy 356.989525 -278.78266) (xy 357.012396 -278.826237) (xy 357.02798 -278.872918) (xy 357.035875 -278.921495)
			(xy 357.03637 -278.946102) (xy 357.365312 -278.946102) (xy 357.369272 -278.897048) (xy 357.381049 -278.849264)
			(xy 357.40034 -278.803988) (xy 357.426643 -278.762392) (xy 357.459278 -278.725555) (xy 357.497399 -278.69443)
			(xy 357.54002 -278.669823) (xy 357.586036 -278.652371) (xy 357.634255 -278.642527) (xy 357.68343 -278.640546)
			(xy 357.732285 -278.646478) (xy 357.779556 -278.66017) (xy 357.824018 -278.681268) (xy 357.864521 -278.709224)
			(xy 357.900014 -278.743316) (xy 357.929579 -278.78266) (xy 357.95245 -278.826237) (xy 357.968034 -278.872918)
			(xy 357.975929 -278.921495) (xy 357.976424 -278.946102) (xy 358.305366 -278.946102) (xy 358.309326 -278.897048)
			(xy 358.321103 -278.849264) (xy 358.340394 -278.803988) (xy 358.366697 -278.762392) (xy 358.399332 -278.725555)
			(xy 358.437453 -278.69443) (xy 358.480074 -278.669823) (xy 358.52609 -278.652371) (xy 358.574309 -278.642527)
			(xy 358.623484 -278.640546) (xy 358.672339 -278.646478) (xy 358.71961 -278.66017) (xy 358.764072 -278.681268)
			(xy 358.804575 -278.709224) (xy 358.840068 -278.743316) (xy 358.869633 -278.78266) (xy 358.892504 -278.826237)
			(xy 358.908088 -278.872918) (xy 358.915983 -278.921495) (xy 358.916478 -278.946102) (xy 361.118924 -278.946102)
			(xy 361.122884 -278.897048) (xy 361.134661 -278.849264) (xy 361.153952 -278.803988) (xy 361.180255 -278.762392)
			(xy 361.21289 -278.725555) (xy 361.251011 -278.69443) (xy 361.293632 -278.669823) (xy 361.339648 -278.652371)
			(xy 361.387867 -278.642527) (xy 361.437042 -278.640546) (xy 361.485897 -278.646478) (xy 361.533168 -278.66017)
			(xy 361.57763 -278.681268) (xy 361.618133 -278.709224) (xy 361.653626 -278.743316) (xy 361.683191 -278.78266)
			(xy 361.706062 -278.826237) (xy 361.721646 -278.872918) (xy 361.729541 -278.921495) (xy 361.730036 -278.946102)
			(xy 362.058978 -278.946102) (xy 362.062938 -278.897048) (xy 362.074715 -278.849264) (xy 362.094006 -278.803988)
			(xy 362.120309 -278.762392) (xy 362.152944 -278.725555) (xy 362.191065 -278.69443) (xy 362.233686 -278.669823)
			(xy 362.279702 -278.652371) (xy 362.327921 -278.642527) (xy 362.377096 -278.640546) (xy 362.425951 -278.646478)
			(xy 362.473222 -278.66017) (xy 362.517684 -278.681268) (xy 362.558187 -278.709224) (xy 362.59368 -278.743316)
			(xy 362.623245 -278.78266) (xy 362.646116 -278.826237) (xy 362.6617 -278.872918) (xy 362.669595 -278.921495)
			(xy 362.67009 -278.946102) (xy 362.999032 -278.946102) (xy 363.002992 -278.897048) (xy 363.014769 -278.849264)
			(xy 363.03406 -278.803988) (xy 363.060363 -278.762392) (xy 363.092998 -278.725555) (xy 363.131119 -278.69443)
			(xy 363.17374 -278.669823) (xy 363.219756 -278.652371) (xy 363.267975 -278.642527) (xy 363.31715 -278.640546)
			(xy 363.366005 -278.646478) (xy 363.413276 -278.66017) (xy 363.457738 -278.681268) (xy 363.498241 -278.709224)
			(xy 363.533734 -278.743316) (xy 363.563299 -278.78266) (xy 363.58617 -278.826237) (xy 363.601754 -278.872918)
			(xy 363.609649 -278.921495) (xy 363.610144 -278.946102) (xy 363.939086 -278.946102) (xy 363.943046 -278.897048)
			(xy 363.954823 -278.849264) (xy 363.974114 -278.803988) (xy 364.000417 -278.762392) (xy 364.033052 -278.725555)
			(xy 364.071173 -278.69443) (xy 364.113794 -278.669823) (xy 364.15981 -278.652371) (xy 364.208029 -278.642527)
			(xy 364.257204 -278.640546) (xy 364.306059 -278.646478) (xy 364.35333 -278.66017) (xy 364.397792 -278.681268)
			(xy 364.438295 -278.709224) (xy 364.473788 -278.743316) (xy 364.503353 -278.78266) (xy 364.526224 -278.826237)
			(xy 364.541808 -278.872918) (xy 364.549703 -278.921495) (xy 364.550198 -278.946102) (xy 366.758994 -278.946102)
			(xy 366.762954 -278.897048) (xy 366.774731 -278.849264) (xy 366.794022 -278.803988) (xy 366.820325 -278.762392)
			(xy 366.85296 -278.725555) (xy 366.891081 -278.69443) (xy 366.933702 -278.669823) (xy 366.979718 -278.652371)
			(xy 367.027937 -278.642527) (xy 367.077112 -278.640546) (xy 367.125967 -278.646478) (xy 367.173238 -278.66017)
			(xy 367.2177 -278.681268) (xy 367.258203 -278.709224) (xy 367.293696 -278.743316) (xy 367.323261 -278.78266)
			(xy 367.346132 -278.826237) (xy 367.361716 -278.872918) (xy 367.369611 -278.921495) (xy 367.370106 -278.946102)
			(xy 369.578902 -278.946102) (xy 369.582862 -278.897048) (xy 369.594639 -278.849264) (xy 369.61393 -278.803988)
			(xy 369.640233 -278.762392) (xy 369.672868 -278.725555) (xy 369.710989 -278.69443) (xy 369.75361 -278.669823)
			(xy 369.799626 -278.652371) (xy 369.847845 -278.642527) (xy 369.89702 -278.640546) (xy 369.945875 -278.646478)
			(xy 369.993146 -278.66017) (xy 370.037608 -278.681268) (xy 370.078111 -278.709224) (xy 370.113604 -278.743316)
			(xy 370.143169 -278.78266) (xy 370.16604 -278.826237) (xy 370.181624 -278.872918) (xy 370.189519 -278.921495)
			(xy 370.190014 -278.946102) (xy 372.399064 -278.946102) (xy 372.403024 -278.897048) (xy 372.414801 -278.849264)
			(xy 372.434092 -278.803988) (xy 372.460395 -278.762392) (xy 372.49303 -278.725555) (xy 372.531151 -278.69443)
			(xy 372.573772 -278.669823) (xy 372.619788 -278.652371) (xy 372.668007 -278.642527) (xy 372.717182 -278.640546)
			(xy 372.766037 -278.646478) (xy 372.813308 -278.66017) (xy 372.85777 -278.681268) (xy 372.898273 -278.709224)
			(xy 372.933766 -278.743316) (xy 372.963331 -278.78266) (xy 372.986202 -278.826237) (xy 373.001786 -278.872918)
			(xy 373.009681 -278.921495) (xy 373.010176 -278.946102) (xy 375.218972 -278.946102) (xy 375.222932 -278.897048)
			(xy 375.234709 -278.849264) (xy 375.254 -278.803988) (xy 375.280303 -278.762392) (xy 375.312938 -278.725555)
			(xy 375.351059 -278.69443) (xy 375.39368 -278.669823) (xy 375.439696 -278.652371) (xy 375.487915 -278.642527)
			(xy 375.53709 -278.640546) (xy 375.585945 -278.646478) (xy 375.633216 -278.66017) (xy 375.677678 -278.681268)
			(xy 375.718181 -278.709224) (xy 375.753674 -278.743316) (xy 375.783239 -278.78266) (xy 375.80611 -278.826237)
			(xy 375.821694 -278.872918) (xy 375.829589 -278.921495) (xy 375.830084 -278.946102) (xy 376.148595 -278.946102)
			(xy 376.15269 -278.895374) (xy 376.164869 -278.84596) (xy 376.184817 -278.79914) (xy 376.212018 -278.756126)
			(xy 376.245766 -278.718032) (xy 376.285188 -278.685845) (xy 376.329262 -278.660399) (xy 376.376848 -278.642352)
			(xy 376.426712 -278.632172) (xy 376.477564 -278.630123) (xy 376.528085 -278.636257) (xy 376.576969 -278.650417)
			(xy 376.622948 -278.672234) (xy 376.664832 -278.701144) (xy 376.701536 -278.736399) (xy 376.732109 -278.777085)
			(xy 376.75576 -278.822148) (xy 376.771876 -278.870422) (xy 376.78004 -278.920656) (xy 376.780552 -278.946102)
			(xy 377.088649 -278.946102) (xy 377.092744 -278.895374) (xy 377.104923 -278.84596) (xy 377.124871 -278.79914)
			(xy 377.152072 -278.756126) (xy 377.18582 -278.718032) (xy 377.225242 -278.685845) (xy 377.269316 -278.660399)
			(xy 377.316902 -278.642352) (xy 377.366766 -278.632172) (xy 377.417618 -278.630123) (xy 377.468139 -278.636257)
			(xy 377.517023 -278.650417) (xy 377.563002 -278.672234) (xy 377.604886 -278.701144) (xy 377.64159 -278.736399)
			(xy 377.672163 -278.777085) (xy 377.695814 -278.822148) (xy 377.71193 -278.870422) (xy 377.720094 -278.920656)
			(xy 377.720606 -278.946102) (xy 377.720094 -278.971548) (xy 377.71193 -279.021782) (xy 377.695814 -279.070056)
			(xy 377.672163 -279.115119) (xy 377.64159 -279.155805) (xy 377.604886 -279.19106) (xy 377.563002 -279.21997)
			(xy 377.517023 -279.241787) (xy 377.468139 -279.255947) (xy 377.417618 -279.262081) (xy 377.366766 -279.260032)
			(xy 377.316902 -279.249852) (xy 377.269316 -279.231805) (xy 377.225242 -279.206359) (xy 377.18582 -279.174172)
			(xy 377.152072 -279.136078) (xy 377.124871 -279.093064) (xy 377.104923 -279.046244) (xy 377.092744 -278.99683)
			(xy 377.088649 -278.946102) (xy 376.780552 -278.946102) (xy 376.78004 -278.971548) (xy 376.771876 -279.021782)
			(xy 376.75576 -279.070056) (xy 376.732109 -279.115119) (xy 376.701536 -279.155805) (xy 376.664832 -279.19106)
			(xy 376.622948 -279.21997) (xy 376.576969 -279.241787) (xy 376.528085 -279.255947) (xy 376.477564 -279.262081)
			(xy 376.426712 -279.260032) (xy 376.376848 -279.249852) (xy 376.329262 -279.231805) (xy 376.285188 -279.206359)
			(xy 376.245766 -279.174172) (xy 376.212018 -279.136078) (xy 376.184817 -279.093064) (xy 376.164869 -279.046244)
			(xy 376.15269 -278.99683) (xy 376.148595 -278.946102) (xy 375.830084 -278.946102) (xy 375.829589 -278.970709)
			(xy 375.821694 -279.019286) (xy 375.80611 -279.065967) (xy 375.783239 -279.109544) (xy 375.753674 -279.148888)
			(xy 375.718181 -279.18298) (xy 375.677678 -279.210936) (xy 375.633216 -279.232034) (xy 375.585945 -279.245726)
			(xy 375.53709 -279.251658) (xy 375.487915 -279.249677) (xy 375.439696 -279.239833) (xy 375.39368 -279.222381)
			(xy 375.351059 -279.197774) (xy 375.312938 -279.166649) (xy 375.280303 -279.129812) (xy 375.254 -279.088216)
			(xy 375.234709 -279.04294) (xy 375.222932 -278.995156) (xy 375.218972 -278.946102) (xy 373.010176 -278.946102)
			(xy 373.009681 -278.970709) (xy 373.001786 -279.019286) (xy 372.986202 -279.065967) (xy 372.963331 -279.109544)
			(xy 372.933766 -279.148888) (xy 372.898273 -279.18298) (xy 372.85777 -279.210936) (xy 372.813308 -279.232034)
			(xy 372.766037 -279.245726) (xy 372.717182 -279.251658) (xy 372.668007 -279.249677) (xy 372.619788 -279.239833)
			(xy 372.573772 -279.222381) (xy 372.531151 -279.197774) (xy 372.49303 -279.166649) (xy 372.460395 -279.129812)
			(xy 372.434092 -279.088216) (xy 372.414801 -279.04294) (xy 372.403024 -278.995156) (xy 372.399064 -278.946102)
			(xy 370.190014 -278.946102) (xy 370.189519 -278.970709) (xy 370.181624 -279.019286) (xy 370.16604 -279.065967)
			(xy 370.143169 -279.109544) (xy 370.113604 -279.148888) (xy 370.078111 -279.18298) (xy 370.037608 -279.210936)
			(xy 369.993146 -279.232034) (xy 369.945875 -279.245726) (xy 369.89702 -279.251658) (xy 369.847845 -279.249677)
			(xy 369.799626 -279.239833) (xy 369.75361 -279.222381) (xy 369.710989 -279.197774) (xy 369.672868 -279.166649)
			(xy 369.640233 -279.129812) (xy 369.61393 -279.088216) (xy 369.594639 -279.04294) (xy 369.582862 -278.995156)
			(xy 369.578902 -278.946102) (xy 367.370106 -278.946102) (xy 367.369611 -278.970709) (xy 367.361716 -279.019286)
			(xy 367.346132 -279.065967) (xy 367.323261 -279.109544) (xy 367.293696 -279.148888) (xy 367.258203 -279.18298)
			(xy 367.2177 -279.210936) (xy 367.173238 -279.232034) (xy 367.125967 -279.245726) (xy 367.077112 -279.251658)
			(xy 367.027937 -279.249677) (xy 366.979718 -279.239833) (xy 366.933702 -279.222381) (xy 366.891081 -279.197774)
			(xy 366.85296 -279.166649) (xy 366.820325 -279.129812) (xy 366.794022 -279.088216) (xy 366.774731 -279.04294)
			(xy 366.762954 -278.995156) (xy 366.758994 -278.946102) (xy 364.550198 -278.946102) (xy 364.549703 -278.970709)
			(xy 364.541808 -279.019286) (xy 364.526224 -279.065967) (xy 364.503353 -279.109544) (xy 364.473788 -279.148888)
			(xy 364.438295 -279.18298) (xy 364.397792 -279.210936) (xy 364.35333 -279.232034) (xy 364.306059 -279.245726)
			(xy 364.257204 -279.251658) (xy 364.208029 -279.249677) (xy 364.15981 -279.239833) (xy 364.113794 -279.222381)
			(xy 364.071173 -279.197774) (xy 364.033052 -279.166649) (xy 364.000417 -279.129812) (xy 363.974114 -279.088216)
			(xy 363.954823 -279.04294) (xy 363.943046 -278.995156) (xy 363.939086 -278.946102) (xy 363.610144 -278.946102)
			(xy 363.609649 -278.970709) (xy 363.601754 -279.019286) (xy 363.58617 -279.065967) (xy 363.563299 -279.109544)
			(xy 363.533734 -279.148888) (xy 363.498241 -279.18298) (xy 363.457738 -279.210936) (xy 363.413276 -279.232034)
			(xy 363.366005 -279.245726) (xy 363.31715 -279.251658) (xy 363.267975 -279.249677) (xy 363.219756 -279.239833)
			(xy 363.17374 -279.222381) (xy 363.131119 -279.197774) (xy 363.092998 -279.166649) (xy 363.060363 -279.129812)
			(xy 363.03406 -279.088216) (xy 363.014769 -279.04294) (xy 363.002992 -278.995156) (xy 362.999032 -278.946102)
			(xy 362.67009 -278.946102) (xy 362.669595 -278.970709) (xy 362.6617 -279.019286) (xy 362.646116 -279.065967)
			(xy 362.623245 -279.109544) (xy 362.59368 -279.148888) (xy 362.558187 -279.18298) (xy 362.517684 -279.210936)
			(xy 362.473222 -279.232034) (xy 362.425951 -279.245726) (xy 362.377096 -279.251658) (xy 362.327921 -279.249677)
			(xy 362.279702 -279.239833) (xy 362.233686 -279.222381) (xy 362.191065 -279.197774) (xy 362.152944 -279.166649)
			(xy 362.120309 -279.129812) (xy 362.094006 -279.088216) (xy 362.074715 -279.04294) (xy 362.062938 -278.995156)
			(xy 362.058978 -278.946102) (xy 361.730036 -278.946102) (xy 361.729541 -278.970709) (xy 361.721646 -279.019286)
			(xy 361.706062 -279.065967) (xy 361.683191 -279.109544) (xy 361.653626 -279.148888) (xy 361.618133 -279.18298)
			(xy 361.57763 -279.210936) (xy 361.533168 -279.232034) (xy 361.485897 -279.245726) (xy 361.437042 -279.251658)
			(xy 361.387867 -279.249677) (xy 361.339648 -279.239833) (xy 361.293632 -279.222381) (xy 361.251011 -279.197774)
			(xy 361.21289 -279.166649) (xy 361.180255 -279.129812) (xy 361.153952 -279.088216) (xy 361.134661 -279.04294)
			(xy 361.122884 -278.995156) (xy 361.118924 -278.946102) (xy 358.916478 -278.946102) (xy 358.915983 -278.970709)
			(xy 358.908088 -279.019286) (xy 358.892504 -279.065967) (xy 358.869633 -279.109544) (xy 358.840068 -279.148888)
			(xy 358.804575 -279.18298) (xy 358.764072 -279.210936) (xy 358.71961 -279.232034) (xy 358.672339 -279.245726)
			(xy 358.623484 -279.251658) (xy 358.574309 -279.249677) (xy 358.52609 -279.239833) (xy 358.480074 -279.222381)
			(xy 358.437453 -279.197774) (xy 358.399332 -279.166649) (xy 358.366697 -279.129812) (xy 358.340394 -279.088216)
			(xy 358.321103 -279.04294) (xy 358.309326 -278.995156) (xy 358.305366 -278.946102) (xy 357.976424 -278.946102)
			(xy 357.975929 -278.970709) (xy 357.968034 -279.019286) (xy 357.95245 -279.065967) (xy 357.929579 -279.109544)
			(xy 357.900014 -279.148888) (xy 357.864521 -279.18298) (xy 357.824018 -279.210936) (xy 357.779556 -279.232034)
			(xy 357.732285 -279.245726) (xy 357.68343 -279.251658) (xy 357.634255 -279.249677) (xy 357.586036 -279.239833)
			(xy 357.54002 -279.222381) (xy 357.497399 -279.197774) (xy 357.459278 -279.166649) (xy 357.426643 -279.129812)
			(xy 357.40034 -279.088216) (xy 357.381049 -279.04294) (xy 357.369272 -278.995156) (xy 357.365312 -278.946102)
			(xy 357.03637 -278.946102) (xy 357.035875 -278.970709) (xy 357.02798 -279.019286) (xy 357.012396 -279.065967)
			(xy 356.989525 -279.109544) (xy 356.95996 -279.148888) (xy 356.924467 -279.18298) (xy 356.883964 -279.210936)
			(xy 356.839502 -279.232034) (xy 356.792231 -279.245726) (xy 356.743376 -279.251658) (xy 356.694201 -279.249677)
			(xy 356.645982 -279.239833) (xy 356.599966 -279.222381) (xy 356.557345 -279.197774) (xy 356.519224 -279.166649)
			(xy 356.486589 -279.129812) (xy 356.460286 -279.088216) (xy 356.440995 -279.04294) (xy 356.429218 -278.995156)
			(xy 356.425258 -278.946102) (xy 356.096316 -278.946102) (xy 356.095821 -278.970709) (xy 356.087926 -279.019286)
			(xy 356.072342 -279.065967) (xy 356.049471 -279.109544) (xy 356.019906 -279.148888) (xy 355.984413 -279.18298)
			(xy 355.94391 -279.210936) (xy 355.899448 -279.232034) (xy 355.852177 -279.245726) (xy 355.803322 -279.251658)
			(xy 355.754147 -279.249677) (xy 355.705928 -279.239833) (xy 355.659912 -279.222381) (xy 355.617291 -279.197774)
			(xy 355.57917 -279.166649) (xy 355.546535 -279.129812) (xy 355.520232 -279.088216) (xy 355.500941 -279.04294)
			(xy 355.489164 -278.995156) (xy 355.485204 -278.946102) (xy 353.276408 -278.946102) (xy 353.275913 -278.970709)
			(xy 353.268018 -279.019286) (xy 353.252434 -279.065967) (xy 353.229563 -279.109544) (xy 353.199998 -279.148888)
			(xy 353.164505 -279.18298) (xy 353.124002 -279.210936) (xy 353.07954 -279.232034) (xy 353.032269 -279.245726)
			(xy 352.983414 -279.251658) (xy 352.934239 -279.249677) (xy 352.88602 -279.239833) (xy 352.840004 -279.222381)
			(xy 352.797383 -279.197774) (xy 352.759262 -279.166649) (xy 352.726627 -279.129812) (xy 352.700324 -279.088216)
			(xy 352.681033 -279.04294) (xy 352.669256 -278.995156) (xy 352.665296 -278.946102) (xy 350.4565 -278.946102)
			(xy 350.456005 -278.970709) (xy 350.44811 -279.019286) (xy 350.432526 -279.065967) (xy 350.409655 -279.109544)
			(xy 350.38009 -279.148888) (xy 350.344597 -279.18298) (xy 350.304094 -279.210936) (xy 350.259632 -279.232034)
			(xy 350.212361 -279.245726) (xy 350.163506 -279.251658) (xy 350.114331 -279.249677) (xy 350.066112 -279.239833)
			(xy 350.020096 -279.222381) (xy 349.977475 -279.197774) (xy 349.939354 -279.166649) (xy 349.906719 -279.129812)
			(xy 349.880416 -279.088216) (xy 349.861125 -279.04294) (xy 349.849348 -278.995156) (xy 349.845388 -278.946102)
			(xy 347.636338 -278.946102) (xy 347.635843 -278.970709) (xy 347.627948 -279.019286) (xy 347.612364 -279.065967)
			(xy 347.589493 -279.109544) (xy 347.559928 -279.148888) (xy 347.524435 -279.18298) (xy 347.483932 -279.210936)
			(xy 347.43947 -279.232034) (xy 347.392199 -279.245726) (xy 347.343344 -279.251658) (xy 347.294169 -279.249677)
			(xy 347.24595 -279.239833) (xy 347.199934 -279.222381) (xy 347.157313 -279.197774) (xy 347.119192 -279.166649)
			(xy 347.086557 -279.129812) (xy 347.060254 -279.088216) (xy 347.040963 -279.04294) (xy 347.029186 -278.995156)
			(xy 347.025226 -278.946102) (xy 344.81643 -278.946102) (xy 344.815935 -278.970709) (xy 344.80804 -279.019286)
			(xy 344.792456 -279.065967) (xy 344.769585 -279.109544) (xy 344.74002 -279.148888) (xy 344.704527 -279.18298)
			(xy 344.664024 -279.210936) (xy 344.619562 -279.232034) (xy 344.572291 -279.245726) (xy 344.523436 -279.251658)
			(xy 344.474261 -279.249677) (xy 344.426042 -279.239833) (xy 344.380026 -279.222381) (xy 344.337405 -279.197774)
			(xy 344.299284 -279.166649) (xy 344.266649 -279.129812) (xy 344.240346 -279.088216) (xy 344.221055 -279.04294)
			(xy 344.209278 -278.995156) (xy 344.205318 -278.946102) (xy 343.88679 -278.946102) (xy 343.886278 -278.971548)
			(xy 343.878114 -279.021782) (xy 343.861998 -279.070056) (xy 343.838347 -279.115119) (xy 343.807774 -279.155805)
			(xy 343.77107 -279.19106) (xy 343.729186 -279.21997) (xy 343.683207 -279.241787) (xy 343.634323 -279.255947)
			(xy 343.583802 -279.262081) (xy 343.53295 -279.260032) (xy 343.483086 -279.249852) (xy 343.4355 -279.231805)
			(xy 343.391426 -279.206359) (xy 343.352004 -279.174172) (xy 343.318256 -279.136078) (xy 343.291055 -279.093064)
			(xy 343.271107 -279.046244) (xy 343.258928 -278.99683) (xy 343.254833 -278.946102) (xy 342.946736 -278.946102)
			(xy 342.946224 -278.971548) (xy 342.93806 -279.021782) (xy 342.921944 -279.070056) (xy 342.898293 -279.115119)
			(xy 342.86772 -279.155805) (xy 342.831016 -279.19106) (xy 342.789132 -279.21997) (xy 342.743153 -279.241787)
			(xy 342.694269 -279.255947) (xy 342.643748 -279.262081) (xy 342.592896 -279.260032) (xy 342.543032 -279.249852)
			(xy 342.495446 -279.231805) (xy 342.451372 -279.206359) (xy 342.41195 -279.174172) (xy 342.378202 -279.136078)
			(xy 342.351001 -279.093064) (xy 342.331053 -279.046244) (xy 342.318874 -278.99683) (xy 342.314779 -278.946102)
			(xy 341.997029 -278.946102) (xy 341.992858 -278.996436) (xy 341.980459 -279.0454) (xy 341.960171 -279.091655)
			(xy 341.932546 -279.133939) (xy 341.898338 -279.171101) (xy 341.85848 -279.202125) (xy 341.81406 -279.226166)
			(xy 341.766288 -279.242568) (xy 341.716468 -279.250883) (xy 341.691214 -279.25141) (xy 341.678451 -279.251274)
			(xy 341.653016 -279.249115) (xy 341.640414 -279.247092) (xy 341.640414 -279.247346) (xy 341.61696 -279.242919)
			(xy 341.571705 -279.227758) (xy 341.529353 -279.205755) (xy 341.49093 -279.177444) (xy 341.457368 -279.143511)
			(xy 341.443056 -279.12441) (xy 341.438992 -279.118568) (xy 341.428324 -279.109932) (xy 341.422482 -279.107392)
			(xy 341.416199 -279.104867) (xy 341.402805 -279.102926) (xy 341.396066 -279.103582) (xy 341.305642 -279.115012)
			(xy 341.293196 -279.116536) (xy 341.28202 -279.125172) (xy 341.276889 -279.129515) (xy 341.268906 -279.140324)
			(xy 341.266272 -279.146508) (xy 341.266272 -279.146762) (xy 341.258702 -279.16566) (xy 341.241158 -279.202401)
			(xy 341.23122 -279.220168) (xy 341.227918 -279.22601) (xy 341.226394 -279.232106) (xy 341.224616 -279.24506)
			(xy 341.224616 -279.404318) (xy 341.224979 -279.413333) (xy 341.231232 -279.430244) (xy 341.236808 -279.437338)
			(xy 341.24265 -279.444196) (xy 341.258652 -279.453086) (xy 341.267542 -279.454356) (xy 341.291259 -279.458464)
			(xy 341.337094 -279.47316) (xy 341.380054 -279.494866) (xy 341.419076 -279.523044) (xy 341.453194 -279.556996)
			(xy 341.481561 -279.595881) (xy 341.503475 -279.638736) (xy 341.518393 -279.684499) (xy 341.525945 -279.732035)
			(xy 341.525945 -279.756108) (xy 341.844879 -279.756108) (xy 341.848974 -279.70538) (xy 341.861153 -279.655966)
			(xy 341.881101 -279.609146) (xy 341.908302 -279.566132) (xy 341.94205 -279.528038) (xy 341.981472 -279.495851)
			(xy 342.025546 -279.470405) (xy 342.073132 -279.452358) (xy 342.122996 -279.442178) (xy 342.173848 -279.440129)
			(xy 342.224369 -279.446263) (xy 342.273253 -279.460423) (xy 342.319232 -279.48224) (xy 342.361116 -279.51115)
			(xy 342.39782 -279.546405) (xy 342.428393 -279.587091) (xy 342.452044 -279.632154) (xy 342.46816 -279.680428)
			(xy 342.476324 -279.730662) (xy 342.476836 -279.756108) (xy 342.795364 -279.756108) (xy 342.799324 -279.707054)
			(xy 342.811101 -279.65927) (xy 342.830392 -279.613994) (xy 342.856695 -279.572398) (xy 342.88933 -279.535561)
			(xy 342.927451 -279.504436) (xy 342.970072 -279.479829) (xy 343.016088 -279.462377) (xy 343.064307 -279.452533)
			(xy 343.113482 -279.450552) (xy 343.162337 -279.456484) (xy 343.209608 -279.470176) (xy 343.25407 -279.491274)
			(xy 343.294573 -279.51923) (xy 343.330066 -279.553322) (xy 343.359631 -279.592666) (xy 343.382502 -279.636243)
			(xy 343.398086 -279.682924) (xy 343.405981 -279.731501) (xy 343.406476 -279.756108) (xy 343.724987 -279.756108)
			(xy 343.729082 -279.70538) (xy 343.741261 -279.655966) (xy 343.761209 -279.609146) (xy 343.78841 -279.566132)
			(xy 343.822158 -279.528038) (xy 343.86158 -279.495851) (xy 343.905654 -279.470405) (xy 343.95324 -279.452358)
			(xy 344.003104 -279.442178) (xy 344.053956 -279.440129) (xy 344.104477 -279.446263) (xy 344.153361 -279.460423)
			(xy 344.19934 -279.48224) (xy 344.241224 -279.51115) (xy 344.277928 -279.546405) (xy 344.308501 -279.587091)
			(xy 344.332152 -279.632154) (xy 344.348268 -279.680428) (xy 344.356432 -279.730662) (xy 344.356944 -279.756108)
			(xy 344.675218 -279.756108) (xy 344.679178 -279.707054) (xy 344.690955 -279.65927) (xy 344.710246 -279.613994)
			(xy 344.736549 -279.572398) (xy 344.769184 -279.535561) (xy 344.807305 -279.504436) (xy 344.849926 -279.479829)
			(xy 344.895942 -279.462377) (xy 344.944161 -279.452533) (xy 344.993336 -279.450552) (xy 345.042191 -279.456484)
			(xy 345.089462 -279.470176) (xy 345.133924 -279.491274) (xy 345.174427 -279.51923) (xy 345.20992 -279.553322)
			(xy 345.239485 -279.592666) (xy 345.262356 -279.636243) (xy 345.27794 -279.682924) (xy 345.285835 -279.731501)
			(xy 345.28633 -279.756108) (xy 345.615272 -279.756108) (xy 345.619232 -279.707054) (xy 345.631009 -279.65927)
			(xy 345.6503 -279.613994) (xy 345.676603 -279.572398) (xy 345.709238 -279.535561) (xy 345.747359 -279.504436)
			(xy 345.78998 -279.479829) (xy 345.835996 -279.462377) (xy 345.884215 -279.452533) (xy 345.93339 -279.450552)
			(xy 345.982245 -279.456484) (xy 346.029516 -279.470176) (xy 346.073978 -279.491274) (xy 346.114481 -279.51923)
			(xy 346.149974 -279.553322) (xy 346.179539 -279.592666) (xy 346.20241 -279.636243) (xy 346.217994 -279.682924)
			(xy 346.225889 -279.731501) (xy 346.226384 -279.756108) (xy 346.555326 -279.756108) (xy 346.559286 -279.707054)
			(xy 346.571063 -279.65927) (xy 346.590354 -279.613994) (xy 346.616657 -279.572398) (xy 346.649292 -279.535561)
			(xy 346.687413 -279.504436) (xy 346.730034 -279.479829) (xy 346.77605 -279.462377) (xy 346.824269 -279.452533)
			(xy 346.873444 -279.450552) (xy 346.922299 -279.456484) (xy 346.96957 -279.470176) (xy 347.014032 -279.491274)
			(xy 347.054535 -279.51923) (xy 347.090028 -279.553322) (xy 347.119593 -279.592666) (xy 347.142464 -279.636243)
			(xy 347.158048 -279.682924) (xy 347.165943 -279.731501) (xy 347.166438 -279.756108) (xy 347.49538 -279.756108)
			(xy 347.49934 -279.707054) (xy 347.511117 -279.65927) (xy 347.530408 -279.613994) (xy 347.556711 -279.572398)
			(xy 347.589346 -279.535561) (xy 347.627467 -279.504436) (xy 347.670088 -279.479829) (xy 347.716104 -279.462377)
			(xy 347.764323 -279.452533) (xy 347.813498 -279.450552) (xy 347.862353 -279.456484) (xy 347.909624 -279.470176)
			(xy 347.954086 -279.491274) (xy 347.994589 -279.51923) (xy 348.030082 -279.553322) (xy 348.059647 -279.592666)
			(xy 348.082518 -279.636243) (xy 348.098102 -279.682924) (xy 348.105997 -279.731501) (xy 348.106492 -279.756108)
			(xy 348.435434 -279.756108) (xy 348.439394 -279.707054) (xy 348.451171 -279.65927) (xy 348.470462 -279.613994)
			(xy 348.496765 -279.572398) (xy 348.5294 -279.535561) (xy 348.567521 -279.504436) (xy 348.610142 -279.479829)
			(xy 348.656158 -279.462377) (xy 348.704377 -279.452533) (xy 348.753552 -279.450552) (xy 348.802407 -279.456484)
			(xy 348.849678 -279.470176) (xy 348.89414 -279.491274) (xy 348.934643 -279.51923) (xy 348.970136 -279.553322)
			(xy 348.999701 -279.592666) (xy 349.022572 -279.636243) (xy 349.038156 -279.682924) (xy 349.046051 -279.731501)
			(xy 349.046546 -279.756108) (xy 349.375234 -279.756108) (xy 349.379194 -279.707054) (xy 349.390971 -279.65927)
			(xy 349.410262 -279.613994) (xy 349.436565 -279.572398) (xy 349.4692 -279.535561) (xy 349.507321 -279.504436)
			(xy 349.549942 -279.479829) (xy 349.595958 -279.462377) (xy 349.644177 -279.452533) (xy 349.693352 -279.450552)
			(xy 349.742207 -279.456484) (xy 349.789478 -279.470176) (xy 349.83394 -279.491274) (xy 349.874443 -279.51923)
			(xy 349.909936 -279.553322) (xy 349.939501 -279.592666) (xy 349.962372 -279.636243) (xy 349.977956 -279.682924)
			(xy 349.985851 -279.731501) (xy 349.986346 -279.756108) (xy 350.315288 -279.756108) (xy 350.319248 -279.707054)
			(xy 350.331025 -279.65927) (xy 350.350316 -279.613994) (xy 350.376619 -279.572398) (xy 350.409254 -279.535561)
			(xy 350.447375 -279.504436) (xy 350.489996 -279.479829) (xy 350.536012 -279.462377) (xy 350.584231 -279.452533)
			(xy 350.633406 -279.450552) (xy 350.682261 -279.456484) (xy 350.729532 -279.470176) (xy 350.773994 -279.491274)
			(xy 350.814497 -279.51923) (xy 350.84999 -279.553322) (xy 350.879555 -279.592666) (xy 350.902426 -279.636243)
			(xy 350.91801 -279.682924) (xy 350.925905 -279.731501) (xy 350.9264 -279.756108) (xy 351.255342 -279.756108)
			(xy 351.259302 -279.707054) (xy 351.271079 -279.65927) (xy 351.29037 -279.613994) (xy 351.316673 -279.572398)
			(xy 351.349308 -279.535561) (xy 351.387429 -279.504436) (xy 351.43005 -279.479829) (xy 351.476066 -279.462377)
			(xy 351.524285 -279.452533) (xy 351.57346 -279.450552) (xy 351.622315 -279.456484) (xy 351.669586 -279.470176)
			(xy 351.714048 -279.491274) (xy 351.754551 -279.51923) (xy 351.790044 -279.553322) (xy 351.819609 -279.592666)
			(xy 351.84248 -279.636243) (xy 351.858064 -279.682924) (xy 351.865959 -279.731501) (xy 351.866454 -279.756108)
			(xy 352.195396 -279.756108) (xy 352.199356 -279.707054) (xy 352.211133 -279.65927) (xy 352.230424 -279.613994)
			(xy 352.256727 -279.572398) (xy 352.289362 -279.535561) (xy 352.327483 -279.504436) (xy 352.370104 -279.479829)
			(xy 352.41612 -279.462377) (xy 352.464339 -279.452533) (xy 352.513514 -279.450552) (xy 352.562369 -279.456484)
			(xy 352.60964 -279.470176) (xy 352.654102 -279.491274) (xy 352.694605 -279.51923) (xy 352.730098 -279.553322)
			(xy 352.759663 -279.592666) (xy 352.782534 -279.636243) (xy 352.798118 -279.682924) (xy 352.806013 -279.731501)
			(xy 352.806508 -279.756108) (xy 353.135196 -279.756108) (xy 353.139156 -279.707054) (xy 353.150933 -279.65927)
			(xy 353.170224 -279.613994) (xy 353.196527 -279.572398) (xy 353.229162 -279.535561) (xy 353.267283 -279.504436)
			(xy 353.309904 -279.479829) (xy 353.35592 -279.462377) (xy 353.404139 -279.452533) (xy 353.453314 -279.450552)
			(xy 353.502169 -279.456484) (xy 353.54944 -279.470176) (xy 353.593902 -279.491274) (xy 353.634405 -279.51923)
			(xy 353.669898 -279.553322) (xy 353.699463 -279.592666) (xy 353.722334 -279.636243) (xy 353.737918 -279.682924)
			(xy 353.745813 -279.731501) (xy 353.746308 -279.756108) (xy 354.07525 -279.756108) (xy 354.07921 -279.707054)
			(xy 354.090987 -279.65927) (xy 354.110278 -279.613994) (xy 354.136581 -279.572398) (xy 354.169216 -279.535561)
			(xy 354.207337 -279.504436) (xy 354.249958 -279.479829) (xy 354.295974 -279.462377) (xy 354.344193 -279.452533)
			(xy 354.393368 -279.450552) (xy 354.442223 -279.456484) (xy 354.489494 -279.470176) (xy 354.533956 -279.491274)
			(xy 354.574459 -279.51923) (xy 354.609952 -279.553322) (xy 354.639517 -279.592666) (xy 354.662388 -279.636243)
			(xy 354.677972 -279.682924) (xy 354.685867 -279.731501) (xy 354.686362 -279.756108) (xy 355.015304 -279.756108)
			(xy 355.019264 -279.707054) (xy 355.031041 -279.65927) (xy 355.050332 -279.613994) (xy 355.076635 -279.572398)
			(xy 355.10927 -279.535561) (xy 355.147391 -279.504436) (xy 355.190012 -279.479829) (xy 355.236028 -279.462377)
			(xy 355.284247 -279.452533) (xy 355.333422 -279.450552) (xy 355.382277 -279.456484) (xy 355.429548 -279.470176)
			(xy 355.47401 -279.491274) (xy 355.514513 -279.51923) (xy 355.550006 -279.553322) (xy 355.579571 -279.592666)
			(xy 355.602442 -279.636243) (xy 355.618026 -279.682924) (xy 355.625921 -279.731501) (xy 355.626416 -279.756108)
			(xy 355.955358 -279.756108) (xy 355.959318 -279.707054) (xy 355.971095 -279.65927) (xy 355.990386 -279.613994)
			(xy 356.016689 -279.572398) (xy 356.049324 -279.535561) (xy 356.087445 -279.504436) (xy 356.130066 -279.479829)
			(xy 356.176082 -279.462377) (xy 356.224301 -279.452533) (xy 356.273476 -279.450552) (xy 356.322331 -279.456484)
			(xy 356.369602 -279.470176) (xy 356.414064 -279.491274) (xy 356.454567 -279.51923) (xy 356.49006 -279.553322)
			(xy 356.519625 -279.592666) (xy 356.542496 -279.636243) (xy 356.55808 -279.682924) (xy 356.565975 -279.731501)
			(xy 356.56647 -279.756108) (xy 356.895412 -279.756108) (xy 356.899372 -279.707054) (xy 356.911149 -279.65927)
			(xy 356.93044 -279.613994) (xy 356.956743 -279.572398) (xy 356.989378 -279.535561) (xy 357.027499 -279.504436)
			(xy 357.07012 -279.479829) (xy 357.116136 -279.462377) (xy 357.164355 -279.452533) (xy 357.21353 -279.450552)
			(xy 357.262385 -279.456484) (xy 357.309656 -279.470176) (xy 357.354118 -279.491274) (xy 357.394621 -279.51923)
			(xy 357.430114 -279.553322) (xy 357.459679 -279.592666) (xy 357.48255 -279.636243) (xy 357.498134 -279.682924)
			(xy 357.506029 -279.731501) (xy 357.506524 -279.756108) (xy 357.835212 -279.756108) (xy 357.839172 -279.707054)
			(xy 357.850949 -279.65927) (xy 357.87024 -279.613994) (xy 357.896543 -279.572398) (xy 357.929178 -279.535561)
			(xy 357.967299 -279.504436) (xy 358.00992 -279.479829) (xy 358.055936 -279.462377) (xy 358.104155 -279.452533)
			(xy 358.15333 -279.450552) (xy 358.202185 -279.456484) (xy 358.249456 -279.470176) (xy 358.293918 -279.491274)
			(xy 358.334421 -279.51923) (xy 358.369914 -279.553322) (xy 358.399479 -279.592666) (xy 358.42235 -279.636243)
			(xy 358.437934 -279.682924) (xy 358.445829 -279.731501) (xy 358.446324 -279.756108) (xy 361.589078 -279.756108)
			(xy 361.593038 -279.707054) (xy 361.604815 -279.65927) (xy 361.624106 -279.613994) (xy 361.650409 -279.572398)
			(xy 361.683044 -279.535561) (xy 361.721165 -279.504436) (xy 361.763786 -279.479829) (xy 361.809802 -279.462377)
			(xy 361.858021 -279.452533) (xy 361.907196 -279.450552) (xy 361.956051 -279.456484) (xy 362.003322 -279.470176)
			(xy 362.047784 -279.491274) (xy 362.088287 -279.51923) (xy 362.12378 -279.553322) (xy 362.153345 -279.592666)
			(xy 362.176216 -279.636243) (xy 362.1918 -279.682924) (xy 362.199695 -279.731501) (xy 362.20019 -279.756108)
			(xy 362.528878 -279.756108) (xy 362.532838 -279.707054) (xy 362.544615 -279.65927) (xy 362.563906 -279.613994)
			(xy 362.590209 -279.572398) (xy 362.622844 -279.535561) (xy 362.660965 -279.504436) (xy 362.703586 -279.479829)
			(xy 362.749602 -279.462377) (xy 362.797821 -279.452533) (xy 362.846996 -279.450552) (xy 362.895851 -279.456484)
			(xy 362.943122 -279.470176) (xy 362.987584 -279.491274) (xy 363.028087 -279.51923) (xy 363.06358 -279.553322)
			(xy 363.093145 -279.592666) (xy 363.116016 -279.636243) (xy 363.1316 -279.682924) (xy 363.139495 -279.731501)
			(xy 363.13999 -279.756108) (xy 363.468932 -279.756108) (xy 363.472892 -279.707054) (xy 363.484669 -279.65927)
			(xy 363.50396 -279.613994) (xy 363.530263 -279.572398) (xy 363.562898 -279.535561) (xy 363.601019 -279.504436)
			(xy 363.64364 -279.479829) (xy 363.689656 -279.462377) (xy 363.737875 -279.452533) (xy 363.78705 -279.450552)
			(xy 363.835905 -279.456484) (xy 363.883176 -279.470176) (xy 363.927638 -279.491274) (xy 363.968141 -279.51923)
			(xy 364.003634 -279.553322) (xy 364.033199 -279.592666) (xy 364.05607 -279.636243) (xy 364.071654 -279.682924)
			(xy 364.079549 -279.731501) (xy 364.080044 -279.756108) (xy 364.408986 -279.756108) (xy 364.412946 -279.707054)
			(xy 364.424723 -279.65927) (xy 364.444014 -279.613994) (xy 364.470317 -279.572398) (xy 364.502952 -279.535561)
			(xy 364.541073 -279.504436) (xy 364.583694 -279.479829) (xy 364.62971 -279.462377) (xy 364.677929 -279.452533)
			(xy 364.727104 -279.450552) (xy 364.775959 -279.456484) (xy 364.82323 -279.470176) (xy 364.867692 -279.491274)
			(xy 364.908195 -279.51923) (xy 364.943688 -279.553322) (xy 364.973253 -279.592666) (xy 364.996124 -279.636243)
			(xy 365.011708 -279.682924) (xy 365.019603 -279.731501) (xy 365.020098 -279.756108) (xy 365.34904 -279.756108)
			(xy 365.353 -279.707054) (xy 365.364777 -279.65927) (xy 365.384068 -279.613994) (xy 365.410371 -279.572398)
			(xy 365.443006 -279.535561) (xy 365.481127 -279.504436) (xy 365.523748 -279.479829) (xy 365.569764 -279.462377)
			(xy 365.617983 -279.452533) (xy 365.667158 -279.450552) (xy 365.716013 -279.456484) (xy 365.763284 -279.470176)
			(xy 365.807746 -279.491274) (xy 365.848249 -279.51923) (xy 365.883742 -279.553322) (xy 365.913307 -279.592666)
			(xy 365.936178 -279.636243) (xy 365.951762 -279.682924) (xy 365.959657 -279.731501) (xy 365.960152 -279.756108)
			(xy 366.289094 -279.756108) (xy 366.293054 -279.707054) (xy 366.304831 -279.65927) (xy 366.324122 -279.613994)
			(xy 366.350425 -279.572398) (xy 366.38306 -279.535561) (xy 366.421181 -279.504436) (xy 366.463802 -279.479829)
			(xy 366.509818 -279.462377) (xy 366.558037 -279.452533) (xy 366.607212 -279.450552) (xy 366.656067 -279.456484)
			(xy 366.703338 -279.470176) (xy 366.7478 -279.491274) (xy 366.788303 -279.51923) (xy 366.823796 -279.553322)
			(xy 366.853361 -279.592666) (xy 366.876232 -279.636243) (xy 366.891816 -279.682924) (xy 366.899711 -279.731501)
			(xy 366.900206 -279.756108) (xy 367.228894 -279.756108) (xy 367.232854 -279.707054) (xy 367.244631 -279.65927)
			(xy 367.263922 -279.613994) (xy 367.290225 -279.572398) (xy 367.32286 -279.535561) (xy 367.360981 -279.504436)
			(xy 367.403602 -279.479829) (xy 367.449618 -279.462377) (xy 367.497837 -279.452533) (xy 367.547012 -279.450552)
			(xy 367.595867 -279.456484) (xy 367.643138 -279.470176) (xy 367.6876 -279.491274) (xy 367.728103 -279.51923)
			(xy 367.763596 -279.553322) (xy 367.793161 -279.592666) (xy 367.816032 -279.636243) (xy 367.831616 -279.682924)
			(xy 367.839511 -279.731501) (xy 367.840006 -279.756108) (xy 368.168948 -279.756108) (xy 368.172908 -279.707054)
			(xy 368.184685 -279.65927) (xy 368.203976 -279.613994) (xy 368.230279 -279.572398) (xy 368.262914 -279.535561)
			(xy 368.301035 -279.504436) (xy 368.343656 -279.479829) (xy 368.389672 -279.462377) (xy 368.437891 -279.452533)
			(xy 368.487066 -279.450552) (xy 368.535921 -279.456484) (xy 368.583192 -279.470176) (xy 368.627654 -279.491274)
			(xy 368.668157 -279.51923) (xy 368.70365 -279.553322) (xy 368.733215 -279.592666) (xy 368.756086 -279.636243)
			(xy 368.77167 -279.682924) (xy 368.779565 -279.731501) (xy 368.78006 -279.756108) (xy 369.109002 -279.756108)
			(xy 369.112962 -279.707054) (xy 369.124739 -279.65927) (xy 369.14403 -279.613994) (xy 369.170333 -279.572398)
			(xy 369.202968 -279.535561) (xy 369.241089 -279.504436) (xy 369.28371 -279.479829) (xy 369.329726 -279.462377)
			(xy 369.377945 -279.452533) (xy 369.42712 -279.450552) (xy 369.475975 -279.456484) (xy 369.523246 -279.470176)
			(xy 369.567708 -279.491274) (xy 369.608211 -279.51923) (xy 369.643704 -279.553322) (xy 369.673269 -279.592666)
			(xy 369.69614 -279.636243) (xy 369.711724 -279.682924) (xy 369.719619 -279.731501) (xy 369.720114 -279.756108)
			(xy 370.049056 -279.756108) (xy 370.053016 -279.707054) (xy 370.064793 -279.65927) (xy 370.084084 -279.613994)
			(xy 370.110387 -279.572398) (xy 370.143022 -279.535561) (xy 370.181143 -279.504436) (xy 370.223764 -279.479829)
			(xy 370.26978 -279.462377) (xy 370.317999 -279.452533) (xy 370.367174 -279.450552) (xy 370.416029 -279.456484)
			(xy 370.4633 -279.470176) (xy 370.507762 -279.491274) (xy 370.548265 -279.51923) (xy 370.583758 -279.553322)
			(xy 370.613323 -279.592666) (xy 370.636194 -279.636243) (xy 370.651778 -279.682924) (xy 370.659673 -279.731501)
			(xy 370.660168 -279.756108) (xy 370.98911 -279.756108) (xy 370.99307 -279.707054) (xy 371.004847 -279.65927)
			(xy 371.024138 -279.613994) (xy 371.050441 -279.572398) (xy 371.083076 -279.535561) (xy 371.121197 -279.504436)
			(xy 371.163818 -279.479829) (xy 371.209834 -279.462377) (xy 371.258053 -279.452533) (xy 371.307228 -279.450552)
			(xy 371.356083 -279.456484) (xy 371.403354 -279.470176) (xy 371.447816 -279.491274) (xy 371.488319 -279.51923)
			(xy 371.523812 -279.553322) (xy 371.553377 -279.592666) (xy 371.576248 -279.636243) (xy 371.591832 -279.682924)
			(xy 371.599727 -279.731501) (xy 371.600222 -279.756108) (xy 371.92891 -279.756108) (xy 371.93287 -279.707054)
			(xy 371.944647 -279.65927) (xy 371.963938 -279.613994) (xy 371.990241 -279.572398) (xy 372.022876 -279.535561)
			(xy 372.060997 -279.504436) (xy 372.103618 -279.479829) (xy 372.149634 -279.462377) (xy 372.197853 -279.452533)
			(xy 372.247028 -279.450552) (xy 372.295883 -279.456484) (xy 372.343154 -279.470176) (xy 372.387616 -279.491274)
			(xy 372.428119 -279.51923) (xy 372.463612 -279.553322) (xy 372.493177 -279.592666) (xy 372.516048 -279.636243)
			(xy 372.531632 -279.682924) (xy 372.539527 -279.731501) (xy 372.540022 -279.756108) (xy 372.868964 -279.756108)
			(xy 372.872924 -279.707054) (xy 372.884701 -279.65927) (xy 372.903992 -279.613994) (xy 372.930295 -279.572398)
			(xy 372.96293 -279.535561) (xy 373.001051 -279.504436) (xy 373.043672 -279.479829) (xy 373.089688 -279.462377)
			(xy 373.137907 -279.452533) (xy 373.187082 -279.450552) (xy 373.235937 -279.456484) (xy 373.283208 -279.470176)
			(xy 373.32767 -279.491274) (xy 373.368173 -279.51923) (xy 373.403666 -279.553322) (xy 373.433231 -279.592666)
			(xy 373.456102 -279.636243) (xy 373.471686 -279.682924) (xy 373.479581 -279.731501) (xy 373.480076 -279.756108)
			(xy 373.809018 -279.756108) (xy 373.812978 -279.707054) (xy 373.824755 -279.65927) (xy 373.844046 -279.613994)
			(xy 373.870349 -279.572398) (xy 373.902984 -279.535561) (xy 373.941105 -279.504436) (xy 373.983726 -279.479829)
			(xy 374.029742 -279.462377) (xy 374.077961 -279.452533) (xy 374.127136 -279.450552) (xy 374.175991 -279.456484)
			(xy 374.223262 -279.470176) (xy 374.267724 -279.491274) (xy 374.308227 -279.51923) (xy 374.34372 -279.553322)
			(xy 374.373285 -279.592666) (xy 374.396156 -279.636243) (xy 374.41174 -279.682924) (xy 374.419635 -279.731501)
			(xy 374.42013 -279.756108) (xy 374.749072 -279.756108) (xy 374.753032 -279.707054) (xy 374.764809 -279.65927)
			(xy 374.7841 -279.613994) (xy 374.810403 -279.572398) (xy 374.843038 -279.535561) (xy 374.881159 -279.504436)
			(xy 374.92378 -279.479829) (xy 374.969796 -279.462377) (xy 375.018015 -279.452533) (xy 375.06719 -279.450552)
			(xy 375.116045 -279.456484) (xy 375.163316 -279.470176) (xy 375.207778 -279.491274) (xy 375.248281 -279.51923)
			(xy 375.283774 -279.553322) (xy 375.313339 -279.592666) (xy 375.33621 -279.636243) (xy 375.351794 -279.682924)
			(xy 375.359689 -279.731501) (xy 375.360184 -279.756108) (xy 375.678695 -279.756108) (xy 375.68279 -279.70538)
			(xy 375.694969 -279.655966) (xy 375.714917 -279.609146) (xy 375.742118 -279.566132) (xy 375.775866 -279.528038)
			(xy 375.815288 -279.495851) (xy 375.859362 -279.470405) (xy 375.906948 -279.452358) (xy 375.956812 -279.442178)
			(xy 376.007664 -279.440129) (xy 376.058185 -279.446263) (xy 376.107069 -279.460423) (xy 376.153048 -279.48224)
			(xy 376.194932 -279.51115) (xy 376.231636 -279.546405) (xy 376.262209 -279.587091) (xy 376.28586 -279.632154)
			(xy 376.301976 -279.680428) (xy 376.31014 -279.730662) (xy 376.310652 -279.756108) (xy 376.628926 -279.756108)
			(xy 376.632886 -279.707054) (xy 376.644663 -279.65927) (xy 376.663954 -279.613994) (xy 376.690257 -279.572398)
			(xy 376.722892 -279.535561) (xy 376.761013 -279.504436) (xy 376.803634 -279.479829) (xy 376.84965 -279.462377)
			(xy 376.897869 -279.452533) (xy 376.947044 -279.450552) (xy 376.995899 -279.456484) (xy 377.04317 -279.470176)
			(xy 377.087632 -279.491274) (xy 377.128135 -279.51923) (xy 377.163628 -279.553322) (xy 377.193193 -279.592666)
			(xy 377.216064 -279.636243) (xy 377.231648 -279.682924) (xy 377.239543 -279.731501) (xy 377.240038 -279.756108)
			(xy 377.558549 -279.756108) (xy 377.562644 -279.70538) (xy 377.574823 -279.655966) (xy 377.594771 -279.609146)
			(xy 377.621972 -279.566132) (xy 377.65572 -279.528038) (xy 377.695142 -279.495851) (xy 377.739216 -279.470405)
			(xy 377.786802 -279.452358) (xy 377.836666 -279.442178) (xy 377.887518 -279.440129) (xy 377.938039 -279.446263)
			(xy 377.986923 -279.460423) (xy 378.032902 -279.48224) (xy 378.074786 -279.51115) (xy 378.11149 -279.546405)
			(xy 378.142063 -279.587091) (xy 378.165714 -279.632154) (xy 378.18183 -279.680428) (xy 378.189994 -279.730662)
			(xy 378.190506 -279.756108) (xy 378.189994 -279.781554) (xy 378.18183 -279.831788) (xy 378.165714 -279.880062)
			(xy 378.142063 -279.925125) (xy 378.11149 -279.965811) (xy 378.074786 -280.001066) (xy 378.032902 -280.029976)
			(xy 377.986923 -280.051793) (xy 377.938039 -280.065953) (xy 377.887518 -280.072087) (xy 377.836666 -280.070038)
			(xy 377.786802 -280.059858) (xy 377.739216 -280.041811) (xy 377.695142 -280.016365) (xy 377.65572 -279.984178)
			(xy 377.621972 -279.946084) (xy 377.594771 -279.90307) (xy 377.574823 -279.85625) (xy 377.562644 -279.806836)
			(xy 377.558549 -279.756108) (xy 377.240038 -279.756108) (xy 377.239543 -279.780715) (xy 377.231648 -279.829292)
			(xy 377.216064 -279.875973) (xy 377.193193 -279.91955) (xy 377.163628 -279.958894) (xy 377.128135 -279.992986)
			(xy 377.087632 -280.020942) (xy 377.04317 -280.04204) (xy 376.995899 -280.055732) (xy 376.947044 -280.061664)
			(xy 376.897869 -280.059683) (xy 376.84965 -280.049839) (xy 376.803634 -280.032387) (xy 376.761013 -280.00778)
			(xy 376.722892 -279.976655) (xy 376.690257 -279.939818) (xy 376.663954 -279.898222) (xy 376.644663 -279.852946)
			(xy 376.632886 -279.805162) (xy 376.628926 -279.756108) (xy 376.310652 -279.756108) (xy 376.31014 -279.781554)
			(xy 376.301976 -279.831788) (xy 376.28586 -279.880062) (xy 376.262209 -279.925125) (xy 376.231636 -279.965811)
			(xy 376.194932 -280.001066) (xy 376.153048 -280.029976) (xy 376.107069 -280.051793) (xy 376.058185 -280.065953)
			(xy 376.007664 -280.072087) (xy 375.956812 -280.070038) (xy 375.906948 -280.059858) (xy 375.859362 -280.041811)
			(xy 375.815288 -280.016365) (xy 375.775866 -279.984178) (xy 375.742118 -279.946084) (xy 375.714917 -279.90307)
			(xy 375.694969 -279.85625) (xy 375.68279 -279.806836) (xy 375.678695 -279.756108) (xy 375.360184 -279.756108)
			(xy 375.359689 -279.780715) (xy 375.351794 -279.829292) (xy 375.33621 -279.875973) (xy 375.313339 -279.91955)
			(xy 375.283774 -279.958894) (xy 375.248281 -279.992986) (xy 375.207778 -280.020942) (xy 375.163316 -280.04204)
			(xy 375.116045 -280.055732) (xy 375.06719 -280.061664) (xy 375.018015 -280.059683) (xy 374.969796 -280.049839)
			(xy 374.92378 -280.032387) (xy 374.881159 -280.00778) (xy 374.843038 -279.976655) (xy 374.810403 -279.939818)
			(xy 374.7841 -279.898222) (xy 374.764809 -279.852946) (xy 374.753032 -279.805162) (xy 374.749072 -279.756108)
			(xy 374.42013 -279.756108) (xy 374.419635 -279.780715) (xy 374.41174 -279.829292) (xy 374.396156 -279.875973)
			(xy 374.373285 -279.91955) (xy 374.34372 -279.958894) (xy 374.308227 -279.992986) (xy 374.267724 -280.020942)
			(xy 374.223262 -280.04204) (xy 374.175991 -280.055732) (xy 374.127136 -280.061664) (xy 374.077961 -280.059683)
			(xy 374.029742 -280.049839) (xy 373.983726 -280.032387) (xy 373.941105 -280.00778) (xy 373.902984 -279.976655)
			(xy 373.870349 -279.939818) (xy 373.844046 -279.898222) (xy 373.824755 -279.852946) (xy 373.812978 -279.805162)
			(xy 373.809018 -279.756108) (xy 373.480076 -279.756108) (xy 373.479581 -279.780715) (xy 373.471686 -279.829292)
			(xy 373.456102 -279.875973) (xy 373.433231 -279.91955) (xy 373.403666 -279.958894) (xy 373.368173 -279.992986)
			(xy 373.32767 -280.020942) (xy 373.283208 -280.04204) (xy 373.235937 -280.055732) (xy 373.187082 -280.061664)
			(xy 373.137907 -280.059683) (xy 373.089688 -280.049839) (xy 373.043672 -280.032387) (xy 373.001051 -280.00778)
			(xy 372.96293 -279.976655) (xy 372.930295 -279.939818) (xy 372.903992 -279.898222) (xy 372.884701 -279.852946)
			(xy 372.872924 -279.805162) (xy 372.868964 -279.756108) (xy 372.540022 -279.756108) (xy 372.539527 -279.780715)
			(xy 372.531632 -279.829292) (xy 372.516048 -279.875973) (xy 372.493177 -279.91955) (xy 372.463612 -279.958894)
			(xy 372.428119 -279.992986) (xy 372.387616 -280.020942) (xy 372.343154 -280.04204) (xy 372.295883 -280.055732)
			(xy 372.247028 -280.061664) (xy 372.197853 -280.059683) (xy 372.149634 -280.049839) (xy 372.103618 -280.032387)
			(xy 372.060997 -280.00778) (xy 372.022876 -279.976655) (xy 371.990241 -279.939818) (xy 371.963938 -279.898222)
			(xy 371.944647 -279.852946) (xy 371.93287 -279.805162) (xy 371.92891 -279.756108) (xy 371.600222 -279.756108)
			(xy 371.599727 -279.780715) (xy 371.591832 -279.829292) (xy 371.576248 -279.875973) (xy 371.553377 -279.91955)
			(xy 371.523812 -279.958894) (xy 371.488319 -279.992986) (xy 371.447816 -280.020942) (xy 371.403354 -280.04204)
			(xy 371.356083 -280.055732) (xy 371.307228 -280.061664) (xy 371.258053 -280.059683) (xy 371.209834 -280.049839)
			(xy 371.163818 -280.032387) (xy 371.121197 -280.00778) (xy 371.083076 -279.976655) (xy 371.050441 -279.939818)
			(xy 371.024138 -279.898222) (xy 371.004847 -279.852946) (xy 370.99307 -279.805162) (xy 370.98911 -279.756108)
			(xy 370.660168 -279.756108) (xy 370.659673 -279.780715) (xy 370.651778 -279.829292) (xy 370.636194 -279.875973)
			(xy 370.613323 -279.91955) (xy 370.583758 -279.958894) (xy 370.548265 -279.992986) (xy 370.507762 -280.020942)
			(xy 370.4633 -280.04204) (xy 370.416029 -280.055732) (xy 370.367174 -280.061664) (xy 370.317999 -280.059683)
			(xy 370.26978 -280.049839) (xy 370.223764 -280.032387) (xy 370.181143 -280.00778) (xy 370.143022 -279.976655)
			(xy 370.110387 -279.939818) (xy 370.084084 -279.898222) (xy 370.064793 -279.852946) (xy 370.053016 -279.805162)
			(xy 370.049056 -279.756108) (xy 369.720114 -279.756108) (xy 369.719619 -279.780715) (xy 369.711724 -279.829292)
			(xy 369.69614 -279.875973) (xy 369.673269 -279.91955) (xy 369.643704 -279.958894) (xy 369.608211 -279.992986)
			(xy 369.567708 -280.020942) (xy 369.523246 -280.04204) (xy 369.475975 -280.055732) (xy 369.42712 -280.061664)
			(xy 369.377945 -280.059683) (xy 369.329726 -280.049839) (xy 369.28371 -280.032387) (xy 369.241089 -280.00778)
			(xy 369.202968 -279.976655) (xy 369.170333 -279.939818) (xy 369.14403 -279.898222) (xy 369.124739 -279.852946)
			(xy 369.112962 -279.805162) (xy 369.109002 -279.756108) (xy 368.78006 -279.756108) (xy 368.779565 -279.780715)
			(xy 368.77167 -279.829292) (xy 368.756086 -279.875973) (xy 368.733215 -279.91955) (xy 368.70365 -279.958894)
			(xy 368.668157 -279.992986) (xy 368.627654 -280.020942) (xy 368.583192 -280.04204) (xy 368.535921 -280.055732)
			(xy 368.487066 -280.061664) (xy 368.437891 -280.059683) (xy 368.389672 -280.049839) (xy 368.343656 -280.032387)
			(xy 368.301035 -280.00778) (xy 368.262914 -279.976655) (xy 368.230279 -279.939818) (xy 368.203976 -279.898222)
			(xy 368.184685 -279.852946) (xy 368.172908 -279.805162) (xy 368.168948 -279.756108) (xy 367.840006 -279.756108)
			(xy 367.839511 -279.780715) (xy 367.831616 -279.829292) (xy 367.816032 -279.875973) (xy 367.793161 -279.91955)
			(xy 367.763596 -279.958894) (xy 367.728103 -279.992986) (xy 367.6876 -280.020942) (xy 367.643138 -280.04204)
			(xy 367.595867 -280.055732) (xy 367.547012 -280.061664) (xy 367.497837 -280.059683) (xy 367.449618 -280.049839)
			(xy 367.403602 -280.032387) (xy 367.360981 -280.00778) (xy 367.32286 -279.976655) (xy 367.290225 -279.939818)
			(xy 367.263922 -279.898222) (xy 367.244631 -279.852946) (xy 367.232854 -279.805162) (xy 367.228894 -279.756108)
			(xy 366.900206 -279.756108) (xy 366.899711 -279.780715) (xy 366.891816 -279.829292) (xy 366.876232 -279.875973)
			(xy 366.853361 -279.91955) (xy 366.823796 -279.958894) (xy 366.788303 -279.992986) (xy 366.7478 -280.020942)
			(xy 366.703338 -280.04204) (xy 366.656067 -280.055732) (xy 366.607212 -280.061664) (xy 366.558037 -280.059683)
			(xy 366.509818 -280.049839) (xy 366.463802 -280.032387) (xy 366.421181 -280.00778) (xy 366.38306 -279.976655)
			(xy 366.350425 -279.939818) (xy 366.324122 -279.898222) (xy 366.304831 -279.852946) (xy 366.293054 -279.805162)
			(xy 366.289094 -279.756108) (xy 365.960152 -279.756108) (xy 365.959657 -279.780715) (xy 365.951762 -279.829292)
			(xy 365.936178 -279.875973) (xy 365.913307 -279.91955) (xy 365.883742 -279.958894) (xy 365.848249 -279.992986)
			(xy 365.807746 -280.020942) (xy 365.763284 -280.04204) (xy 365.716013 -280.055732) (xy 365.667158 -280.061664)
			(xy 365.617983 -280.059683) (xy 365.569764 -280.049839) (xy 365.523748 -280.032387) (xy 365.481127 -280.00778)
			(xy 365.443006 -279.976655) (xy 365.410371 -279.939818) (xy 365.384068 -279.898222) (xy 365.364777 -279.852946)
			(xy 365.353 -279.805162) (xy 365.34904 -279.756108) (xy 365.020098 -279.756108) (xy 365.019603 -279.780715)
			(xy 365.011708 -279.829292) (xy 364.996124 -279.875973) (xy 364.973253 -279.91955) (xy 364.943688 -279.958894)
			(xy 364.908195 -279.992986) (xy 364.867692 -280.020942) (xy 364.82323 -280.04204) (xy 364.775959 -280.055732)
			(xy 364.727104 -280.061664) (xy 364.677929 -280.059683) (xy 364.62971 -280.049839) (xy 364.583694 -280.032387)
			(xy 364.541073 -280.00778) (xy 364.502952 -279.976655) (xy 364.470317 -279.939818) (xy 364.444014 -279.898222)
			(xy 364.424723 -279.852946) (xy 364.412946 -279.805162) (xy 364.408986 -279.756108) (xy 364.080044 -279.756108)
			(xy 364.079549 -279.780715) (xy 364.071654 -279.829292) (xy 364.05607 -279.875973) (xy 364.033199 -279.91955)
			(xy 364.003634 -279.958894) (xy 363.968141 -279.992986) (xy 363.927638 -280.020942) (xy 363.883176 -280.04204)
			(xy 363.835905 -280.055732) (xy 363.78705 -280.061664) (xy 363.737875 -280.059683) (xy 363.689656 -280.049839)
			(xy 363.64364 -280.032387) (xy 363.601019 -280.00778) (xy 363.562898 -279.976655) (xy 363.530263 -279.939818)
			(xy 363.50396 -279.898222) (xy 363.484669 -279.852946) (xy 363.472892 -279.805162) (xy 363.468932 -279.756108)
			(xy 363.13999 -279.756108) (xy 363.139495 -279.780715) (xy 363.1316 -279.829292) (xy 363.116016 -279.875973)
			(xy 363.093145 -279.91955) (xy 363.06358 -279.958894) (xy 363.028087 -279.992986) (xy 362.987584 -280.020942)
			(xy 362.943122 -280.04204) (xy 362.895851 -280.055732) (xy 362.846996 -280.061664) (xy 362.797821 -280.059683)
			(xy 362.749602 -280.049839) (xy 362.703586 -280.032387) (xy 362.660965 -280.00778) (xy 362.622844 -279.976655)
			(xy 362.590209 -279.939818) (xy 362.563906 -279.898222) (xy 362.544615 -279.852946) (xy 362.532838 -279.805162)
			(xy 362.528878 -279.756108) (xy 362.20019 -279.756108) (xy 362.199695 -279.780715) (xy 362.1918 -279.829292)
			(xy 362.176216 -279.875973) (xy 362.153345 -279.91955) (xy 362.12378 -279.958894) (xy 362.088287 -279.992986)
			(xy 362.047784 -280.020942) (xy 362.003322 -280.04204) (xy 361.956051 -280.055732) (xy 361.907196 -280.061664)
			(xy 361.858021 -280.059683) (xy 361.809802 -280.049839) (xy 361.763786 -280.032387) (xy 361.721165 -280.00778)
			(xy 361.683044 -279.976655) (xy 361.650409 -279.939818) (xy 361.624106 -279.898222) (xy 361.604815 -279.852946)
			(xy 361.593038 -279.805162) (xy 361.589078 -279.756108) (xy 358.446324 -279.756108) (xy 358.445829 -279.780715)
			(xy 358.437934 -279.829292) (xy 358.42235 -279.875973) (xy 358.399479 -279.91955) (xy 358.369914 -279.958894)
			(xy 358.334421 -279.992986) (xy 358.293918 -280.020942) (xy 358.249456 -280.04204) (xy 358.202185 -280.055732)
			(xy 358.15333 -280.061664) (xy 358.104155 -280.059683) (xy 358.055936 -280.049839) (xy 358.00992 -280.032387)
			(xy 357.967299 -280.00778) (xy 357.929178 -279.976655) (xy 357.896543 -279.939818) (xy 357.87024 -279.898222)
			(xy 357.850949 -279.852946) (xy 357.839172 -279.805162) (xy 357.835212 -279.756108) (xy 357.506524 -279.756108)
			(xy 357.506029 -279.780715) (xy 357.498134 -279.829292) (xy 357.48255 -279.875973) (xy 357.459679 -279.91955)
			(xy 357.430114 -279.958894) (xy 357.394621 -279.992986) (xy 357.354118 -280.020942) (xy 357.309656 -280.04204)
			(xy 357.262385 -280.055732) (xy 357.21353 -280.061664) (xy 357.164355 -280.059683) (xy 357.116136 -280.049839)
			(xy 357.07012 -280.032387) (xy 357.027499 -280.00778) (xy 356.989378 -279.976655) (xy 356.956743 -279.939818)
			(xy 356.93044 -279.898222) (xy 356.911149 -279.852946) (xy 356.899372 -279.805162) (xy 356.895412 -279.756108)
			(xy 356.56647 -279.756108) (xy 356.565975 -279.780715) (xy 356.55808 -279.829292) (xy 356.542496 -279.875973)
			(xy 356.519625 -279.91955) (xy 356.49006 -279.958894) (xy 356.454567 -279.992986) (xy 356.414064 -280.020942)
			(xy 356.369602 -280.04204) (xy 356.322331 -280.055732) (xy 356.273476 -280.061664) (xy 356.224301 -280.059683)
			(xy 356.176082 -280.049839) (xy 356.130066 -280.032387) (xy 356.087445 -280.00778) (xy 356.049324 -279.976655)
			(xy 356.016689 -279.939818) (xy 355.990386 -279.898222) (xy 355.971095 -279.852946) (xy 355.959318 -279.805162)
			(xy 355.955358 -279.756108) (xy 355.626416 -279.756108) (xy 355.625921 -279.780715) (xy 355.618026 -279.829292)
			(xy 355.602442 -279.875973) (xy 355.579571 -279.91955) (xy 355.550006 -279.958894) (xy 355.514513 -279.992986)
			(xy 355.47401 -280.020942) (xy 355.429548 -280.04204) (xy 355.382277 -280.055732) (xy 355.333422 -280.061664)
			(xy 355.284247 -280.059683) (xy 355.236028 -280.049839) (xy 355.190012 -280.032387) (xy 355.147391 -280.00778)
			(xy 355.10927 -279.976655) (xy 355.076635 -279.939818) (xy 355.050332 -279.898222) (xy 355.031041 -279.852946)
			(xy 355.019264 -279.805162) (xy 355.015304 -279.756108) (xy 354.686362 -279.756108) (xy 354.685867 -279.780715)
			(xy 354.677972 -279.829292) (xy 354.662388 -279.875973) (xy 354.639517 -279.91955) (xy 354.609952 -279.958894)
			(xy 354.574459 -279.992986) (xy 354.533956 -280.020942) (xy 354.489494 -280.04204) (xy 354.442223 -280.055732)
			(xy 354.393368 -280.061664) (xy 354.344193 -280.059683) (xy 354.295974 -280.049839) (xy 354.249958 -280.032387)
			(xy 354.207337 -280.00778) (xy 354.169216 -279.976655) (xy 354.136581 -279.939818) (xy 354.110278 -279.898222)
			(xy 354.090987 -279.852946) (xy 354.07921 -279.805162) (xy 354.07525 -279.756108) (xy 353.746308 -279.756108)
			(xy 353.745813 -279.780715) (xy 353.737918 -279.829292) (xy 353.722334 -279.875973) (xy 353.699463 -279.91955)
			(xy 353.669898 -279.958894) (xy 353.634405 -279.992986) (xy 353.593902 -280.020942) (xy 353.54944 -280.04204)
			(xy 353.502169 -280.055732) (xy 353.453314 -280.061664) (xy 353.404139 -280.059683) (xy 353.35592 -280.049839)
			(xy 353.309904 -280.032387) (xy 353.267283 -280.00778) (xy 353.229162 -279.976655) (xy 353.196527 -279.939818)
			(xy 353.170224 -279.898222) (xy 353.150933 -279.852946) (xy 353.139156 -279.805162) (xy 353.135196 -279.756108)
			(xy 352.806508 -279.756108) (xy 352.806013 -279.780715) (xy 352.798118 -279.829292) (xy 352.782534 -279.875973)
			(xy 352.759663 -279.91955) (xy 352.730098 -279.958894) (xy 352.694605 -279.992986) (xy 352.654102 -280.020942)
			(xy 352.60964 -280.04204) (xy 352.562369 -280.055732) (xy 352.513514 -280.061664) (xy 352.464339 -280.059683)
			(xy 352.41612 -280.049839) (xy 352.370104 -280.032387) (xy 352.327483 -280.00778) (xy 352.289362 -279.976655)
			(xy 352.256727 -279.939818) (xy 352.230424 -279.898222) (xy 352.211133 -279.852946) (xy 352.199356 -279.805162)
			(xy 352.195396 -279.756108) (xy 351.866454 -279.756108) (xy 351.865959 -279.780715) (xy 351.858064 -279.829292)
			(xy 351.84248 -279.875973) (xy 351.819609 -279.91955) (xy 351.790044 -279.958894) (xy 351.754551 -279.992986)
			(xy 351.714048 -280.020942) (xy 351.669586 -280.04204) (xy 351.622315 -280.055732) (xy 351.57346 -280.061664)
			(xy 351.524285 -280.059683) (xy 351.476066 -280.049839) (xy 351.43005 -280.032387) (xy 351.387429 -280.00778)
			(xy 351.349308 -279.976655) (xy 351.316673 -279.939818) (xy 351.29037 -279.898222) (xy 351.271079 -279.852946)
			(xy 351.259302 -279.805162) (xy 351.255342 -279.756108) (xy 350.9264 -279.756108) (xy 350.925905 -279.780715)
			(xy 350.91801 -279.829292) (xy 350.902426 -279.875973) (xy 350.879555 -279.91955) (xy 350.84999 -279.958894)
			(xy 350.814497 -279.992986) (xy 350.773994 -280.020942) (xy 350.729532 -280.04204) (xy 350.682261 -280.055732)
			(xy 350.633406 -280.061664) (xy 350.584231 -280.059683) (xy 350.536012 -280.049839) (xy 350.489996 -280.032387)
			(xy 350.447375 -280.00778) (xy 350.409254 -279.976655) (xy 350.376619 -279.939818) (xy 350.350316 -279.898222)
			(xy 350.331025 -279.852946) (xy 350.319248 -279.805162) (xy 350.315288 -279.756108) (xy 349.986346 -279.756108)
			(xy 349.985851 -279.780715) (xy 349.977956 -279.829292) (xy 349.962372 -279.875973) (xy 349.939501 -279.91955)
			(xy 349.909936 -279.958894) (xy 349.874443 -279.992986) (xy 349.83394 -280.020942) (xy 349.789478 -280.04204)
			(xy 349.742207 -280.055732) (xy 349.693352 -280.061664) (xy 349.644177 -280.059683) (xy 349.595958 -280.049839)
			(xy 349.549942 -280.032387) (xy 349.507321 -280.00778) (xy 349.4692 -279.976655) (xy 349.436565 -279.939818)
			(xy 349.410262 -279.898222) (xy 349.390971 -279.852946) (xy 349.379194 -279.805162) (xy 349.375234 -279.756108)
			(xy 349.046546 -279.756108) (xy 349.046051 -279.780715) (xy 349.038156 -279.829292) (xy 349.022572 -279.875973)
			(xy 348.999701 -279.91955) (xy 348.970136 -279.958894) (xy 348.934643 -279.992986) (xy 348.89414 -280.020942)
			(xy 348.849678 -280.04204) (xy 348.802407 -280.055732) (xy 348.753552 -280.061664) (xy 348.704377 -280.059683)
			(xy 348.656158 -280.049839) (xy 348.610142 -280.032387) (xy 348.567521 -280.00778) (xy 348.5294 -279.976655)
			(xy 348.496765 -279.939818) (xy 348.470462 -279.898222) (xy 348.451171 -279.852946) (xy 348.439394 -279.805162)
			(xy 348.435434 -279.756108) (xy 348.106492 -279.756108) (xy 348.105997 -279.780715) (xy 348.098102 -279.829292)
			(xy 348.082518 -279.875973) (xy 348.059647 -279.91955) (xy 348.030082 -279.958894) (xy 347.994589 -279.992986)
			(xy 347.954086 -280.020942) (xy 347.909624 -280.04204) (xy 347.862353 -280.055732) (xy 347.813498 -280.061664)
			(xy 347.764323 -280.059683) (xy 347.716104 -280.049839) (xy 347.670088 -280.032387) (xy 347.627467 -280.00778)
			(xy 347.589346 -279.976655) (xy 347.556711 -279.939818) (xy 347.530408 -279.898222) (xy 347.511117 -279.852946)
			(xy 347.49934 -279.805162) (xy 347.49538 -279.756108) (xy 347.166438 -279.756108) (xy 347.165943 -279.780715)
			(xy 347.158048 -279.829292) (xy 347.142464 -279.875973) (xy 347.119593 -279.91955) (xy 347.090028 -279.958894)
			(xy 347.054535 -279.992986) (xy 347.014032 -280.020942) (xy 346.96957 -280.04204) (xy 346.922299 -280.055732)
			(xy 346.873444 -280.061664) (xy 346.824269 -280.059683) (xy 346.77605 -280.049839) (xy 346.730034 -280.032387)
			(xy 346.687413 -280.00778) (xy 346.649292 -279.976655) (xy 346.616657 -279.939818) (xy 346.590354 -279.898222)
			(xy 346.571063 -279.852946) (xy 346.559286 -279.805162) (xy 346.555326 -279.756108) (xy 346.226384 -279.756108)
			(xy 346.225889 -279.780715) (xy 346.217994 -279.829292) (xy 346.20241 -279.875973) (xy 346.179539 -279.91955)
			(xy 346.149974 -279.958894) (xy 346.114481 -279.992986) (xy 346.073978 -280.020942) (xy 346.029516 -280.04204)
			(xy 345.982245 -280.055732) (xy 345.93339 -280.061664) (xy 345.884215 -280.059683) (xy 345.835996 -280.049839)
			(xy 345.78998 -280.032387) (xy 345.747359 -280.00778) (xy 345.709238 -279.976655) (xy 345.676603 -279.939818)
			(xy 345.6503 -279.898222) (xy 345.631009 -279.852946) (xy 345.619232 -279.805162) (xy 345.615272 -279.756108)
			(xy 345.28633 -279.756108) (xy 345.285835 -279.780715) (xy 345.27794 -279.829292) (xy 345.262356 -279.875973)
			(xy 345.239485 -279.91955) (xy 345.20992 -279.958894) (xy 345.174427 -279.992986) (xy 345.133924 -280.020942)
			(xy 345.089462 -280.04204) (xy 345.042191 -280.055732) (xy 344.993336 -280.061664) (xy 344.944161 -280.059683)
			(xy 344.895942 -280.049839) (xy 344.849926 -280.032387) (xy 344.807305 -280.00778) (xy 344.769184 -279.976655)
			(xy 344.736549 -279.939818) (xy 344.710246 -279.898222) (xy 344.690955 -279.852946) (xy 344.679178 -279.805162)
			(xy 344.675218 -279.756108) (xy 344.356944 -279.756108) (xy 344.356432 -279.781554) (xy 344.348268 -279.831788)
			(xy 344.332152 -279.880062) (xy 344.308501 -279.925125) (xy 344.277928 -279.965811) (xy 344.241224 -280.001066)
			(xy 344.19934 -280.029976) (xy 344.153361 -280.051793) (xy 344.104477 -280.065953) (xy 344.053956 -280.072087)
			(xy 344.003104 -280.070038) (xy 343.95324 -280.059858) (xy 343.905654 -280.041811) (xy 343.86158 -280.016365)
			(xy 343.822158 -279.984178) (xy 343.78841 -279.946084) (xy 343.761209 -279.90307) (xy 343.741261 -279.85625)
			(xy 343.729082 -279.806836) (xy 343.724987 -279.756108) (xy 343.406476 -279.756108) (xy 343.405981 -279.780715)
			(xy 343.398086 -279.829292) (xy 343.382502 -279.875973) (xy 343.359631 -279.91955) (xy 343.330066 -279.958894)
			(xy 343.294573 -279.992986) (xy 343.25407 -280.020942) (xy 343.209608 -280.04204) (xy 343.162337 -280.055732)
			(xy 343.113482 -280.061664) (xy 343.064307 -280.059683) (xy 343.016088 -280.049839) (xy 342.970072 -280.032387)
			(xy 342.927451 -280.00778) (xy 342.88933 -279.976655) (xy 342.856695 -279.939818) (xy 342.830392 -279.898222)
			(xy 342.811101 -279.852946) (xy 342.799324 -279.805162) (xy 342.795364 -279.756108) (xy 342.476836 -279.756108)
			(xy 342.476324 -279.781554) (xy 342.46816 -279.831788) (xy 342.452044 -279.880062) (xy 342.428393 -279.925125)
			(xy 342.39782 -279.965811) (xy 342.361116 -280.001066) (xy 342.319232 -280.029976) (xy 342.273253 -280.051793)
			(xy 342.224369 -280.065953) (xy 342.173848 -280.072087) (xy 342.122996 -280.070038) (xy 342.073132 -280.059858)
			(xy 342.025546 -280.041811) (xy 341.981472 -280.016365) (xy 341.94205 -279.984178) (xy 341.908302 -279.946084)
			(xy 341.881101 -279.90307) (xy 341.861153 -279.85625) (xy 341.848974 -279.806836) (xy 341.844879 -279.756108)
			(xy 341.525945 -279.756108) (xy 341.525945 -279.780168) (xy 341.518392 -279.827704) (xy 341.503474 -279.873466)
			(xy 341.481559 -279.916321) (xy 341.453192 -279.955206) (xy 341.419074 -279.989158) (xy 341.380052 -280.017335)
			(xy 341.337091 -280.039041) (xy 341.291257 -280.053737) (xy 341.267542 -280.05786) (xy 341.258652 -280.05913)
			(xy 341.24265 -280.06802) (xy 341.236808 -280.074878) (xy 341.231219 -280.081963) (xy 341.224969 -280.098881)
			(xy 341.224616 -280.107898) (xy 341.224616 -280.267156) (xy 341.22485 -280.273673) (xy 341.228191 -280.286273)
			(xy 341.23122 -280.292048) (xy 341.241158 -280.309815) (xy 341.258699 -280.346557) (xy 341.266272 -280.365454)
			(xy 341.266272 -280.365708) (xy 341.2689 -280.371897) (xy 341.276875 -280.382717) (xy 341.28202 -280.387044)
			(xy 341.293196 -280.39568) (xy 341.305642 -280.397204) (xy 341.395812 -280.408634) (xy 341.402691 -280.409231)
			(xy 341.41634 -280.407173) (xy 341.422736 -280.40457) (xy 341.428578 -280.40203) (xy 341.438992 -280.393648)
			(xy 341.44331 -280.387806) (xy 341.457773 -280.368502) (xy 341.491759 -280.334276) (xy 341.530697 -280.30581)
			(xy 341.573621 -280.283812) (xy 341.619467 -280.268825) (xy 341.667098 -280.261223) (xy 341.691214 -280.260806)
			(xy 341.716467 -280.261329) (xy 341.766285 -280.269644) (xy 341.814055 -280.286045) (xy 341.858473 -280.310085)
			(xy 341.89833 -280.341108) (xy 341.932536 -280.378268) (xy 341.96016 -280.420551) (xy 341.980448 -280.466804)
			(xy 341.992846 -280.515766) (xy 341.997017 -280.5661) (xy 341.997016 -280.566114) (xy 342.314779 -280.566114)
			(xy 342.318874 -280.515386) (xy 342.331053 -280.465972) (xy 342.351001 -280.419152) (xy 342.378202 -280.376138)
			(xy 342.41195 -280.338044) (xy 342.451372 -280.305857) (xy 342.495446 -280.280411) (xy 342.543032 -280.262364)
			(xy 342.592896 -280.252184) (xy 342.643748 -280.250135) (xy 342.694269 -280.256269) (xy 342.743153 -280.270429)
			(xy 342.789132 -280.292246) (xy 342.831016 -280.321156) (xy 342.86772 -280.356411) (xy 342.898293 -280.397097)
			(xy 342.921944 -280.44216) (xy 342.93806 -280.490434) (xy 342.946224 -280.540668) (xy 342.946736 -280.566114)
			(xy 343.254833 -280.566114) (xy 343.258928 -280.515386) (xy 343.271107 -280.465972) (xy 343.291055 -280.419152)
			(xy 343.318256 -280.376138) (xy 343.352004 -280.338044) (xy 343.391426 -280.305857) (xy 343.4355 -280.280411)
			(xy 343.483086 -280.262364) (xy 343.53295 -280.252184) (xy 343.583802 -280.250135) (xy 343.634323 -280.256269)
			(xy 343.683207 -280.270429) (xy 343.729186 -280.292246) (xy 343.77107 -280.321156) (xy 343.807774 -280.356411)
			(xy 343.838347 -280.397097) (xy 343.861998 -280.44216) (xy 343.878114 -280.490434) (xy 343.886278 -280.540668)
			(xy 343.88679 -280.566114) (xy 344.205318 -280.566114) (xy 344.209278 -280.51706) (xy 344.221055 -280.469276)
			(xy 344.240346 -280.424) (xy 344.266649 -280.382404) (xy 344.299284 -280.345567) (xy 344.337405 -280.314442)
			(xy 344.380026 -280.289835) (xy 344.426042 -280.272383) (xy 344.474261 -280.262539) (xy 344.523436 -280.260558)
			(xy 344.572291 -280.26649) (xy 344.619562 -280.280182) (xy 344.664024 -280.30128) (xy 344.704527 -280.329236)
			(xy 344.74002 -280.363328) (xy 344.769585 -280.402672) (xy 344.792456 -280.446249) (xy 344.80804 -280.49293)
			(xy 344.815935 -280.541507) (xy 344.81643 -280.566114) (xy 345.145372 -280.566114) (xy 345.149332 -280.51706)
			(xy 345.161109 -280.469276) (xy 345.1804 -280.424) (xy 345.206703 -280.382404) (xy 345.239338 -280.345567)
			(xy 345.277459 -280.314442) (xy 345.32008 -280.289835) (xy 345.366096 -280.272383) (xy 345.414315 -280.262539)
			(xy 345.46349 -280.260558) (xy 345.512345 -280.26649) (xy 345.559616 -280.280182) (xy 345.604078 -280.30128)
			(xy 345.644581 -280.329236) (xy 345.680074 -280.363328) (xy 345.709639 -280.402672) (xy 345.73251 -280.446249)
			(xy 345.748094 -280.49293) (xy 345.755989 -280.541507) (xy 345.756484 -280.566114) (xy 346.085426 -280.566114)
			(xy 346.089386 -280.51706) (xy 346.101163 -280.469276) (xy 346.120454 -280.424) (xy 346.146757 -280.382404)
			(xy 346.179392 -280.345567) (xy 346.217513 -280.314442) (xy 346.260134 -280.289835) (xy 346.30615 -280.272383)
			(xy 346.354369 -280.262539) (xy 346.403544 -280.260558) (xy 346.452399 -280.26649) (xy 346.49967 -280.280182)
			(xy 346.544132 -280.30128) (xy 346.584635 -280.329236) (xy 346.620128 -280.363328) (xy 346.649693 -280.402672)
			(xy 346.672564 -280.446249) (xy 346.688148 -280.49293) (xy 346.696043 -280.541507) (xy 346.696538 -280.566114)
			(xy 347.025226 -280.566114) (xy 347.029186 -280.51706) (xy 347.040963 -280.469276) (xy 347.060254 -280.424)
			(xy 347.086557 -280.382404) (xy 347.119192 -280.345567) (xy 347.157313 -280.314442) (xy 347.199934 -280.289835)
			(xy 347.24595 -280.272383) (xy 347.294169 -280.262539) (xy 347.343344 -280.260558) (xy 347.392199 -280.26649)
			(xy 347.43947 -280.280182) (xy 347.483932 -280.30128) (xy 347.524435 -280.329236) (xy 347.559928 -280.363328)
			(xy 347.589493 -280.402672) (xy 347.612364 -280.446249) (xy 347.627948 -280.49293) (xy 347.635843 -280.541507)
			(xy 347.636338 -280.566114) (xy 347.96528 -280.566114) (xy 347.96924 -280.51706) (xy 347.981017 -280.469276)
			(xy 348.000308 -280.424) (xy 348.026611 -280.382404) (xy 348.059246 -280.345567) (xy 348.097367 -280.314442)
			(xy 348.139988 -280.289835) (xy 348.186004 -280.272383) (xy 348.234223 -280.262539) (xy 348.283398 -280.260558)
			(xy 348.332253 -280.26649) (xy 348.379524 -280.280182) (xy 348.423986 -280.30128) (xy 348.464489 -280.329236)
			(xy 348.499982 -280.363328) (xy 348.529547 -280.402672) (xy 348.552418 -280.446249) (xy 348.568002 -280.49293)
			(xy 348.575897 -280.541507) (xy 348.576392 -280.566114) (xy 348.905334 -280.566114) (xy 348.909294 -280.51706)
			(xy 348.921071 -280.469276) (xy 348.940362 -280.424) (xy 348.966665 -280.382404) (xy 348.9993 -280.345567)
			(xy 349.037421 -280.314442) (xy 349.080042 -280.289835) (xy 349.126058 -280.272383) (xy 349.174277 -280.262539)
			(xy 349.223452 -280.260558) (xy 349.272307 -280.26649) (xy 349.319578 -280.280182) (xy 349.36404 -280.30128)
			(xy 349.404543 -280.329236) (xy 349.440036 -280.363328) (xy 349.469601 -280.402672) (xy 349.492472 -280.446249)
			(xy 349.508056 -280.49293) (xy 349.515951 -280.541507) (xy 349.516446 -280.566114) (xy 349.845388 -280.566114)
			(xy 349.849348 -280.51706) (xy 349.861125 -280.469276) (xy 349.880416 -280.424) (xy 349.906719 -280.382404)
			(xy 349.939354 -280.345567) (xy 349.977475 -280.314442) (xy 350.020096 -280.289835) (xy 350.066112 -280.272383)
			(xy 350.114331 -280.262539) (xy 350.163506 -280.260558) (xy 350.212361 -280.26649) (xy 350.259632 -280.280182)
			(xy 350.304094 -280.30128) (xy 350.344597 -280.329236) (xy 350.38009 -280.363328) (xy 350.409655 -280.402672)
			(xy 350.432526 -280.446249) (xy 350.44811 -280.49293) (xy 350.456005 -280.541507) (xy 350.4565 -280.566114)
			(xy 350.785442 -280.566114) (xy 350.789402 -280.51706) (xy 350.801179 -280.469276) (xy 350.82047 -280.424)
			(xy 350.846773 -280.382404) (xy 350.879408 -280.345567) (xy 350.917529 -280.314442) (xy 350.96015 -280.289835)
			(xy 351.006166 -280.272383) (xy 351.054385 -280.262539) (xy 351.10356 -280.260558) (xy 351.152415 -280.26649)
			(xy 351.199686 -280.280182) (xy 351.244148 -280.30128) (xy 351.284651 -280.329236) (xy 351.320144 -280.363328)
			(xy 351.349709 -280.402672) (xy 351.37258 -280.446249) (xy 351.388164 -280.49293) (xy 351.396059 -280.541507)
			(xy 351.396554 -280.566114) (xy 351.725242 -280.566114) (xy 351.729202 -280.51706) (xy 351.740979 -280.469276)
			(xy 351.76027 -280.424) (xy 351.786573 -280.382404) (xy 351.819208 -280.345567) (xy 351.857329 -280.314442)
			(xy 351.89995 -280.289835) (xy 351.945966 -280.272383) (xy 351.994185 -280.262539) (xy 352.04336 -280.260558)
			(xy 352.092215 -280.26649) (xy 352.139486 -280.280182) (xy 352.183948 -280.30128) (xy 352.224451 -280.329236)
			(xy 352.259944 -280.363328) (xy 352.289509 -280.402672) (xy 352.31238 -280.446249) (xy 352.327964 -280.49293)
			(xy 352.335859 -280.541507) (xy 352.336354 -280.566114) (xy 352.665296 -280.566114) (xy 352.669256 -280.51706)
			(xy 352.681033 -280.469276) (xy 352.700324 -280.424) (xy 352.726627 -280.382404) (xy 352.759262 -280.345567)
			(xy 352.797383 -280.314442) (xy 352.840004 -280.289835) (xy 352.88602 -280.272383) (xy 352.934239 -280.262539)
			(xy 352.983414 -280.260558) (xy 353.032269 -280.26649) (xy 353.07954 -280.280182) (xy 353.124002 -280.30128)
			(xy 353.164505 -280.329236) (xy 353.199998 -280.363328) (xy 353.229563 -280.402672) (xy 353.252434 -280.446249)
			(xy 353.268018 -280.49293) (xy 353.275913 -280.541507) (xy 353.276408 -280.566114) (xy 353.60535 -280.566114)
			(xy 353.60931 -280.51706) (xy 353.621087 -280.469276) (xy 353.640378 -280.424) (xy 353.666681 -280.382404)
			(xy 353.699316 -280.345567) (xy 353.737437 -280.314442) (xy 353.780058 -280.289835) (xy 353.826074 -280.272383)
			(xy 353.874293 -280.262539) (xy 353.923468 -280.260558) (xy 353.972323 -280.26649) (xy 354.019594 -280.280182)
			(xy 354.064056 -280.30128) (xy 354.104559 -280.329236) (xy 354.140052 -280.363328) (xy 354.169617 -280.402672)
			(xy 354.192488 -280.446249) (xy 354.208072 -280.49293) (xy 354.215967 -280.541507) (xy 354.216462 -280.566114)
			(xy 354.545404 -280.566114) (xy 354.549364 -280.51706) (xy 354.561141 -280.469276) (xy 354.580432 -280.424)
			(xy 354.606735 -280.382404) (xy 354.63937 -280.345567) (xy 354.677491 -280.314442) (xy 354.720112 -280.289835)
			(xy 354.766128 -280.272383) (xy 354.814347 -280.262539) (xy 354.863522 -280.260558) (xy 354.912377 -280.26649)
			(xy 354.959648 -280.280182) (xy 355.00411 -280.30128) (xy 355.044613 -280.329236) (xy 355.080106 -280.363328)
			(xy 355.109671 -280.402672) (xy 355.132542 -280.446249) (xy 355.148126 -280.49293) (xy 355.156021 -280.541507)
			(xy 355.156516 -280.566114) (xy 355.485204 -280.566114) (xy 355.489164 -280.51706) (xy 355.500941 -280.469276)
			(xy 355.520232 -280.424) (xy 355.546535 -280.382404) (xy 355.57917 -280.345567) (xy 355.617291 -280.314442)
			(xy 355.659912 -280.289835) (xy 355.705928 -280.272383) (xy 355.754147 -280.262539) (xy 355.803322 -280.260558)
			(xy 355.852177 -280.26649) (xy 355.899448 -280.280182) (xy 355.94391 -280.30128) (xy 355.984413 -280.329236)
			(xy 356.019906 -280.363328) (xy 356.049471 -280.402672) (xy 356.072342 -280.446249) (xy 356.087926 -280.49293)
			(xy 356.095821 -280.541507) (xy 356.096316 -280.566114) (xy 358.305366 -280.566114) (xy 358.309326 -280.51706)
			(xy 358.321103 -280.469276) (xy 358.340394 -280.424) (xy 358.366697 -280.382404) (xy 358.399332 -280.345567)
			(xy 358.437453 -280.314442) (xy 358.480074 -280.289835) (xy 358.52609 -280.272383) (xy 358.574309 -280.262539)
			(xy 358.623484 -280.260558) (xy 358.672339 -280.26649) (xy 358.71961 -280.280182) (xy 358.764072 -280.30128)
			(xy 358.804575 -280.329236) (xy 358.840068 -280.363328) (xy 358.869633 -280.402672) (xy 358.892504 -280.446249)
			(xy 358.908088 -280.49293) (xy 358.915983 -280.541507) (xy 358.916478 -280.566114) (xy 361.118924 -280.566114)
			(xy 361.122884 -280.51706) (xy 361.134661 -280.469276) (xy 361.153952 -280.424) (xy 361.180255 -280.382404)
			(xy 361.21289 -280.345567) (xy 361.251011 -280.314442) (xy 361.293632 -280.289835) (xy 361.339648 -280.272383)
			(xy 361.387867 -280.262539) (xy 361.437042 -280.260558) (xy 361.485897 -280.26649) (xy 361.533168 -280.280182)
			(xy 361.57763 -280.30128) (xy 361.618133 -280.329236) (xy 361.653626 -280.363328) (xy 361.683191 -280.402672)
			(xy 361.706062 -280.446249) (xy 361.721646 -280.49293) (xy 361.729541 -280.541507) (xy 361.730036 -280.566114)
			(xy 363.939086 -280.566114) (xy 363.943046 -280.51706) (xy 363.954823 -280.469276) (xy 363.974114 -280.424)
			(xy 364.000417 -280.382404) (xy 364.033052 -280.345567) (xy 364.071173 -280.314442) (xy 364.113794 -280.289835)
			(xy 364.15981 -280.272383) (xy 364.208029 -280.262539) (xy 364.257204 -280.260558) (xy 364.306059 -280.26649)
			(xy 364.35333 -280.280182) (xy 364.397792 -280.30128) (xy 364.438295 -280.329236) (xy 364.473788 -280.363328)
			(xy 364.503353 -280.402672) (xy 364.526224 -280.446249) (xy 364.541808 -280.49293) (xy 364.549703 -280.541507)
			(xy 364.550198 -280.566114) (xy 364.878886 -280.566114) (xy 364.882846 -280.51706) (xy 364.894623 -280.469276)
			(xy 364.913914 -280.424) (xy 364.940217 -280.382404) (xy 364.972852 -280.345567) (xy 365.010973 -280.314442)
			(xy 365.053594 -280.289835) (xy 365.09961 -280.272383) (xy 365.147829 -280.262539) (xy 365.197004 -280.260558)
			(xy 365.245859 -280.26649) (xy 365.29313 -280.280182) (xy 365.337592 -280.30128) (xy 365.378095 -280.329236)
			(xy 365.413588 -280.363328) (xy 365.443153 -280.402672) (xy 365.466024 -280.446249) (xy 365.481608 -280.49293)
			(xy 365.489503 -280.541507) (xy 365.489998 -280.566114) (xy 365.81894 -280.566114) (xy 365.8229 -280.51706)
			(xy 365.834677 -280.469276) (xy 365.853968 -280.424) (xy 365.880271 -280.382404) (xy 365.912906 -280.345567)
			(xy 365.951027 -280.314442) (xy 365.993648 -280.289835) (xy 366.039664 -280.272383) (xy 366.087883 -280.262539)
			(xy 366.137058 -280.260558) (xy 366.185913 -280.26649) (xy 366.233184 -280.280182) (xy 366.277646 -280.30128)
			(xy 366.318149 -280.329236) (xy 366.353642 -280.363328) (xy 366.383207 -280.402672) (xy 366.406078 -280.446249)
			(xy 366.421662 -280.49293) (xy 366.429557 -280.541507) (xy 366.430052 -280.566114) (xy 366.758994 -280.566114)
			(xy 366.762954 -280.51706) (xy 366.774731 -280.469276) (xy 366.794022 -280.424) (xy 366.820325 -280.382404)
			(xy 366.85296 -280.345567) (xy 366.891081 -280.314442) (xy 366.933702 -280.289835) (xy 366.979718 -280.272383)
			(xy 367.027937 -280.262539) (xy 367.077112 -280.260558) (xy 367.125967 -280.26649) (xy 367.173238 -280.280182)
			(xy 367.2177 -280.30128) (xy 367.258203 -280.329236) (xy 367.293696 -280.363328) (xy 367.323261 -280.402672)
			(xy 367.346132 -280.446249) (xy 367.361716 -280.49293) (xy 367.369611 -280.541507) (xy 367.370106 -280.566114)
			(xy 367.699048 -280.566114) (xy 367.703008 -280.51706) (xy 367.714785 -280.469276) (xy 367.734076 -280.424)
			(xy 367.760379 -280.382404) (xy 367.793014 -280.345567) (xy 367.831135 -280.314442) (xy 367.873756 -280.289835)
			(xy 367.919772 -280.272383) (xy 367.967991 -280.262539) (xy 368.017166 -280.260558) (xy 368.066021 -280.26649)
			(xy 368.113292 -280.280182) (xy 368.157754 -280.30128) (xy 368.198257 -280.329236) (xy 368.23375 -280.363328)
			(xy 368.263315 -280.402672) (xy 368.286186 -280.446249) (xy 368.30177 -280.49293) (xy 368.309665 -280.541507)
			(xy 368.31016 -280.566114) (xy 368.639102 -280.566114) (xy 368.643062 -280.51706) (xy 368.654839 -280.469276)
			(xy 368.67413 -280.424) (xy 368.700433 -280.382404) (xy 368.733068 -280.345567) (xy 368.771189 -280.314442)
			(xy 368.81381 -280.289835) (xy 368.859826 -280.272383) (xy 368.908045 -280.262539) (xy 368.95722 -280.260558)
			(xy 369.006075 -280.26649) (xy 369.053346 -280.280182) (xy 369.097808 -280.30128) (xy 369.138311 -280.329236)
			(xy 369.173804 -280.363328) (xy 369.203369 -280.402672) (xy 369.22624 -280.446249) (xy 369.241824 -280.49293)
			(xy 369.249719 -280.541507) (xy 369.250214 -280.566114) (xy 369.578902 -280.566114) (xy 369.582862 -280.51706)
			(xy 369.594639 -280.469276) (xy 369.61393 -280.424) (xy 369.640233 -280.382404) (xy 369.672868 -280.345567)
			(xy 369.710989 -280.314442) (xy 369.75361 -280.289835) (xy 369.799626 -280.272383) (xy 369.847845 -280.262539)
			(xy 369.89702 -280.260558) (xy 369.945875 -280.26649) (xy 369.993146 -280.280182) (xy 370.037608 -280.30128)
			(xy 370.078111 -280.329236) (xy 370.113604 -280.363328) (xy 370.143169 -280.402672) (xy 370.16604 -280.446249)
			(xy 370.181624 -280.49293) (xy 370.189519 -280.541507) (xy 370.190014 -280.566114) (xy 370.518956 -280.566114)
			(xy 370.522916 -280.51706) (xy 370.534693 -280.469276) (xy 370.553984 -280.424) (xy 370.580287 -280.382404)
			(xy 370.612922 -280.345567) (xy 370.651043 -280.314442) (xy 370.693664 -280.289835) (xy 370.73968 -280.272383)
			(xy 370.787899 -280.262539) (xy 370.837074 -280.260558) (xy 370.885929 -280.26649) (xy 370.9332 -280.280182)
			(xy 370.977662 -280.30128) (xy 371.018165 -280.329236) (xy 371.053658 -280.363328) (xy 371.083223 -280.402672)
			(xy 371.106094 -280.446249) (xy 371.121678 -280.49293) (xy 371.129573 -280.541507) (xy 371.130068 -280.566114)
			(xy 371.45901 -280.566114) (xy 371.46297 -280.51706) (xy 371.474747 -280.469276) (xy 371.494038 -280.424)
			(xy 371.520341 -280.382404) (xy 371.552976 -280.345567) (xy 371.591097 -280.314442) (xy 371.633718 -280.289835)
			(xy 371.679734 -280.272383) (xy 371.727953 -280.262539) (xy 371.777128 -280.260558) (xy 371.825983 -280.26649)
			(xy 371.873254 -280.280182) (xy 371.917716 -280.30128) (xy 371.958219 -280.329236) (xy 371.993712 -280.363328)
			(xy 372.023277 -280.402672) (xy 372.046148 -280.446249) (xy 372.061732 -280.49293) (xy 372.069627 -280.541507)
			(xy 372.070122 -280.566114) (xy 372.399064 -280.566114) (xy 372.403024 -280.51706) (xy 372.414801 -280.469276)
			(xy 372.434092 -280.424) (xy 372.460395 -280.382404) (xy 372.49303 -280.345567) (xy 372.531151 -280.314442)
			(xy 372.573772 -280.289835) (xy 372.619788 -280.272383) (xy 372.668007 -280.262539) (xy 372.717182 -280.260558)
			(xy 372.766037 -280.26649) (xy 372.813308 -280.280182) (xy 372.85777 -280.30128) (xy 372.898273 -280.329236)
			(xy 372.933766 -280.363328) (xy 372.963331 -280.402672) (xy 372.986202 -280.446249) (xy 373.001786 -280.49293)
			(xy 373.009681 -280.541507) (xy 373.010176 -280.566114) (xy 373.339118 -280.566114) (xy 373.343078 -280.51706)
			(xy 373.354855 -280.469276) (xy 373.374146 -280.424) (xy 373.400449 -280.382404) (xy 373.433084 -280.345567)
			(xy 373.471205 -280.314442) (xy 373.513826 -280.289835) (xy 373.559842 -280.272383) (xy 373.608061 -280.262539)
			(xy 373.657236 -280.260558) (xy 373.706091 -280.26649) (xy 373.753362 -280.280182) (xy 373.797824 -280.30128)
			(xy 373.838327 -280.329236) (xy 373.87382 -280.363328) (xy 373.903385 -280.402672) (xy 373.926256 -280.446249)
			(xy 373.94184 -280.49293) (xy 373.949735 -280.541507) (xy 373.95023 -280.566114) (xy 374.278918 -280.566114)
			(xy 374.282878 -280.51706) (xy 374.294655 -280.469276) (xy 374.313946 -280.424) (xy 374.340249 -280.382404)
			(xy 374.372884 -280.345567) (xy 374.411005 -280.314442) (xy 374.453626 -280.289835) (xy 374.499642 -280.272383)
			(xy 374.547861 -280.262539) (xy 374.597036 -280.260558) (xy 374.645891 -280.26649) (xy 374.693162 -280.280182)
			(xy 374.737624 -280.30128) (xy 374.778127 -280.329236) (xy 374.81362 -280.363328) (xy 374.843185 -280.402672)
			(xy 374.866056 -280.446249) (xy 374.88164 -280.49293) (xy 374.889535 -280.541507) (xy 374.89003 -280.566114)
			(xy 375.218972 -280.566114) (xy 375.222932 -280.51706) (xy 375.234709 -280.469276) (xy 375.254 -280.424)
			(xy 375.280303 -280.382404) (xy 375.312938 -280.345567) (xy 375.351059 -280.314442) (xy 375.39368 -280.289835)
			(xy 375.439696 -280.272383) (xy 375.487915 -280.262539) (xy 375.53709 -280.260558) (xy 375.585945 -280.26649)
			(xy 375.633216 -280.280182) (xy 375.677678 -280.30128) (xy 375.718181 -280.329236) (xy 375.753674 -280.363328)
			(xy 375.783239 -280.402672) (xy 375.80611 -280.446249) (xy 375.821694 -280.49293) (xy 375.829589 -280.541507)
			(xy 375.830084 -280.566114) (xy 376.148595 -280.566114) (xy 376.15269 -280.515386) (xy 376.164869 -280.465972)
			(xy 376.184817 -280.419152) (xy 376.212018 -280.376138) (xy 376.245766 -280.338044) (xy 376.285188 -280.305857)
			(xy 376.329262 -280.280411) (xy 376.376848 -280.262364) (xy 376.426712 -280.252184) (xy 376.477564 -280.250135)
			(xy 376.528085 -280.256269) (xy 376.576969 -280.270429) (xy 376.622948 -280.292246) (xy 376.664832 -280.321156)
			(xy 376.701536 -280.356411) (xy 376.732109 -280.397097) (xy 376.75576 -280.44216) (xy 376.771876 -280.490434)
			(xy 376.78004 -280.540668) (xy 376.780552 -280.566114) (xy 377.088649 -280.566114) (xy 377.092744 -280.515386)
			(xy 377.104923 -280.465972) (xy 377.124871 -280.419152) (xy 377.152072 -280.376138) (xy 377.18582 -280.338044)
			(xy 377.225242 -280.305857) (xy 377.269316 -280.280411) (xy 377.316902 -280.262364) (xy 377.366766 -280.252184)
			(xy 377.417618 -280.250135) (xy 377.468139 -280.256269) (xy 377.517023 -280.270429) (xy 377.563002 -280.292246)
			(xy 377.604886 -280.321156) (xy 377.64159 -280.356411) (xy 377.672163 -280.397097) (xy 377.695814 -280.44216)
			(xy 377.71193 -280.490434) (xy 377.720094 -280.540668) (xy 377.720606 -280.566114) (xy 377.720094 -280.59156)
			(xy 377.71193 -280.641794) (xy 377.695814 -280.690068) (xy 377.672163 -280.735131) (xy 377.64159 -280.775817)
			(xy 377.604886 -280.811072) (xy 377.563002 -280.839982) (xy 377.517023 -280.861799) (xy 377.468139 -280.875959)
			(xy 377.417618 -280.882093) (xy 377.366766 -280.880044) (xy 377.316902 -280.869864) (xy 377.269316 -280.851817)
			(xy 377.225242 -280.826371) (xy 377.18582 -280.794184) (xy 377.152072 -280.75609) (xy 377.124871 -280.713076)
			(xy 377.104923 -280.666256) (xy 377.092744 -280.616842) (xy 377.088649 -280.566114) (xy 376.780552 -280.566114)
			(xy 376.78004 -280.59156) (xy 376.771876 -280.641794) (xy 376.75576 -280.690068) (xy 376.732109 -280.735131)
			(xy 376.701536 -280.775817) (xy 376.664832 -280.811072) (xy 376.622948 -280.839982) (xy 376.576969 -280.861799)
			(xy 376.528085 -280.875959) (xy 376.477564 -280.882093) (xy 376.426712 -280.880044) (xy 376.376848 -280.869864)
			(xy 376.329262 -280.851817) (xy 376.285188 -280.826371) (xy 376.245766 -280.794184) (xy 376.212018 -280.75609)
			(xy 376.184817 -280.713076) (xy 376.164869 -280.666256) (xy 376.15269 -280.616842) (xy 376.148595 -280.566114)
			(xy 375.830084 -280.566114) (xy 375.829589 -280.590721) (xy 375.821694 -280.639298) (xy 375.80611 -280.685979)
			(xy 375.783239 -280.729556) (xy 375.753674 -280.7689) (xy 375.718181 -280.802992) (xy 375.677678 -280.830948)
			(xy 375.633216 -280.852046) (xy 375.585945 -280.865738) (xy 375.53709 -280.87167) (xy 375.487915 -280.869689)
			(xy 375.439696 -280.859845) (xy 375.39368 -280.842393) (xy 375.351059 -280.817786) (xy 375.312938 -280.786661)
			(xy 375.280303 -280.749824) (xy 375.254 -280.708228) (xy 375.234709 -280.662952) (xy 375.222932 -280.615168)
			(xy 375.218972 -280.566114) (xy 374.89003 -280.566114) (xy 374.889535 -280.590721) (xy 374.88164 -280.639298)
			(xy 374.866056 -280.685979) (xy 374.843185 -280.729556) (xy 374.81362 -280.7689) (xy 374.778127 -280.802992)
			(xy 374.737624 -280.830948) (xy 374.693162 -280.852046) (xy 374.645891 -280.865738) (xy 374.597036 -280.87167)
			(xy 374.547861 -280.869689) (xy 374.499642 -280.859845) (xy 374.453626 -280.842393) (xy 374.411005 -280.817786)
			(xy 374.372884 -280.786661) (xy 374.340249 -280.749824) (xy 374.313946 -280.708228) (xy 374.294655 -280.662952)
			(xy 374.282878 -280.615168) (xy 374.278918 -280.566114) (xy 373.95023 -280.566114) (xy 373.949735 -280.590721)
			(xy 373.94184 -280.639298) (xy 373.926256 -280.685979) (xy 373.903385 -280.729556) (xy 373.87382 -280.7689)
			(xy 373.838327 -280.802992) (xy 373.797824 -280.830948) (xy 373.753362 -280.852046) (xy 373.706091 -280.865738)
			(xy 373.657236 -280.87167) (xy 373.608061 -280.869689) (xy 373.559842 -280.859845) (xy 373.513826 -280.842393)
			(xy 373.471205 -280.817786) (xy 373.433084 -280.786661) (xy 373.400449 -280.749824) (xy 373.374146 -280.708228)
			(xy 373.354855 -280.662952) (xy 373.343078 -280.615168) (xy 373.339118 -280.566114) (xy 373.010176 -280.566114)
			(xy 373.009681 -280.590721) (xy 373.001786 -280.639298) (xy 372.986202 -280.685979) (xy 372.963331 -280.729556)
			(xy 372.933766 -280.7689) (xy 372.898273 -280.802992) (xy 372.85777 -280.830948) (xy 372.813308 -280.852046)
			(xy 372.766037 -280.865738) (xy 372.717182 -280.87167) (xy 372.668007 -280.869689) (xy 372.619788 -280.859845)
			(xy 372.573772 -280.842393) (xy 372.531151 -280.817786) (xy 372.49303 -280.786661) (xy 372.460395 -280.749824)
			(xy 372.434092 -280.708228) (xy 372.414801 -280.662952) (xy 372.403024 -280.615168) (xy 372.399064 -280.566114)
			(xy 372.070122 -280.566114) (xy 372.069627 -280.590721) (xy 372.061732 -280.639298) (xy 372.046148 -280.685979)
			(xy 372.023277 -280.729556) (xy 371.993712 -280.7689) (xy 371.958219 -280.802992) (xy 371.917716 -280.830948)
			(xy 371.873254 -280.852046) (xy 371.825983 -280.865738) (xy 371.777128 -280.87167) (xy 371.727953 -280.869689)
			(xy 371.679734 -280.859845) (xy 371.633718 -280.842393) (xy 371.591097 -280.817786) (xy 371.552976 -280.786661)
			(xy 371.520341 -280.749824) (xy 371.494038 -280.708228) (xy 371.474747 -280.662952) (xy 371.46297 -280.615168)
			(xy 371.45901 -280.566114) (xy 371.130068 -280.566114) (xy 371.129573 -280.590721) (xy 371.121678 -280.639298)
			(xy 371.106094 -280.685979) (xy 371.083223 -280.729556) (xy 371.053658 -280.7689) (xy 371.018165 -280.802992)
			(xy 370.977662 -280.830948) (xy 370.9332 -280.852046) (xy 370.885929 -280.865738) (xy 370.837074 -280.87167)
			(xy 370.787899 -280.869689) (xy 370.73968 -280.859845) (xy 370.693664 -280.842393) (xy 370.651043 -280.817786)
			(xy 370.612922 -280.786661) (xy 370.580287 -280.749824) (xy 370.553984 -280.708228) (xy 370.534693 -280.662952)
			(xy 370.522916 -280.615168) (xy 370.518956 -280.566114) (xy 370.190014 -280.566114) (xy 370.189519 -280.590721)
			(xy 370.181624 -280.639298) (xy 370.16604 -280.685979) (xy 370.143169 -280.729556) (xy 370.113604 -280.7689)
			(xy 370.078111 -280.802992) (xy 370.037608 -280.830948) (xy 369.993146 -280.852046) (xy 369.945875 -280.865738)
			(xy 369.89702 -280.87167) (xy 369.847845 -280.869689) (xy 369.799626 -280.859845) (xy 369.75361 -280.842393)
			(xy 369.710989 -280.817786) (xy 369.672868 -280.786661) (xy 369.640233 -280.749824) (xy 369.61393 -280.708228)
			(xy 369.594639 -280.662952) (xy 369.582862 -280.615168) (xy 369.578902 -280.566114) (xy 369.250214 -280.566114)
			(xy 369.249719 -280.590721) (xy 369.241824 -280.639298) (xy 369.22624 -280.685979) (xy 369.203369 -280.729556)
			(xy 369.173804 -280.7689) (xy 369.138311 -280.802992) (xy 369.097808 -280.830948) (xy 369.053346 -280.852046)
			(xy 369.006075 -280.865738) (xy 368.95722 -280.87167) (xy 368.908045 -280.869689) (xy 368.859826 -280.859845)
			(xy 368.81381 -280.842393) (xy 368.771189 -280.817786) (xy 368.733068 -280.786661) (xy 368.700433 -280.749824)
			(xy 368.67413 -280.708228) (xy 368.654839 -280.662952) (xy 368.643062 -280.615168) (xy 368.639102 -280.566114)
			(xy 368.31016 -280.566114) (xy 368.309665 -280.590721) (xy 368.30177 -280.639298) (xy 368.286186 -280.685979)
			(xy 368.263315 -280.729556) (xy 368.23375 -280.7689) (xy 368.198257 -280.802992) (xy 368.157754 -280.830948)
			(xy 368.113292 -280.852046) (xy 368.066021 -280.865738) (xy 368.017166 -280.87167) (xy 367.967991 -280.869689)
			(xy 367.919772 -280.859845) (xy 367.873756 -280.842393) (xy 367.831135 -280.817786) (xy 367.793014 -280.786661)
			(xy 367.760379 -280.749824) (xy 367.734076 -280.708228) (xy 367.714785 -280.662952) (xy 367.703008 -280.615168)
			(xy 367.699048 -280.566114) (xy 367.370106 -280.566114) (xy 367.369611 -280.590721) (xy 367.361716 -280.639298)
			(xy 367.346132 -280.685979) (xy 367.323261 -280.729556) (xy 367.293696 -280.7689) (xy 367.258203 -280.802992)
			(xy 367.2177 -280.830948) (xy 367.173238 -280.852046) (xy 367.125967 -280.865738) (xy 367.077112 -280.87167)
			(xy 367.027937 -280.869689) (xy 366.979718 -280.859845) (xy 366.933702 -280.842393) (xy 366.891081 -280.817786)
			(xy 366.85296 -280.786661) (xy 366.820325 -280.749824) (xy 366.794022 -280.708228) (xy 366.774731 -280.662952)
			(xy 366.762954 -280.615168) (xy 366.758994 -280.566114) (xy 366.430052 -280.566114) (xy 366.429557 -280.590721)
			(xy 366.421662 -280.639298) (xy 366.406078 -280.685979) (xy 366.383207 -280.729556) (xy 366.353642 -280.7689)
			(xy 366.318149 -280.802992) (xy 366.277646 -280.830948) (xy 366.233184 -280.852046) (xy 366.185913 -280.865738)
			(xy 366.137058 -280.87167) (xy 366.087883 -280.869689) (xy 366.039664 -280.859845) (xy 365.993648 -280.842393)
			(xy 365.951027 -280.817786) (xy 365.912906 -280.786661) (xy 365.880271 -280.749824) (xy 365.853968 -280.708228)
			(xy 365.834677 -280.662952) (xy 365.8229 -280.615168) (xy 365.81894 -280.566114) (xy 365.489998 -280.566114)
			(xy 365.489503 -280.590721) (xy 365.481608 -280.639298) (xy 365.466024 -280.685979) (xy 365.443153 -280.729556)
			(xy 365.413588 -280.7689) (xy 365.378095 -280.802992) (xy 365.337592 -280.830948) (xy 365.29313 -280.852046)
			(xy 365.245859 -280.865738) (xy 365.197004 -280.87167) (xy 365.147829 -280.869689) (xy 365.09961 -280.859845)
			(xy 365.053594 -280.842393) (xy 365.010973 -280.817786) (xy 364.972852 -280.786661) (xy 364.940217 -280.749824)
			(xy 364.913914 -280.708228) (xy 364.894623 -280.662952) (xy 364.882846 -280.615168) (xy 364.878886 -280.566114)
			(xy 364.550198 -280.566114) (xy 364.549703 -280.590721) (xy 364.541808 -280.639298) (xy 364.526224 -280.685979)
			(xy 364.503353 -280.729556) (xy 364.473788 -280.7689) (xy 364.438295 -280.802992) (xy 364.397792 -280.830948)
			(xy 364.35333 -280.852046) (xy 364.306059 -280.865738) (xy 364.257204 -280.87167) (xy 364.208029 -280.869689)
			(xy 364.15981 -280.859845) (xy 364.113794 -280.842393) (xy 364.071173 -280.817786) (xy 364.033052 -280.786661)
			(xy 364.000417 -280.749824) (xy 363.974114 -280.708228) (xy 363.954823 -280.662952) (xy 363.943046 -280.615168)
			(xy 363.939086 -280.566114) (xy 361.730036 -280.566114) (xy 361.729541 -280.590721) (xy 361.721646 -280.639298)
			(xy 361.706062 -280.685979) (xy 361.683191 -280.729556) (xy 361.653626 -280.7689) (xy 361.618133 -280.802992)
			(xy 361.57763 -280.830948) (xy 361.533168 -280.852046) (xy 361.485897 -280.865738) (xy 361.437042 -280.87167)
			(xy 361.387867 -280.869689) (xy 361.339648 -280.859845) (xy 361.293632 -280.842393) (xy 361.251011 -280.817786)
			(xy 361.21289 -280.786661) (xy 361.180255 -280.749824) (xy 361.153952 -280.708228) (xy 361.134661 -280.662952)
			(xy 361.122884 -280.615168) (xy 361.118924 -280.566114) (xy 358.916478 -280.566114) (xy 358.915983 -280.590721)
			(xy 358.908088 -280.639298) (xy 358.892504 -280.685979) (xy 358.869633 -280.729556) (xy 358.840068 -280.7689)
			(xy 358.804575 -280.802992) (xy 358.764072 -280.830948) (xy 358.71961 -280.852046) (xy 358.672339 -280.865738)
			(xy 358.623484 -280.87167) (xy 358.574309 -280.869689) (xy 358.52609 -280.859845) (xy 358.480074 -280.842393)
			(xy 358.437453 -280.817786) (xy 358.399332 -280.786661) (xy 358.366697 -280.749824) (xy 358.340394 -280.708228)
			(xy 358.321103 -280.662952) (xy 358.309326 -280.615168) (xy 358.305366 -280.566114) (xy 356.096316 -280.566114)
			(xy 356.095821 -280.590721) (xy 356.087926 -280.639298) (xy 356.072342 -280.685979) (xy 356.049471 -280.729556)
			(xy 356.019906 -280.7689) (xy 355.984413 -280.802992) (xy 355.94391 -280.830948) (xy 355.899448 -280.852046)
			(xy 355.852177 -280.865738) (xy 355.803322 -280.87167) (xy 355.754147 -280.869689) (xy 355.705928 -280.859845)
			(xy 355.659912 -280.842393) (xy 355.617291 -280.817786) (xy 355.57917 -280.786661) (xy 355.546535 -280.749824)
			(xy 355.520232 -280.708228) (xy 355.500941 -280.662952) (xy 355.489164 -280.615168) (xy 355.485204 -280.566114)
			(xy 355.156516 -280.566114) (xy 355.156021 -280.590721) (xy 355.148126 -280.639298) (xy 355.132542 -280.685979)
			(xy 355.109671 -280.729556) (xy 355.080106 -280.7689) (xy 355.044613 -280.802992) (xy 355.00411 -280.830948)
			(xy 354.959648 -280.852046) (xy 354.912377 -280.865738) (xy 354.863522 -280.87167) (xy 354.814347 -280.869689)
			(xy 354.766128 -280.859845) (xy 354.720112 -280.842393) (xy 354.677491 -280.817786) (xy 354.63937 -280.786661)
			(xy 354.606735 -280.749824) (xy 354.580432 -280.708228) (xy 354.561141 -280.662952) (xy 354.549364 -280.615168)
			(xy 354.545404 -280.566114) (xy 354.216462 -280.566114) (xy 354.215967 -280.590721) (xy 354.208072 -280.639298)
			(xy 354.192488 -280.685979) (xy 354.169617 -280.729556) (xy 354.140052 -280.7689) (xy 354.104559 -280.802992)
			(xy 354.064056 -280.830948) (xy 354.019594 -280.852046) (xy 353.972323 -280.865738) (xy 353.923468 -280.87167)
			(xy 353.874293 -280.869689) (xy 353.826074 -280.859845) (xy 353.780058 -280.842393) (xy 353.737437 -280.817786)
			(xy 353.699316 -280.786661) (xy 353.666681 -280.749824) (xy 353.640378 -280.708228) (xy 353.621087 -280.662952)
			(xy 353.60931 -280.615168) (xy 353.60535 -280.566114) (xy 353.276408 -280.566114) (xy 353.275913 -280.590721)
			(xy 353.268018 -280.639298) (xy 353.252434 -280.685979) (xy 353.229563 -280.729556) (xy 353.199998 -280.7689)
			(xy 353.164505 -280.802992) (xy 353.124002 -280.830948) (xy 353.07954 -280.852046) (xy 353.032269 -280.865738)
			(xy 352.983414 -280.87167) (xy 352.934239 -280.869689) (xy 352.88602 -280.859845) (xy 352.840004 -280.842393)
			(xy 352.797383 -280.817786) (xy 352.759262 -280.786661) (xy 352.726627 -280.749824) (xy 352.700324 -280.708228)
			(xy 352.681033 -280.662952) (xy 352.669256 -280.615168) (xy 352.665296 -280.566114) (xy 352.336354 -280.566114)
			(xy 352.335859 -280.590721) (xy 352.327964 -280.639298) (xy 352.31238 -280.685979) (xy 352.289509 -280.729556)
			(xy 352.259944 -280.7689) (xy 352.224451 -280.802992) (xy 352.183948 -280.830948) (xy 352.139486 -280.852046)
			(xy 352.092215 -280.865738) (xy 352.04336 -280.87167) (xy 351.994185 -280.869689) (xy 351.945966 -280.859845)
			(xy 351.89995 -280.842393) (xy 351.857329 -280.817786) (xy 351.819208 -280.786661) (xy 351.786573 -280.749824)
			(xy 351.76027 -280.708228) (xy 351.740979 -280.662952) (xy 351.729202 -280.615168) (xy 351.725242 -280.566114)
			(xy 351.396554 -280.566114) (xy 351.396059 -280.590721) (xy 351.388164 -280.639298) (xy 351.37258 -280.685979)
			(xy 351.349709 -280.729556) (xy 351.320144 -280.7689) (xy 351.284651 -280.802992) (xy 351.244148 -280.830948)
			(xy 351.199686 -280.852046) (xy 351.152415 -280.865738) (xy 351.10356 -280.87167) (xy 351.054385 -280.869689)
			(xy 351.006166 -280.859845) (xy 350.96015 -280.842393) (xy 350.917529 -280.817786) (xy 350.879408 -280.786661)
			(xy 350.846773 -280.749824) (xy 350.82047 -280.708228) (xy 350.801179 -280.662952) (xy 350.789402 -280.615168)
			(xy 350.785442 -280.566114) (xy 350.4565 -280.566114) (xy 350.456005 -280.590721) (xy 350.44811 -280.639298)
			(xy 350.432526 -280.685979) (xy 350.409655 -280.729556) (xy 350.38009 -280.7689) (xy 350.344597 -280.802992)
			(xy 350.304094 -280.830948) (xy 350.259632 -280.852046) (xy 350.212361 -280.865738) (xy 350.163506 -280.87167)
			(xy 350.114331 -280.869689) (xy 350.066112 -280.859845) (xy 350.020096 -280.842393) (xy 349.977475 -280.817786)
			(xy 349.939354 -280.786661) (xy 349.906719 -280.749824) (xy 349.880416 -280.708228) (xy 349.861125 -280.662952)
			(xy 349.849348 -280.615168) (xy 349.845388 -280.566114) (xy 349.516446 -280.566114) (xy 349.515951 -280.590721)
			(xy 349.508056 -280.639298) (xy 349.492472 -280.685979) (xy 349.469601 -280.729556) (xy 349.440036 -280.7689)
			(xy 349.404543 -280.802992) (xy 349.36404 -280.830948) (xy 349.319578 -280.852046) (xy 349.272307 -280.865738)
			(xy 349.223452 -280.87167) (xy 349.174277 -280.869689) (xy 349.126058 -280.859845) (xy 349.080042 -280.842393)
			(xy 349.037421 -280.817786) (xy 348.9993 -280.786661) (xy 348.966665 -280.749824) (xy 348.940362 -280.708228)
			(xy 348.921071 -280.662952) (xy 348.909294 -280.615168) (xy 348.905334 -280.566114) (xy 348.576392 -280.566114)
			(xy 348.575897 -280.590721) (xy 348.568002 -280.639298) (xy 348.552418 -280.685979) (xy 348.529547 -280.729556)
			(xy 348.499982 -280.7689) (xy 348.464489 -280.802992) (xy 348.423986 -280.830948) (xy 348.379524 -280.852046)
			(xy 348.332253 -280.865738) (xy 348.283398 -280.87167) (xy 348.234223 -280.869689) (xy 348.186004 -280.859845)
			(xy 348.139988 -280.842393) (xy 348.097367 -280.817786) (xy 348.059246 -280.786661) (xy 348.026611 -280.749824)
			(xy 348.000308 -280.708228) (xy 347.981017 -280.662952) (xy 347.96924 -280.615168) (xy 347.96528 -280.566114)
			(xy 347.636338 -280.566114) (xy 347.635843 -280.590721) (xy 347.627948 -280.639298) (xy 347.612364 -280.685979)
			(xy 347.589493 -280.729556) (xy 347.559928 -280.7689) (xy 347.524435 -280.802992) (xy 347.483932 -280.830948)
			(xy 347.43947 -280.852046) (xy 347.392199 -280.865738) (xy 347.343344 -280.87167) (xy 347.294169 -280.869689)
			(xy 347.24595 -280.859845) (xy 347.199934 -280.842393) (xy 347.157313 -280.817786) (xy 347.119192 -280.786661)
			(xy 347.086557 -280.749824) (xy 347.060254 -280.708228) (xy 347.040963 -280.662952) (xy 347.029186 -280.615168)
			(xy 347.025226 -280.566114) (xy 346.696538 -280.566114) (xy 346.696043 -280.590721) (xy 346.688148 -280.639298)
			(xy 346.672564 -280.685979) (xy 346.649693 -280.729556) (xy 346.620128 -280.7689) (xy 346.584635 -280.802992)
			(xy 346.544132 -280.830948) (xy 346.49967 -280.852046) (xy 346.452399 -280.865738) (xy 346.403544 -280.87167)
			(xy 346.354369 -280.869689) (xy 346.30615 -280.859845) (xy 346.260134 -280.842393) (xy 346.217513 -280.817786)
			(xy 346.179392 -280.786661) (xy 346.146757 -280.749824) (xy 346.120454 -280.708228) (xy 346.101163 -280.662952)
			(xy 346.089386 -280.615168) (xy 346.085426 -280.566114) (xy 345.756484 -280.566114) (xy 345.755989 -280.590721)
			(xy 345.748094 -280.639298) (xy 345.73251 -280.685979) (xy 345.709639 -280.729556) (xy 345.680074 -280.7689)
			(xy 345.644581 -280.802992) (xy 345.604078 -280.830948) (xy 345.559616 -280.852046) (xy 345.512345 -280.865738)
			(xy 345.46349 -280.87167) (xy 345.414315 -280.869689) (xy 345.366096 -280.859845) (xy 345.32008 -280.842393)
			(xy 345.277459 -280.817786) (xy 345.239338 -280.786661) (xy 345.206703 -280.749824) (xy 345.1804 -280.708228)
			(xy 345.161109 -280.662952) (xy 345.149332 -280.615168) (xy 345.145372 -280.566114) (xy 344.81643 -280.566114)
			(xy 344.815935 -280.590721) (xy 344.80804 -280.639298) (xy 344.792456 -280.685979) (xy 344.769585 -280.729556)
			(xy 344.74002 -280.7689) (xy 344.704527 -280.802992) (xy 344.664024 -280.830948) (xy 344.619562 -280.852046)
			(xy 344.572291 -280.865738) (xy 344.523436 -280.87167) (xy 344.474261 -280.869689) (xy 344.426042 -280.859845)
			(xy 344.380026 -280.842393) (xy 344.337405 -280.817786) (xy 344.299284 -280.786661) (xy 344.266649 -280.749824)
			(xy 344.240346 -280.708228) (xy 344.221055 -280.662952) (xy 344.209278 -280.615168) (xy 344.205318 -280.566114)
			(xy 343.88679 -280.566114) (xy 343.886278 -280.59156) (xy 343.878114 -280.641794) (xy 343.861998 -280.690068)
			(xy 343.838347 -280.735131) (xy 343.807774 -280.775817) (xy 343.77107 -280.811072) (xy 343.729186 -280.839982)
			(xy 343.683207 -280.861799) (xy 343.634323 -280.875959) (xy 343.583802 -280.882093) (xy 343.53295 -280.880044)
			(xy 343.483086 -280.869864) (xy 343.4355 -280.851817) (xy 343.391426 -280.826371) (xy 343.352004 -280.794184)
			(xy 343.318256 -280.75609) (xy 343.291055 -280.713076) (xy 343.271107 -280.666256) (xy 343.258928 -280.616842)
			(xy 343.254833 -280.566114) (xy 342.946736 -280.566114) (xy 342.946224 -280.59156) (xy 342.93806 -280.641794)
			(xy 342.921944 -280.690068) (xy 342.898293 -280.735131) (xy 342.86772 -280.775817) (xy 342.831016 -280.811072)
			(xy 342.789132 -280.839982) (xy 342.743153 -280.861799) (xy 342.694269 -280.875959) (xy 342.643748 -280.882093)
			(xy 342.592896 -280.880044) (xy 342.543032 -280.869864) (xy 342.495446 -280.851817) (xy 342.451372 -280.826371)
			(xy 342.41195 -280.794184) (xy 342.378202 -280.75609) (xy 342.351001 -280.713076) (xy 342.331053 -280.666256)
			(xy 342.318874 -280.616842) (xy 342.314779 -280.566114) (xy 341.997016 -280.566114) (xy 341.992846 -280.616434)
			(xy 341.980448 -280.665396) (xy 341.96016 -280.711649) (xy 341.932536 -280.753932) (xy 341.89833 -280.791092)
			(xy 341.858473 -280.822115) (xy 341.814055 -280.846155) (xy 341.766285 -280.862556) (xy 341.716467 -280.870871)
			(xy 341.691214 -280.871422) (xy 341.678451 -280.871286) (xy 341.653016 -280.869127) (xy 341.640414 -280.867104)
			(xy 341.640414 -280.867358) (xy 341.61696 -280.862931) (xy 341.571705 -280.847771) (xy 341.529352 -280.825768)
			(xy 341.490928 -280.797458) (xy 341.457364 -280.763526) (xy 341.443056 -280.744422) (xy 341.438992 -280.73858)
			(xy 341.428324 -280.729944) (xy 341.422482 -280.727404) (xy 341.416199 -280.724878) (xy 341.402805 -280.722937)
			(xy 341.396066 -280.723594) (xy 341.305642 -280.735024) (xy 341.293196 -280.736548) (xy 341.28202 -280.745184)
			(xy 341.27689 -280.749527) (xy 341.26891 -280.760338) (xy 341.266272 -280.76652) (xy 341.266272 -280.766774)
			(xy 341.258701 -280.785672) (xy 341.241157 -280.822412) (xy 341.23122 -280.84018) (xy 341.227918 -280.846022)
			(xy 341.226394 -280.852118) (xy 341.224616 -280.865072) (xy 341.224616 -281.02433) (xy 341.224981 -281.033344)
			(xy 341.231237 -281.050253) (xy 341.236808 -281.05735) (xy 341.24265 -281.064208) (xy 341.258652 -281.073098)
			(xy 341.267542 -281.074368) (xy 341.291259 -281.078476) (xy 341.337091 -281.093171) (xy 341.380049 -281.114877)
			(xy 341.41907 -281.143054) (xy 341.453186 -281.177005) (xy 341.481551 -281.215889) (xy 341.503464 -281.258742)
			(xy 341.518382 -281.304503) (xy 341.525933 -281.352038) (xy 341.525933 -281.37612) (xy 341.844879 -281.37612)
			(xy 341.848974 -281.325392) (xy 341.861153 -281.275978) (xy 341.881101 -281.229158) (xy 341.908302 -281.186144)
			(xy 341.94205 -281.14805) (xy 341.981472 -281.115863) (xy 342.025546 -281.090417) (xy 342.073132 -281.07237)
			(xy 342.122996 -281.06219) (xy 342.173848 -281.060141) (xy 342.224369 -281.066275) (xy 342.273253 -281.080435)
			(xy 342.319232 -281.102252) (xy 342.361116 -281.131162) (xy 342.39782 -281.166417) (xy 342.428393 -281.207103)
			(xy 342.452044 -281.252166) (xy 342.46816 -281.30044) (xy 342.476324 -281.350674) (xy 342.476836 -281.37612)
			(xy 342.795364 -281.37612) (xy 342.799324 -281.327066) (xy 342.811101 -281.279282) (xy 342.830392 -281.234006)
			(xy 342.856695 -281.19241) (xy 342.88933 -281.155573) (xy 342.927451 -281.124448) (xy 342.970072 -281.099841)
			(xy 343.016088 -281.082389) (xy 343.064307 -281.072545) (xy 343.113482 -281.070564) (xy 343.162337 -281.076496)
			(xy 343.209608 -281.090188) (xy 343.25407 -281.111286) (xy 343.294573 -281.139242) (xy 343.330066 -281.173334)
			(xy 343.359631 -281.212678) (xy 343.382502 -281.256255) (xy 343.398086 -281.302936) (xy 343.405981 -281.351513)
			(xy 343.406476 -281.37612) (xy 343.724987 -281.37612) (xy 343.729082 -281.325392) (xy 343.741261 -281.275978)
			(xy 343.761209 -281.229158) (xy 343.78841 -281.186144) (xy 343.822158 -281.14805) (xy 343.86158 -281.115863)
			(xy 343.905654 -281.090417) (xy 343.95324 -281.07237) (xy 344.003104 -281.06219) (xy 344.053956 -281.060141)
			(xy 344.104477 -281.066275) (xy 344.153361 -281.080435) (xy 344.19934 -281.102252) (xy 344.241224 -281.131162)
			(xy 344.277928 -281.166417) (xy 344.308501 -281.207103) (xy 344.332152 -281.252166) (xy 344.348268 -281.30044)
			(xy 344.356432 -281.350674) (xy 344.356944 -281.37612) (xy 344.675218 -281.37612) (xy 344.679178 -281.327066)
			(xy 344.690955 -281.279282) (xy 344.710246 -281.234006) (xy 344.736549 -281.19241) (xy 344.769184 -281.155573)
			(xy 344.807305 -281.124448) (xy 344.849926 -281.099841) (xy 344.895942 -281.082389) (xy 344.944161 -281.072545)
			(xy 344.993336 -281.070564) (xy 345.042191 -281.076496) (xy 345.089462 -281.090188) (xy 345.133924 -281.111286)
			(xy 345.174427 -281.139242) (xy 345.20992 -281.173334) (xy 345.239485 -281.212678) (xy 345.262356 -281.256255)
			(xy 345.27794 -281.302936) (xy 345.285835 -281.351513) (xy 345.28633 -281.3761) (xy 345.615289 -281.3761)
			(xy 345.619459 -281.325768) (xy 345.631857 -281.276808) (xy 345.652144 -281.230557) (xy 345.679766 -281.188275)
			(xy 345.713971 -281.151116) (xy 345.753825 -281.120094) (xy 345.798241 -281.096054) (xy 345.846008 -281.079652)
			(xy 345.895824 -281.071335) (xy 345.921076 -281.070812) (xy 346.86113 -281.070812) (xy 346.886385 -281.071296)
			(xy 346.936207 -281.079614) (xy 346.983979 -281.096019) (xy 347.028401 -281.120062) (xy 347.068259 -281.151089)
			(xy 347.102467 -281.188252) (xy 347.130092 -281.230539) (xy 347.150381 -281.276796) (xy 347.16278 -281.325762)
			(xy 347.166951 -281.3761) (xy 347.166949 -281.37612) (xy 347.49538 -281.37612) (xy 347.49934 -281.327066)
			(xy 347.511117 -281.279282) (xy 347.530408 -281.234006) (xy 347.556711 -281.19241) (xy 347.589346 -281.155573)
			(xy 347.627467 -281.124448) (xy 347.670088 -281.099841) (xy 347.716104 -281.082389) (xy 347.764323 -281.072545)
			(xy 347.813498 -281.070564) (xy 347.862353 -281.076496) (xy 347.909624 -281.090188) (xy 347.954086 -281.111286)
			(xy 347.994589 -281.139242) (xy 348.030082 -281.173334) (xy 348.059647 -281.212678) (xy 348.082518 -281.256255)
			(xy 348.098102 -281.302936) (xy 348.105997 -281.351513) (xy 348.106492 -281.3761) (xy 348.43536 -281.3761)
			(xy 348.439532 -281.325756) (xy 348.451934 -281.276786) (xy 348.472227 -281.230526) (xy 348.499859 -281.188237)
			(xy 348.534075 -281.151073) (xy 348.573942 -281.120048) (xy 348.618371 -281.096009) (xy 348.666152 -281.079611)
			(xy 348.71598 -281.071302) (xy 348.741238 -281.070812) (xy 349.681292 -281.070812) (xy 349.706552 -281.071264)
			(xy 349.756383 -281.079578) (xy 349.804165 -281.095981) (xy 349.848596 -281.120025) (xy 349.888464 -281.151054)
			(xy 349.92268 -281.188222) (xy 349.950312 -281.230515) (xy 349.970606 -281.276779) (xy 349.983008 -281.325753)
			(xy 349.98718 -281.3761) (xy 349.987178 -281.37612) (xy 350.315288 -281.37612) (xy 350.319248 -281.327066)
			(xy 350.331025 -281.279282) (xy 350.350316 -281.234006) (xy 350.376619 -281.19241) (xy 350.409254 -281.155573)
			(xy 350.447375 -281.124448) (xy 350.489996 -281.099841) (xy 350.536012 -281.082389) (xy 350.584231 -281.072545)
			(xy 350.633406 -281.070564) (xy 350.682261 -281.076496) (xy 350.729532 -281.090188) (xy 350.773994 -281.111286)
			(xy 350.814497 -281.139242) (xy 350.84999 -281.173334) (xy 350.879555 -281.212678) (xy 350.902426 -281.256255)
			(xy 350.91801 -281.302936) (xy 350.925905 -281.351513) (xy 350.9264 -281.37612) (xy 353.135196 -281.37612)
			(xy 353.139156 -281.327066) (xy 353.150933 -281.279282) (xy 353.170224 -281.234006) (xy 353.196527 -281.19241)
			(xy 353.229162 -281.155573) (xy 353.267283 -281.124448) (xy 353.309904 -281.099841) (xy 353.35592 -281.082389)
			(xy 353.404139 -281.072545) (xy 353.453314 -281.070564) (xy 353.502169 -281.076496) (xy 353.54944 -281.090188)
			(xy 353.593902 -281.111286) (xy 353.634405 -281.139242) (xy 353.669898 -281.173334) (xy 353.699463 -281.212678)
			(xy 353.722334 -281.256255) (xy 353.737918 -281.302936) (xy 353.745813 -281.351513) (xy 353.746308 -281.37612)
			(xy 355.955358 -281.37612) (xy 355.959318 -281.327066) (xy 355.971095 -281.279282) (xy 355.990386 -281.234006)
			(xy 356.016689 -281.19241) (xy 356.049324 -281.155573) (xy 356.087445 -281.124448) (xy 356.130066 -281.099841)
			(xy 356.176082 -281.082389) (xy 356.224301 -281.072545) (xy 356.273476 -281.070564) (xy 356.322331 -281.076496)
			(xy 356.369602 -281.090188) (xy 356.414064 -281.111286) (xy 356.454567 -281.139242) (xy 356.49006 -281.173334)
			(xy 356.519625 -281.212678) (xy 356.542496 -281.256255) (xy 356.55808 -281.302936) (xy 356.565975 -281.351513)
			(xy 356.56647 -281.37612) (xy 356.895412 -281.37612) (xy 356.899372 -281.327066) (xy 356.911149 -281.279282)
			(xy 356.93044 -281.234006) (xy 356.956743 -281.19241) (xy 356.989378 -281.155573) (xy 357.027499 -281.124448)
			(xy 357.07012 -281.099841) (xy 357.116136 -281.082389) (xy 357.164355 -281.072545) (xy 357.21353 -281.070564)
			(xy 357.262385 -281.076496) (xy 357.309656 -281.090188) (xy 357.354118 -281.111286) (xy 357.394621 -281.139242)
			(xy 357.430114 -281.173334) (xy 357.459679 -281.212678) (xy 357.48255 -281.256255) (xy 357.498134 -281.302936)
			(xy 357.506029 -281.351513) (xy 357.506524 -281.37612) (xy 357.835212 -281.37612) (xy 357.839172 -281.327066)
			(xy 357.850949 -281.279282) (xy 357.87024 -281.234006) (xy 357.896543 -281.19241) (xy 357.929178 -281.155573)
			(xy 357.967299 -281.124448) (xy 358.00992 -281.099841) (xy 358.055936 -281.082389) (xy 358.104155 -281.072545)
			(xy 358.15333 -281.070564) (xy 358.202185 -281.076496) (xy 358.249456 -281.090188) (xy 358.293918 -281.111286)
			(xy 358.334421 -281.139242) (xy 358.369914 -281.173334) (xy 358.399479 -281.212678) (xy 358.42235 -281.256255)
			(xy 358.437934 -281.302936) (xy 358.445829 -281.351513) (xy 358.446324 -281.37612) (xy 361.589078 -281.37612)
			(xy 361.593038 -281.327066) (xy 361.604815 -281.279282) (xy 361.624106 -281.234006) (xy 361.650409 -281.19241)
			(xy 361.683044 -281.155573) (xy 361.721165 -281.124448) (xy 361.763786 -281.099841) (xy 361.809802 -281.082389)
			(xy 361.858021 -281.072545) (xy 361.907196 -281.070564) (xy 361.956051 -281.076496) (xy 362.003322 -281.090188)
			(xy 362.047784 -281.111286) (xy 362.088287 -281.139242) (xy 362.12378 -281.173334) (xy 362.153345 -281.212678)
			(xy 362.176216 -281.256255) (xy 362.1918 -281.302936) (xy 362.199695 -281.351513) (xy 362.20019 -281.37612)
			(xy 362.528878 -281.37612) (xy 362.532838 -281.327066) (xy 362.544615 -281.279282) (xy 362.563906 -281.234006)
			(xy 362.590209 -281.19241) (xy 362.622844 -281.155573) (xy 362.660965 -281.124448) (xy 362.703586 -281.099841)
			(xy 362.749602 -281.082389) (xy 362.797821 -281.072545) (xy 362.846996 -281.070564) (xy 362.895851 -281.076496)
			(xy 362.943122 -281.090188) (xy 362.987584 -281.111286) (xy 363.028087 -281.139242) (xy 363.06358 -281.173334)
			(xy 363.093145 -281.212678) (xy 363.116016 -281.256255) (xy 363.1316 -281.302936) (xy 363.139495 -281.351513)
			(xy 363.13999 -281.37612) (xy 363.468932 -281.37612) (xy 363.472892 -281.327066) (xy 363.484669 -281.279282)
			(xy 363.50396 -281.234006) (xy 363.530263 -281.19241) (xy 363.562898 -281.155573) (xy 363.601019 -281.124448)
			(xy 363.64364 -281.099841) (xy 363.689656 -281.082389) (xy 363.737875 -281.072545) (xy 363.78705 -281.070564)
			(xy 363.835905 -281.076496) (xy 363.883176 -281.090188) (xy 363.927638 -281.111286) (xy 363.968141 -281.139242)
			(xy 364.003634 -281.173334) (xy 364.033199 -281.212678) (xy 364.05607 -281.256255) (xy 364.071654 -281.302936)
			(xy 364.079549 -281.351513) (xy 364.080044 -281.37612) (xy 366.289094 -281.37612) (xy 366.293054 -281.327066)
			(xy 366.304831 -281.279282) (xy 366.324122 -281.234006) (xy 366.350425 -281.19241) (xy 366.38306 -281.155573)
			(xy 366.421181 -281.124448) (xy 366.463802 -281.099841) (xy 366.509818 -281.082389) (xy 366.558037 -281.072545)
			(xy 366.607212 -281.070564) (xy 366.656067 -281.076496) (xy 366.703338 -281.090188) (xy 366.7478 -281.111286)
			(xy 366.788303 -281.139242) (xy 366.823796 -281.173334) (xy 366.853361 -281.212678) (xy 366.876232 -281.256255)
			(xy 366.891816 -281.302936) (xy 366.899711 -281.351513) (xy 366.900206 -281.37612) (xy 369.109002 -281.37612)
			(xy 369.112962 -281.327066) (xy 369.124739 -281.279282) (xy 369.14403 -281.234006) (xy 369.170333 -281.19241)
			(xy 369.202968 -281.155573) (xy 369.241089 -281.124448) (xy 369.28371 -281.099841) (xy 369.329726 -281.082389)
			(xy 369.377945 -281.072545) (xy 369.42712 -281.070564) (xy 369.475975 -281.076496) (xy 369.523246 -281.090188)
			(xy 369.567708 -281.111286) (xy 369.608211 -281.139242) (xy 369.643704 -281.173334) (xy 369.673269 -281.212678)
			(xy 369.69614 -281.256255) (xy 369.711724 -281.302936) (xy 369.719619 -281.351513) (xy 369.720114 -281.3761)
			(xy 370.049089 -281.3761) (xy 370.053259 -281.325769) (xy 370.065656 -281.276811) (xy 370.085941 -281.230561)
			(xy 370.113562 -281.18828) (xy 370.147764 -281.151122) (xy 370.187616 -281.120099) (xy 370.23203 -281.096058)
			(xy 370.279795 -281.079655) (xy 370.329608 -281.071337) (xy 370.35486 -281.070812) (xy 371.294914 -281.070812)
			(xy 371.32017 -281.071295) (xy 371.369993 -281.079611) (xy 371.417768 -281.096014) (xy 371.462192 -281.120057)
			(xy 371.502053 -281.151083) (xy 371.536263 -281.188247) (xy 371.56389 -281.230535) (xy 371.58418 -281.276793)
			(xy 371.59658 -281.32576) (xy 371.600751 -281.3761) (xy 371.600749 -281.37612) (xy 371.92891 -281.37612)
			(xy 371.93287 -281.327066) (xy 371.944647 -281.279282) (xy 371.963938 -281.234006) (xy 371.990241 -281.19241)
			(xy 372.022876 -281.155573) (xy 372.060997 -281.124448) (xy 372.103618 -281.099841) (xy 372.149634 -281.082389)
			(xy 372.197853 -281.072545) (xy 372.247028 -281.070564) (xy 372.295883 -281.076496) (xy 372.343154 -281.090188)
			(xy 372.387616 -281.111286) (xy 372.428119 -281.139242) (xy 372.463612 -281.173334) (xy 372.493177 -281.212678)
			(xy 372.516048 -281.256255) (xy 372.531632 -281.302936) (xy 372.539527 -281.351513) (xy 372.540022 -281.3761)
			(xy 372.868989 -281.3761) (xy 372.873159 -281.325768) (xy 372.885556 -281.27681) (xy 372.905842 -281.230559)
			(xy 372.933464 -281.188278) (xy 372.967667 -281.151119) (xy 373.00752 -281.120096) (xy 373.051935 -281.096056)
			(xy 373.099702 -281.079653) (xy 373.149516 -281.071336) (xy 373.174768 -281.070812) (xy 374.114822 -281.070812)
			(xy 374.140078 -281.071295) (xy 374.1899 -281.079613) (xy 374.237674 -281.096016) (xy 374.282096 -281.120059)
			(xy 374.321956 -281.151086) (xy 374.356165 -281.18825) (xy 374.383791 -281.230537) (xy 374.404081 -281.276795)
			(xy 374.41648 -281.325761) (xy 374.420651 -281.3761) (xy 374.420649 -281.37612) (xy 374.749072 -281.37612)
			(xy 374.753032 -281.327066) (xy 374.764809 -281.279282) (xy 374.7841 -281.234006) (xy 374.810403 -281.19241)
			(xy 374.843038 -281.155573) (xy 374.881159 -281.124448) (xy 374.92378 -281.099841) (xy 374.969796 -281.082389)
			(xy 375.018015 -281.072545) (xy 375.06719 -281.070564) (xy 375.116045 -281.076496) (xy 375.163316 -281.090188)
			(xy 375.207778 -281.111286) (xy 375.248281 -281.139242) (xy 375.283774 -281.173334) (xy 375.313339 -281.212678)
			(xy 375.33621 -281.256255) (xy 375.351794 -281.302936) (xy 375.359689 -281.351513) (xy 375.360184 -281.37612)
			(xy 375.678695 -281.37612) (xy 375.68279 -281.325392) (xy 375.694969 -281.275978) (xy 375.714917 -281.229158)
			(xy 375.742118 -281.186144) (xy 375.775866 -281.14805) (xy 375.815288 -281.115863) (xy 375.859362 -281.090417)
			(xy 375.906948 -281.07237) (xy 375.956812 -281.06219) (xy 376.007664 -281.060141) (xy 376.058185 -281.066275)
			(xy 376.107069 -281.080435) (xy 376.153048 -281.102252) (xy 376.194932 -281.131162) (xy 376.231636 -281.166417)
			(xy 376.262209 -281.207103) (xy 376.28586 -281.252166) (xy 376.301976 -281.30044) (xy 376.31014 -281.350674)
			(xy 376.310652 -281.37612) (xy 376.628926 -281.37612) (xy 376.632886 -281.327066) (xy 376.644663 -281.279282)
			(xy 376.663954 -281.234006) (xy 376.690257 -281.19241) (xy 376.722892 -281.155573) (xy 376.761013 -281.124448)
			(xy 376.803634 -281.099841) (xy 376.84965 -281.082389) (xy 376.897869 -281.072545) (xy 376.947044 -281.070564)
			(xy 376.995899 -281.076496) (xy 377.04317 -281.090188) (xy 377.087632 -281.111286) (xy 377.128135 -281.139242)
			(xy 377.163628 -281.173334) (xy 377.193193 -281.212678) (xy 377.216064 -281.256255) (xy 377.231648 -281.302936)
			(xy 377.239543 -281.351513) (xy 377.240038 -281.37612) (xy 377.558549 -281.37612) (xy 377.562644 -281.325392)
			(xy 377.574823 -281.275978) (xy 377.594771 -281.229158) (xy 377.621972 -281.186144) (xy 377.65572 -281.14805)
			(xy 377.695142 -281.115863) (xy 377.739216 -281.090417) (xy 377.786802 -281.07237) (xy 377.836666 -281.06219)
			(xy 377.887518 -281.060141) (xy 377.938039 -281.066275) (xy 377.986923 -281.080435) (xy 378.032902 -281.102252)
			(xy 378.074786 -281.131162) (xy 378.11149 -281.166417) (xy 378.142063 -281.207103) (xy 378.165714 -281.252166)
			(xy 378.18183 -281.30044) (xy 378.189994 -281.350674) (xy 378.190506 -281.37612) (xy 378.189994 -281.401566)
			(xy 378.18183 -281.4518) (xy 378.165714 -281.500074) (xy 378.142063 -281.545137) (xy 378.11149 -281.585823)
			(xy 378.074786 -281.621078) (xy 378.032902 -281.649988) (xy 377.986923 -281.671805) (xy 377.938039 -281.685965)
			(xy 377.887518 -281.692099) (xy 377.836666 -281.69005) (xy 377.786802 -281.67987) (xy 377.739216 -281.661823)
			(xy 377.695142 -281.636377) (xy 377.65572 -281.60419) (xy 377.621972 -281.566096) (xy 377.594771 -281.523082)
			(xy 377.574823 -281.476262) (xy 377.562644 -281.426848) (xy 377.558549 -281.37612) (xy 377.240038 -281.37612)
			(xy 377.239543 -281.400727) (xy 377.231648 -281.449304) (xy 377.216064 -281.495985) (xy 377.193193 -281.539562)
			(xy 377.163628 -281.578906) (xy 377.128135 -281.612998) (xy 377.087632 -281.640954) (xy 377.04317 -281.662052)
			(xy 376.995899 -281.675744) (xy 376.947044 -281.681676) (xy 376.897869 -281.679695) (xy 376.84965 -281.669851)
			(xy 376.803634 -281.652399) (xy 376.761013 -281.627792) (xy 376.722892 -281.596667) (xy 376.690257 -281.55983)
			(xy 376.663954 -281.518234) (xy 376.644663 -281.472958) (xy 376.632886 -281.425174) (xy 376.628926 -281.37612)
			(xy 376.310652 -281.37612) (xy 376.31014 -281.401566) (xy 376.301976 -281.4518) (xy 376.28586 -281.500074)
			(xy 376.262209 -281.545137) (xy 376.231636 -281.585823) (xy 376.194932 -281.621078) (xy 376.153048 -281.649988)
			(xy 376.107069 -281.671805) (xy 376.058185 -281.685965) (xy 376.007664 -281.692099) (xy 375.956812 -281.69005)
			(xy 375.906948 -281.67987) (xy 375.859362 -281.661823) (xy 375.815288 -281.636377) (xy 375.775866 -281.60419)
			(xy 375.742118 -281.566096) (xy 375.714917 -281.523082) (xy 375.694969 -281.476262) (xy 375.68279 -281.426848)
			(xy 375.678695 -281.37612) (xy 375.360184 -281.37612) (xy 375.359689 -281.400727) (xy 375.351794 -281.449304)
			(xy 375.33621 -281.495985) (xy 375.313339 -281.539562) (xy 375.283774 -281.578906) (xy 375.248281 -281.612998)
			(xy 375.207778 -281.640954) (xy 375.163316 -281.662052) (xy 375.116045 -281.675744) (xy 375.06719 -281.681676)
			(xy 375.018015 -281.679695) (xy 374.969796 -281.669851) (xy 374.92378 -281.652399) (xy 374.881159 -281.627792)
			(xy 374.843038 -281.596667) (xy 374.810403 -281.55983) (xy 374.7841 -281.518234) (xy 374.764809 -281.472958)
			(xy 374.753032 -281.425174) (xy 374.749072 -281.37612) (xy 374.420649 -281.37612) (xy 374.41648 -281.426439)
			(xy 374.404081 -281.475405) (xy 374.383791 -281.521663) (xy 374.356165 -281.56395) (xy 374.321956 -281.601114)
			(xy 374.282096 -281.632141) (xy 374.237674 -281.656184) (xy 374.1899 -281.672587) (xy 374.140078 -281.680905)
			(xy 374.114822 -281.681428) (xy 373.174768 -281.681428) (xy 373.149516 -281.680864) (xy 373.099702 -281.672547)
			(xy 373.051935 -281.656144) (xy 373.00752 -281.632104) (xy 372.967667 -281.601081) (xy 372.933464 -281.563922)
			(xy 372.905842 -281.521641) (xy 372.885556 -281.47539) (xy 372.873159 -281.426432) (xy 372.868989 -281.3761)
			(xy 372.540022 -281.3761) (xy 372.540022 -281.37612) (xy 372.539527 -281.400727) (xy 372.531632 -281.449304)
			(xy 372.516048 -281.495985) (xy 372.493177 -281.539562) (xy 372.463612 -281.578906) (xy 372.428119 -281.612998)
			(xy 372.387616 -281.640954) (xy 372.343154 -281.662052) (xy 372.295883 -281.675744) (xy 372.247028 -281.681676)
			(xy 372.197853 -281.679695) (xy 372.149634 -281.669851) (xy 372.103618 -281.652399) (xy 372.060997 -281.627792)
			(xy 372.022876 -281.596667) (xy 371.990241 -281.55983) (xy 371.963938 -281.518234) (xy 371.944647 -281.472958)
			(xy 371.93287 -281.425174) (xy 371.92891 -281.37612) (xy 371.600749 -281.37612) (xy 371.59658 -281.42644)
			(xy 371.58418 -281.475407) (xy 371.56389 -281.521665) (xy 371.536263 -281.563953) (xy 371.502053 -281.601117)
			(xy 371.462192 -281.632143) (xy 371.417768 -281.656186) (xy 371.369993 -281.672589) (xy 371.32017 -281.680905)
			(xy 371.294914 -281.681428) (xy 370.35486 -281.681428) (xy 370.329609 -281.680863) (xy 370.279795 -281.672545)
			(xy 370.23203 -281.656142) (xy 370.187616 -281.632101) (xy 370.147764 -281.601078) (xy 370.113562 -281.56392)
			(xy 370.085941 -281.521639) (xy 370.065656 -281.475389) (xy 370.053259 -281.426431) (xy 370.049089 -281.3761)
			(xy 369.720114 -281.3761) (xy 369.720114 -281.37612) (xy 369.719619 -281.400727) (xy 369.711724 -281.449304)
			(xy 369.69614 -281.495985) (xy 369.673269 -281.539562) (xy 369.643704 -281.578906) (xy 369.608211 -281.612998)
			(xy 369.567708 -281.640954) (xy 369.523246 -281.662052) (xy 369.475975 -281.675744) (xy 369.42712 -281.681676)
			(xy 369.377945 -281.679695) (xy 369.329726 -281.669851) (xy 369.28371 -281.652399) (xy 369.241089 -281.627792)
			(xy 369.202968 -281.596667) (xy 369.170333 -281.55983) (xy 369.14403 -281.518234) (xy 369.124739 -281.472958)
			(xy 369.112962 -281.425174) (xy 369.109002 -281.37612) (xy 366.900206 -281.37612) (xy 366.899711 -281.400727)
			(xy 366.891816 -281.449304) (xy 366.876232 -281.495985) (xy 366.853361 -281.539562) (xy 366.823796 -281.578906)
			(xy 366.788303 -281.612998) (xy 366.7478 -281.640954) (xy 366.703338 -281.662052) (xy 366.656067 -281.675744)
			(xy 366.607212 -281.681676) (xy 366.558037 -281.679695) (xy 366.509818 -281.669851) (xy 366.463802 -281.652399)
			(xy 366.421181 -281.627792) (xy 366.38306 -281.596667) (xy 366.350425 -281.55983) (xy 366.324122 -281.518234)
			(xy 366.304831 -281.472958) (xy 366.293054 -281.425174) (xy 366.289094 -281.37612) (xy 364.080044 -281.37612)
			(xy 364.079549 -281.400727) (xy 364.071654 -281.449304) (xy 364.05607 -281.495985) (xy 364.033199 -281.539562)
			(xy 364.003634 -281.578906) (xy 363.968141 -281.612998) (xy 363.927638 -281.640954) (xy 363.883176 -281.662052)
			(xy 363.835905 -281.675744) (xy 363.78705 -281.681676) (xy 363.737875 -281.679695) (xy 363.689656 -281.669851)
			(xy 363.64364 -281.652399) (xy 363.601019 -281.627792) (xy 363.562898 -281.596667) (xy 363.530263 -281.55983)
			(xy 363.50396 -281.518234) (xy 363.484669 -281.472958) (xy 363.472892 -281.425174) (xy 363.468932 -281.37612)
			(xy 363.13999 -281.37612) (xy 363.139495 -281.400727) (xy 363.1316 -281.449304) (xy 363.116016 -281.495985)
			(xy 363.093145 -281.539562) (xy 363.06358 -281.578906) (xy 363.028087 -281.612998) (xy 362.987584 -281.640954)
			(xy 362.943122 -281.662052) (xy 362.895851 -281.675744) (xy 362.846996 -281.681676) (xy 362.797821 -281.679695)
			(xy 362.749602 -281.669851) (xy 362.703586 -281.652399) (xy 362.660965 -281.627792) (xy 362.622844 -281.596667)
			(xy 362.590209 -281.55983) (xy 362.563906 -281.518234) (xy 362.544615 -281.472958) (xy 362.532838 -281.425174)
			(xy 362.528878 -281.37612) (xy 362.20019 -281.37612) (xy 362.199695 -281.400727) (xy 362.1918 -281.449304)
			(xy 362.176216 -281.495985) (xy 362.153345 -281.539562) (xy 362.12378 -281.578906) (xy 362.088287 -281.612998)
			(xy 362.047784 -281.640954) (xy 362.003322 -281.662052) (xy 361.956051 -281.675744) (xy 361.907196 -281.681676)
			(xy 361.858021 -281.679695) (xy 361.809802 -281.669851) (xy 361.763786 -281.652399) (xy 361.721165 -281.627792)
			(xy 361.683044 -281.596667) (xy 361.650409 -281.55983) (xy 361.624106 -281.518234) (xy 361.604815 -281.472958)
			(xy 361.593038 -281.425174) (xy 361.589078 -281.37612) (xy 358.446324 -281.37612) (xy 358.445829 -281.400727)
			(xy 358.437934 -281.449304) (xy 358.42235 -281.495985) (xy 358.399479 -281.539562) (xy 358.369914 -281.578906)
			(xy 358.334421 -281.612998) (xy 358.293918 -281.640954) (xy 358.249456 -281.662052) (xy 358.202185 -281.675744)
			(xy 358.15333 -281.681676) (xy 358.104155 -281.679695) (xy 358.055936 -281.669851) (xy 358.00992 -281.652399)
			(xy 357.967299 -281.627792) (xy 357.929178 -281.596667) (xy 357.896543 -281.55983) (xy 357.87024 -281.518234)
			(xy 357.850949 -281.472958) (xy 357.839172 -281.425174) (xy 357.835212 -281.37612) (xy 357.506524 -281.37612)
			(xy 357.506029 -281.400727) (xy 357.498134 -281.449304) (xy 357.48255 -281.495985) (xy 357.459679 -281.539562)
			(xy 357.430114 -281.578906) (xy 357.394621 -281.612998) (xy 357.354118 -281.640954) (xy 357.309656 -281.662052)
			(xy 357.262385 -281.675744) (xy 357.21353 -281.681676) (xy 357.164355 -281.679695) (xy 357.116136 -281.669851)
			(xy 357.07012 -281.652399) (xy 357.027499 -281.627792) (xy 356.989378 -281.596667) (xy 356.956743 -281.55983)
			(xy 356.93044 -281.518234) (xy 356.911149 -281.472958) (xy 356.899372 -281.425174) (xy 356.895412 -281.37612)
			(xy 356.56647 -281.37612) (xy 356.565975 -281.400727) (xy 356.55808 -281.449304) (xy 356.542496 -281.495985)
			(xy 356.519625 -281.539562) (xy 356.49006 -281.578906) (xy 356.454567 -281.612998) (xy 356.414064 -281.640954)
			(xy 356.369602 -281.662052) (xy 356.322331 -281.675744) (xy 356.273476 -281.681676) (xy 356.224301 -281.679695)
			(xy 356.176082 -281.669851) (xy 356.130066 -281.652399) (xy 356.087445 -281.627792) (xy 356.049324 -281.596667)
			(xy 356.016689 -281.55983) (xy 355.990386 -281.518234) (xy 355.971095 -281.472958) (xy 355.959318 -281.425174)
			(xy 355.955358 -281.37612) (xy 353.746308 -281.37612) (xy 353.745813 -281.400727) (xy 353.737918 -281.449304)
			(xy 353.722334 -281.495985) (xy 353.699463 -281.539562) (xy 353.669898 -281.578906) (xy 353.634405 -281.612998)
			(xy 353.593902 -281.640954) (xy 353.54944 -281.662052) (xy 353.502169 -281.675744) (xy 353.453314 -281.681676)
			(xy 353.404139 -281.679695) (xy 353.35592 -281.669851) (xy 353.309904 -281.652399) (xy 353.267283 -281.627792)
			(xy 353.229162 -281.596667) (xy 353.196527 -281.55983) (xy 353.170224 -281.518234) (xy 353.150933 -281.472958)
			(xy 353.139156 -281.425174) (xy 353.135196 -281.37612) (xy 350.9264 -281.37612) (xy 350.925905 -281.400727)
			(xy 350.91801 -281.449304) (xy 350.902426 -281.495985) (xy 350.879555 -281.539562) (xy 350.84999 -281.578906)
			(xy 350.814497 -281.612998) (xy 350.773994 -281.640954) (xy 350.729532 -281.662052) (xy 350.682261 -281.675744)
			(xy 350.633406 -281.681676) (xy 350.584231 -281.679695) (xy 350.536012 -281.669851) (xy 350.489996 -281.652399)
			(xy 350.447375 -281.627792) (xy 350.409254 -281.596667) (xy 350.376619 -281.55983) (xy 350.350316 -281.518234)
			(xy 350.331025 -281.472958) (xy 350.319248 -281.425174) (xy 350.315288 -281.37612) (xy 349.987178 -281.37612)
			(xy 349.983008 -281.426447) (xy 349.970606 -281.475421) (xy 349.950312 -281.521685) (xy 349.92268 -281.563978)
			(xy 349.888464 -281.601146) (xy 349.848596 -281.632175) (xy 349.804165 -281.656219) (xy 349.756383 -281.672622)
			(xy 349.706552 -281.680936) (xy 349.681292 -281.681428) (xy 348.741238 -281.681428) (xy 348.71598 -281.680898)
			(xy 348.666152 -281.672589) (xy 348.618371 -281.656191) (xy 348.573941 -281.632152) (xy 348.534075 -281.601127)
			(xy 348.499859 -281.563963) (xy 348.472227 -281.521674) (xy 348.451934 -281.475414) (xy 348.439532 -281.426444)
			(xy 348.43536 -281.3761) (xy 348.106492 -281.3761) (xy 348.106492 -281.37612) (xy 348.105997 -281.400727)
			(xy 348.098102 -281.449304) (xy 348.082518 -281.495985) (xy 348.059647 -281.539562) (xy 348.030082 -281.578906)
			(xy 347.994589 -281.612998) (xy 347.954086 -281.640954) (xy 347.909624 -281.662052) (xy 347.862353 -281.675744)
			(xy 347.813498 -281.681676) (xy 347.764323 -281.679695) (xy 347.716104 -281.669851) (xy 347.670088 -281.652399)
			(xy 347.627467 -281.627792) (xy 347.589346 -281.596667) (xy 347.556711 -281.55983) (xy 347.530408 -281.518234)
			(xy 347.511117 -281.472958) (xy 347.49934 -281.425174) (xy 347.49538 -281.37612) (xy 347.166949 -281.37612)
			(xy 347.16278 -281.426438) (xy 347.150381 -281.475404) (xy 347.130092 -281.521661) (xy 347.102467 -281.563948)
			(xy 347.068259 -281.601111) (xy 347.028401 -281.632138) (xy 346.983979 -281.656181) (xy 346.936207 -281.672586)
			(xy 346.886385 -281.680904) (xy 346.86113 -281.681428) (xy 345.921076 -281.681428) (xy 345.895824 -281.680865)
			(xy 345.846008 -281.672548) (xy 345.798241 -281.656146) (xy 345.753825 -281.632106) (xy 345.713971 -281.601084)
			(xy 345.679766 -281.563925) (xy 345.652144 -281.521643) (xy 345.631857 -281.475392) (xy 345.619459 -281.426432)
			(xy 345.615289 -281.3761) (xy 345.28633 -281.3761) (xy 345.28633 -281.37612) (xy 345.285835 -281.400727)
			(xy 345.27794 -281.449304) (xy 345.262356 -281.495985) (xy 345.239485 -281.539562) (xy 345.20992 -281.578906)
			(xy 345.174427 -281.612998) (xy 345.133924 -281.640954) (xy 345.089462 -281.662052) (xy 345.042191 -281.675744)
			(xy 344.993336 -281.681676) (xy 344.944161 -281.679695) (xy 344.895942 -281.669851) (xy 344.849926 -281.652399)
			(xy 344.807305 -281.627792) (xy 344.769184 -281.596667) (xy 344.736549 -281.55983) (xy 344.710246 -281.518234)
			(xy 344.690955 -281.472958) (xy 344.679178 -281.425174) (xy 344.675218 -281.37612) (xy 344.356944 -281.37612)
			(xy 344.356432 -281.401566) (xy 344.348268 -281.4518) (xy 344.332152 -281.500074) (xy 344.308501 -281.545137)
			(xy 344.277928 -281.585823) (xy 344.241224 -281.621078) (xy 344.19934 -281.649988) (xy 344.153361 -281.671805)
			(xy 344.104477 -281.685965) (xy 344.053956 -281.692099) (xy 344.003104 -281.69005) (xy 343.95324 -281.67987)
			(xy 343.905654 -281.661823) (xy 343.86158 -281.636377) (xy 343.822158 -281.60419) (xy 343.78841 -281.566096)
			(xy 343.761209 -281.523082) (xy 343.741261 -281.476262) (xy 343.729082 -281.426848) (xy 343.724987 -281.37612)
			(xy 343.406476 -281.37612) (xy 343.405981 -281.400727) (xy 343.398086 -281.449304) (xy 343.382502 -281.495985)
			(xy 343.359631 -281.539562) (xy 343.330066 -281.578906) (xy 343.294573 -281.612998) (xy 343.25407 -281.640954)
			(xy 343.209608 -281.662052) (xy 343.162337 -281.675744) (xy 343.113482 -281.681676) (xy 343.064307 -281.679695)
			(xy 343.016088 -281.669851) (xy 342.970072 -281.652399) (xy 342.927451 -281.627792) (xy 342.88933 -281.596667)
			(xy 342.856695 -281.55983) (xy 342.830392 -281.518234) (xy 342.811101 -281.472958) (xy 342.799324 -281.425174)
			(xy 342.795364 -281.37612) (xy 342.476836 -281.37612) (xy 342.476324 -281.401566) (xy 342.46816 -281.4518)
			(xy 342.452044 -281.500074) (xy 342.428393 -281.545137) (xy 342.39782 -281.585823) (xy 342.361116 -281.621078)
			(xy 342.319232 -281.649988) (xy 342.273253 -281.671805) (xy 342.224369 -281.685965) (xy 342.173848 -281.692099)
			(xy 342.122996 -281.69005) (xy 342.073132 -281.67987) (xy 342.025546 -281.661823) (xy 341.981472 -281.636377)
			(xy 341.94205 -281.60419) (xy 341.908302 -281.566096) (xy 341.881101 -281.523082) (xy 341.861153 -281.476262)
			(xy 341.848974 -281.426848) (xy 341.844879 -281.37612) (xy 341.525933 -281.37612) (xy 341.525933 -281.400168)
			(xy 341.51838 -281.447703) (xy 341.503462 -281.493463) (xy 341.481548 -281.536316) (xy 341.453182 -281.575199)
			(xy 341.419065 -281.60915) (xy 341.380044 -281.637326) (xy 341.337085 -281.659031) (xy 341.291253 -281.673726)
			(xy 341.267542 -281.677872) (xy 341.258652 -281.679142) (xy 341.24265 -281.688032) (xy 341.236808 -281.69489)
			(xy 341.23122 -281.701976) (xy 341.224974 -281.718893) (xy 341.224616 -281.72791) (xy 341.224616 -281.880564)
			(xy 341.224754 -281.885454) (xy 341.226675 -281.895046) (xy 341.228426 -281.899614) (xy 341.232236 -281.907234)
			(xy 341.232998 -281.908504) (xy 341.238995 -281.919082) (xy 341.250174 -281.940681) (xy 341.25535 -281.951684)
			(xy 341.268558 -281.982672) (xy 341.268558 -281.982926) (xy 341.271254 -281.989126) (xy 341.279365 -281.999936)
			(xy 341.28456 -282.004262) (xy 341.28964 -282.008326) (xy 341.30234 -282.01366) (xy 341.397844 -282.025852)
			(xy 341.406973 -282.026652) (xy 341.424801 -282.02247) (xy 341.432642 -282.017724) (xy 341.436184 -282.015224)
			(xy 341.442435 -282.009216) (xy 341.445088 -282.005786) (xy 341.445088 -282.005532) (xy 341.459581 -281.98656)
			(xy 341.49347 -281.952934) (xy 341.532178 -281.924991) (xy 341.574763 -281.903412) (xy 341.620187 -281.888723)
			(xy 341.667344 -281.881281) (xy 341.691214 -281.880818) (xy 341.716466 -281.881341) (xy 341.766282 -281.889655)
			(xy 341.81405 -281.906056) (xy 341.858467 -281.930095) (xy 341.898322 -281.961117) (xy 341.932527 -281.998275)
			(xy 341.96015 -282.040557) (xy 341.980437 -282.086808) (xy 341.992834 -282.135768) (xy 341.997005 -282.1861)
			(xy 341.997003 -282.186126) (xy 342.314779 -282.186126) (xy 342.318874 -282.135398) (xy 342.331053 -282.085984)
			(xy 342.351001 -282.039164) (xy 342.378202 -281.99615) (xy 342.41195 -281.958056) (xy 342.451372 -281.925869)
			(xy 342.495446 -281.900423) (xy 342.543032 -281.882376) (xy 342.592896 -281.872196) (xy 342.643748 -281.870147)
			(xy 342.694269 -281.876281) (xy 342.743153 -281.890441) (xy 342.789132 -281.912258) (xy 342.831016 -281.941168)
			(xy 342.86772 -281.976423) (xy 342.898293 -282.017109) (xy 342.921944 -282.062172) (xy 342.93806 -282.110446)
			(xy 342.946224 -282.16068) (xy 342.946736 -282.186126) (xy 343.254833 -282.186126) (xy 343.258928 -282.135398)
			(xy 343.271107 -282.085984) (xy 343.291055 -282.039164) (xy 343.318256 -281.99615) (xy 343.352004 -281.958056)
			(xy 343.391426 -281.925869) (xy 343.4355 -281.900423) (xy 343.483086 -281.882376) (xy 343.53295 -281.872196)
			(xy 343.583802 -281.870147) (xy 343.634323 -281.876281) (xy 343.683207 -281.890441) (xy 343.729186 -281.912258)
			(xy 343.77107 -281.941168) (xy 343.807774 -281.976423) (xy 343.838347 -282.017109) (xy 343.861998 -282.062172)
			(xy 343.878114 -282.110446) (xy 343.886278 -282.16068) (xy 343.88679 -282.186126) (xy 344.205318 -282.186126)
			(xy 344.209278 -282.137072) (xy 344.221055 -282.089288) (xy 344.240346 -282.044012) (xy 344.266649 -282.002416)
			(xy 344.299284 -281.965579) (xy 344.337405 -281.934454) (xy 344.380026 -281.909847) (xy 344.426042 -281.892395)
			(xy 344.474261 -281.882551) (xy 344.523436 -281.88057) (xy 344.572291 -281.886502) (xy 344.619562 -281.900194)
			(xy 344.664024 -281.921292) (xy 344.704527 -281.949248) (xy 344.74002 -281.98334) (xy 344.769585 -282.022684)
			(xy 344.792456 -282.066261) (xy 344.80804 -282.112942) (xy 344.815935 -282.161519) (xy 344.81643 -282.186126)
			(xy 345.145372 -282.186126) (xy 345.149332 -282.137072) (xy 345.161109 -282.089288) (xy 345.1804 -282.044012)
			(xy 345.206703 -282.002416) (xy 345.239338 -281.965579) (xy 345.277459 -281.934454) (xy 345.32008 -281.909847)
			(xy 345.366096 -281.892395) (xy 345.414315 -281.882551) (xy 345.46349 -281.88057) (xy 345.512345 -281.886502)
			(xy 345.559616 -281.900194) (xy 345.604078 -281.921292) (xy 345.644581 -281.949248) (xy 345.680074 -281.98334)
			(xy 345.709639 -282.022684) (xy 345.73251 -282.066261) (xy 345.748094 -282.112942) (xy 345.755989 -282.161519)
			(xy 345.756484 -282.186126) (xy 346.085426 -282.186126) (xy 346.089386 -282.137072) (xy 346.101163 -282.089288)
			(xy 346.120454 -282.044012) (xy 346.146757 -282.002416) (xy 346.179392 -281.965579) (xy 346.217513 -281.934454)
			(xy 346.260134 -281.909847) (xy 346.30615 -281.892395) (xy 346.354369 -281.882551) (xy 346.403544 -281.88057)
			(xy 346.452399 -281.886502) (xy 346.49967 -281.900194) (xy 346.544132 -281.921292) (xy 346.584635 -281.949248)
			(xy 346.620128 -281.98334) (xy 346.649693 -282.022684) (xy 346.672564 -282.066261) (xy 346.688148 -282.112942)
			(xy 346.696043 -282.161519) (xy 346.696538 -282.186126) (xy 347.025226 -282.186126) (xy 347.029186 -282.137072)
			(xy 347.040963 -282.089288) (xy 347.060254 -282.044012) (xy 347.086557 -282.002416) (xy 347.119192 -281.965579)
			(xy 347.157313 -281.934454) (xy 347.199934 -281.909847) (xy 347.24595 -281.892395) (xy 347.294169 -281.882551)
			(xy 347.343344 -281.88057) (xy 347.392199 -281.886502) (xy 347.43947 -281.900194) (xy 347.483932 -281.921292)
			(xy 347.524435 -281.949248) (xy 347.559928 -281.98334) (xy 347.589493 -282.022684) (xy 347.612364 -282.066261)
			(xy 347.627948 -282.112942) (xy 347.635843 -282.161519) (xy 347.636338 -282.186126) (xy 347.96528 -282.186126)
			(xy 347.96924 -282.137072) (xy 347.981017 -282.089288) (xy 348.000308 -282.044012) (xy 348.026611 -282.002416)
			(xy 348.059246 -281.965579) (xy 348.097367 -281.934454) (xy 348.139988 -281.909847) (xy 348.186004 -281.892395)
			(xy 348.234223 -281.882551) (xy 348.283398 -281.88057) (xy 348.332253 -281.886502) (xy 348.379524 -281.900194)
			(xy 348.423986 -281.921292) (xy 348.464489 -281.949248) (xy 348.499982 -281.98334) (xy 348.529547 -282.022684)
			(xy 348.552418 -282.066261) (xy 348.568002 -282.112942) (xy 348.575897 -282.161519) (xy 348.576392 -282.186126)
			(xy 348.905334 -282.186126) (xy 348.909294 -282.137072) (xy 348.921071 -282.089288) (xy 348.940362 -282.044012)
			(xy 348.966665 -282.002416) (xy 348.9993 -281.965579) (xy 349.037421 -281.934454) (xy 349.080042 -281.909847)
			(xy 349.126058 -281.892395) (xy 349.174277 -281.882551) (xy 349.223452 -281.88057) (xy 349.272307 -281.886502)
			(xy 349.319578 -281.900194) (xy 349.36404 -281.921292) (xy 349.404543 -281.949248) (xy 349.440036 -281.98334)
			(xy 349.469601 -282.022684) (xy 349.492472 -282.066261) (xy 349.508056 -282.112942) (xy 349.515951 -282.161519)
			(xy 349.516446 -282.186126) (xy 349.845388 -282.186126) (xy 349.849348 -282.137072) (xy 349.861125 -282.089288)
			(xy 349.880416 -282.044012) (xy 349.906719 -282.002416) (xy 349.939354 -281.965579) (xy 349.977475 -281.934454)
			(xy 350.020096 -281.909847) (xy 350.066112 -281.892395) (xy 350.114331 -281.882551) (xy 350.163506 -281.88057)
			(xy 350.212361 -281.886502) (xy 350.259632 -281.900194) (xy 350.304094 -281.921292) (xy 350.344597 -281.949248)
			(xy 350.38009 -281.98334) (xy 350.409655 -282.022684) (xy 350.432526 -282.066261) (xy 350.44811 -282.112942)
			(xy 350.456005 -282.161519) (xy 350.4565 -282.186126) (xy 350.785442 -282.186126) (xy 350.789402 -282.137072)
			(xy 350.801179 -282.089288) (xy 350.82047 -282.044012) (xy 350.846773 -282.002416) (xy 350.879408 -281.965579)
			(xy 350.917529 -281.934454) (xy 350.96015 -281.909847) (xy 351.006166 -281.892395) (xy 351.054385 -281.882551)
			(xy 351.10356 -281.88057) (xy 351.152415 -281.886502) (xy 351.199686 -281.900194) (xy 351.244148 -281.921292)
			(xy 351.284651 -281.949248) (xy 351.320144 -281.98334) (xy 351.349709 -282.022684) (xy 351.37258 -282.066261)
			(xy 351.388164 -282.112942) (xy 351.396059 -282.161519) (xy 351.396554 -282.186126) (xy 351.725242 -282.186126)
			(xy 351.729202 -282.137072) (xy 351.740979 -282.089288) (xy 351.76027 -282.044012) (xy 351.786573 -282.002416)
			(xy 351.819208 -281.965579) (xy 351.857329 -281.934454) (xy 351.89995 -281.909847) (xy 351.945966 -281.892395)
			(xy 351.994185 -281.882551) (xy 352.04336 -281.88057) (xy 352.092215 -281.886502) (xy 352.139486 -281.900194)
			(xy 352.183948 -281.921292) (xy 352.224451 -281.949248) (xy 352.259944 -281.98334) (xy 352.289509 -282.022684)
			(xy 352.31238 -282.066261) (xy 352.327964 -282.112942) (xy 352.335859 -282.161519) (xy 352.336354 -282.186126)
			(xy 352.665296 -282.186126) (xy 352.669256 -282.137072) (xy 352.681033 -282.089288) (xy 352.700324 -282.044012)
			(xy 352.726627 -282.002416) (xy 352.759262 -281.965579) (xy 352.797383 -281.934454) (xy 352.840004 -281.909847)
			(xy 352.88602 -281.892395) (xy 352.934239 -281.882551) (xy 352.983414 -281.88057) (xy 353.032269 -281.886502)
			(xy 353.07954 -281.900194) (xy 353.124002 -281.921292) (xy 353.164505 -281.949248) (xy 353.199998 -281.98334)
			(xy 353.229563 -282.022684) (xy 353.252434 -282.066261) (xy 353.268018 -282.112942) (xy 353.275913 -282.161519)
			(xy 353.276408 -282.186126) (xy 353.60535 -282.186126) (xy 353.60931 -282.137072) (xy 353.621087 -282.089288)
			(xy 353.640378 -282.044012) (xy 353.666681 -282.002416) (xy 353.699316 -281.965579) (xy 353.737437 -281.934454)
			(xy 353.780058 -281.909847) (xy 353.826074 -281.892395) (xy 353.874293 -281.882551) (xy 353.923468 -281.88057)
			(xy 353.972323 -281.886502) (xy 354.019594 -281.900194) (xy 354.064056 -281.921292) (xy 354.104559 -281.949248)
			(xy 354.140052 -281.98334) (xy 354.169617 -282.022684) (xy 354.192488 -282.066261) (xy 354.208072 -282.112942)
			(xy 354.215967 -282.161519) (xy 354.216462 -282.186126) (xy 354.545404 -282.186126) (xy 354.549364 -282.137072)
			(xy 354.561141 -282.089288) (xy 354.580432 -282.044012) (xy 354.606735 -282.002416) (xy 354.63937 -281.965579)
			(xy 354.677491 -281.934454) (xy 354.720112 -281.909847) (xy 354.766128 -281.892395) (xy 354.814347 -281.882551)
			(xy 354.863522 -281.88057) (xy 354.912377 -281.886502) (xy 354.959648 -281.900194) (xy 355.00411 -281.921292)
			(xy 355.044613 -281.949248) (xy 355.080106 -281.98334) (xy 355.109671 -282.022684) (xy 355.132542 -282.066261)
			(xy 355.148126 -282.112942) (xy 355.156021 -282.161519) (xy 355.156516 -282.186126) (xy 355.485204 -282.186126)
			(xy 355.489164 -282.137072) (xy 355.500941 -282.089288) (xy 355.520232 -282.044012) (xy 355.546535 -282.002416)
			(xy 355.57917 -281.965579) (xy 355.617291 -281.934454) (xy 355.659912 -281.909847) (xy 355.705928 -281.892395)
			(xy 355.754147 -281.882551) (xy 355.803322 -281.88057) (xy 355.852177 -281.886502) (xy 355.899448 -281.900194)
			(xy 355.94391 -281.921292) (xy 355.984413 -281.949248) (xy 356.019906 -281.98334) (xy 356.049471 -282.022684)
			(xy 356.072342 -282.066261) (xy 356.087926 -282.112942) (xy 356.095821 -282.161519) (xy 356.096315 -282.1861)
			(xy 356.42504 -282.1861) (xy 356.429214 -282.135728) (xy 356.441621 -282.08673) (xy 356.461923 -282.040442)
			(xy 356.489566 -281.998127) (xy 356.523797 -281.960938) (xy 356.563681 -281.92989) (xy 356.608132 -281.90583)
			(xy 356.655936 -281.889414) (xy 356.70579 -281.881089) (xy 356.731062 -281.880564) (xy 357.671116 -281.880564)
			(xy 357.696394 -281.881035) (xy 357.746259 -281.889359) (xy 357.794074 -281.905776) (xy 357.838536 -281.929839)
			(xy 357.87843 -281.960892) (xy 357.912669 -281.998088) (xy 357.940319 -282.040411) (xy 357.960627 -282.086709)
			(xy 357.973037 -282.135717) (xy 357.977212 -282.1861) (xy 357.97721 -282.186126) (xy 358.305366 -282.186126)
			(xy 358.309326 -282.137072) (xy 358.321103 -282.089288) (xy 358.340394 -282.044012) (xy 358.366697 -282.002416)
			(xy 358.399332 -281.965579) (xy 358.437453 -281.934454) (xy 358.480074 -281.909847) (xy 358.52609 -281.892395)
			(xy 358.574309 -281.882551) (xy 358.623484 -281.88057) (xy 358.672339 -281.886502) (xy 358.71961 -281.900194)
			(xy 358.764072 -281.921292) (xy 358.804575 -281.949248) (xy 358.840068 -281.98334) (xy 358.869633 -282.022684)
			(xy 358.892504 -282.066261) (xy 358.908088 -282.112942) (xy 358.915983 -282.161519) (xy 358.916478 -282.186126)
			(xy 361.118924 -282.186126) (xy 361.122884 -282.137072) (xy 361.134661 -282.089288) (xy 361.153952 -282.044012)
			(xy 361.180255 -282.002416) (xy 361.21289 -281.965579) (xy 361.251011 -281.934454) (xy 361.293632 -281.909847)
			(xy 361.339648 -281.892395) (xy 361.387867 -281.882551) (xy 361.437042 -281.88057) (xy 361.485897 -281.886502)
			(xy 361.533168 -281.900194) (xy 361.57763 -281.921292) (xy 361.618133 -281.949248) (xy 361.653626 -281.98334)
			(xy 361.683191 -282.022684) (xy 361.706062 -282.066261) (xy 361.721646 -282.112942) (xy 361.729541 -282.161519)
			(xy 361.730035 -282.1861) (xy 362.05874 -282.1861) (xy 362.062914 -282.135726) (xy 362.075322 -282.086726)
			(xy 362.095626 -282.040437) (xy 362.123271 -281.99812) (xy 362.157505 -281.960931) (xy 362.197392 -281.929883)
			(xy 362.241845 -281.905824) (xy 362.289652 -281.88941) (xy 362.339509 -281.881087) (xy 362.364782 -281.880564)
			(xy 363.304836 -281.880564) (xy 363.330113 -281.881037) (xy 363.379975 -281.889363) (xy 363.427788 -281.905782)
			(xy 363.472246 -281.929846) (xy 363.512138 -281.960899) (xy 363.546374 -281.998094) (xy 363.574022 -282.040417)
			(xy 363.594328 -282.086713) (xy 363.606737 -282.135719) (xy 363.610912 -282.1861) (xy 363.61091 -282.186126)
			(xy 363.939086 -282.186126) (xy 363.943046 -282.137072) (xy 363.954823 -282.089288) (xy 363.974114 -282.044012)
			(xy 364.000417 -282.002416) (xy 364.033052 -281.965579) (xy 364.071173 -281.934454) (xy 364.113794 -281.909847)
			(xy 364.15981 -281.892395) (xy 364.208029 -281.882551) (xy 364.257204 -281.88057) (xy 364.306059 -281.886502)
			(xy 364.35333 -281.900194) (xy 364.397792 -281.921292) (xy 364.438295 -281.949248) (xy 364.473788 -281.98334)
			(xy 364.503353 -282.022684) (xy 364.526224 -282.066261) (xy 364.541808 -282.112942) (xy 364.549703 -282.161519)
			(xy 364.550198 -282.186126) (xy 364.878886 -282.186126) (xy 364.882846 -282.137072) (xy 364.894623 -282.089288)
			(xy 364.913914 -282.044012) (xy 364.940217 -282.002416) (xy 364.972852 -281.965579) (xy 365.010973 -281.934454)
			(xy 365.053594 -281.909847) (xy 365.09961 -281.892395) (xy 365.147829 -281.882551) (xy 365.197004 -281.88057)
			(xy 365.245859 -281.886502) (xy 365.29313 -281.900194) (xy 365.337592 -281.921292) (xy 365.378095 -281.949248)
			(xy 365.413588 -281.98334) (xy 365.443153 -282.022684) (xy 365.466024 -282.066261) (xy 365.481608 -282.112942)
			(xy 365.489503 -282.161519) (xy 365.489998 -282.186126) (xy 365.81894 -282.186126) (xy 365.8229 -282.137072)
			(xy 365.834677 -282.089288) (xy 365.853968 -282.044012) (xy 365.880271 -282.002416) (xy 365.912906 -281.965579)
			(xy 365.951027 -281.934454) (xy 365.993648 -281.909847) (xy 366.039664 -281.892395) (xy 366.087883 -281.882551)
			(xy 366.137058 -281.88057) (xy 366.185913 -281.886502) (xy 366.233184 -281.900194) (xy 366.277646 -281.921292)
			(xy 366.318149 -281.949248) (xy 366.353642 -281.98334) (xy 366.383207 -282.022684) (xy 366.406078 -282.066261)
			(xy 366.421662 -282.112942) (xy 366.429557 -282.161519) (xy 366.430052 -282.186126) (xy 366.758994 -282.186126)
			(xy 366.762954 -282.137072) (xy 366.774731 -282.089288) (xy 366.794022 -282.044012) (xy 366.820325 -282.002416)
			(xy 366.85296 -281.965579) (xy 366.891081 -281.934454) (xy 366.933702 -281.909847) (xy 366.979718 -281.892395)
			(xy 367.027937 -281.882551) (xy 367.077112 -281.88057) (xy 367.125967 -281.886502) (xy 367.173238 -281.900194)
			(xy 367.2177 -281.921292) (xy 367.258203 -281.949248) (xy 367.293696 -281.98334) (xy 367.323261 -282.022684)
			(xy 367.346132 -282.066261) (xy 367.361716 -282.112942) (xy 367.369611 -282.161519) (xy 367.370106 -282.186126)
			(xy 367.699048 -282.186126) (xy 367.703008 -282.137072) (xy 367.714785 -282.089288) (xy 367.734076 -282.044012)
			(xy 367.760379 -282.002416) (xy 367.793014 -281.965579) (xy 367.831135 -281.934454) (xy 367.873756 -281.909847)
			(xy 367.919772 -281.892395) (xy 367.967991 -281.882551) (xy 368.017166 -281.88057) (xy 368.066021 -281.886502)
			(xy 368.113292 -281.900194) (xy 368.157754 -281.921292) (xy 368.198257 -281.949248) (xy 368.23375 -281.98334)
			(xy 368.263315 -282.022684) (xy 368.286186 -282.066261) (xy 368.30177 -282.112942) (xy 368.309665 -282.161519)
			(xy 368.31016 -282.186126) (xy 368.639102 -282.186126) (xy 368.643062 -282.137072) (xy 368.654839 -282.089288)
			(xy 368.67413 -282.044012) (xy 368.700433 -282.002416) (xy 368.733068 -281.965579) (xy 368.771189 -281.934454)
			(xy 368.81381 -281.909847) (xy 368.859826 -281.892395) (xy 368.908045 -281.882551) (xy 368.95722 -281.88057)
			(xy 369.006075 -281.886502) (xy 369.053346 -281.900194) (xy 369.097808 -281.921292) (xy 369.138311 -281.949248)
			(xy 369.173804 -281.98334) (xy 369.203369 -282.022684) (xy 369.22624 -282.066261) (xy 369.241824 -282.112942)
			(xy 369.249719 -282.161519) (xy 369.250214 -282.186126) (xy 369.578902 -282.186126) (xy 369.582862 -282.137072)
			(xy 369.594639 -282.089288) (xy 369.61393 -282.044012) (xy 369.640233 -282.002416) (xy 369.672868 -281.965579)
			(xy 369.710989 -281.934454) (xy 369.75361 -281.909847) (xy 369.799626 -281.892395) (xy 369.847845 -281.882551)
			(xy 369.89702 -281.88057) (xy 369.945875 -281.886502) (xy 369.993146 -281.900194) (xy 370.037608 -281.921292)
			(xy 370.078111 -281.949248) (xy 370.113604 -281.98334) (xy 370.143169 -282.022684) (xy 370.16604 -282.066261)
			(xy 370.181624 -282.112942) (xy 370.189519 -282.161519) (xy 370.190014 -282.186126) (xy 370.518956 -282.186126)
			(xy 370.522916 -282.137072) (xy 370.534693 -282.089288) (xy 370.553984 -282.044012) (xy 370.580287 -282.002416)
			(xy 370.612922 -281.965579) (xy 370.651043 -281.934454) (xy 370.693664 -281.909847) (xy 370.73968 -281.892395)
			(xy 370.787899 -281.882551) (xy 370.837074 -281.88057) (xy 370.885929 -281.886502) (xy 370.9332 -281.900194)
			(xy 370.977662 -281.921292) (xy 371.018165 -281.949248) (xy 371.053658 -281.98334) (xy 371.083223 -282.022684)
			(xy 371.106094 -282.066261) (xy 371.121678 -282.112942) (xy 371.129573 -282.161519) (xy 371.130068 -282.186126)
			(xy 371.45901 -282.186126) (xy 371.46297 -282.137072) (xy 371.474747 -282.089288) (xy 371.494038 -282.044012)
			(xy 371.520341 -282.002416) (xy 371.552976 -281.965579) (xy 371.591097 -281.934454) (xy 371.633718 -281.909847)
			(xy 371.679734 -281.892395) (xy 371.727953 -281.882551) (xy 371.777128 -281.88057) (xy 371.825983 -281.886502)
			(xy 371.873254 -281.900194) (xy 371.917716 -281.921292) (xy 371.958219 -281.949248) (xy 371.993712 -281.98334)
			(xy 372.023277 -282.022684) (xy 372.046148 -282.066261) (xy 372.061732 -282.112942) (xy 372.069627 -282.161519)
			(xy 372.070122 -282.186126) (xy 372.399064 -282.186126) (xy 372.403024 -282.137072) (xy 372.414801 -282.089288)
			(xy 372.434092 -282.044012) (xy 372.460395 -282.002416) (xy 372.49303 -281.965579) (xy 372.531151 -281.934454)
			(xy 372.573772 -281.909847) (xy 372.619788 -281.892395) (xy 372.668007 -281.882551) (xy 372.717182 -281.88057)
			(xy 372.766037 -281.886502) (xy 372.813308 -281.900194) (xy 372.85777 -281.921292) (xy 372.898273 -281.949248)
			(xy 372.933766 -281.98334) (xy 372.963331 -282.022684) (xy 372.986202 -282.066261) (xy 373.001786 -282.112942)
			(xy 373.009681 -282.161519) (xy 373.010176 -282.186126) (xy 373.339118 -282.186126) (xy 373.343078 -282.137072)
			(xy 373.354855 -282.089288) (xy 373.374146 -282.044012) (xy 373.400449 -282.002416) (xy 373.433084 -281.965579)
			(xy 373.471205 -281.934454) (xy 373.513826 -281.909847) (xy 373.559842 -281.892395) (xy 373.608061 -281.882551)
			(xy 373.657236 -281.88057) (xy 373.706091 -281.886502) (xy 373.753362 -281.900194) (xy 373.797824 -281.921292)
			(xy 373.838327 -281.949248) (xy 373.87382 -281.98334) (xy 373.903385 -282.022684) (xy 373.926256 -282.066261)
			(xy 373.94184 -282.112942) (xy 373.949735 -282.161519) (xy 373.95023 -282.186126) (xy 374.278918 -282.186126)
			(xy 374.282878 -282.137072) (xy 374.294655 -282.089288) (xy 374.313946 -282.044012) (xy 374.340249 -282.002416)
			(xy 374.372884 -281.965579) (xy 374.411005 -281.934454) (xy 374.453626 -281.909847) (xy 374.499642 -281.892395)
			(xy 374.547861 -281.882551) (xy 374.597036 -281.88057) (xy 374.645891 -281.886502) (xy 374.693162 -281.900194)
			(xy 374.737624 -281.921292) (xy 374.778127 -281.949248) (xy 374.81362 -281.98334) (xy 374.843185 -282.022684)
			(xy 374.866056 -282.066261) (xy 374.88164 -282.112942) (xy 374.889535 -282.161519) (xy 374.89003 -282.186126)
			(xy 375.218972 -282.186126) (xy 375.222932 -282.137072) (xy 375.234709 -282.089288) (xy 375.254 -282.044012)
			(xy 375.280303 -282.002416) (xy 375.312938 -281.965579) (xy 375.351059 -281.934454) (xy 375.39368 -281.909847)
			(xy 375.439696 -281.892395) (xy 375.487915 -281.882551) (xy 375.53709 -281.88057) (xy 375.585945 -281.886502)
			(xy 375.633216 -281.900194) (xy 375.677678 -281.921292) (xy 375.718181 -281.949248) (xy 375.753674 -281.98334)
			(xy 375.783239 -282.022684) (xy 375.80611 -282.066261) (xy 375.821694 -282.112942) (xy 375.829589 -282.161519)
			(xy 375.830084 -282.186126) (xy 376.148595 -282.186126) (xy 376.15269 -282.135398) (xy 376.164869 -282.085984)
			(xy 376.184817 -282.039164) (xy 376.212018 -281.99615) (xy 376.245766 -281.958056) (xy 376.285188 -281.925869)
			(xy 376.329262 -281.900423) (xy 376.376848 -281.882376) (xy 376.426712 -281.872196) (xy 376.477564 -281.870147)
			(xy 376.528085 -281.876281) (xy 376.576969 -281.890441) (xy 376.622948 -281.912258) (xy 376.664832 -281.941168)
			(xy 376.701536 -281.976423) (xy 376.732109 -282.017109) (xy 376.75576 -282.062172) (xy 376.771876 -282.110446)
			(xy 376.78004 -282.16068) (xy 376.780552 -282.186126) (xy 377.088649 -282.186126) (xy 377.092744 -282.135398)
			(xy 377.104923 -282.085984) (xy 377.124871 -282.039164) (xy 377.152072 -281.99615) (xy 377.18582 -281.958056)
			(xy 377.225242 -281.925869) (xy 377.269316 -281.900423) (xy 377.316902 -281.882376) (xy 377.366766 -281.872196)
			(xy 377.417618 -281.870147) (xy 377.468139 -281.876281) (xy 377.517023 -281.890441) (xy 377.563002 -281.912258)
			(xy 377.604886 -281.941168) (xy 377.64159 -281.976423) (xy 377.672163 -282.017109) (xy 377.695814 -282.062172)
			(xy 377.71193 -282.110446) (xy 377.720094 -282.16068) (xy 377.720606 -282.186126) (xy 377.720094 -282.211572)
			(xy 377.71193 -282.261806) (xy 377.695814 -282.31008) (xy 377.672163 -282.355143) (xy 377.64159 -282.395829)
			(xy 377.604886 -282.431084) (xy 377.563002 -282.459994) (xy 377.517023 -282.481811) (xy 377.468139 -282.495971)
			(xy 377.417618 -282.502105) (xy 377.366766 -282.500056) (xy 377.316902 -282.489876) (xy 377.269316 -282.471829)
			(xy 377.225242 -282.446383) (xy 377.18582 -282.414196) (xy 377.152072 -282.376102) (xy 377.124871 -282.333088)
			(xy 377.104923 -282.286268) (xy 377.092744 -282.236854) (xy 377.088649 -282.186126) (xy 376.780552 -282.186126)
			(xy 376.78004 -282.211572) (xy 376.771876 -282.261806) (xy 376.75576 -282.31008) (xy 376.732109 -282.355143)
			(xy 376.701536 -282.395829) (xy 376.664832 -282.431084) (xy 376.622948 -282.459994) (xy 376.576969 -282.481811)
			(xy 376.528085 -282.495971) (xy 376.477564 -282.502105) (xy 376.426712 -282.500056) (xy 376.376848 -282.489876)
			(xy 376.329262 -282.471829) (xy 376.285188 -282.446383) (xy 376.245766 -282.414196) (xy 376.212018 -282.376102)
			(xy 376.184817 -282.333088) (xy 376.164869 -282.286268) (xy 376.15269 -282.236854) (xy 376.148595 -282.186126)
			(xy 375.830084 -282.186126) (xy 375.829589 -282.210733) (xy 375.821694 -282.25931) (xy 375.80611 -282.305991)
			(xy 375.783239 -282.349568) (xy 375.753674 -282.388912) (xy 375.718181 -282.423004) (xy 375.677678 -282.45096)
			(xy 375.633216 -282.472058) (xy 375.585945 -282.48575) (xy 375.53709 -282.491682) (xy 375.487915 -282.489701)
			(xy 375.439696 -282.479857) (xy 375.39368 -282.462405) (xy 375.351059 -282.437798) (xy 375.312938 -282.406673)
			(xy 375.280303 -282.369836) (xy 375.254 -282.32824) (xy 375.234709 -282.282964) (xy 375.222932 -282.23518)
			(xy 375.218972 -282.186126) (xy 374.89003 -282.186126) (xy 374.889535 -282.210733) (xy 374.88164 -282.25931)
			(xy 374.866056 -282.305991) (xy 374.843185 -282.349568) (xy 374.81362 -282.388912) (xy 374.778127 -282.423004)
			(xy 374.737624 -282.45096) (xy 374.693162 -282.472058) (xy 374.645891 -282.48575) (xy 374.597036 -282.491682)
			(xy 374.547861 -282.489701) (xy 374.499642 -282.479857) (xy 374.453626 -282.462405) (xy 374.411005 -282.437798)
			(xy 374.372884 -282.406673) (xy 374.340249 -282.369836) (xy 374.313946 -282.32824) (xy 374.294655 -282.282964)
			(xy 374.282878 -282.23518) (xy 374.278918 -282.186126) (xy 373.95023 -282.186126) (xy 373.949735 -282.210733)
			(xy 373.94184 -282.25931) (xy 373.926256 -282.305991) (xy 373.903385 -282.349568) (xy 373.87382 -282.388912)
			(xy 373.838327 -282.423004) (xy 373.797824 -282.45096) (xy 373.753362 -282.472058) (xy 373.706091 -282.48575)
			(xy 373.657236 -282.491682) (xy 373.608061 -282.489701) (xy 373.559842 -282.479857) (xy 373.513826 -282.462405)
			(xy 373.471205 -282.437798) (xy 373.433084 -282.406673) (xy 373.400449 -282.369836) (xy 373.374146 -282.32824)
			(xy 373.354855 -282.282964) (xy 373.343078 -282.23518) (xy 373.339118 -282.186126) (xy 373.010176 -282.186126)
			(xy 373.009681 -282.210733) (xy 373.001786 -282.25931) (xy 372.986202 -282.305991) (xy 372.963331 -282.349568)
			(xy 372.933766 -282.388912) (xy 372.898273 -282.423004) (xy 372.85777 -282.45096) (xy 372.813308 -282.472058)
			(xy 372.766037 -282.48575) (xy 372.717182 -282.491682) (xy 372.668007 -282.489701) (xy 372.619788 -282.479857)
			(xy 372.573772 -282.462405) (xy 372.531151 -282.437798) (xy 372.49303 -282.406673) (xy 372.460395 -282.369836)
			(xy 372.434092 -282.32824) (xy 372.414801 -282.282964) (xy 372.403024 -282.23518) (xy 372.399064 -282.186126)
			(xy 372.070122 -282.186126) (xy 372.069627 -282.210733) (xy 372.061732 -282.25931) (xy 372.046148 -282.305991)
			(xy 372.023277 -282.349568) (xy 371.993712 -282.388912) (xy 371.958219 -282.423004) (xy 371.917716 -282.45096)
			(xy 371.873254 -282.472058) (xy 371.825983 -282.48575) (xy 371.777128 -282.491682) (xy 371.727953 -282.489701)
			(xy 371.679734 -282.479857) (xy 371.633718 -282.462405) (xy 371.591097 -282.437798) (xy 371.552976 -282.406673)
			(xy 371.520341 -282.369836) (xy 371.494038 -282.32824) (xy 371.474747 -282.282964) (xy 371.46297 -282.23518)
			(xy 371.45901 -282.186126) (xy 371.130068 -282.186126) (xy 371.129573 -282.210733) (xy 371.121678 -282.25931)
			(xy 371.106094 -282.305991) (xy 371.083223 -282.349568) (xy 371.053658 -282.388912) (xy 371.018165 -282.423004)
			(xy 370.977662 -282.45096) (xy 370.9332 -282.472058) (xy 370.885929 -282.48575) (xy 370.837074 -282.491682)
			(xy 370.787899 -282.489701) (xy 370.73968 -282.479857) (xy 370.693664 -282.462405) (xy 370.651043 -282.437798)
			(xy 370.612922 -282.406673) (xy 370.580287 -282.369836) (xy 370.553984 -282.32824) (xy 370.534693 -282.282964)
			(xy 370.522916 -282.23518) (xy 370.518956 -282.186126) (xy 370.190014 -282.186126) (xy 370.189519 -282.210733)
			(xy 370.181624 -282.25931) (xy 370.16604 -282.305991) (xy 370.143169 -282.349568) (xy 370.113604 -282.388912)
			(xy 370.078111 -282.423004) (xy 370.037608 -282.45096) (xy 369.993146 -282.472058) (xy 369.945875 -282.48575)
			(xy 369.89702 -282.491682) (xy 369.847845 -282.489701) (xy 369.799626 -282.479857) (xy 369.75361 -282.462405)
			(xy 369.710989 -282.437798) (xy 369.672868 -282.406673) (xy 369.640233 -282.369836) (xy 369.61393 -282.32824)
			(xy 369.594639 -282.282964) (xy 369.582862 -282.23518) (xy 369.578902 -282.186126) (xy 369.250214 -282.186126)
			(xy 369.249719 -282.210733) (xy 369.241824 -282.25931) (xy 369.22624 -282.305991) (xy 369.203369 -282.349568)
			(xy 369.173804 -282.388912) (xy 369.138311 -282.423004) (xy 369.097808 -282.45096) (xy 369.053346 -282.472058)
			(xy 369.006075 -282.48575) (xy 368.95722 -282.491682) (xy 368.908045 -282.489701) (xy 368.859826 -282.479857)
			(xy 368.81381 -282.462405) (xy 368.771189 -282.437798) (xy 368.733068 -282.406673) (xy 368.700433 -282.369836)
			(xy 368.67413 -282.32824) (xy 368.654839 -282.282964) (xy 368.643062 -282.23518) (xy 368.639102 -282.186126)
			(xy 368.31016 -282.186126) (xy 368.309665 -282.210733) (xy 368.30177 -282.25931) (xy 368.286186 -282.305991)
			(xy 368.263315 -282.349568) (xy 368.23375 -282.388912) (xy 368.198257 -282.423004) (xy 368.157754 -282.45096)
			(xy 368.113292 -282.472058) (xy 368.066021 -282.48575) (xy 368.017166 -282.491682) (xy 367.967991 -282.489701)
			(xy 367.919772 -282.479857) (xy 367.873756 -282.462405) (xy 367.831135 -282.437798) (xy 367.793014 -282.406673)
			(xy 367.760379 -282.369836) (xy 367.734076 -282.32824) (xy 367.714785 -282.282964) (xy 367.703008 -282.23518)
			(xy 367.699048 -282.186126) (xy 367.370106 -282.186126) (xy 367.369611 -282.210733) (xy 367.361716 -282.25931)
			(xy 367.346132 -282.305991) (xy 367.323261 -282.349568) (xy 367.293696 -282.388912) (xy 367.258203 -282.423004)
			(xy 367.2177 -282.45096) (xy 367.173238 -282.472058) (xy 367.125967 -282.48575) (xy 367.077112 -282.491682)
			(xy 367.027937 -282.489701) (xy 366.979718 -282.479857) (xy 366.933702 -282.462405) (xy 366.891081 -282.437798)
			(xy 366.85296 -282.406673) (xy 366.820325 -282.369836) (xy 366.794022 -282.32824) (xy 366.774731 -282.282964)
			(xy 366.762954 -282.23518) (xy 366.758994 -282.186126) (xy 366.430052 -282.186126) (xy 366.429557 -282.210733)
			(xy 366.421662 -282.25931) (xy 366.406078 -282.305991) (xy 366.383207 -282.349568) (xy 366.353642 -282.388912)
			(xy 366.318149 -282.423004) (xy 366.277646 -282.45096) (xy 366.233184 -282.472058) (xy 366.185913 -282.48575)
			(xy 366.137058 -282.491682) (xy 366.087883 -282.489701) (xy 366.039664 -282.479857) (xy 365.993648 -282.462405)
			(xy 365.951027 -282.437798) (xy 365.912906 -282.406673) (xy 365.880271 -282.369836) (xy 365.853968 -282.32824)
			(xy 365.834677 -282.282964) (xy 365.8229 -282.23518) (xy 365.81894 -282.186126) (xy 365.489998 -282.186126)
			(xy 365.489503 -282.210733) (xy 365.481608 -282.25931) (xy 365.466024 -282.305991) (xy 365.443153 -282.349568)
			(xy 365.413588 -282.388912) (xy 365.378095 -282.423004) (xy 365.337592 -282.45096) (xy 365.29313 -282.472058)
			(xy 365.245859 -282.48575) (xy 365.197004 -282.491682) (xy 365.147829 -282.489701) (xy 365.09961 -282.479857)
			(xy 365.053594 -282.462405) (xy 365.010973 -282.437798) (xy 364.972852 -282.406673) (xy 364.940217 -282.369836)
			(xy 364.913914 -282.32824) (xy 364.894623 -282.282964) (xy 364.882846 -282.23518) (xy 364.878886 -282.186126)
			(xy 364.550198 -282.186126) (xy 364.549703 -282.210733) (xy 364.541808 -282.25931) (xy 364.526224 -282.305991)
			(xy 364.503353 -282.349568) (xy 364.473788 -282.388912) (xy 364.438295 -282.423004) (xy 364.397792 -282.45096)
			(xy 364.35333 -282.472058) (xy 364.306059 -282.48575) (xy 364.257204 -282.491682) (xy 364.208029 -282.489701)
			(xy 364.15981 -282.479857) (xy 364.113794 -282.462405) (xy 364.071173 -282.437798) (xy 364.033052 -282.406673)
			(xy 364.000417 -282.369836) (xy 363.974114 -282.32824) (xy 363.954823 -282.282964) (xy 363.943046 -282.23518)
			(xy 363.939086 -282.186126) (xy 363.61091 -282.186126) (xy 363.606737 -282.236481) (xy 363.594328 -282.285487)
			(xy 363.574022 -282.331783) (xy 363.546374 -282.374106) (xy 363.512138 -282.411301) (xy 363.472246 -282.442354)
			(xy 363.427788 -282.466418) (xy 363.379975 -282.482837) (xy 363.330113 -282.491163) (xy 363.304836 -282.491688)
			(xy 362.364782 -282.491688) (xy 362.339509 -282.491113) (xy 362.289652 -282.48279) (xy 362.241845 -282.466376)
			(xy 362.197392 -282.442317) (xy 362.157505 -282.411269) (xy 362.123271 -282.37408) (xy 362.095626 -282.331763)
			(xy 362.075322 -282.285474) (xy 362.062914 -282.236474) (xy 362.05874 -282.1861) (xy 361.730035 -282.1861)
			(xy 361.730036 -282.186126) (xy 361.729541 -282.210733) (xy 361.721646 -282.25931) (xy 361.706062 -282.305991)
			(xy 361.683191 -282.349568) (xy 361.653626 -282.388912) (xy 361.618133 -282.423004) (xy 361.57763 -282.45096)
			(xy 361.533168 -282.472058) (xy 361.485897 -282.48575) (xy 361.437042 -282.491682) (xy 361.387867 -282.489701)
			(xy 361.339648 -282.479857) (xy 361.293632 -282.462405) (xy 361.251011 -282.437798) (xy 361.21289 -282.406673)
			(xy 361.180255 -282.369836) (xy 361.153952 -282.32824) (xy 361.134661 -282.282964) (xy 361.122884 -282.23518)
			(xy 361.118924 -282.186126) (xy 358.916478 -282.186126) (xy 358.915983 -282.210733) (xy 358.908088 -282.25931)
			(xy 358.892504 -282.305991) (xy 358.869633 -282.349568) (xy 358.840068 -282.388912) (xy 358.804575 -282.423004)
			(xy 358.764072 -282.45096) (xy 358.71961 -282.472058) (xy 358.672339 -282.48575) (xy 358.623484 -282.491682)
			(xy 358.574309 -282.489701) (xy 358.52609 -282.479857) (xy 358.480074 -282.462405) (xy 358.437453 -282.437798)
			(xy 358.399332 -282.406673) (xy 358.366697 -282.369836) (xy 358.340394 -282.32824) (xy 358.321103 -282.282964)
			(xy 358.309326 -282.23518) (xy 358.305366 -282.186126) (xy 357.97721 -282.186126) (xy 357.973037 -282.236483)
			(xy 357.960627 -282.285491) (xy 357.940319 -282.331789) (xy 357.912669 -282.374112) (xy 357.87843 -282.411308)
			(xy 357.838536 -282.442361) (xy 357.794074 -282.466424) (xy 357.746259 -282.482841) (xy 357.696394 -282.491165)
			(xy 357.671116 -282.491688) (xy 356.731062 -282.491688) (xy 356.70579 -282.491111) (xy 356.655936 -282.482786)
			(xy 356.608132 -282.46637) (xy 356.563681 -282.44231) (xy 356.523797 -282.411262) (xy 356.489566 -282.374073)
			(xy 356.461923 -282.331758) (xy 356.441621 -282.28547) (xy 356.429214 -282.236472) (xy 356.42504 -282.1861)
			(xy 356.096315 -282.1861) (xy 356.096316 -282.186126) (xy 356.095821 -282.210733) (xy 356.087926 -282.25931)
			(xy 356.072342 -282.305991) (xy 356.049471 -282.349568) (xy 356.019906 -282.388912) (xy 355.984413 -282.423004)
			(xy 355.94391 -282.45096) (xy 355.899448 -282.472058) (xy 355.852177 -282.48575) (xy 355.803322 -282.491682)
			(xy 355.754147 -282.489701) (xy 355.705928 -282.479857) (xy 355.659912 -282.462405) (xy 355.617291 -282.437798)
			(xy 355.57917 -282.406673) (xy 355.546535 -282.369836) (xy 355.520232 -282.32824) (xy 355.500941 -282.282964)
			(xy 355.489164 -282.23518) (xy 355.485204 -282.186126) (xy 355.156516 -282.186126) (xy 355.156021 -282.210733)
			(xy 355.148126 -282.25931) (xy 355.132542 -282.305991) (xy 355.109671 -282.349568) (xy 355.080106 -282.388912)
			(xy 355.044613 -282.423004) (xy 355.00411 -282.45096) (xy 354.959648 -282.472058) (xy 354.912377 -282.48575)
			(xy 354.863522 -282.491682) (xy 354.814347 -282.489701) (xy 354.766128 -282.479857) (xy 354.720112 -282.462405)
			(xy 354.677491 -282.437798) (xy 354.63937 -282.406673) (xy 354.606735 -282.369836) (xy 354.580432 -282.32824)
			(xy 354.561141 -282.282964) (xy 354.549364 -282.23518) (xy 354.545404 -282.186126) (xy 354.216462 -282.186126)
			(xy 354.215967 -282.210733) (xy 354.208072 -282.25931) (xy 354.192488 -282.305991) (xy 354.169617 -282.349568)
			(xy 354.140052 -282.388912) (xy 354.104559 -282.423004) (xy 354.064056 -282.45096) (xy 354.019594 -282.472058)
			(xy 353.972323 -282.48575) (xy 353.923468 -282.491682) (xy 353.874293 -282.489701) (xy 353.826074 -282.479857)
			(xy 353.780058 -282.462405) (xy 353.737437 -282.437798) (xy 353.699316 -282.406673) (xy 353.666681 -282.369836)
			(xy 353.640378 -282.32824) (xy 353.621087 -282.282964) (xy 353.60931 -282.23518) (xy 353.60535 -282.186126)
			(xy 353.276408 -282.186126) (xy 353.275913 -282.210733) (xy 353.268018 -282.25931) (xy 353.252434 -282.305991)
			(xy 353.229563 -282.349568) (xy 353.199998 -282.388912) (xy 353.164505 -282.423004) (xy 353.124002 -282.45096)
			(xy 353.07954 -282.472058) (xy 353.032269 -282.48575) (xy 352.983414 -282.491682) (xy 352.934239 -282.489701)
			(xy 352.88602 -282.479857) (xy 352.840004 -282.462405) (xy 352.797383 -282.437798) (xy 352.759262 -282.406673)
			(xy 352.726627 -282.369836) (xy 352.700324 -282.32824) (xy 352.681033 -282.282964) (xy 352.669256 -282.23518)
			(xy 352.665296 -282.186126) (xy 352.336354 -282.186126) (xy 352.335859 -282.210733) (xy 352.327964 -282.25931)
			(xy 352.31238 -282.305991) (xy 352.289509 -282.349568) (xy 352.259944 -282.388912) (xy 352.224451 -282.423004)
			(xy 352.183948 -282.45096) (xy 352.139486 -282.472058) (xy 352.092215 -282.48575) (xy 352.04336 -282.491682)
			(xy 351.994185 -282.489701) (xy 351.945966 -282.479857) (xy 351.89995 -282.462405) (xy 351.857329 -282.437798)
			(xy 351.819208 -282.406673) (xy 351.786573 -282.369836) (xy 351.76027 -282.32824) (xy 351.740979 -282.282964)
			(xy 351.729202 -282.23518) (xy 351.725242 -282.186126) (xy 351.396554 -282.186126) (xy 351.396059 -282.210733)
			(xy 351.388164 -282.25931) (xy 351.37258 -282.305991) (xy 351.349709 -282.349568) (xy 351.320144 -282.388912)
			(xy 351.284651 -282.423004) (xy 351.244148 -282.45096) (xy 351.199686 -282.472058) (xy 351.152415 -282.48575)
			(xy 351.10356 -282.491682) (xy 351.054385 -282.489701) (xy 351.006166 -282.479857) (xy 350.96015 -282.462405)
			(xy 350.917529 -282.437798) (xy 350.879408 -282.406673) (xy 350.846773 -282.369836) (xy 350.82047 -282.32824)
			(xy 350.801179 -282.282964) (xy 350.789402 -282.23518) (xy 350.785442 -282.186126) (xy 350.4565 -282.186126)
			(xy 350.456005 -282.210733) (xy 350.44811 -282.25931) (xy 350.432526 -282.305991) (xy 350.409655 -282.349568)
			(xy 350.38009 -282.388912) (xy 350.344597 -282.423004) (xy 350.304094 -282.45096) (xy 350.259632 -282.472058)
			(xy 350.212361 -282.48575) (xy 350.163506 -282.491682) (xy 350.114331 -282.489701) (xy 350.066112 -282.479857)
			(xy 350.020096 -282.462405) (xy 349.977475 -282.437798) (xy 349.939354 -282.406673) (xy 349.906719 -282.369836)
			(xy 349.880416 -282.32824) (xy 349.861125 -282.282964) (xy 349.849348 -282.23518) (xy 349.845388 -282.186126)
			(xy 349.516446 -282.186126) (xy 349.515951 -282.210733) (xy 349.508056 -282.25931) (xy 349.492472 -282.305991)
			(xy 349.469601 -282.349568) (xy 349.440036 -282.388912) (xy 349.404543 -282.423004) (xy 349.36404 -282.45096)
			(xy 349.319578 -282.472058) (xy 349.272307 -282.48575) (xy 349.223452 -282.491682) (xy 349.174277 -282.489701)
			(xy 349.126058 -282.479857) (xy 349.080042 -282.462405) (xy 349.037421 -282.437798) (xy 348.9993 -282.406673)
			(xy 348.966665 -282.369836) (xy 348.940362 -282.32824) (xy 348.921071 -282.282964) (xy 348.909294 -282.23518)
			(xy 348.905334 -282.186126) (xy 348.576392 -282.186126) (xy 348.575897 -282.210733) (xy 348.568002 -282.25931)
			(xy 348.552418 -282.305991) (xy 348.529547 -282.349568) (xy 348.499982 -282.388912) (xy 348.464489 -282.423004)
			(xy 348.423986 -282.45096) (xy 348.379524 -282.472058) (xy 348.332253 -282.48575) (xy 348.283398 -282.491682)
			(xy 348.234223 -282.489701) (xy 348.186004 -282.479857) (xy 348.139988 -282.462405) (xy 348.097367 -282.437798)
			(xy 348.059246 -282.406673) (xy 348.026611 -282.369836) (xy 348.000308 -282.32824) (xy 347.981017 -282.282964)
			(xy 347.96924 -282.23518) (xy 347.96528 -282.186126) (xy 347.636338 -282.186126) (xy 347.635843 -282.210733)
			(xy 347.627948 -282.25931) (xy 347.612364 -282.305991) (xy 347.589493 -282.349568) (xy 347.559928 -282.388912)
			(xy 347.524435 -282.423004) (xy 347.483932 -282.45096) (xy 347.43947 -282.472058) (xy 347.392199 -282.48575)
			(xy 347.343344 -282.491682) (xy 347.294169 -282.489701) (xy 347.24595 -282.479857) (xy 347.199934 -282.462405)
			(xy 347.157313 -282.437798) (xy 347.119192 -282.406673) (xy 347.086557 -282.369836) (xy 347.060254 -282.32824)
			(xy 347.040963 -282.282964) (xy 347.029186 -282.23518) (xy 347.025226 -282.186126) (xy 346.696538 -282.186126)
			(xy 346.696043 -282.210733) (xy 346.688148 -282.25931) (xy 346.672564 -282.305991) (xy 346.649693 -282.349568)
			(xy 346.620128 -282.388912) (xy 346.584635 -282.423004) (xy 346.544132 -282.45096) (xy 346.49967 -282.472058)
			(xy 346.452399 -282.48575) (xy 346.403544 -282.491682) (xy 346.354369 -282.489701) (xy 346.30615 -282.479857)
			(xy 346.260134 -282.462405) (xy 346.217513 -282.437798) (xy 346.179392 -282.406673) (xy 346.146757 -282.369836)
			(xy 346.120454 -282.32824) (xy 346.101163 -282.282964) (xy 346.089386 -282.23518) (xy 346.085426 -282.186126)
			(xy 345.756484 -282.186126) (xy 345.755989 -282.210733) (xy 345.748094 -282.25931) (xy 345.73251 -282.305991)
			(xy 345.709639 -282.349568) (xy 345.680074 -282.388912) (xy 345.644581 -282.423004) (xy 345.604078 -282.45096)
			(xy 345.559616 -282.472058) (xy 345.512345 -282.48575) (xy 345.46349 -282.491682) (xy 345.414315 -282.489701)
			(xy 345.366096 -282.479857) (xy 345.32008 -282.462405) (xy 345.277459 -282.437798) (xy 345.239338 -282.406673)
			(xy 345.206703 -282.369836) (xy 345.1804 -282.32824) (xy 345.161109 -282.282964) (xy 345.149332 -282.23518)
			(xy 345.145372 -282.186126) (xy 344.81643 -282.186126) (xy 344.815935 -282.210733) (xy 344.80804 -282.25931)
			(xy 344.792456 -282.305991) (xy 344.769585 -282.349568) (xy 344.74002 -282.388912) (xy 344.704527 -282.423004)
			(xy 344.664024 -282.45096) (xy 344.619562 -282.472058) (xy 344.572291 -282.48575) (xy 344.523436 -282.491682)
			(xy 344.474261 -282.489701) (xy 344.426042 -282.479857) (xy 344.380026 -282.462405) (xy 344.337405 -282.437798)
			(xy 344.299284 -282.406673) (xy 344.266649 -282.369836) (xy 344.240346 -282.32824) (xy 344.221055 -282.282964)
			(xy 344.209278 -282.23518) (xy 344.205318 -282.186126) (xy 343.88679 -282.186126) (xy 343.886278 -282.211572)
			(xy 343.878114 -282.261806) (xy 343.861998 -282.31008) (xy 343.838347 -282.355143) (xy 343.807774 -282.395829)
			(xy 343.77107 -282.431084) (xy 343.729186 -282.459994) (xy 343.683207 -282.481811) (xy 343.634323 -282.495971)
			(xy 343.583802 -282.502105) (xy 343.53295 -282.500056) (xy 343.483086 -282.489876) (xy 343.4355 -282.471829)
			(xy 343.391426 -282.446383) (xy 343.352004 -282.414196) (xy 343.318256 -282.376102) (xy 343.291055 -282.333088)
			(xy 343.271107 -282.286268) (xy 343.258928 -282.236854) (xy 343.254833 -282.186126) (xy 342.946736 -282.186126)
			(xy 342.946224 -282.211572) (xy 342.93806 -282.261806) (xy 342.921944 -282.31008) (xy 342.898293 -282.355143)
			(xy 342.86772 -282.395829) (xy 342.831016 -282.431084) (xy 342.789132 -282.459994) (xy 342.743153 -282.481811)
			(xy 342.694269 -282.495971) (xy 342.643748 -282.502105) (xy 342.592896 -282.500056) (xy 342.543032 -282.489876)
			(xy 342.495446 -282.471829) (xy 342.451372 -282.446383) (xy 342.41195 -282.414196) (xy 342.378202 -282.376102)
			(xy 342.351001 -282.333088) (xy 342.331053 -282.286268) (xy 342.318874 -282.236854) (xy 342.314779 -282.186126)
			(xy 341.997003 -282.186126) (xy 341.992834 -282.236432) (xy 341.980437 -282.285392) (xy 341.96015 -282.331643)
			(xy 341.932527 -282.373925) (xy 341.898322 -282.411083) (xy 341.858467 -282.442105) (xy 341.81405 -282.466144)
			(xy 341.766282 -282.482545) (xy 341.716466 -282.490859) (xy 341.691214 -282.491434) (xy 341.667344 -282.490973)
			(xy 341.620185 -282.48354) (xy 341.574759 -282.468854) (xy 341.532175 -282.447272) (xy 341.493472 -282.419321)
			(xy 341.459594 -282.385683) (xy 341.445088 -282.36672) (xy 341.445088 -282.366466) (xy 341.442434 -282.363038)
			(xy 341.436174 -282.357042) (xy 341.432642 -282.354528) (xy 341.424814 -282.349752) (xy 341.406975 -282.34557)
			(xy 341.397844 -282.3464) (xy 341.309198 -282.35783) (xy 341.302437 -282.358902) (xy 341.28981 -282.364175)
			(xy 341.284306 -282.368244) (xy 341.278972 -282.372308) (xy 341.271098 -282.382976) (xy 341.268558 -282.38958)
			(xy 341.26058 -282.409294) (xy 341.242018 -282.447564) (xy 341.231474 -282.466034) (xy 341.231474 -282.466288)
			(xy 341.228353 -282.472106) (xy 341.224873 -282.484837) (xy 341.224616 -282.491434) (xy 341.224616 -282.644342)
			(xy 341.224983 -282.653355) (xy 341.231242 -282.670261) (xy 341.236808 -282.677362) (xy 341.24265 -282.68422)
			(xy 341.258652 -282.69311) (xy 341.267542 -282.69438) (xy 341.291258 -282.698488) (xy 341.337088 -282.713183)
			(xy 341.380045 -282.734888) (xy 341.419064 -282.763064) (xy 341.453178 -282.797015) (xy 341.481542 -282.835897)
			(xy 341.503454 -282.878749) (xy 341.51837 -282.924508) (xy 341.525922 -282.97204) (xy 341.525921 -282.996132)
			(xy 341.844879 -282.996132) (xy 341.848974 -282.945404) (xy 341.861153 -282.89599) (xy 341.881101 -282.84917)
			(xy 341.908302 -282.806156) (xy 341.94205 -282.768062) (xy 341.981472 -282.735875) (xy 342.025546 -282.710429)
			(xy 342.073132 -282.692382) (xy 342.122996 -282.682202) (xy 342.173848 -282.680153) (xy 342.224369 -282.686287)
			(xy 342.273253 -282.700447) (xy 342.319232 -282.722264) (xy 342.361116 -282.751174) (xy 342.39782 -282.786429)
			(xy 342.428393 -282.827115) (xy 342.452044 -282.872178) (xy 342.46816 -282.920452) (xy 342.476324 -282.970686)
			(xy 342.476836 -282.996132) (xy 342.795364 -282.996132) (xy 342.799324 -282.947078) (xy 342.811101 -282.899294)
			(xy 342.830392 -282.854018) (xy 342.856695 -282.812422) (xy 342.88933 -282.775585) (xy 342.927451 -282.74446)
			(xy 342.970072 -282.719853) (xy 343.016088 -282.702401) (xy 343.064307 -282.692557) (xy 343.113482 -282.690576)
			(xy 343.162337 -282.696508) (xy 343.209608 -282.7102) (xy 343.25407 -282.731298) (xy 343.294573 -282.759254)
			(xy 343.330066 -282.793346) (xy 343.359631 -282.83269) (xy 343.382502 -282.876267) (xy 343.398086 -282.922948)
			(xy 343.405981 -282.971525) (xy 343.406476 -282.996132) (xy 343.724987 -282.996132) (xy 343.729082 -282.945404)
			(xy 343.741261 -282.89599) (xy 343.761209 -282.84917) (xy 343.78841 -282.806156) (xy 343.822158 -282.768062)
			(xy 343.86158 -282.735875) (xy 343.905654 -282.710429) (xy 343.95324 -282.692382) (xy 344.003104 -282.682202)
			(xy 344.053956 -282.680153) (xy 344.104477 -282.686287) (xy 344.153361 -282.700447) (xy 344.19934 -282.722264)
			(xy 344.241224 -282.751174) (xy 344.277928 -282.786429) (xy 344.308501 -282.827115) (xy 344.332152 -282.872178)
			(xy 344.348268 -282.920452) (xy 344.356432 -282.970686) (xy 344.356944 -282.996132) (xy 344.675218 -282.996132)
			(xy 344.679178 -282.947078) (xy 344.690955 -282.899294) (xy 344.710246 -282.854018) (xy 344.736549 -282.812422)
			(xy 344.769184 -282.775585) (xy 344.807305 -282.74446) (xy 344.849926 -282.719853) (xy 344.895942 -282.702401)
			(xy 344.944161 -282.692557) (xy 344.993336 -282.690576) (xy 345.042191 -282.696508) (xy 345.089462 -282.7102)
			(xy 345.133924 -282.731298) (xy 345.174427 -282.759254) (xy 345.20992 -282.793346) (xy 345.239485 -282.83269)
			(xy 345.262356 -282.876267) (xy 345.27794 -282.922948) (xy 345.285835 -282.971525) (xy 345.286329 -282.9961)
			(xy 345.615301 -282.9961) (xy 345.619471 -282.94577) (xy 345.631868 -282.896812) (xy 345.652154 -282.850562)
			(xy 345.679775 -282.808282) (xy 345.713979 -282.771125) (xy 345.753831 -282.740104) (xy 345.798246 -282.716065)
			(xy 345.846011 -282.699663) (xy 345.895825 -282.691347) (xy 345.921076 -282.690824) (xy 346.86113 -282.690824)
			(xy 346.886386 -282.691284) (xy 346.936209 -282.699603) (xy 346.983984 -282.716008) (xy 347.028407 -282.740052)
			(xy 347.068267 -282.77108) (xy 347.102477 -282.808245) (xy 347.130103 -282.850534) (xy 347.150393 -282.896792)
			(xy 347.162792 -282.94576) (xy 347.166963 -282.9961) (xy 347.16696 -282.996132) (xy 347.49538 -282.996132)
			(xy 347.49934 -282.947078) (xy 347.511117 -282.899294) (xy 347.530408 -282.854018) (xy 347.556711 -282.812422)
			(xy 347.589346 -282.775585) (xy 347.627467 -282.74446) (xy 347.670088 -282.719853) (xy 347.716104 -282.702401)
			(xy 347.764323 -282.692557) (xy 347.813498 -282.690576) (xy 347.862353 -282.696508) (xy 347.909624 -282.7102)
			(xy 347.954086 -282.731298) (xy 347.994589 -282.759254) (xy 348.030082 -282.793346) (xy 348.059647 -282.83269)
			(xy 348.082518 -282.876267) (xy 348.098102 -282.922948) (xy 348.105997 -282.971525) (xy 348.106491 -282.9961)
			(xy 348.435372 -282.9961) (xy 348.439544 -282.945758) (xy 348.451945 -282.89679) (xy 348.472238 -282.850531)
			(xy 348.499869 -282.808244) (xy 348.534083 -282.771081) (xy 348.573948 -282.740058) (xy 348.618376 -282.71602)
			(xy 348.666155 -282.699622) (xy 348.715981 -282.691314) (xy 348.741238 -282.690824) (xy 349.681292 -282.690824)
			(xy 349.706553 -282.691252) (xy 349.756386 -282.699567) (xy 349.80417 -282.71597) (xy 349.848603 -282.740015)
			(xy 349.888472 -282.771045) (xy 349.92269 -282.808215) (xy 349.950323 -282.850509) (xy 349.970617 -282.896775)
			(xy 349.98302 -282.945751) (xy 349.987192 -282.9961) (xy 349.987189 -282.996132) (xy 350.315288 -282.996132)
			(xy 350.319248 -282.947078) (xy 350.331025 -282.899294) (xy 350.350316 -282.854018) (xy 350.376619 -282.812422)
			(xy 350.409254 -282.775585) (xy 350.447375 -282.74446) (xy 350.489996 -282.719853) (xy 350.536012 -282.702401)
			(xy 350.584231 -282.692557) (xy 350.633406 -282.690576) (xy 350.682261 -282.696508) (xy 350.729532 -282.7102)
			(xy 350.773994 -282.731298) (xy 350.814497 -282.759254) (xy 350.84999 -282.793346) (xy 350.879555 -282.83269)
			(xy 350.902426 -282.876267) (xy 350.91801 -282.922948) (xy 350.925905 -282.971525) (xy 350.926399 -282.9961)
			(xy 351.255272 -282.9961) (xy 351.259444 -282.945758) (xy 351.271846 -282.896789) (xy 351.292139 -282.850529)
			(xy 351.319771 -282.808241) (xy 351.353986 -282.771079) (xy 351.393852 -282.740055) (xy 351.438281 -282.716017)
			(xy 351.486061 -282.699621) (xy 351.535888 -282.691313) (xy 351.561146 -282.690824) (xy 352.5012 -282.690824)
			(xy 352.526458 -282.691282) (xy 352.576285 -282.699596) (xy 352.624064 -282.715999) (xy 352.668491 -282.740042)
			(xy 352.708355 -282.771069) (xy 352.742569 -282.808235) (xy 352.770198 -282.850525) (xy 352.79049 -282.896786)
			(xy 352.802891 -282.945757) (xy 352.807063 -282.9961) (xy 352.80706 -282.996132) (xy 353.135196 -282.996132)
			(xy 353.139156 -282.947078) (xy 353.150933 -282.899294) (xy 353.170224 -282.854018) (xy 353.196527 -282.812422)
			(xy 353.229162 -282.775585) (xy 353.267283 -282.74446) (xy 353.309904 -282.719853) (xy 353.35592 -282.702401)
			(xy 353.404139 -282.692557) (xy 353.453314 -282.690576) (xy 353.502169 -282.696508) (xy 353.54944 -282.7102)
			(xy 353.593902 -282.731298) (xy 353.634405 -282.759254) (xy 353.669898 -282.793346) (xy 353.699463 -282.83269)
			(xy 353.722334 -282.876267) (xy 353.737918 -282.922948) (xy 353.745813 -282.971525) (xy 353.746307 -282.9961)
			(xy 354.075301 -282.9961) (xy 354.079471 -282.945772) (xy 354.091867 -282.896816) (xy 354.112151 -282.850569)
			(xy 354.13977 -282.80829) (xy 354.17397 -282.771133) (xy 354.213819 -282.740111) (xy 354.258231 -282.716071)
			(xy 354.305993 -282.699668) (xy 354.355804 -282.691349) (xy 354.381054 -282.690824) (xy 355.321108 -282.690824)
			(xy 355.346366 -282.691282) (xy 355.396191 -282.699598) (xy 355.443969 -282.716001) (xy 355.488395 -282.740045)
			(xy 355.528258 -282.771072) (xy 355.562471 -282.808238) (xy 355.5901 -282.850528) (xy 355.610391 -282.896788)
			(xy 355.622792 -282.945757) (xy 355.626963 -282.9961) (xy 355.62696 -282.996132) (xy 355.955358 -282.996132)
			(xy 355.959318 -282.947078) (xy 355.971095 -282.899294) (xy 355.990386 -282.854018) (xy 356.016689 -282.812422)
			(xy 356.049324 -282.775585) (xy 356.087445 -282.74446) (xy 356.130066 -282.719853) (xy 356.176082 -282.702401)
			(xy 356.224301 -282.692557) (xy 356.273476 -282.690576) (xy 356.322331 -282.696508) (xy 356.369602 -282.7102)
			(xy 356.414064 -282.731298) (xy 356.454567 -282.759254) (xy 356.49006 -282.793346) (xy 356.519625 -282.83269)
			(xy 356.542496 -282.876267) (xy 356.55808 -282.922948) (xy 356.565975 -282.971525) (xy 356.56647 -282.996132)
			(xy 363.468932 -282.996132) (xy 363.472892 -282.947078) (xy 363.484669 -282.899294) (xy 363.50396 -282.854018)
			(xy 363.530263 -282.812422) (xy 363.562898 -282.775585) (xy 363.601019 -282.74446) (xy 363.64364 -282.719853)
			(xy 363.689656 -282.702401) (xy 363.737875 -282.692557) (xy 363.78705 -282.690576) (xy 363.835905 -282.696508)
			(xy 363.883176 -282.7102) (xy 363.927638 -282.731298) (xy 363.968141 -282.759254) (xy 364.003634 -282.793346)
			(xy 364.033199 -282.83269) (xy 364.05607 -282.876267) (xy 364.071654 -282.922948) (xy 364.079549 -282.971525)
			(xy 364.080043 -282.9961) (xy 364.409001 -282.9961) (xy 364.413172 -282.945768) (xy 364.425569 -282.896809)
			(xy 364.445856 -282.850559) (xy 364.473479 -282.808278) (xy 364.507684 -282.77112) (xy 364.547539 -282.740099)
			(xy 364.591955 -282.71606) (xy 364.639723 -282.69966) (xy 364.689538 -282.691346) (xy 364.71479 -282.690824)
			(xy 365.654844 -282.690824) (xy 365.6801 -282.691285) (xy 365.729921 -282.699605) (xy 365.777694 -282.716012)
			(xy 365.822115 -282.740057) (xy 365.861972 -282.771085) (xy 365.89618 -282.80825) (xy 365.923805 -282.850538)
			(xy 365.944094 -282.896795) (xy 365.956492 -282.945761) (xy 365.960663 -282.9961) (xy 365.96066 -282.996132)
			(xy 366.289094 -282.996132) (xy 366.293054 -282.947078) (xy 366.304831 -282.899294) (xy 366.324122 -282.854018)
			(xy 366.350425 -282.812422) (xy 366.38306 -282.775585) (xy 366.421181 -282.74446) (xy 366.463802 -282.719853)
			(xy 366.509818 -282.702401) (xy 366.558037 -282.692557) (xy 366.607212 -282.690576) (xy 366.656067 -282.696508)
			(xy 366.703338 -282.7102) (xy 366.7478 -282.731298) (xy 366.788303 -282.759254) (xy 366.823796 -282.793346)
			(xy 366.853361 -282.83269) (xy 366.876232 -282.876267) (xy 366.891816 -282.922948) (xy 366.899711 -282.971525)
			(xy 366.900205 -282.9961) (xy 367.228901 -282.9961) (xy 367.233072 -282.945767) (xy 367.24547 -282.896808)
			(xy 367.265758 -282.850556) (xy 367.293381 -282.808275) (xy 367.327587 -282.771117) (xy 367.367443 -282.740096)
			(xy 367.411861 -282.716058) (xy 367.459629 -282.699659) (xy 367.509445 -282.691346) (xy 367.534698 -282.690824)
			(xy 368.474752 -282.690824) (xy 368.500015 -282.691249) (xy 368.549853 -282.699558) (xy 368.597643 -282.715958)
			(xy 368.642082 -282.740001) (xy 368.681956 -282.771031) (xy 368.716179 -282.808201) (xy 368.743817 -282.850498)
			(xy 368.764115 -282.896767) (xy 368.776519 -282.945747) (xy 368.780692 -282.9961) (xy 368.780689 -282.996132)
			(xy 369.109002 -282.996132) (xy 369.112962 -282.947078) (xy 369.124739 -282.899294) (xy 369.14403 -282.854018)
			(xy 369.170333 -282.812422) (xy 369.202968 -282.775585) (xy 369.241089 -282.74446) (xy 369.28371 -282.719853)
			(xy 369.329726 -282.702401) (xy 369.377945 -282.692557) (xy 369.42712 -282.690576) (xy 369.475975 -282.696508)
			(xy 369.523246 -282.7102) (xy 369.567708 -282.731298) (xy 369.608211 -282.759254) (xy 369.643704 -282.793346)
			(xy 369.673269 -282.83269) (xy 369.69614 -282.876267) (xy 369.711724 -282.922948) (xy 369.719619 -282.971525)
			(xy 369.720113 -282.9961) (xy 370.049101 -282.9961) (xy 370.053271 -282.945771) (xy 370.065667 -282.896815)
			(xy 370.085952 -282.850567) (xy 370.113571 -282.808288) (xy 370.147772 -282.771131) (xy 370.187623 -282.740109)
			(xy 370.232035 -282.716069) (xy 370.279798 -282.699667) (xy 370.329609 -282.691349) (xy 370.35486 -282.690824)
			(xy 371.294914 -282.690824) (xy 371.320171 -282.691283) (xy 371.369996 -282.699599) (xy 371.417773 -282.716003)
			(xy 371.462199 -282.740047) (xy 371.502061 -282.771074) (xy 371.536273 -282.80824) (xy 371.563901 -282.850529)
			(xy 371.584191 -282.896789) (xy 371.596592 -282.945758) (xy 371.600763 -282.9961) (xy 371.60076 -282.996132)
			(xy 371.92891 -282.996132) (xy 371.93287 -282.947078) (xy 371.944647 -282.899294) (xy 371.963938 -282.854018)
			(xy 371.990241 -282.812422) (xy 372.022876 -282.775585) (xy 372.060997 -282.74446) (xy 372.103618 -282.719853)
			(xy 372.149634 -282.702401) (xy 372.197853 -282.692557) (xy 372.247028 -282.690576) (xy 372.295883 -282.696508)
			(xy 372.343154 -282.7102) (xy 372.387616 -282.731298) (xy 372.428119 -282.759254) (xy 372.463612 -282.793346)
			(xy 372.493177 -282.83269) (xy 372.516048 -282.876267) (xy 372.531632 -282.922948) (xy 372.539527 -282.971525)
			(xy 372.540021 -282.9961) (xy 372.869001 -282.9961) (xy 372.873171 -282.94577) (xy 372.885568 -282.896814)
			(xy 372.905853 -282.850565) (xy 372.933473 -282.808285) (xy 372.967676 -282.771128) (xy 373.007527 -282.740106)
			(xy 373.05194 -282.716067) (xy 373.099705 -282.699665) (xy 373.149517 -282.691348) (xy 373.174768 -282.690824)
			(xy 374.114822 -282.690824) (xy 374.140079 -282.691283) (xy 374.189903 -282.699601) (xy 374.237679 -282.716005)
			(xy 374.282103 -282.740049) (xy 374.321964 -282.771077) (xy 374.356175 -282.808242) (xy 374.383802 -282.850531)
			(xy 374.404092 -282.896791) (xy 374.416492 -282.945759) (xy 374.420663 -282.9961) (xy 374.42066 -282.996132)
			(xy 374.749072 -282.996132) (xy 374.753032 -282.947078) (xy 374.764809 -282.899294) (xy 374.7841 -282.854018)
			(xy 374.810403 -282.812422) (xy 374.843038 -282.775585) (xy 374.881159 -282.74446) (xy 374.92378 -282.719853)
			(xy 374.969796 -282.702401) (xy 375.018015 -282.692557) (xy 375.06719 -282.690576) (xy 375.116045 -282.696508)
			(xy 375.163316 -282.7102) (xy 375.207778 -282.731298) (xy 375.248281 -282.759254) (xy 375.283774 -282.793346)
			(xy 375.313339 -282.83269) (xy 375.33621 -282.876267) (xy 375.351794 -282.922948) (xy 375.359689 -282.971525)
			(xy 375.360184 -282.996132) (xy 375.678695 -282.996132) (xy 375.68279 -282.945404) (xy 375.694969 -282.89599)
			(xy 375.714917 -282.84917) (xy 375.742118 -282.806156) (xy 375.775866 -282.768062) (xy 375.815288 -282.735875)
			(xy 375.859362 -282.710429) (xy 375.906948 -282.692382) (xy 375.956812 -282.682202) (xy 376.007664 -282.680153)
			(xy 376.058185 -282.686287) (xy 376.107069 -282.700447) (xy 376.153048 -282.722264) (xy 376.194932 -282.751174)
			(xy 376.231636 -282.786429) (xy 376.262209 -282.827115) (xy 376.28586 -282.872178) (xy 376.301976 -282.920452)
			(xy 376.31014 -282.970686) (xy 376.310652 -282.996132) (xy 376.628926 -282.996132) (xy 376.632886 -282.947078)
			(xy 376.644663 -282.899294) (xy 376.663954 -282.854018) (xy 376.690257 -282.812422) (xy 376.722892 -282.775585)
			(xy 376.761013 -282.74446) (xy 376.803634 -282.719853) (xy 376.84965 -282.702401) (xy 376.897869 -282.692557)
			(xy 376.947044 -282.690576) (xy 376.995899 -282.696508) (xy 377.04317 -282.7102) (xy 377.087632 -282.731298)
			(xy 377.128135 -282.759254) (xy 377.163628 -282.793346) (xy 377.193193 -282.83269) (xy 377.216064 -282.876267)
			(xy 377.231648 -282.922948) (xy 377.239543 -282.971525) (xy 377.240038 -282.996132) (xy 377.558549 -282.996132)
			(xy 377.562644 -282.945404) (xy 377.574823 -282.89599) (xy 377.594771 -282.84917) (xy 377.621972 -282.806156)
			(xy 377.65572 -282.768062) (xy 377.695142 -282.735875) (xy 377.739216 -282.710429) (xy 377.786802 -282.692382)
			(xy 377.836666 -282.682202) (xy 377.887518 -282.680153) (xy 377.938039 -282.686287) (xy 377.986923 -282.700447)
			(xy 378.032902 -282.722264) (xy 378.074786 -282.751174) (xy 378.11149 -282.786429) (xy 378.142063 -282.827115)
			(xy 378.165714 -282.872178) (xy 378.18183 -282.920452) (xy 378.189994 -282.970686) (xy 378.190506 -282.996132)
			(xy 378.189994 -283.021578) (xy 378.18183 -283.071812) (xy 378.165714 -283.120086) (xy 378.142063 -283.165149)
			(xy 378.11149 -283.205835) (xy 378.074786 -283.24109) (xy 378.032902 -283.27) (xy 377.986923 -283.291817)
			(xy 377.938039 -283.305977) (xy 377.887518 -283.312111) (xy 377.836666 -283.310062) (xy 377.786802 -283.299882)
			(xy 377.739216 -283.281835) (xy 377.695142 -283.256389) (xy 377.65572 -283.224202) (xy 377.621972 -283.186108)
			(xy 377.594771 -283.143094) (xy 377.574823 -283.096274) (xy 377.562644 -283.04686) (xy 377.558549 -282.996132)
			(xy 377.240038 -282.996132) (xy 377.239543 -283.020739) (xy 377.231648 -283.069316) (xy 377.216064 -283.115997)
			(xy 377.193193 -283.159574) (xy 377.163628 -283.198918) (xy 377.128135 -283.23301) (xy 377.087632 -283.260966)
			(xy 377.04317 -283.282064) (xy 376.995899 -283.295756) (xy 376.947044 -283.301688) (xy 376.897869 -283.299707)
			(xy 376.84965 -283.289863) (xy 376.803634 -283.272411) (xy 376.761013 -283.247804) (xy 376.722892 -283.216679)
			(xy 376.690257 -283.179842) (xy 376.663954 -283.138246) (xy 376.644663 -283.09297) (xy 376.632886 -283.045186)
			(xy 376.628926 -282.996132) (xy 376.310652 -282.996132) (xy 376.31014 -283.021578) (xy 376.301976 -283.071812)
			(xy 376.28586 -283.120086) (xy 376.262209 -283.165149) (xy 376.231636 -283.205835) (xy 376.194932 -283.24109)
			(xy 376.153048 -283.27) (xy 376.107069 -283.291817) (xy 376.058185 -283.305977) (xy 376.007664 -283.312111)
			(xy 375.956812 -283.310062) (xy 375.906948 -283.299882) (xy 375.859362 -283.281835) (xy 375.815288 -283.256389)
			(xy 375.775866 -283.224202) (xy 375.742118 -283.186108) (xy 375.714917 -283.143094) (xy 375.694969 -283.096274)
			(xy 375.68279 -283.04686) (xy 375.678695 -282.996132) (xy 375.360184 -282.996132) (xy 375.359689 -283.020739)
			(xy 375.351794 -283.069316) (xy 375.33621 -283.115997) (xy 375.313339 -283.159574) (xy 375.283774 -283.198918)
			(xy 375.248281 -283.23301) (xy 375.207778 -283.260966) (xy 375.163316 -283.282064) (xy 375.116045 -283.295756)
			(xy 375.06719 -283.301688) (xy 375.018015 -283.299707) (xy 374.969796 -283.289863) (xy 374.92378 -283.272411)
			(xy 374.881159 -283.247804) (xy 374.843038 -283.216679) (xy 374.810403 -283.179842) (xy 374.7841 -283.138246)
			(xy 374.764809 -283.09297) (xy 374.753032 -283.045186) (xy 374.749072 -282.996132) (xy 374.42066 -282.996132)
			(xy 374.416492 -283.046441) (xy 374.404092 -283.095409) (xy 374.383802 -283.141669) (xy 374.356175 -283.183958)
			(xy 374.321964 -283.221123) (xy 374.282103 -283.252151) (xy 374.237679 -283.276195) (xy 374.189903 -283.292599)
			(xy 374.140079 -283.300917) (xy 374.114822 -283.30144) (xy 373.174768 -283.30144) (xy 373.149517 -283.300852)
			(xy 373.099705 -283.292535) (xy 373.05194 -283.276133) (xy 373.007527 -283.252094) (xy 372.967676 -283.221072)
			(xy 372.933473 -283.183915) (xy 372.905853 -283.141635) (xy 372.885568 -283.095386) (xy 372.873171 -283.04643)
			(xy 372.869001 -282.9961) (xy 372.540021 -282.9961) (xy 372.540022 -282.996132) (xy 372.539527 -283.020739)
			(xy 372.531632 -283.069316) (xy 372.516048 -283.115997) (xy 372.493177 -283.159574) (xy 372.463612 -283.198918)
			(xy 372.428119 -283.23301) (xy 372.387616 -283.260966) (xy 372.343154 -283.282064) (xy 372.295883 -283.295756)
			(xy 372.247028 -283.301688) (xy 372.197853 -283.299707) (xy 372.149634 -283.289863) (xy 372.103618 -283.272411)
			(xy 372.060997 -283.247804) (xy 372.022876 -283.216679) (xy 371.990241 -283.179842) (xy 371.963938 -283.138246)
			(xy 371.944647 -283.09297) (xy 371.93287 -283.045186) (xy 371.92891 -282.996132) (xy 371.60076 -282.996132)
			(xy 371.596592 -283.046442) (xy 371.584191 -283.095411) (xy 371.563901 -283.141671) (xy 371.536273 -283.18396)
			(xy 371.502061 -283.221126) (xy 371.462199 -283.252153) (xy 371.417773 -283.276197) (xy 371.369996 -283.292601)
			(xy 371.320171 -283.300917) (xy 371.294914 -283.30144) (xy 370.35486 -283.30144) (xy 370.329609 -283.300851)
			(xy 370.279798 -283.292533) (xy 370.232035 -283.276131) (xy 370.187623 -283.252091) (xy 370.147772 -283.221069)
			(xy 370.113571 -283.183912) (xy 370.085952 -283.141633) (xy 370.065667 -283.095385) (xy 370.053271 -283.046429)
			(xy 370.049101 -282.9961) (xy 369.720113 -282.9961) (xy 369.720114 -282.996132) (xy 369.719619 -283.020739)
			(xy 369.711724 -283.069316) (xy 369.69614 -283.115997) (xy 369.673269 -283.159574) (xy 369.643704 -283.198918)
			(xy 369.608211 -283.23301) (xy 369.567708 -283.260966) (xy 369.523246 -283.282064) (xy 369.475975 -283.295756)
			(xy 369.42712 -283.301688) (xy 369.377945 -283.299707) (xy 369.329726 -283.289863) (xy 369.28371 -283.272411)
			(xy 369.241089 -283.247804) (xy 369.202968 -283.216679) (xy 369.170333 -283.179842) (xy 369.14403 -283.138246)
			(xy 369.124739 -283.09297) (xy 369.112962 -283.045186) (xy 369.109002 -282.996132) (xy 368.780689 -282.996132)
			(xy 368.776519 -283.046453) (xy 368.764115 -283.095433) (xy 368.743817 -283.141702) (xy 368.716179 -283.183999)
			(xy 368.681956 -283.221169) (xy 368.642082 -283.252199) (xy 368.597643 -283.276242) (xy 368.549853 -283.292642)
			(xy 368.500015 -283.300951) (xy 368.474752 -283.30144) (xy 367.534698 -283.30144) (xy 367.509445 -283.300854)
			(xy 367.459629 -283.292541) (xy 367.411861 -283.276142) (xy 367.367443 -283.252104) (xy 367.327587 -283.221083)
			(xy 367.293381 -283.183925) (xy 367.265758 -283.141644) (xy 367.24547 -283.095392) (xy 367.233072 -283.046433)
			(xy 367.228901 -282.9961) (xy 366.900205 -282.9961) (xy 366.900206 -282.996132) (xy 366.899711 -283.020739)
			(xy 366.891816 -283.069316) (xy 366.876232 -283.115997) (xy 366.853361 -283.159574) (xy 366.823796 -283.198918)
			(xy 366.788303 -283.23301) (xy 366.7478 -283.260966) (xy 366.703338 -283.282064) (xy 366.656067 -283.295756)
			(xy 366.607212 -283.301688) (xy 366.558037 -283.299707) (xy 366.509818 -283.289863) (xy 366.463802 -283.272411)
			(xy 366.421181 -283.247804) (xy 366.38306 -283.216679) (xy 366.350425 -283.179842) (xy 366.324122 -283.138246)
			(xy 366.304831 -283.09297) (xy 366.293054 -283.045186) (xy 366.289094 -282.996132) (xy 365.96066 -282.996132)
			(xy 365.956492 -283.046439) (xy 365.944094 -283.095405) (xy 365.923805 -283.141662) (xy 365.89618 -283.18395)
			(xy 365.861972 -283.221115) (xy 365.822115 -283.252143) (xy 365.777694 -283.276188) (xy 365.729921 -283.292595)
			(xy 365.6801 -283.300915) (xy 365.654844 -283.30144) (xy 364.71479 -283.30144) (xy 364.689538 -283.300854)
			(xy 364.639723 -283.29254) (xy 364.591955 -283.27614) (xy 364.547539 -283.252101) (xy 364.507684 -283.22108)
			(xy 364.473479 -283.183922) (xy 364.445856 -283.141641) (xy 364.425569 -283.095391) (xy 364.413172 -283.046432)
			(xy 364.409001 -282.9961) (xy 364.080043 -282.9961) (xy 364.080044 -282.996132) (xy 364.079549 -283.020739)
			(xy 364.071654 -283.069316) (xy 364.05607 -283.115997) (xy 364.033199 -283.159574) (xy 364.003634 -283.198918)
			(xy 363.968141 -283.23301) (xy 363.927638 -283.260966) (xy 363.883176 -283.282064) (xy 363.835905 -283.295756)
			(xy 363.78705 -283.301688) (xy 363.737875 -283.299707) (xy 363.689656 -283.289863) (xy 363.64364 -283.272411)
			(xy 363.601019 -283.247804) (xy 363.562898 -283.216679) (xy 363.530263 -283.179842) (xy 363.50396 -283.138246)
			(xy 363.484669 -283.09297) (xy 363.472892 -283.045186) (xy 363.468932 -282.996132) (xy 356.56647 -282.996132)
			(xy 356.565975 -283.020739) (xy 356.55808 -283.069316) (xy 356.542496 -283.115997) (xy 356.519625 -283.159574)
			(xy 356.49006 -283.198918) (xy 356.454567 -283.23301) (xy 356.414064 -283.260966) (xy 356.369602 -283.282064)
			(xy 356.322331 -283.295756) (xy 356.273476 -283.301688) (xy 356.224301 -283.299707) (xy 356.176082 -283.289863)
			(xy 356.130066 -283.272411) (xy 356.087445 -283.247804) (xy 356.049324 -283.216679) (xy 356.016689 -283.179842)
			(xy 355.990386 -283.138246) (xy 355.971095 -283.09297) (xy 355.959318 -283.045186) (xy 355.955358 -282.996132)
			(xy 355.62696 -282.996132) (xy 355.622792 -283.046443) (xy 355.610391 -283.095412) (xy 355.5901 -283.141672)
			(xy 355.562471 -283.183962) (xy 355.528258 -283.221128) (xy 355.488395 -283.252155) (xy 355.443969 -283.276199)
			(xy 355.396191 -283.292602) (xy 355.346366 -283.300918) (xy 355.321108 -283.30144) (xy 354.381054 -283.30144)
			(xy 354.355804 -283.300851) (xy 354.305993 -283.292532) (xy 354.258231 -283.276129) (xy 354.213819 -283.252089)
			(xy 354.17397 -283.221067) (xy 354.13977 -283.18391) (xy 354.112151 -283.141631) (xy 354.091867 -283.095384)
			(xy 354.079471 -283.046428) (xy 354.075301 -282.9961) (xy 353.746307 -282.9961) (xy 353.746308 -282.996132)
			(xy 353.745813 -283.020739) (xy 353.737918 -283.069316) (xy 353.722334 -283.115997) (xy 353.699463 -283.159574)
			(xy 353.669898 -283.198918) (xy 353.634405 -283.23301) (xy 353.593902 -283.260966) (xy 353.54944 -283.282064)
			(xy 353.502169 -283.295756) (xy 353.453314 -283.301688) (xy 353.404139 -283.299707) (xy 353.35592 -283.289863)
			(xy 353.309904 -283.272411) (xy 353.267283 -283.247804) (xy 353.229162 -283.216679) (xy 353.196527 -283.179842)
			(xy 353.170224 -283.138246) (xy 353.150933 -283.09297) (xy 353.139156 -283.045186) (xy 353.135196 -282.996132)
			(xy 352.80706 -282.996132) (xy 352.802891 -283.046443) (xy 352.79049 -283.095414) (xy 352.770198 -283.141675)
			(xy 352.742569 -283.183965) (xy 352.708355 -283.221131) (xy 352.668491 -283.252158) (xy 352.624064 -283.276201)
			(xy 352.576285 -283.292604) (xy 352.526458 -283.300918) (xy 352.5012 -283.30144) (xy 351.561146 -283.30144)
			(xy 351.535888 -283.300887) (xy 351.486061 -283.292579) (xy 351.438281 -283.276183) (xy 351.393852 -283.252145)
			(xy 351.353986 -283.221121) (xy 351.319771 -283.183959) (xy 351.292139 -283.141671) (xy 351.271846 -283.095411)
			(xy 351.259444 -283.046442) (xy 351.255272 -282.9961) (xy 350.926399 -282.9961) (xy 350.9264 -282.996132)
			(xy 350.925905 -283.020739) (xy 350.91801 -283.069316) (xy 350.902426 -283.115997) (xy 350.879555 -283.159574)
			(xy 350.84999 -283.198918) (xy 350.814497 -283.23301) (xy 350.773994 -283.260966) (xy 350.729532 -283.282064)
			(xy 350.682261 -283.295756) (xy 350.633406 -283.301688) (xy 350.584231 -283.299707) (xy 350.536012 -283.289863)
			(xy 350.489996 -283.272411) (xy 350.447375 -283.247804) (xy 350.409254 -283.216679) (xy 350.376619 -283.179842)
			(xy 350.350316 -283.138246) (xy 350.331025 -283.09297) (xy 350.319248 -283.045186) (xy 350.315288 -282.996132)
			(xy 349.987189 -282.996132) (xy 349.98302 -283.046449) (xy 349.970617 -283.095425) (xy 349.950323 -283.141691)
			(xy 349.92269 -283.183985) (xy 349.888472 -283.221155) (xy 349.848603 -283.252185) (xy 349.80417 -283.27623)
			(xy 349.756386 -283.292633) (xy 349.706553 -283.300948) (xy 349.681292 -283.30144) (xy 348.741238 -283.30144)
			(xy 348.715981 -283.300886) (xy 348.666155 -283.292578) (xy 348.618376 -283.27618) (xy 348.573948 -283.252142)
			(xy 348.534083 -283.221119) (xy 348.499869 -283.183956) (xy 348.472238 -283.141669) (xy 348.451945 -283.09541)
			(xy 348.439544 -283.046442) (xy 348.435372 -282.9961) (xy 348.106491 -282.9961) (xy 348.106492 -282.996132)
			(xy 348.105997 -283.020739) (xy 348.098102 -283.069316) (xy 348.082518 -283.115997) (xy 348.059647 -283.159574)
			(xy 348.030082 -283.198918) (xy 347.994589 -283.23301) (xy 347.954086 -283.260966) (xy 347.909624 -283.282064)
			(xy 347.862353 -283.295756) (xy 347.813498 -283.301688) (xy 347.764323 -283.299707) (xy 347.716104 -283.289863)
			(xy 347.670088 -283.272411) (xy 347.627467 -283.247804) (xy 347.589346 -283.216679) (xy 347.556711 -283.179842)
			(xy 347.530408 -283.138246) (xy 347.511117 -283.09297) (xy 347.49934 -283.045186) (xy 347.49538 -282.996132)
			(xy 347.16696 -282.996132) (xy 347.162792 -283.04644) (xy 347.150393 -283.095408) (xy 347.130103 -283.141666)
			(xy 347.102477 -283.183955) (xy 347.068267 -283.22112) (xy 347.028407 -283.252148) (xy 346.983984 -283.276192)
			(xy 346.936209 -283.292597) (xy 346.886386 -283.300916) (xy 346.86113 -283.30144) (xy 345.921076 -283.30144)
			(xy 345.895825 -283.300853) (xy 345.846011 -283.292537) (xy 345.798246 -283.276135) (xy 345.753831 -283.252096)
			(xy 345.713979 -283.221075) (xy 345.679775 -283.183918) (xy 345.652154 -283.141638) (xy 345.631868 -283.095388)
			(xy 345.619471 -283.04643) (xy 345.615301 -282.9961) (xy 345.286329 -282.9961) (xy 345.28633 -282.996132)
			(xy 345.285835 -283.020739) (xy 345.27794 -283.069316) (xy 345.262356 -283.115997) (xy 345.239485 -283.159574)
			(xy 345.20992 -283.198918) (xy 345.174427 -283.23301) (xy 345.133924 -283.260966) (xy 345.089462 -283.282064)
			(xy 345.042191 -283.295756) (xy 344.993336 -283.301688) (xy 344.944161 -283.299707) (xy 344.895942 -283.289863)
			(xy 344.849926 -283.272411) (xy 344.807305 -283.247804) (xy 344.769184 -283.216679) (xy 344.736549 -283.179842)
			(xy 344.710246 -283.138246) (xy 344.690955 -283.09297) (xy 344.679178 -283.045186) (xy 344.675218 -282.996132)
			(xy 344.356944 -282.996132) (xy 344.356432 -283.021578) (xy 344.348268 -283.071812) (xy 344.332152 -283.120086)
			(xy 344.308501 -283.165149) (xy 344.277928 -283.205835) (xy 344.241224 -283.24109) (xy 344.19934 -283.27)
			(xy 344.153361 -283.291817) (xy 344.104477 -283.305977) (xy 344.053956 -283.312111) (xy 344.003104 -283.310062)
			(xy 343.95324 -283.299882) (xy 343.905654 -283.281835) (xy 343.86158 -283.256389) (xy 343.822158 -283.224202)
			(xy 343.78841 -283.186108) (xy 343.761209 -283.143094) (xy 343.741261 -283.096274) (xy 343.729082 -283.04686)
			(xy 343.724987 -282.996132) (xy 343.406476 -282.996132) (xy 343.405981 -283.020739) (xy 343.398086 -283.069316)
			(xy 343.382502 -283.115997) (xy 343.359631 -283.159574) (xy 343.330066 -283.198918) (xy 343.294573 -283.23301)
			(xy 343.25407 -283.260966) (xy 343.209608 -283.282064) (xy 343.162337 -283.295756) (xy 343.113482 -283.301688)
			(xy 343.064307 -283.299707) (xy 343.016088 -283.289863) (xy 342.970072 -283.272411) (xy 342.927451 -283.247804)
			(xy 342.88933 -283.216679) (xy 342.856695 -283.179842) (xy 342.830392 -283.138246) (xy 342.811101 -283.09297)
			(xy 342.799324 -283.045186) (xy 342.795364 -282.996132) (xy 342.476836 -282.996132) (xy 342.476324 -283.021578)
			(xy 342.46816 -283.071812) (xy 342.452044 -283.120086) (xy 342.428393 -283.165149) (xy 342.39782 -283.205835)
			(xy 342.361116 -283.24109) (xy 342.319232 -283.27) (xy 342.273253 -283.291817) (xy 342.224369 -283.305977)
			(xy 342.173848 -283.312111) (xy 342.122996 -283.310062) (xy 342.073132 -283.299882) (xy 342.025546 -283.281835)
			(xy 341.981472 -283.256389) (xy 341.94205 -283.224202) (xy 341.908302 -283.186108) (xy 341.881101 -283.143094)
			(xy 341.861153 -283.096274) (xy 341.848974 -283.04686) (xy 341.844879 -282.996132) (xy 341.525921 -282.996132)
			(xy 341.525921 -283.020169) (xy 341.518368 -283.067702) (xy 341.50345 -283.11346) (xy 341.481537 -283.156311)
			(xy 341.453172 -283.195193) (xy 341.419056 -283.229142) (xy 341.380037 -283.257317) (xy 341.337079 -283.279021)
			(xy 341.291248 -283.293715) (xy 341.267542 -283.297884) (xy 341.258652 -283.299154) (xy 341.24265 -283.308044)
			(xy 341.236808 -283.314902) (xy 341.231222 -283.321988) (xy 341.22498 -283.338906) (xy 341.224616 -283.347922)
			(xy 341.224616 -283.50718) (xy 341.224853 -283.513696) (xy 341.228199 -283.526294) (xy 341.23122 -283.532072)
			(xy 341.24116 -283.549838) (xy 341.258706 -283.586578) (xy 341.266272 -283.605478) (xy 341.266272 -283.605732)
			(xy 341.268902 -283.611919) (xy 341.27688 -283.622735) (xy 341.28202 -283.627068) (xy 341.293196 -283.635704)
			(xy 341.305642 -283.637228) (xy 341.395812 -283.648658) (xy 341.402691 -283.649256) (xy 341.416339 -283.647195)
			(xy 341.422736 -283.644594) (xy 341.428578 -283.642054) (xy 341.438992 -283.633672) (xy 341.44331 -283.62783)
			(xy 341.457776 -283.60853) (xy 341.491765 -283.574312) (xy 341.530704 -283.545854) (xy 341.573628 -283.523861)
			(xy 341.619472 -283.508878) (xy 341.667099 -283.501278) (xy 341.691214 -283.50083) (xy 341.716465 -283.501353)
			(xy 341.766279 -283.509667) (xy 341.814045 -283.526067) (xy 341.85846 -283.550105) (xy 341.898313 -283.581126)
			(xy 341.932517 -283.618283) (xy 341.960139 -283.660563) (xy 341.980425 -283.706812) (xy 341.992823 -283.75577)
			(xy 341.996993 -283.8061) (xy 341.99699 -283.806138) (xy 342.314779 -283.806138) (xy 342.318874 -283.75541)
			(xy 342.331053 -283.705996) (xy 342.351001 -283.659176) (xy 342.378202 -283.616162) (xy 342.41195 -283.578068)
			(xy 342.451372 -283.545881) (xy 342.495446 -283.520435) (xy 342.543032 -283.502388) (xy 342.592896 -283.492208)
			(xy 342.643748 -283.490159) (xy 342.694269 -283.496293) (xy 342.743153 -283.510453) (xy 342.789132 -283.53227)
			(xy 342.831016 -283.56118) (xy 342.86772 -283.596435) (xy 342.898293 -283.637121) (xy 342.921944 -283.682184)
			(xy 342.93806 -283.730458) (xy 342.946224 -283.780692) (xy 342.946736 -283.806138) (xy 343.254833 -283.806138)
			(xy 343.258928 -283.75541) (xy 343.271107 -283.705996) (xy 343.291055 -283.659176) (xy 343.318256 -283.616162)
			(xy 343.352004 -283.578068) (xy 343.391426 -283.545881) (xy 343.4355 -283.520435) (xy 343.483086 -283.502388)
			(xy 343.53295 -283.492208) (xy 343.583802 -283.490159) (xy 343.634323 -283.496293) (xy 343.683207 -283.510453)
			(xy 343.729186 -283.53227) (xy 343.77107 -283.56118) (xy 343.807774 -283.596435) (xy 343.838347 -283.637121)
			(xy 343.861998 -283.682184) (xy 343.878114 -283.730458) (xy 343.886278 -283.780692) (xy 343.88679 -283.806138)
			(xy 344.205318 -283.806138) (xy 344.209278 -283.757084) (xy 344.221055 -283.7093) (xy 344.240346 -283.664024)
			(xy 344.266649 -283.622428) (xy 344.299284 -283.585591) (xy 344.337405 -283.554466) (xy 344.380026 -283.529859)
			(xy 344.426042 -283.512407) (xy 344.474261 -283.502563) (xy 344.523436 -283.500582) (xy 344.572291 -283.506514)
			(xy 344.619562 -283.520206) (xy 344.664024 -283.541304) (xy 344.704527 -283.56926) (xy 344.74002 -283.603352)
			(xy 344.769585 -283.642696) (xy 344.792456 -283.686273) (xy 344.80804 -283.732954) (xy 344.815935 -283.781531)
			(xy 344.81643 -283.806138) (xy 347.025226 -283.806138) (xy 347.029186 -283.757084) (xy 347.040963 -283.7093)
			(xy 347.060254 -283.664024) (xy 347.086557 -283.622428) (xy 347.119192 -283.585591) (xy 347.157313 -283.554466)
			(xy 347.199934 -283.529859) (xy 347.24595 -283.512407) (xy 347.294169 -283.502563) (xy 347.343344 -283.500582)
			(xy 347.392199 -283.506514) (xy 347.43947 -283.520206) (xy 347.483932 -283.541304) (xy 347.524435 -283.56926)
			(xy 347.559928 -283.603352) (xy 347.589493 -283.642696) (xy 347.612364 -283.686273) (xy 347.627948 -283.732954)
			(xy 347.635843 -283.781531) (xy 347.636338 -283.806138) (xy 349.845388 -283.806138) (xy 349.849348 -283.757084)
			(xy 349.861125 -283.7093) (xy 349.880416 -283.664024) (xy 349.906719 -283.622428) (xy 349.939354 -283.585591)
			(xy 349.977475 -283.554466) (xy 350.020096 -283.529859) (xy 350.066112 -283.512407) (xy 350.114331 -283.502563)
			(xy 350.163506 -283.500582) (xy 350.212361 -283.506514) (xy 350.259632 -283.520206) (xy 350.304094 -283.541304)
			(xy 350.344597 -283.56926) (xy 350.38009 -283.603352) (xy 350.409655 -283.642696) (xy 350.432526 -283.686273)
			(xy 350.44811 -283.732954) (xy 350.456005 -283.781531) (xy 350.4565 -283.806138) (xy 352.665296 -283.806138)
			(xy 352.669256 -283.757084) (xy 352.681033 -283.7093) (xy 352.700324 -283.664024) (xy 352.726627 -283.622428)
			(xy 352.759262 -283.585591) (xy 352.797383 -283.554466) (xy 352.840004 -283.529859) (xy 352.88602 -283.512407)
			(xy 352.934239 -283.502563) (xy 352.983414 -283.500582) (xy 353.032269 -283.506514) (xy 353.07954 -283.520206)
			(xy 353.124002 -283.541304) (xy 353.164505 -283.56926) (xy 353.199998 -283.603352) (xy 353.229563 -283.642696)
			(xy 353.252434 -283.686273) (xy 353.268018 -283.732954) (xy 353.275913 -283.781531) (xy 353.276408 -283.806138)
			(xy 355.485204 -283.806138) (xy 355.489164 -283.757084) (xy 355.500941 -283.7093) (xy 355.520232 -283.664024)
			(xy 355.546535 -283.622428) (xy 355.57917 -283.585591) (xy 355.617291 -283.554466) (xy 355.659912 -283.529859)
			(xy 355.705928 -283.512407) (xy 355.754147 -283.502563) (xy 355.803322 -283.500582) (xy 355.852177 -283.506514)
			(xy 355.899448 -283.520206) (xy 355.94391 -283.541304) (xy 355.984413 -283.56926) (xy 356.019906 -283.603352)
			(xy 356.049471 -283.642696) (xy 356.072342 -283.686273) (xy 356.087926 -283.732954) (xy 356.095821 -283.781531)
			(xy 356.096315 -283.8061) (xy 356.425052 -283.8061) (xy 356.429226 -283.75573) (xy 356.441632 -283.706734)
			(xy 356.461934 -283.660448) (xy 356.489576 -283.618134) (xy 356.523805 -283.580947) (xy 356.563688 -283.5499)
			(xy 356.608136 -283.525841) (xy 356.655939 -283.509425) (xy 356.705791 -283.501101) (xy 356.731062 -283.500576)
			(xy 357.671116 -283.500576) (xy 357.696395 -283.501023) (xy 357.746262 -283.509347) (xy 357.794079 -283.525765)
			(xy 357.838542 -283.549829) (xy 357.878438 -283.580883) (xy 357.912679 -283.61808) (xy 357.94033 -283.660406)
			(xy 357.960638 -283.706705) (xy 357.973049 -283.755715) (xy 357.977224 -283.8061) (xy 357.977221 -283.806138)
			(xy 358.305366 -283.806138) (xy 358.309326 -283.757084) (xy 358.321103 -283.7093) (xy 358.340394 -283.664024)
			(xy 358.366697 -283.622428) (xy 358.399332 -283.585591) (xy 358.437453 -283.554466) (xy 358.480074 -283.529859)
			(xy 358.52609 -283.512407) (xy 358.574309 -283.502563) (xy 358.623484 -283.500582) (xy 358.672339 -283.506514)
			(xy 358.71961 -283.520206) (xy 358.764072 -283.541304) (xy 358.804575 -283.56926) (xy 358.840068 -283.603352)
			(xy 358.869633 -283.642696) (xy 358.892504 -283.686273) (xy 358.908088 -283.732954) (xy 358.915983 -283.781531)
			(xy 358.916478 -283.806138) (xy 361.118924 -283.806138) (xy 361.122884 -283.757084) (xy 361.134661 -283.7093)
			(xy 361.153952 -283.664024) (xy 361.180255 -283.622428) (xy 361.21289 -283.585591) (xy 361.251011 -283.554466)
			(xy 361.293632 -283.529859) (xy 361.339648 -283.512407) (xy 361.387867 -283.502563) (xy 361.437042 -283.500582)
			(xy 361.485897 -283.506514) (xy 361.533168 -283.520206) (xy 361.57763 -283.541304) (xy 361.618133 -283.56926)
			(xy 361.653626 -283.603352) (xy 361.683191 -283.642696) (xy 361.706062 -283.686273) (xy 361.721646 -283.732954)
			(xy 361.729541 -283.781531) (xy 361.730035 -283.8061) (xy 362.058752 -283.8061) (xy 362.062926 -283.755728)
			(xy 362.075334 -283.70673) (xy 362.095637 -283.660442) (xy 362.123281 -283.618128) (xy 362.157513 -283.58094)
			(xy 362.197398 -283.549894) (xy 362.24185 -283.525835) (xy 362.289655 -283.509421) (xy 362.33951 -283.501099)
			(xy 362.364782 -283.500576) (xy 363.304836 -283.500576) (xy 363.330114 -283.501025) (xy 363.379978 -283.509351)
			(xy 363.427793 -283.525771) (xy 363.472253 -283.549836) (xy 363.512146 -283.58089) (xy 363.546384 -283.618087)
			(xy 363.574033 -283.660411) (xy 363.594339 -283.706709) (xy 363.606749 -283.755717) (xy 363.610924 -283.8061)
			(xy 363.610921 -283.806138) (xy 363.939086 -283.806138) (xy 363.943046 -283.757084) (xy 363.954823 -283.7093)
			(xy 363.974114 -283.664024) (xy 364.000417 -283.622428) (xy 364.033052 -283.585591) (xy 364.071173 -283.554466)
			(xy 364.113794 -283.529859) (xy 364.15981 -283.512407) (xy 364.208029 -283.502563) (xy 364.257204 -283.500582)
			(xy 364.306059 -283.506514) (xy 364.35333 -283.520206) (xy 364.397792 -283.541304) (xy 364.438295 -283.56926)
			(xy 364.473788 -283.603352) (xy 364.503353 -283.642696) (xy 364.526224 -283.686273) (xy 364.541808 -283.732954)
			(xy 364.549703 -283.781531) (xy 364.550198 -283.806138) (xy 366.758994 -283.806138) (xy 366.762954 -283.757084)
			(xy 366.774731 -283.7093) (xy 366.794022 -283.664024) (xy 366.820325 -283.622428) (xy 366.85296 -283.585591)
			(xy 366.891081 -283.554466) (xy 366.933702 -283.529859) (xy 366.979718 -283.512407) (xy 367.027937 -283.502563)
			(xy 367.077112 -283.500582) (xy 367.125967 -283.506514) (xy 367.173238 -283.520206) (xy 367.2177 -283.541304)
			(xy 367.258203 -283.56926) (xy 367.293696 -283.603352) (xy 367.323261 -283.642696) (xy 367.346132 -283.686273)
			(xy 367.361716 -283.732954) (xy 367.369611 -283.781531) (xy 367.370106 -283.806138) (xy 369.578902 -283.806138)
			(xy 369.582862 -283.757084) (xy 369.594639 -283.7093) (xy 369.61393 -283.664024) (xy 369.640233 -283.622428)
			(xy 369.672868 -283.585591) (xy 369.710989 -283.554466) (xy 369.75361 -283.529859) (xy 369.799626 -283.512407)
			(xy 369.847845 -283.502563) (xy 369.89702 -283.500582) (xy 369.945875 -283.506514) (xy 369.993146 -283.520206)
			(xy 370.037608 -283.541304) (xy 370.078111 -283.56926) (xy 370.113604 -283.603352) (xy 370.143169 -283.642696)
			(xy 370.16604 -283.686273) (xy 370.181624 -283.732954) (xy 370.189519 -283.781531) (xy 370.190014 -283.806138)
			(xy 372.399064 -283.806138) (xy 372.403024 -283.757084) (xy 372.414801 -283.7093) (xy 372.434092 -283.664024)
			(xy 372.460395 -283.622428) (xy 372.49303 -283.585591) (xy 372.531151 -283.554466) (xy 372.573772 -283.529859)
			(xy 372.619788 -283.512407) (xy 372.668007 -283.502563) (xy 372.717182 -283.500582) (xy 372.766037 -283.506514)
			(xy 372.813308 -283.520206) (xy 372.85777 -283.541304) (xy 372.898273 -283.56926) (xy 372.933766 -283.603352)
			(xy 372.963331 -283.642696) (xy 372.986202 -283.686273) (xy 373.001786 -283.732954) (xy 373.009681 -283.781531)
			(xy 373.010176 -283.806138) (xy 375.218972 -283.806138) (xy 375.222932 -283.757084) (xy 375.234709 -283.7093)
			(xy 375.254 -283.664024) (xy 375.280303 -283.622428) (xy 375.312938 -283.585591) (xy 375.351059 -283.554466)
			(xy 375.39368 -283.529859) (xy 375.439696 -283.512407) (xy 375.487915 -283.502563) (xy 375.53709 -283.500582)
			(xy 375.585945 -283.506514) (xy 375.633216 -283.520206) (xy 375.677678 -283.541304) (xy 375.718181 -283.56926)
			(xy 375.753674 -283.603352) (xy 375.783239 -283.642696) (xy 375.80611 -283.686273) (xy 375.821694 -283.732954)
			(xy 375.829589 -283.781531) (xy 375.830084 -283.806138) (xy 376.148595 -283.806138) (xy 376.15269 -283.75541)
			(xy 376.164869 -283.705996) (xy 376.184817 -283.659176) (xy 376.212018 -283.616162) (xy 376.245766 -283.578068)
			(xy 376.285188 -283.545881) (xy 376.329262 -283.520435) (xy 376.376848 -283.502388) (xy 376.426712 -283.492208)
			(xy 376.477564 -283.490159) (xy 376.528085 -283.496293) (xy 376.576969 -283.510453) (xy 376.622948 -283.53227)
			(xy 376.664832 -283.56118) (xy 376.701536 -283.596435) (xy 376.732109 -283.637121) (xy 376.75576 -283.682184)
			(xy 376.771876 -283.730458) (xy 376.78004 -283.780692) (xy 376.780552 -283.806138) (xy 377.088649 -283.806138)
			(xy 377.092744 -283.75541) (xy 377.104923 -283.705996) (xy 377.124871 -283.659176) (xy 377.152072 -283.616162)
			(xy 377.18582 -283.578068) (xy 377.225242 -283.545881) (xy 377.269316 -283.520435) (xy 377.316902 -283.502388)
			(xy 377.366766 -283.492208) (xy 377.417618 -283.490159) (xy 377.468139 -283.496293) (xy 377.517023 -283.510453)
			(xy 377.563002 -283.53227) (xy 377.604886 -283.56118) (xy 377.64159 -283.596435) (xy 377.672163 -283.637121)
			(xy 377.695814 -283.682184) (xy 377.71193 -283.730458) (xy 377.720094 -283.780692) (xy 377.720606 -283.806138)
			(xy 377.720094 -283.831584) (xy 377.71193 -283.881818) (xy 377.695814 -283.930092) (xy 377.672163 -283.975155)
			(xy 377.64159 -284.015841) (xy 377.604886 -284.051096) (xy 377.563002 -284.080006) (xy 377.517023 -284.101823)
			(xy 377.468139 -284.115983) (xy 377.417618 -284.122117) (xy 377.366766 -284.120068) (xy 377.316902 -284.109888)
			(xy 377.269316 -284.091841) (xy 377.225242 -284.066395) (xy 377.18582 -284.034208) (xy 377.152072 -283.996114)
			(xy 377.124871 -283.9531) (xy 377.104923 -283.90628) (xy 377.092744 -283.856866) (xy 377.088649 -283.806138)
			(xy 376.780552 -283.806138) (xy 376.78004 -283.831584) (xy 376.771876 -283.881818) (xy 376.75576 -283.930092)
			(xy 376.732109 -283.975155) (xy 376.701536 -284.015841) (xy 376.664832 -284.051096) (xy 376.622948 -284.080006)
			(xy 376.576969 -284.101823) (xy 376.528085 -284.115983) (xy 376.477564 -284.122117) (xy 376.426712 -284.120068)
			(xy 376.376848 -284.109888) (xy 376.329262 -284.091841) (xy 376.285188 -284.066395) (xy 376.245766 -284.034208)
			(xy 376.212018 -283.996114) (xy 376.184817 -283.9531) (xy 376.164869 -283.90628) (xy 376.15269 -283.856866)
			(xy 376.148595 -283.806138) (xy 375.830084 -283.806138) (xy 375.829589 -283.830745) (xy 375.821694 -283.879322)
			(xy 375.80611 -283.926003) (xy 375.783239 -283.96958) (xy 375.753674 -284.008924) (xy 375.718181 -284.043016)
			(xy 375.677678 -284.070972) (xy 375.633216 -284.09207) (xy 375.585945 -284.105762) (xy 375.53709 -284.111694)
			(xy 375.487915 -284.109713) (xy 375.439696 -284.099869) (xy 375.39368 -284.082417) (xy 375.351059 -284.05781)
			(xy 375.312938 -284.026685) (xy 375.280303 -283.989848) (xy 375.254 -283.948252) (xy 375.234709 -283.902976)
			(xy 375.222932 -283.855192) (xy 375.218972 -283.806138) (xy 373.010176 -283.806138) (xy 373.009681 -283.830745)
			(xy 373.001786 -283.879322) (xy 372.986202 -283.926003) (xy 372.963331 -283.96958) (xy 372.933766 -284.008924)
			(xy 372.898273 -284.043016) (xy 372.85777 -284.070972) (xy 372.813308 -284.09207) (xy 372.766037 -284.105762)
			(xy 372.717182 -284.111694) (xy 372.668007 -284.109713) (xy 372.619788 -284.099869) (xy 372.573772 -284.082417)
			(xy 372.531151 -284.05781) (xy 372.49303 -284.026685) (xy 372.460395 -283.989848) (xy 372.434092 -283.948252)
			(xy 372.414801 -283.902976) (xy 372.403024 -283.855192) (xy 372.399064 -283.806138) (xy 370.190014 -283.806138)
			(xy 370.189519 -283.830745) (xy 370.181624 -283.879322) (xy 370.16604 -283.926003) (xy 370.143169 -283.96958)
			(xy 370.113604 -284.008924) (xy 370.078111 -284.043016) (xy 370.037608 -284.070972) (xy 369.993146 -284.09207)
			(xy 369.945875 -284.105762) (xy 369.89702 -284.111694) (xy 369.847845 -284.109713) (xy 369.799626 -284.099869)
			(xy 369.75361 -284.082417) (xy 369.710989 -284.05781) (xy 369.672868 -284.026685) (xy 369.640233 -283.989848)
			(xy 369.61393 -283.948252) (xy 369.594639 -283.902976) (xy 369.582862 -283.855192) (xy 369.578902 -283.806138)
			(xy 367.370106 -283.806138) (xy 367.369611 -283.830745) (xy 367.361716 -283.879322) (xy 367.346132 -283.926003)
			(xy 367.323261 -283.96958) (xy 367.293696 -284.008924) (xy 367.258203 -284.043016) (xy 367.2177 -284.070972)
			(xy 367.173238 -284.09207) (xy 367.125967 -284.105762) (xy 367.077112 -284.111694) (xy 367.027937 -284.109713)
			(xy 366.979718 -284.099869) (xy 366.933702 -284.082417) (xy 366.891081 -284.05781) (xy 366.85296 -284.026685)
			(xy 366.820325 -283.989848) (xy 366.794022 -283.948252) (xy 366.774731 -283.902976) (xy 366.762954 -283.855192)
			(xy 366.758994 -283.806138) (xy 364.550198 -283.806138) (xy 364.549703 -283.830745) (xy 364.541808 -283.879322)
			(xy 364.526224 -283.926003) (xy 364.503353 -283.96958) (xy 364.473788 -284.008924) (xy 364.438295 -284.043016)
			(xy 364.397792 -284.070972) (xy 364.35333 -284.09207) (xy 364.306059 -284.105762) (xy 364.257204 -284.111694)
			(xy 364.208029 -284.109713) (xy 364.15981 -284.099869) (xy 364.113794 -284.082417) (xy 364.071173 -284.05781)
			(xy 364.033052 -284.026685) (xy 364.000417 -283.989848) (xy 363.974114 -283.948252) (xy 363.954823 -283.902976)
			(xy 363.943046 -283.855192) (xy 363.939086 -283.806138) (xy 363.610921 -283.806138) (xy 363.606749 -283.856483)
			(xy 363.594339 -283.905491) (xy 363.574033 -283.951789) (xy 363.546384 -283.994113) (xy 363.512146 -284.03131)
			(xy 363.472253 -284.062364) (xy 363.427793 -284.086429) (xy 363.379978 -284.102849) (xy 363.330114 -284.111175)
			(xy 363.304836 -284.1117) (xy 362.364782 -284.1117) (xy 362.33951 -284.111101) (xy 362.289655 -284.102779)
			(xy 362.24185 -284.086365) (xy 362.197398 -284.062306) (xy 362.157513 -284.03126) (xy 362.123281 -283.994072)
			(xy 362.095637 -283.951758) (xy 362.075334 -283.90547) (xy 362.062926 -283.856472) (xy 362.058752 -283.8061)
			(xy 361.730035 -283.8061) (xy 361.730036 -283.806138) (xy 361.729541 -283.830745) (xy 361.721646 -283.879322)
			(xy 361.706062 -283.926003) (xy 361.683191 -283.96958) (xy 361.653626 -284.008924) (xy 361.618133 -284.043016)
			(xy 361.57763 -284.070972) (xy 361.533168 -284.09207) (xy 361.485897 -284.105762) (xy 361.437042 -284.111694)
			(xy 361.387867 -284.109713) (xy 361.339648 -284.099869) (xy 361.293632 -284.082417) (xy 361.251011 -284.05781)
			(xy 361.21289 -284.026685) (xy 361.180255 -283.989848) (xy 361.153952 -283.948252) (xy 361.134661 -283.902976)
			(xy 361.122884 -283.855192) (xy 361.118924 -283.806138) (xy 358.916478 -283.806138) (xy 358.915983 -283.830745)
			(xy 358.908088 -283.879322) (xy 358.892504 -283.926003) (xy 358.869633 -283.96958) (xy 358.840068 -284.008924)
			(xy 358.804575 -284.043016) (xy 358.764072 -284.070972) (xy 358.71961 -284.09207) (xy 358.672339 -284.105762)
			(xy 358.623484 -284.111694) (xy 358.574309 -284.109713) (xy 358.52609 -284.099869) (xy 358.480074 -284.082417)
			(xy 358.437453 -284.05781) (xy 358.399332 -284.026685) (xy 358.366697 -283.989848) (xy 358.340394 -283.948252)
			(xy 358.321103 -283.902976) (xy 358.309326 -283.855192) (xy 358.305366 -283.806138) (xy 357.977221 -283.806138)
			(xy 357.973049 -283.856485) (xy 357.960638 -283.905495) (xy 357.94033 -283.951794) (xy 357.912679 -283.99412)
			(xy 357.878438 -284.031317) (xy 357.838542 -284.062371) (xy 357.794079 -284.086435) (xy 357.746262 -284.102853)
			(xy 357.696395 -284.111177) (xy 357.671116 -284.1117) (xy 356.731062 -284.1117) (xy 356.705791 -284.111099)
			(xy 356.655939 -284.102775) (xy 356.608136 -284.086359) (xy 356.563688 -284.0623) (xy 356.523805 -284.031253)
			(xy 356.489576 -283.994066) (xy 356.461934 -283.951752) (xy 356.441632 -283.905466) (xy 356.429226 -283.85647)
			(xy 356.425052 -283.8061) (xy 356.096315 -283.8061) (xy 356.096316 -283.806138) (xy 356.095821 -283.830745)
			(xy 356.087926 -283.879322) (xy 356.072342 -283.926003) (xy 356.049471 -283.96958) (xy 356.019906 -284.008924)
			(xy 355.984413 -284.043016) (xy 355.94391 -284.070972) (xy 355.899448 -284.09207) (xy 355.852177 -284.105762)
			(xy 355.803322 -284.111694) (xy 355.754147 -284.109713) (xy 355.705928 -284.099869) (xy 355.659912 -284.082417)
			(xy 355.617291 -284.05781) (xy 355.57917 -284.026685) (xy 355.546535 -283.989848) (xy 355.520232 -283.948252)
			(xy 355.500941 -283.902976) (xy 355.489164 -283.855192) (xy 355.485204 -283.806138) (xy 353.276408 -283.806138)
			(xy 353.275913 -283.830745) (xy 353.268018 -283.879322) (xy 353.252434 -283.926003) (xy 353.229563 -283.96958)
			(xy 353.199998 -284.008924) (xy 353.164505 -284.043016) (xy 353.124002 -284.070972) (xy 353.07954 -284.09207)
			(xy 353.032269 -284.105762) (xy 352.983414 -284.111694) (xy 352.934239 -284.109713) (xy 352.88602 -284.099869)
			(xy 352.840004 -284.082417) (xy 352.797383 -284.05781) (xy 352.759262 -284.026685) (xy 352.726627 -283.989848)
			(xy 352.700324 -283.948252) (xy 352.681033 -283.902976) (xy 352.669256 -283.855192) (xy 352.665296 -283.806138)
			(xy 350.4565 -283.806138) (xy 350.456005 -283.830745) (xy 350.44811 -283.879322) (xy 350.432526 -283.926003)
			(xy 350.409655 -283.96958) (xy 350.38009 -284.008924) (xy 350.344597 -284.043016) (xy 350.304094 -284.070972)
			(xy 350.259632 -284.09207) (xy 350.212361 -284.105762) (xy 350.163506 -284.111694) (xy 350.114331 -284.109713)
			(xy 350.066112 -284.099869) (xy 350.020096 -284.082417) (xy 349.977475 -284.05781) (xy 349.939354 -284.026685)
			(xy 349.906719 -283.989848) (xy 349.880416 -283.948252) (xy 349.861125 -283.902976) (xy 349.849348 -283.855192)
			(xy 349.845388 -283.806138) (xy 347.636338 -283.806138) (xy 347.635843 -283.830745) (xy 347.627948 -283.879322)
			(xy 347.612364 -283.926003) (xy 347.589493 -283.96958) (xy 347.559928 -284.008924) (xy 347.524435 -284.043016)
			(xy 347.483932 -284.070972) (xy 347.43947 -284.09207) (xy 347.392199 -284.105762) (xy 347.343344 -284.111694)
			(xy 347.294169 -284.109713) (xy 347.24595 -284.099869) (xy 347.199934 -284.082417) (xy 347.157313 -284.05781)
			(xy 347.119192 -284.026685) (xy 347.086557 -283.989848) (xy 347.060254 -283.948252) (xy 347.040963 -283.902976)
			(xy 347.029186 -283.855192) (xy 347.025226 -283.806138) (xy 344.81643 -283.806138) (xy 344.815935 -283.830745)
			(xy 344.80804 -283.879322) (xy 344.792456 -283.926003) (xy 344.769585 -283.96958) (xy 344.74002 -284.008924)
			(xy 344.704527 -284.043016) (xy 344.664024 -284.070972) (xy 344.619562 -284.09207) (xy 344.572291 -284.105762)
			(xy 344.523436 -284.111694) (xy 344.474261 -284.109713) (xy 344.426042 -284.099869) (xy 344.380026 -284.082417)
			(xy 344.337405 -284.05781) (xy 344.299284 -284.026685) (xy 344.266649 -283.989848) (xy 344.240346 -283.948252)
			(xy 344.221055 -283.902976) (xy 344.209278 -283.855192) (xy 344.205318 -283.806138) (xy 343.88679 -283.806138)
			(xy 343.886278 -283.831584) (xy 343.878114 -283.881818) (xy 343.861998 -283.930092) (xy 343.838347 -283.975155)
			(xy 343.807774 -284.015841) (xy 343.77107 -284.051096) (xy 343.729186 -284.080006) (xy 343.683207 -284.101823)
			(xy 343.634323 -284.115983) (xy 343.583802 -284.122117) (xy 343.53295 -284.120068) (xy 343.483086 -284.109888)
			(xy 343.4355 -284.091841) (xy 343.391426 -284.066395) (xy 343.352004 -284.034208) (xy 343.318256 -283.996114)
			(xy 343.291055 -283.9531) (xy 343.271107 -283.90628) (xy 343.258928 -283.856866) (xy 343.254833 -283.806138)
			(xy 342.946736 -283.806138) (xy 342.946224 -283.831584) (xy 342.93806 -283.881818) (xy 342.921944 -283.930092)
			(xy 342.898293 -283.975155) (xy 342.86772 -284.015841) (xy 342.831016 -284.051096) (xy 342.789132 -284.080006)
			(xy 342.743153 -284.101823) (xy 342.694269 -284.115983) (xy 342.643748 -284.122117) (xy 342.592896 -284.120068)
			(xy 342.543032 -284.109888) (xy 342.495446 -284.091841) (xy 342.451372 -284.066395) (xy 342.41195 -284.034208)
			(xy 342.378202 -283.996114) (xy 342.351001 -283.9531) (xy 342.331053 -283.90628) (xy 342.318874 -283.856866)
			(xy 342.314779 -283.806138) (xy 341.99699 -283.806138) (xy 341.992823 -283.85643) (xy 341.980425 -283.905388)
			(xy 341.960139 -283.951637) (xy 341.932517 -283.993917) (xy 341.898313 -284.031074) (xy 341.85846 -284.062095)
			(xy 341.814045 -284.086133) (xy 341.766279 -284.102533) (xy 341.716465 -284.110847) (xy 341.691214 -284.111446)
			(xy 341.678451 -284.11131) (xy 341.653016 -284.109152) (xy 341.640414 -284.107128) (xy 341.640414 -284.107382)
			(xy 341.61696 -284.102956) (xy 341.571704 -284.087796) (xy 341.529349 -284.065795) (xy 341.490923 -284.037485)
			(xy 341.457358 -284.003555) (xy 341.443056 -283.984446) (xy 341.438992 -283.978604) (xy 341.428324 -283.969968)
			(xy 341.422482 -283.967428) (xy 341.416199 -283.964906) (xy 341.402805 -283.962967) (xy 341.396066 -283.963618)
			(xy 341.305642 -283.975048) (xy 341.293196 -283.976572) (xy 341.28202 -283.985208) (xy 341.276892 -283.989552)
			(xy 341.268916 -284.000365) (xy 341.266272 -284.006544) (xy 341.266272 -284.006798) (xy 341.258701 -284.025695)
			(xy 341.241155 -284.062435) (xy 341.23122 -284.080204) (xy 341.227918 -284.086046) (xy 341.226394 -284.092142)
			(xy 341.224616 -284.105096) (xy 341.224616 -284.264354) (xy 341.224985 -284.273367) (xy 341.231247 -284.29027)
			(xy 341.236808 -284.297374) (xy 341.24265 -284.304232) (xy 341.258652 -284.313122) (xy 341.267542 -284.314392)
			(xy 341.291257 -284.3185) (xy 341.337085 -284.333195) (xy 341.38004 -284.354899) (xy 341.419057 -284.383075)
			(xy 341.45317 -284.417024) (xy 341.481533 -284.455905) (xy 341.503444 -284.498755) (xy 341.518359 -284.544512)
			(xy 341.52591 -284.592043) (xy 341.525909 -284.616144) (xy 341.844879 -284.616144) (xy 341.848974 -284.565416)
			(xy 341.861153 -284.516002) (xy 341.881101 -284.469182) (xy 341.908302 -284.426168) (xy 341.94205 -284.388074)
			(xy 341.981472 -284.355887) (xy 342.025546 -284.330441) (xy 342.073132 -284.312394) (xy 342.122996 -284.302214)
			(xy 342.173848 -284.300165) (xy 342.224369 -284.306299) (xy 342.273253 -284.320459) (xy 342.319232 -284.342276)
			(xy 342.361116 -284.371186) (xy 342.39782 -284.406441) (xy 342.428393 -284.447127) (xy 342.452044 -284.49219)
			(xy 342.46816 -284.540464) (xy 342.476324 -284.590698) (xy 342.476836 -284.616144) (xy 342.795364 -284.616144)
			(xy 342.799324 -284.56709) (xy 342.811101 -284.519306) (xy 342.830392 -284.47403) (xy 342.856695 -284.432434)
			(xy 342.88933 -284.395597) (xy 342.927451 -284.364472) (xy 342.970072 -284.339865) (xy 343.016088 -284.322413)
			(xy 343.064307 -284.312569) (xy 343.113482 -284.310588) (xy 343.162337 -284.31652) (xy 343.209608 -284.330212)
			(xy 343.25407 -284.35131) (xy 343.294573 -284.379266) (xy 343.330066 -284.413358) (xy 343.359631 -284.452702)
			(xy 343.382502 -284.496279) (xy 343.398086 -284.54296) (xy 343.405981 -284.591537) (xy 343.406476 -284.616144)
			(xy 343.724987 -284.616144) (xy 343.729082 -284.565416) (xy 343.741261 -284.516002) (xy 343.761209 -284.469182)
			(xy 343.78841 -284.426168) (xy 343.822158 -284.388074) (xy 343.86158 -284.355887) (xy 343.905654 -284.330441)
			(xy 343.95324 -284.312394) (xy 344.003104 -284.302214) (xy 344.053956 -284.300165) (xy 344.104477 -284.306299)
			(xy 344.153361 -284.320459) (xy 344.19934 -284.342276) (xy 344.241224 -284.371186) (xy 344.277928 -284.406441)
			(xy 344.308501 -284.447127) (xy 344.332152 -284.49219) (xy 344.348268 -284.540464) (xy 344.356432 -284.590698)
			(xy 344.356944 -284.616144) (xy 344.675218 -284.616144) (xy 344.679178 -284.56709) (xy 344.690955 -284.519306)
			(xy 344.710246 -284.47403) (xy 344.736549 -284.432434) (xy 344.769184 -284.395597) (xy 344.807305 -284.364472)
			(xy 344.849926 -284.339865) (xy 344.895942 -284.322413) (xy 344.944161 -284.312569) (xy 344.993336 -284.310588)
			(xy 345.042191 -284.31652) (xy 345.089462 -284.330212) (xy 345.133924 -284.35131) (xy 345.174427 -284.379266)
			(xy 345.20992 -284.413358) (xy 345.239485 -284.452702) (xy 345.262356 -284.496279) (xy 345.27794 -284.54296)
			(xy 345.285835 -284.591537) (xy 345.286329 -284.6161) (xy 345.615313 -284.6161) (xy 345.619483 -284.565772)
			(xy 345.63188 -284.516816) (xy 345.652165 -284.470568) (xy 345.679785 -284.42829) (xy 345.713987 -284.391134)
			(xy 345.753838 -284.360114) (xy 345.798251 -284.336076) (xy 345.846014 -284.319675) (xy 345.895826 -284.311359)
			(xy 345.921076 -284.310836) (xy 346.86113 -284.310836) (xy 346.886387 -284.311272) (xy 346.936213 -284.31959)
			(xy 346.983989 -284.335996) (xy 347.028414 -284.360042) (xy 347.068275 -284.391071) (xy 347.102487 -284.428237)
			(xy 347.130114 -284.470528) (xy 347.150404 -284.516788) (xy 347.162804 -284.565758) (xy 347.166976 -284.6161)
			(xy 347.166972 -284.616144) (xy 347.49538 -284.616144) (xy 347.49934 -284.56709) (xy 347.511117 -284.519306)
			(xy 347.530408 -284.47403) (xy 347.556711 -284.432434) (xy 347.589346 -284.395597) (xy 347.627467 -284.364472)
			(xy 347.670088 -284.339865) (xy 347.716104 -284.322413) (xy 347.764323 -284.312569) (xy 347.813498 -284.310588)
			(xy 347.862353 -284.31652) (xy 347.909624 -284.330212) (xy 347.954086 -284.35131) (xy 347.994589 -284.379266)
			(xy 348.030082 -284.413358) (xy 348.059647 -284.452702) (xy 348.082518 -284.496279) (xy 348.098102 -284.54296)
			(xy 348.105997 -284.591537) (xy 348.106491 -284.6161) (xy 348.435384 -284.6161) (xy 348.439556 -284.56576)
			(xy 348.451957 -284.516794) (xy 348.472249 -284.470537) (xy 348.499878 -284.428251) (xy 348.534091 -284.39109)
			(xy 348.573955 -284.360068) (xy 348.618381 -284.336031) (xy 348.666158 -284.319634) (xy 348.715982 -284.311326)
			(xy 348.741238 -284.310836) (xy 349.681292 -284.310836) (xy 349.706554 -284.31124) (xy 349.756388 -284.319555)
			(xy 349.804175 -284.335959) (xy 349.848609 -284.360005) (xy 349.88848 -284.391036) (xy 349.922699 -284.428207)
			(xy 349.950333 -284.470504) (xy 349.970629 -284.516772) (xy 349.983032 -284.565749) (xy 349.987204 -284.6161)
			(xy 349.9872 -284.616144) (xy 350.315288 -284.616144) (xy 350.319248 -284.56709) (xy 350.331025 -284.519306)
			(xy 350.350316 -284.47403) (xy 350.376619 -284.432434) (xy 350.409254 -284.395597) (xy 350.447375 -284.364472)
			(xy 350.489996 -284.339865) (xy 350.536012 -284.322413) (xy 350.584231 -284.312569) (xy 350.633406 -284.310588)
			(xy 350.682261 -284.31652) (xy 350.729532 -284.330212) (xy 350.773994 -284.35131) (xy 350.814497 -284.379266)
			(xy 350.84999 -284.413358) (xy 350.879555 -284.452702) (xy 350.902426 -284.496279) (xy 350.91801 -284.54296)
			(xy 350.925905 -284.591537) (xy 350.926399 -284.6161) (xy 351.255284 -284.6161) (xy 351.259456 -284.56576)
			(xy 351.271857 -284.516793) (xy 351.29215 -284.470535) (xy 351.31978 -284.428249) (xy 351.353994 -284.391087)
			(xy 351.393859 -284.360065) (xy 351.438286 -284.336028) (xy 351.486064 -284.319632) (xy 351.535889 -284.311325)
			(xy 351.561146 -284.310836) (xy 352.5012 -284.310836) (xy 352.526459 -284.311269) (xy 352.576288 -284.319584)
			(xy 352.624069 -284.335987) (xy 352.668498 -284.360031) (xy 352.708364 -284.39106) (xy 352.742579 -284.428227)
			(xy 352.770209 -284.470519) (xy 352.790502 -284.516782) (xy 352.802904 -284.565755) (xy 352.807076 -284.6161)
			(xy 352.807072 -284.616144) (xy 353.135196 -284.616144) (xy 353.139156 -284.56709) (xy 353.150933 -284.519306)
			(xy 353.170224 -284.47403) (xy 353.196527 -284.432434) (xy 353.229162 -284.395597) (xy 353.267283 -284.364472)
			(xy 353.309904 -284.339865) (xy 353.35592 -284.322413) (xy 353.404139 -284.312569) (xy 353.453314 -284.310588)
			(xy 353.502169 -284.31652) (xy 353.54944 -284.330212) (xy 353.593902 -284.35131) (xy 353.634405 -284.379266)
			(xy 353.669898 -284.413358) (xy 353.699463 -284.452702) (xy 353.722334 -284.496279) (xy 353.737918 -284.54296)
			(xy 353.745813 -284.591537) (xy 353.746307 -284.6161) (xy 354.075313 -284.6161) (xy 354.079483 -284.565774)
			(xy 354.091878 -284.51682) (xy 354.112161 -284.470574) (xy 354.139779 -284.428297) (xy 354.173978 -284.391142)
			(xy 354.213826 -284.360121) (xy 354.258236 -284.336082) (xy 354.305996 -284.31968) (xy 354.355805 -284.311361)
			(xy 354.381054 -284.310836) (xy 355.321108 -284.310836) (xy 355.346367 -284.31127) (xy 355.396195 -284.319586)
			(xy 355.443974 -284.33599) (xy 355.488402 -284.360034) (xy 355.528267 -284.391063) (xy 355.562481 -284.42823)
			(xy 355.590111 -284.470522) (xy 355.610403 -284.516784) (xy 355.622804 -284.565755) (xy 355.626976 -284.6161)
			(xy 355.626972 -284.616144) (xy 355.955358 -284.616144) (xy 355.959318 -284.56709) (xy 355.971095 -284.519306)
			(xy 355.990386 -284.47403) (xy 356.016689 -284.432434) (xy 356.049324 -284.395597) (xy 356.087445 -284.364472)
			(xy 356.130066 -284.339865) (xy 356.176082 -284.322413) (xy 356.224301 -284.312569) (xy 356.273476 -284.310588)
			(xy 356.322331 -284.31652) (xy 356.369602 -284.330212) (xy 356.414064 -284.35131) (xy 356.454567 -284.379266)
			(xy 356.49006 -284.413358) (xy 356.519625 -284.452702) (xy 356.542496 -284.496279) (xy 356.55808 -284.54296)
			(xy 356.565975 -284.591537) (xy 356.56647 -284.616144) (xy 356.895412 -284.616144) (xy 356.899372 -284.56709)
			(xy 356.911149 -284.519306) (xy 356.93044 -284.47403) (xy 356.956743 -284.432434) (xy 356.989378 -284.395597)
			(xy 357.027499 -284.364472) (xy 357.07012 -284.339865) (xy 357.116136 -284.322413) (xy 357.164355 -284.312569)
			(xy 357.21353 -284.310588) (xy 357.262385 -284.31652) (xy 357.309656 -284.330212) (xy 357.354118 -284.35131)
			(xy 357.394621 -284.379266) (xy 357.430114 -284.413358) (xy 357.459679 -284.452702) (xy 357.48255 -284.496279)
			(xy 357.498134 -284.54296) (xy 357.506029 -284.591537) (xy 357.506524 -284.616144) (xy 357.835212 -284.616144)
			(xy 357.839172 -284.56709) (xy 357.850949 -284.519306) (xy 357.87024 -284.47403) (xy 357.896543 -284.432434)
			(xy 357.929178 -284.395597) (xy 357.967299 -284.364472) (xy 358.00992 -284.339865) (xy 358.055936 -284.322413)
			(xy 358.104155 -284.312569) (xy 358.15333 -284.310588) (xy 358.202185 -284.31652) (xy 358.249456 -284.330212)
			(xy 358.293918 -284.35131) (xy 358.334421 -284.379266) (xy 358.369914 -284.413358) (xy 358.399479 -284.452702)
			(xy 358.42235 -284.496279) (xy 358.437934 -284.54296) (xy 358.445829 -284.591537) (xy 358.446324 -284.616144)
			(xy 361.589078 -284.616144) (xy 361.593038 -284.56709) (xy 361.604815 -284.519306) (xy 361.624106 -284.47403)
			(xy 361.650409 -284.432434) (xy 361.683044 -284.395597) (xy 361.721165 -284.364472) (xy 361.763786 -284.339865)
			(xy 361.809802 -284.322413) (xy 361.858021 -284.312569) (xy 361.907196 -284.310588) (xy 361.956051 -284.31652)
			(xy 362.003322 -284.330212) (xy 362.047784 -284.35131) (xy 362.088287 -284.379266) (xy 362.12378 -284.413358)
			(xy 362.153345 -284.452702) (xy 362.176216 -284.496279) (xy 362.1918 -284.54296) (xy 362.199695 -284.591537)
			(xy 362.20019 -284.616144) (xy 362.528878 -284.616144) (xy 362.532838 -284.56709) (xy 362.544615 -284.519306)
			(xy 362.563906 -284.47403) (xy 362.590209 -284.432434) (xy 362.622844 -284.395597) (xy 362.660965 -284.364472)
			(xy 362.703586 -284.339865) (xy 362.749602 -284.322413) (xy 362.797821 -284.312569) (xy 362.846996 -284.310588)
			(xy 362.895851 -284.31652) (xy 362.943122 -284.330212) (xy 362.987584 -284.35131) (xy 363.028087 -284.379266)
			(xy 363.06358 -284.413358) (xy 363.093145 -284.452702) (xy 363.116016 -284.496279) (xy 363.1316 -284.54296)
			(xy 363.139495 -284.591537) (xy 363.13999 -284.616144) (xy 363.468932 -284.616144) (xy 363.472892 -284.56709)
			(xy 363.484669 -284.519306) (xy 363.50396 -284.47403) (xy 363.530263 -284.432434) (xy 363.562898 -284.395597)
			(xy 363.601019 -284.364472) (xy 363.64364 -284.339865) (xy 363.689656 -284.322413) (xy 363.737875 -284.312569)
			(xy 363.78705 -284.310588) (xy 363.835905 -284.31652) (xy 363.883176 -284.330212) (xy 363.927638 -284.35131)
			(xy 363.968141 -284.379266) (xy 364.003634 -284.413358) (xy 364.033199 -284.452702) (xy 364.05607 -284.496279)
			(xy 364.071654 -284.54296) (xy 364.079549 -284.591537) (xy 364.080043 -284.6161) (xy 364.409013 -284.6161)
			(xy 364.413183 -284.56577) (xy 364.425581 -284.516813) (xy 364.445867 -284.470564) (xy 364.473488 -284.428285)
			(xy 364.507692 -284.391129) (xy 364.547545 -284.360109) (xy 364.59196 -284.336071) (xy 364.639726 -284.319672)
			(xy 364.689539 -284.311358) (xy 364.71479 -284.310836) (xy 365.654844 -284.310836) (xy 365.680101 -284.311273)
			(xy 365.729924 -284.319593) (xy 365.777699 -284.336) (xy 365.822121 -284.360047) (xy 365.861981 -284.391076)
			(xy 365.89619 -284.428242) (xy 365.923816 -284.470532) (xy 365.944105 -284.516791) (xy 365.956505 -284.565759)
			(xy 365.960676 -284.6161) (xy 365.960672 -284.616144) (xy 366.289094 -284.616144) (xy 366.293054 -284.56709)
			(xy 366.304831 -284.519306) (xy 366.324122 -284.47403) (xy 366.350425 -284.432434) (xy 366.38306 -284.395597)
			(xy 366.421181 -284.364472) (xy 366.463802 -284.339865) (xy 366.509818 -284.322413) (xy 366.558037 -284.312569)
			(xy 366.607212 -284.310588) (xy 366.656067 -284.31652) (xy 366.703338 -284.330212) (xy 366.7478 -284.35131)
			(xy 366.788303 -284.379266) (xy 366.823796 -284.413358) (xy 366.853361 -284.452702) (xy 366.876232 -284.496279)
			(xy 366.891816 -284.54296) (xy 366.899711 -284.591537) (xy 366.900205 -284.6161) (xy 367.228913 -284.6161)
			(xy 367.233084 -284.565769) (xy 367.245481 -284.516812) (xy 367.265768 -284.470562) (xy 367.293391 -284.428282)
			(xy 367.327595 -284.391126) (xy 367.367449 -284.360106) (xy 367.411865 -284.336069) (xy 367.459632 -284.31967)
			(xy 367.509446 -284.311358) (xy 367.534698 -284.310836) (xy 368.474752 -284.310836) (xy 368.500016 -284.311237)
			(xy 368.549856 -284.319547) (xy 368.597648 -284.335947) (xy 368.642088 -284.359991) (xy 368.681965 -284.391022)
			(xy 368.716189 -284.428194) (xy 368.743827 -284.470492) (xy 368.764126 -284.516764) (xy 368.776531 -284.565745)
			(xy 368.780704 -284.6161) (xy 368.7807 -284.616144) (xy 369.109002 -284.616144) (xy 369.112962 -284.56709)
			(xy 369.124739 -284.519306) (xy 369.14403 -284.47403) (xy 369.170333 -284.432434) (xy 369.202968 -284.395597)
			(xy 369.241089 -284.364472) (xy 369.28371 -284.339865) (xy 369.329726 -284.322413) (xy 369.377945 -284.312569)
			(xy 369.42712 -284.310588) (xy 369.475975 -284.31652) (xy 369.523246 -284.330212) (xy 369.567708 -284.35131)
			(xy 369.608211 -284.379266) (xy 369.643704 -284.413358) (xy 369.673269 -284.452702) (xy 369.69614 -284.496279)
			(xy 369.711724 -284.54296) (xy 369.719619 -284.591537) (xy 369.720113 -284.6161) (xy 370.049113 -284.6161)
			(xy 370.053283 -284.565773) (xy 370.065679 -284.516819) (xy 370.085962 -284.470573) (xy 370.113581 -284.428295)
			(xy 370.147781 -284.391139) (xy 370.187629 -284.360119) (xy 370.23204 -284.33608) (xy 370.279801 -284.319678)
			(xy 370.32961 -284.311361) (xy 370.35486 -284.310836) (xy 371.294914 -284.310836) (xy 371.320172 -284.31127)
			(xy 371.369999 -284.319587) (xy 371.417778 -284.335992) (xy 371.462205 -284.360036) (xy 371.502069 -284.391065)
			(xy 371.536282 -284.428232) (xy 371.563912 -284.470523) (xy 371.584203 -284.516785) (xy 371.596604 -284.565756)
			(xy 371.600776 -284.6161) (xy 371.600772 -284.616144) (xy 371.92891 -284.616144) (xy 371.93287 -284.56709)
			(xy 371.944647 -284.519306) (xy 371.963938 -284.47403) (xy 371.990241 -284.432434) (xy 372.022876 -284.395597)
			(xy 372.060997 -284.364472) (xy 372.103618 -284.339865) (xy 372.149634 -284.322413) (xy 372.197853 -284.312569)
			(xy 372.247028 -284.310588) (xy 372.295883 -284.31652) (xy 372.343154 -284.330212) (xy 372.387616 -284.35131)
			(xy 372.428119 -284.379266) (xy 372.463612 -284.413358) (xy 372.493177 -284.452702) (xy 372.516048 -284.496279)
			(xy 372.531632 -284.54296) (xy 372.539527 -284.591537) (xy 372.540021 -284.6161) (xy 372.869013 -284.6161)
			(xy 372.873183 -284.565772) (xy 372.885579 -284.516818) (xy 372.905864 -284.47057) (xy 372.933483 -284.428292)
			(xy 372.967684 -284.391137) (xy 373.007533 -284.360116) (xy 373.051945 -284.336078) (xy 373.099708 -284.319677)
			(xy 373.149518 -284.31136) (xy 373.174768 -284.310836) (xy 374.114822 -284.310836) (xy 374.14008 -284.311271)
			(xy 374.189906 -284.319589) (xy 374.237684 -284.335994) (xy 374.28211 -284.360039) (xy 374.321972 -284.391068)
			(xy 374.356184 -284.428235) (xy 374.383813 -284.470525) (xy 374.404104 -284.516787) (xy 374.416504 -284.565757)
			(xy 374.420676 -284.6161) (xy 374.420672 -284.616144) (xy 374.749072 -284.616144) (xy 374.753032 -284.56709)
			(xy 374.764809 -284.519306) (xy 374.7841 -284.47403) (xy 374.810403 -284.432434) (xy 374.843038 -284.395597)
			(xy 374.881159 -284.364472) (xy 374.92378 -284.339865) (xy 374.969796 -284.322413) (xy 375.018015 -284.312569)
			(xy 375.06719 -284.310588) (xy 375.116045 -284.31652) (xy 375.163316 -284.330212) (xy 375.207778 -284.35131)
			(xy 375.248281 -284.379266) (xy 375.283774 -284.413358) (xy 375.313339 -284.452702) (xy 375.33621 -284.496279)
			(xy 375.351794 -284.54296) (xy 375.359689 -284.591537) (xy 375.360184 -284.616144) (xy 375.678695 -284.616144)
			(xy 375.68279 -284.565416) (xy 375.694969 -284.516002) (xy 375.714917 -284.469182) (xy 375.742118 -284.426168)
			(xy 375.775866 -284.388074) (xy 375.815288 -284.355887) (xy 375.859362 -284.330441) (xy 375.906948 -284.312394)
			(xy 375.956812 -284.302214) (xy 376.007664 -284.300165) (xy 376.058185 -284.306299) (xy 376.107069 -284.320459)
			(xy 376.153048 -284.342276) (xy 376.194932 -284.371186) (xy 376.231636 -284.406441) (xy 376.262209 -284.447127)
			(xy 376.28586 -284.49219) (xy 376.301976 -284.540464) (xy 376.31014 -284.590698) (xy 376.310652 -284.616144)
			(xy 376.628926 -284.616144) (xy 376.632886 -284.56709) (xy 376.644663 -284.519306) (xy 376.663954 -284.47403)
			(xy 376.690257 -284.432434) (xy 376.722892 -284.395597) (xy 376.761013 -284.364472) (xy 376.803634 -284.339865)
			(xy 376.84965 -284.322413) (xy 376.897869 -284.312569) (xy 376.947044 -284.310588) (xy 376.995899 -284.31652)
			(xy 377.04317 -284.330212) (xy 377.087632 -284.35131) (xy 377.128135 -284.379266) (xy 377.163628 -284.413358)
			(xy 377.193193 -284.452702) (xy 377.216064 -284.496279) (xy 377.231648 -284.54296) (xy 377.239543 -284.591537)
			(xy 377.240038 -284.616144) (xy 377.558549 -284.616144) (xy 377.562644 -284.565416) (xy 377.574823 -284.516002)
			(xy 377.594771 -284.469182) (xy 377.621972 -284.426168) (xy 377.65572 -284.388074) (xy 377.695142 -284.355887)
			(xy 377.739216 -284.330441) (xy 377.786802 -284.312394) (xy 377.836666 -284.302214) (xy 377.887518 -284.300165)
			(xy 377.938039 -284.306299) (xy 377.986923 -284.320459) (xy 378.032902 -284.342276) (xy 378.074786 -284.371186)
			(xy 378.11149 -284.406441) (xy 378.142063 -284.447127) (xy 378.165714 -284.49219) (xy 378.18183 -284.540464)
			(xy 378.189994 -284.590698) (xy 378.190506 -284.616144) (xy 378.189994 -284.64159) (xy 378.18183 -284.691824)
			(xy 378.165714 -284.740098) (xy 378.142063 -284.785161) (xy 378.11149 -284.825847) (xy 378.074786 -284.861102)
			(xy 378.032902 -284.890012) (xy 377.986923 -284.911829) (xy 377.938039 -284.925989) (xy 377.887518 -284.932123)
			(xy 377.836666 -284.930074) (xy 377.786802 -284.919894) (xy 377.739216 -284.901847) (xy 377.695142 -284.876401)
			(xy 377.65572 -284.844214) (xy 377.621972 -284.80612) (xy 377.594771 -284.763106) (xy 377.574823 -284.716286)
			(xy 377.562644 -284.666872) (xy 377.558549 -284.616144) (xy 377.240038 -284.616144) (xy 377.239543 -284.640751)
			(xy 377.231648 -284.689328) (xy 377.216064 -284.736009) (xy 377.193193 -284.779586) (xy 377.163628 -284.81893)
			(xy 377.128135 -284.853022) (xy 377.087632 -284.880978) (xy 377.04317 -284.902076) (xy 376.995899 -284.915768)
			(xy 376.947044 -284.9217) (xy 376.897869 -284.919719) (xy 376.84965 -284.909875) (xy 376.803634 -284.892423)
			(xy 376.761013 -284.867816) (xy 376.722892 -284.836691) (xy 376.690257 -284.799854) (xy 376.663954 -284.758258)
			(xy 376.644663 -284.712982) (xy 376.632886 -284.665198) (xy 376.628926 -284.616144) (xy 376.310652 -284.616144)
			(xy 376.31014 -284.64159) (xy 376.301976 -284.691824) (xy 376.28586 -284.740098) (xy 376.262209 -284.785161)
			(xy 376.231636 -284.825847) (xy 376.194932 -284.861102) (xy 376.153048 -284.890012) (xy 376.107069 -284.911829)
			(xy 376.058185 -284.925989) (xy 376.007664 -284.932123) (xy 375.956812 -284.930074) (xy 375.906948 -284.919894)
			(xy 375.859362 -284.901847) (xy 375.815288 -284.876401) (xy 375.775866 -284.844214) (xy 375.742118 -284.80612)
			(xy 375.714917 -284.763106) (xy 375.694969 -284.716286) (xy 375.68279 -284.666872) (xy 375.678695 -284.616144)
			(xy 375.360184 -284.616144) (xy 375.359689 -284.640751) (xy 375.351794 -284.689328) (xy 375.33621 -284.736009)
			(xy 375.313339 -284.779586) (xy 375.283774 -284.81893) (xy 375.248281 -284.853022) (xy 375.207778 -284.880978)
			(xy 375.163316 -284.902076) (xy 375.116045 -284.915768) (xy 375.06719 -284.9217) (xy 375.018015 -284.919719)
			(xy 374.969796 -284.909875) (xy 374.92378 -284.892423) (xy 374.881159 -284.867816) (xy 374.843038 -284.836691)
			(xy 374.810403 -284.799854) (xy 374.7841 -284.758258) (xy 374.764809 -284.712982) (xy 374.753032 -284.665198)
			(xy 374.749072 -284.616144) (xy 374.420672 -284.616144) (xy 374.416504 -284.666443) (xy 374.404104 -284.715413)
			(xy 374.383813 -284.761675) (xy 374.356184 -284.803965) (xy 374.321972 -284.841132) (xy 374.28211 -284.872161)
			(xy 374.237684 -284.896206) (xy 374.189906 -284.912611) (xy 374.14008 -284.920929) (xy 374.114822 -284.921452)
			(xy 373.174768 -284.921452) (xy 373.149518 -284.92084) (xy 373.099708 -284.912523) (xy 373.051945 -284.896122)
			(xy 373.007533 -284.872084) (xy 372.967684 -284.841063) (xy 372.933483 -284.803908) (xy 372.905864 -284.76163)
			(xy 372.885579 -284.715382) (xy 372.873183 -284.666428) (xy 372.869013 -284.6161) (xy 372.540021 -284.6161)
			(xy 372.540022 -284.616144) (xy 372.539527 -284.640751) (xy 372.531632 -284.689328) (xy 372.516048 -284.736009)
			(xy 372.493177 -284.779586) (xy 372.463612 -284.81893) (xy 372.428119 -284.853022) (xy 372.387616 -284.880978)
			(xy 372.343154 -284.902076) (xy 372.295883 -284.915768) (xy 372.247028 -284.9217) (xy 372.197853 -284.919719)
			(xy 372.149634 -284.909875) (xy 372.103618 -284.892423) (xy 372.060997 -284.867816) (xy 372.022876 -284.836691)
			(xy 371.990241 -284.799854) (xy 371.963938 -284.758258) (xy 371.944647 -284.712982) (xy 371.93287 -284.665198)
			(xy 371.92891 -284.616144) (xy 371.600772 -284.616144) (xy 371.596604 -284.666444) (xy 371.584203 -284.715415)
			(xy 371.563912 -284.761677) (xy 371.536282 -284.803968) (xy 371.502069 -284.841135) (xy 371.462205 -284.872164)
			(xy 371.417778 -284.896208) (xy 371.369999 -284.912613) (xy 371.320172 -284.92093) (xy 371.294914 -284.921452)
			(xy 370.35486 -284.921452) (xy 370.32961 -284.920839) (xy 370.279801 -284.912522) (xy 370.23204 -284.89612)
			(xy 370.187629 -284.872081) (xy 370.147781 -284.841061) (xy 370.113581 -284.803905) (xy 370.085962 -284.761627)
			(xy 370.065679 -284.715381) (xy 370.053283 -284.666427) (xy 370.049113 -284.6161) (xy 369.720113 -284.6161)
			(xy 369.720114 -284.616144) (xy 369.719619 -284.640751) (xy 369.711724 -284.689328) (xy 369.69614 -284.736009)
			(xy 369.673269 -284.779586) (xy 369.643704 -284.81893) (xy 369.608211 -284.853022) (xy 369.567708 -284.880978)
			(xy 369.523246 -284.902076) (xy 369.475975 -284.915768) (xy 369.42712 -284.9217) (xy 369.377945 -284.919719)
			(xy 369.329726 -284.909875) (xy 369.28371 -284.892423) (xy 369.241089 -284.867816) (xy 369.202968 -284.836691)
			(xy 369.170333 -284.799854) (xy 369.14403 -284.758258) (xy 369.124739 -284.712982) (xy 369.112962 -284.665198)
			(xy 369.109002 -284.616144) (xy 368.7807 -284.616144) (xy 368.776531 -284.666455) (xy 368.764126 -284.715436)
			(xy 368.743827 -284.761708) (xy 368.716189 -284.804006) (xy 368.681965 -284.841178) (xy 368.642088 -284.872209)
			(xy 368.597648 -284.896253) (xy 368.549856 -284.912653) (xy 368.500016 -284.920963) (xy 368.474752 -284.921452)
			(xy 367.534698 -284.921452) (xy 367.509446 -284.920842) (xy 367.459632 -284.91253) (xy 367.411865 -284.896131)
			(xy 367.367449 -284.872094) (xy 367.327595 -284.841074) (xy 367.293391 -284.803918) (xy 367.265768 -284.761638)
			(xy 367.245481 -284.715388) (xy 367.233084 -284.666431) (xy 367.228913 -284.6161) (xy 366.900205 -284.6161)
			(xy 366.900206 -284.616144) (xy 366.899711 -284.640751) (xy 366.891816 -284.689328) (xy 366.876232 -284.736009)
			(xy 366.853361 -284.779586) (xy 366.823796 -284.81893) (xy 366.788303 -284.853022) (xy 366.7478 -284.880978)
			(xy 366.703338 -284.902076) (xy 366.656067 -284.915768) (xy 366.607212 -284.9217) (xy 366.558037 -284.919719)
			(xy 366.509818 -284.909875) (xy 366.463802 -284.892423) (xy 366.421181 -284.867816) (xy 366.38306 -284.836691)
			(xy 366.350425 -284.799854) (xy 366.324122 -284.758258) (xy 366.304831 -284.712982) (xy 366.293054 -284.665198)
			(xy 366.289094 -284.616144) (xy 365.960672 -284.616144) (xy 365.956505 -284.666441) (xy 365.944105 -284.715409)
			(xy 365.923816 -284.761668) (xy 365.89619 -284.803958) (xy 365.861981 -284.841124) (xy 365.822121 -284.872153)
			(xy 365.777699 -284.8962) (xy 365.729924 -284.912607) (xy 365.680101 -284.920927) (xy 365.654844 -284.921452)
			(xy 364.71479 -284.921452) (xy 364.689539 -284.920842) (xy 364.639726 -284.912528) (xy 364.59196 -284.896129)
			(xy 364.547545 -284.872091) (xy 364.507692 -284.841071) (xy 364.473489 -284.803915) (xy 364.445867 -284.761636)
			(xy 364.425581 -284.715387) (xy 364.413183 -284.66643) (xy 364.409013 -284.6161) (xy 364.080043 -284.6161)
			(xy 364.080044 -284.616144) (xy 364.079549 -284.640751) (xy 364.071654 -284.689328) (xy 364.05607 -284.736009)
			(xy 364.033199 -284.779586) (xy 364.003634 -284.81893) (xy 363.968141 -284.853022) (xy 363.927638 -284.880978)
			(xy 363.883176 -284.902076) (xy 363.835905 -284.915768) (xy 363.78705 -284.9217) (xy 363.737875 -284.919719)
			(xy 363.689656 -284.909875) (xy 363.64364 -284.892423) (xy 363.601019 -284.867816) (xy 363.562898 -284.836691)
			(xy 363.530263 -284.799854) (xy 363.50396 -284.758258) (xy 363.484669 -284.712982) (xy 363.472892 -284.665198)
			(xy 363.468932 -284.616144) (xy 363.13999 -284.616144) (xy 363.139495 -284.640751) (xy 363.1316 -284.689328)
			(xy 363.116016 -284.736009) (xy 363.093145 -284.779586) (xy 363.06358 -284.81893) (xy 363.028087 -284.853022)
			(xy 362.987584 -284.880978) (xy 362.943122 -284.902076) (xy 362.895851 -284.915768) (xy 362.846996 -284.9217)
			(xy 362.797821 -284.919719) (xy 362.749602 -284.909875) (xy 362.703586 -284.892423) (xy 362.660965 -284.867816)
			(xy 362.622844 -284.836691) (xy 362.590209 -284.799854) (xy 362.563906 -284.758258) (xy 362.544615 -284.712982)
			(xy 362.532838 -284.665198) (xy 362.528878 -284.616144) (xy 362.20019 -284.616144) (xy 362.199695 -284.640751)
			(xy 362.1918 -284.689328) (xy 362.176216 -284.736009) (xy 362.153345 -284.779586) (xy 362.12378 -284.81893)
			(xy 362.088287 -284.853022) (xy 362.047784 -284.880978) (xy 362.003322 -284.902076) (xy 361.956051 -284.915768)
			(xy 361.907196 -284.9217) (xy 361.858021 -284.919719) (xy 361.809802 -284.909875) (xy 361.763786 -284.892423)
			(xy 361.721165 -284.867816) (xy 361.683044 -284.836691) (xy 361.650409 -284.799854) (xy 361.624106 -284.758258)
			(xy 361.604815 -284.712982) (xy 361.593038 -284.665198) (xy 361.589078 -284.616144) (xy 358.446324 -284.616144)
			(xy 358.445829 -284.640751) (xy 358.437934 -284.689328) (xy 358.42235 -284.736009) (xy 358.399479 -284.779586)
			(xy 358.369914 -284.81893) (xy 358.334421 -284.853022) (xy 358.293918 -284.880978) (xy 358.249456 -284.902076)
			(xy 358.202185 -284.915768) (xy 358.15333 -284.9217) (xy 358.104155 -284.919719) (xy 358.055936 -284.909875)
			(xy 358.00992 -284.892423) (xy 357.967299 -284.867816) (xy 357.929178 -284.836691) (xy 357.896543 -284.799854)
			(xy 357.87024 -284.758258) (xy 357.850949 -284.712982) (xy 357.839172 -284.665198) (xy 357.835212 -284.616144)
			(xy 357.506524 -284.616144) (xy 357.506029 -284.640751) (xy 357.498134 -284.689328) (xy 357.48255 -284.736009)
			(xy 357.459679 -284.779586) (xy 357.430114 -284.81893) (xy 357.394621 -284.853022) (xy 357.354118 -284.880978)
			(xy 357.309656 -284.902076) (xy 357.262385 -284.915768) (xy 357.21353 -284.9217) (xy 357.164355 -284.919719)
			(xy 357.116136 -284.909875) (xy 357.07012 -284.892423) (xy 357.027499 -284.867816) (xy 356.989378 -284.836691)
			(xy 356.956743 -284.799854) (xy 356.93044 -284.758258) (xy 356.911149 -284.712982) (xy 356.899372 -284.665198)
			(xy 356.895412 -284.616144) (xy 356.56647 -284.616144) (xy 356.565975 -284.640751) (xy 356.55808 -284.689328)
			(xy 356.542496 -284.736009) (xy 356.519625 -284.779586) (xy 356.49006 -284.81893) (xy 356.454567 -284.853022)
			(xy 356.414064 -284.880978) (xy 356.369602 -284.902076) (xy 356.322331 -284.915768) (xy 356.273476 -284.9217)
			(xy 356.224301 -284.919719) (xy 356.176082 -284.909875) (xy 356.130066 -284.892423) (xy 356.087445 -284.867816)
			(xy 356.049324 -284.836691) (xy 356.016689 -284.799854) (xy 355.990386 -284.758258) (xy 355.971095 -284.712982)
			(xy 355.959318 -284.665198) (xy 355.955358 -284.616144) (xy 355.626972 -284.616144) (xy 355.622804 -284.666445)
			(xy 355.610403 -284.715416) (xy 355.590111 -284.761678) (xy 355.562481 -284.80397) (xy 355.528267 -284.841137)
			(xy 355.488402 -284.872166) (xy 355.443974 -284.89621) (xy 355.396195 -284.912614) (xy 355.346367 -284.92093)
			(xy 355.321108 -284.921452) (xy 354.381054 -284.921452) (xy 354.355805 -284.920839) (xy 354.305996 -284.91252)
			(xy 354.258236 -284.896118) (xy 354.213826 -284.872079) (xy 354.173978 -284.841058) (xy 354.139779 -284.803903)
			(xy 354.112161 -284.761626) (xy 354.091878 -284.71538) (xy 354.079483 -284.666426) (xy 354.075313 -284.6161)
			(xy 353.746307 -284.6161) (xy 353.746308 -284.616144) (xy 353.745813 -284.640751) (xy 353.737918 -284.689328)
			(xy 353.722334 -284.736009) (xy 353.699463 -284.779586) (xy 353.669898 -284.81893) (xy 353.634405 -284.853022)
			(xy 353.593902 -284.880978) (xy 353.54944 -284.902076) (xy 353.502169 -284.915768) (xy 353.453314 -284.9217)
			(xy 353.404139 -284.919719) (xy 353.35592 -284.909875) (xy 353.309904 -284.892423) (xy 353.267283 -284.867816)
			(xy 353.229162 -284.836691) (xy 353.196527 -284.799854) (xy 353.170224 -284.758258) (xy 353.150933 -284.712982)
			(xy 353.139156 -284.665198) (xy 353.135196 -284.616144) (xy 352.807072 -284.616144) (xy 352.802904 -284.666445)
			(xy 352.790502 -284.715418) (xy 352.770209 -284.761681) (xy 352.742579 -284.803973) (xy 352.708364 -284.84114)
			(xy 352.668498 -284.872169) (xy 352.624069 -284.896213) (xy 352.576288 -284.912616) (xy 352.526459 -284.920931)
			(xy 352.5012 -284.921452) (xy 351.561146 -284.921452) (xy 351.535889 -284.920875) (xy 351.486064 -284.912568)
			(xy 351.438286 -284.896172) (xy 351.393859 -284.872135) (xy 351.353994 -284.841113) (xy 351.31978 -284.803951)
			(xy 351.29215 -284.761665) (xy 351.271857 -284.715407) (xy 351.259456 -284.66644) (xy 351.255284 -284.6161)
			(xy 350.926399 -284.6161) (xy 350.9264 -284.616144) (xy 350.925905 -284.640751) (xy 350.91801 -284.689328)
			(xy 350.902426 -284.736009) (xy 350.879555 -284.779586) (xy 350.84999 -284.81893) (xy 350.814497 -284.853022)
			(xy 350.773994 -284.880978) (xy 350.729532 -284.902076) (xy 350.682261 -284.915768) (xy 350.633406 -284.9217)
			(xy 350.584231 -284.919719) (xy 350.536012 -284.909875) (xy 350.489996 -284.892423) (xy 350.447375 -284.867816)
			(xy 350.409254 -284.836691) (xy 350.376619 -284.799854) (xy 350.350316 -284.758258) (xy 350.331025 -284.712982)
			(xy 350.319248 -284.665198) (xy 350.315288 -284.616144) (xy 349.9872 -284.616144) (xy 349.983032 -284.666451)
			(xy 349.970629 -284.715428) (xy 349.950333 -284.761696) (xy 349.922699 -284.803993) (xy 349.88848 -284.841164)
			(xy 349.848609 -284.872195) (xy 349.804175 -284.896241) (xy 349.756388 -284.912645) (xy 349.706554 -284.92096)
			(xy 349.681292 -284.921452) (xy 348.741238 -284.921452) (xy 348.715982 -284.920874) (xy 348.666158 -284.912566)
			(xy 348.618381 -284.896169) (xy 348.573955 -284.872132) (xy 348.534091 -284.84111) (xy 348.499878 -284.803949)
			(xy 348.472249 -284.761663) (xy 348.451957 -284.715406) (xy 348.439556 -284.66644) (xy 348.435384 -284.6161)
			(xy 348.106491 -284.6161) (xy 348.106492 -284.616144) (xy 348.105997 -284.640751) (xy 348.098102 -284.689328)
			(xy 348.082518 -284.736009) (xy 348.059647 -284.779586) (xy 348.030082 -284.81893) (xy 347.994589 -284.853022)
			(xy 347.954086 -284.880978) (xy 347.909624 -284.902076) (xy 347.862353 -284.915768) (xy 347.813498 -284.9217)
			(xy 347.764323 -284.919719) (xy 347.716104 -284.909875) (xy 347.670088 -284.892423) (xy 347.627467 -284.867816)
			(xy 347.589346 -284.836691) (xy 347.556711 -284.799854) (xy 347.530408 -284.758258) (xy 347.511117 -284.712982)
			(xy 347.49934 -284.665198) (xy 347.49538 -284.616144) (xy 347.166972 -284.616144) (xy 347.162804 -284.666442)
			(xy 347.150404 -284.715412) (xy 347.130114 -284.761672) (xy 347.102487 -284.803963) (xy 347.068275 -284.841129)
			(xy 347.028414 -284.872158) (xy 346.983989 -284.896204) (xy 346.936213 -284.91261) (xy 346.886387 -284.920928)
			(xy 346.86113 -284.921452) (xy 345.921076 -284.921452) (xy 345.895826 -284.920841) (xy 345.846014 -284.912525)
			(xy 345.798251 -284.896124) (xy 345.753838 -284.872086) (xy 345.713987 -284.841066) (xy 345.679785 -284.80391)
			(xy 345.652165 -284.761632) (xy 345.63188 -284.715384) (xy 345.619483 -284.666428) (xy 345.615313 -284.6161)
			(xy 345.286329 -284.6161) (xy 345.28633 -284.616144) (xy 345.285835 -284.640751) (xy 345.27794 -284.689328)
			(xy 345.262356 -284.736009) (xy 345.239485 -284.779586) (xy 345.20992 -284.81893) (xy 345.174427 -284.853022)
			(xy 345.133924 -284.880978) (xy 345.089462 -284.902076) (xy 345.042191 -284.915768) (xy 344.993336 -284.9217)
			(xy 344.944161 -284.919719) (xy 344.895942 -284.909875) (xy 344.849926 -284.892423) (xy 344.807305 -284.867816)
			(xy 344.769184 -284.836691) (xy 344.736549 -284.799854) (xy 344.710246 -284.758258) (xy 344.690955 -284.712982)
			(xy 344.679178 -284.665198) (xy 344.675218 -284.616144) (xy 344.356944 -284.616144) (xy 344.356432 -284.64159)
			(xy 344.348268 -284.691824) (xy 344.332152 -284.740098) (xy 344.308501 -284.785161) (xy 344.277928 -284.825847)
			(xy 344.241224 -284.861102) (xy 344.19934 -284.890012) (xy 344.153361 -284.911829) (xy 344.104477 -284.925989)
			(xy 344.053956 -284.932123) (xy 344.003104 -284.930074) (xy 343.95324 -284.919894) (xy 343.905654 -284.901847)
			(xy 343.86158 -284.876401) (xy 343.822158 -284.844214) (xy 343.78841 -284.80612) (xy 343.761209 -284.763106)
			(xy 343.741261 -284.716286) (xy 343.729082 -284.666872) (xy 343.724987 -284.616144) (xy 343.406476 -284.616144)
			(xy 343.405981 -284.640751) (xy 343.398086 -284.689328) (xy 343.382502 -284.736009) (xy 343.359631 -284.779586)
			(xy 343.330066 -284.81893) (xy 343.294573 -284.853022) (xy 343.25407 -284.880978) (xy 343.209608 -284.902076)
			(xy 343.162337 -284.915768) (xy 343.113482 -284.9217) (xy 343.064307 -284.919719) (xy 343.016088 -284.909875)
			(xy 342.970072 -284.892423) (xy 342.927451 -284.867816) (xy 342.88933 -284.836691) (xy 342.856695 -284.799854)
			(xy 342.830392 -284.758258) (xy 342.811101 -284.712982) (xy 342.799324 -284.665198) (xy 342.795364 -284.616144)
			(xy 342.476836 -284.616144) (xy 342.476324 -284.64159) (xy 342.46816 -284.691824) (xy 342.452044 -284.740098)
			(xy 342.428393 -284.785161) (xy 342.39782 -284.825847) (xy 342.361116 -284.861102) (xy 342.319232 -284.890012)
			(xy 342.273253 -284.911829) (xy 342.224369 -284.925989) (xy 342.173848 -284.932123) (xy 342.122996 -284.930074)
			(xy 342.073132 -284.919894) (xy 342.025546 -284.901847) (xy 341.981472 -284.876401) (xy 341.94205 -284.844214)
			(xy 341.908302 -284.80612) (xy 341.881101 -284.763106) (xy 341.861153 -284.716286) (xy 341.848974 -284.666872)
			(xy 341.844879 -284.616144) (xy 341.525909 -284.616144) (xy 341.525909 -284.64017) (xy 341.518356 -284.687701)
			(xy 341.503439 -284.733458) (xy 341.481526 -284.776307) (xy 341.453161 -284.815187) (xy 341.419047 -284.849134)
			(xy 341.380029 -284.877308) (xy 341.337073 -284.89901) (xy 341.291244 -284.913703) (xy 341.267542 -284.917896)
			(xy 341.258652 -284.919166) (xy 341.24265 -284.928056) (xy 341.236808 -284.934914) (xy 341.231224 -284.942001)
			(xy 341.224986 -284.958918) (xy 341.224616 -284.967934) (xy 341.224616 -285.127192) (xy 341.224855 -285.133707)
			(xy 341.228203 -285.146304) (xy 341.23122 -285.152084) (xy 341.24116 -285.169851) (xy 341.258705 -285.206591)
			(xy 341.266272 -285.22549) (xy 341.266272 -285.225744) (xy 341.268903 -285.23193) (xy 341.276883 -285.242744)
			(xy 341.28202 -285.24708) (xy 341.293196 -285.255716) (xy 341.305642 -285.25724) (xy 341.395812 -285.26867)
			(xy 341.402691 -285.269268) (xy 341.41634 -285.267207) (xy 341.422736 -285.264606) (xy 341.428578 -285.262066)
			(xy 341.438992 -285.253684) (xy 341.44331 -285.247842) (xy 341.457775 -285.228542) (xy 341.491764 -285.194322)
			(xy 341.530703 -285.165863) (xy 341.573627 -285.143869) (xy 341.619471 -285.128886) (xy 341.667099 -285.121285)
			(xy 341.691214 -285.120842) (xy 341.716464 -285.121364) (xy 341.766276 -285.129679) (xy 341.81404 -285.146078)
			(xy 341.858454 -285.170115) (xy 341.898305 -285.201135) (xy 341.932508 -285.23829) (xy 341.960128 -285.280568)
			(xy 341.980414 -285.326816) (xy 341.992811 -285.375772) (xy 341.996981 -285.4261) (xy 341.996977 -285.42615)
			(xy 342.314779 -285.42615) (xy 342.318874 -285.375422) (xy 342.331053 -285.326008) (xy 342.351001 -285.279188)
			(xy 342.378202 -285.236174) (xy 342.41195 -285.19808) (xy 342.451372 -285.165893) (xy 342.495446 -285.140447)
			(xy 342.543032 -285.1224) (xy 342.592896 -285.11222) (xy 342.643748 -285.110171) (xy 342.694269 -285.116305)
			(xy 342.743153 -285.130465) (xy 342.789132 -285.152282) (xy 342.831016 -285.181192) (xy 342.86772 -285.216447)
			(xy 342.898293 -285.257133) (xy 342.921944 -285.302196) (xy 342.93806 -285.35047) (xy 342.946224 -285.400704)
			(xy 342.946736 -285.42615) (xy 343.254833 -285.42615) (xy 343.258928 -285.375422) (xy 343.271107 -285.326008)
			(xy 343.291055 -285.279188) (xy 343.318256 -285.236174) (xy 343.352004 -285.19808) (xy 343.391426 -285.165893)
			(xy 343.4355 -285.140447) (xy 343.483086 -285.1224) (xy 343.53295 -285.11222) (xy 343.583802 -285.110171)
			(xy 343.634323 -285.116305) (xy 343.683207 -285.130465) (xy 343.729186 -285.152282) (xy 343.77107 -285.181192)
			(xy 343.807774 -285.216447) (xy 343.838347 -285.257133) (xy 343.861998 -285.302196) (xy 343.878114 -285.35047)
			(xy 343.886278 -285.400704) (xy 343.88679 -285.42615) (xy 344.205318 -285.42615) (xy 344.209278 -285.377096)
			(xy 344.221055 -285.329312) (xy 344.240346 -285.284036) (xy 344.266649 -285.24244) (xy 344.299284 -285.205603)
			(xy 344.337405 -285.174478) (xy 344.380026 -285.149871) (xy 344.426042 -285.132419) (xy 344.474261 -285.122575)
			(xy 344.523436 -285.120594) (xy 344.572291 -285.126526) (xy 344.619562 -285.140218) (xy 344.664024 -285.161316)
			(xy 344.704527 -285.189272) (xy 344.74002 -285.223364) (xy 344.769585 -285.262708) (xy 344.792456 -285.306285)
			(xy 344.80804 -285.352966) (xy 344.815935 -285.401543) (xy 344.81643 -285.42615) (xy 344.815935 -285.450757)
			(xy 344.80804 -285.499334) (xy 344.792456 -285.546015) (xy 344.769585 -285.589592) (xy 344.74002 -285.628936)
			(xy 344.704527 -285.663028) (xy 344.664024 -285.690984) (xy 344.619562 -285.712082) (xy 344.572291 -285.725774)
			(xy 344.523436 -285.731706) (xy 344.474261 -285.729725) (xy 344.426042 -285.719881) (xy 344.380026 -285.702429)
			(xy 344.337405 -285.677822) (xy 344.299284 -285.646697) (xy 344.266649 -285.60986) (xy 344.240346 -285.568264)
			(xy 344.221055 -285.522988) (xy 344.209278 -285.475204) (xy 344.205318 -285.42615) (xy 343.88679 -285.42615)
			(xy 343.886278 -285.451596) (xy 343.878114 -285.50183) (xy 343.861998 -285.550104) (xy 343.838347 -285.595167)
			(xy 343.807774 -285.635853) (xy 343.77107 -285.671108) (xy 343.729186 -285.700018) (xy 343.683207 -285.721835)
			(xy 343.634323 -285.735995) (xy 343.583802 -285.742129) (xy 343.53295 -285.74008) (xy 343.483086 -285.7299)
			(xy 343.4355 -285.711853) (xy 343.391426 -285.686407) (xy 343.352004 -285.65422) (xy 343.318256 -285.616126)
			(xy 343.291055 -285.573112) (xy 343.271107 -285.526292) (xy 343.258928 -285.476878) (xy 343.254833 -285.42615)
			(xy 342.946736 -285.42615) (xy 342.946224 -285.451596) (xy 342.93806 -285.50183) (xy 342.921944 -285.550104)
			(xy 342.898293 -285.595167) (xy 342.86772 -285.635853) (xy 342.831016 -285.671108) (xy 342.789132 -285.700018)
			(xy 342.743153 -285.721835) (xy 342.694269 -285.735995) (xy 342.643748 -285.742129) (xy 342.592896 -285.74008)
			(xy 342.543032 -285.7299) (xy 342.495446 -285.711853) (xy 342.451372 -285.686407) (xy 342.41195 -285.65422)
			(xy 342.378202 -285.616126) (xy 342.351001 -285.573112) (xy 342.331053 -285.526292) (xy 342.318874 -285.476878)
			(xy 342.314779 -285.42615) (xy 341.996977 -285.42615) (xy 341.992811 -285.476428) (xy 341.980414 -285.525384)
			(xy 341.960128 -285.571632) (xy 341.932508 -285.61391) (xy 341.898305 -285.651065) (xy 341.858454 -285.682085)
			(xy 341.81404 -285.706122) (xy 341.766276 -285.722521) (xy 341.716464 -285.730836) (xy 341.691214 -285.731458)
			(xy 341.678451 -285.731322) (xy 341.653016 -285.729164) (xy 341.640414 -285.72714) (xy 341.640414 -285.727394)
			(xy 341.616961 -285.722966) (xy 341.571708 -285.707803) (xy 341.529358 -285.685798) (xy 341.490939 -285.657484)
			(xy 341.457382 -285.623548) (xy 341.443056 -285.604458) (xy 341.438992 -285.598616) (xy 341.428324 -285.58998)
			(xy 341.422482 -285.58744) (xy 341.416199 -285.584917) (xy 341.402805 -285.582978) (xy 341.396066 -285.58363)
			(xy 341.305642 -285.59506) (xy 341.293196 -285.596584) (xy 341.28202 -285.60522) (xy 341.276885 -285.60956)
			(xy 341.268892 -285.620365) (xy 341.266272 -285.626556) (xy 341.266272 -285.62681) (xy 341.258703 -285.645709)
			(xy 341.241163 -285.682451) (xy 341.23122 -285.700216) (xy 341.227918 -285.706058) (xy 341.226394 -285.712154)
			(xy 341.224616 -285.725108) (xy 341.224616 -285.884366) (xy 341.22497 -285.893384) (xy 341.23121 -285.910307)
			(xy 341.236808 -285.917386) (xy 341.24265 -285.924244) (xy 341.258652 -285.933134) (xy 341.267542 -285.934404)
			(xy 341.291264 -285.938512) (xy 341.337106 -285.953209) (xy 341.380074 -285.974918) (xy 341.419104 -286.0031)
			(xy 341.453227 -286.037057) (xy 341.4816 -286.075948) (xy 341.503519 -286.118809) (xy 341.518441 -286.164579)
			(xy 341.525996 -286.212123) (xy 341.525996 -286.236156) (xy 341.844879 -286.236156) (xy 341.848974 -286.185428)
			(xy 341.861153 -286.136014) (xy 341.881101 -286.089194) (xy 341.908302 -286.04618) (xy 341.94205 -286.008086)
			(xy 341.981472 -285.975899) (xy 342.025546 -285.950453) (xy 342.073132 -285.932406) (xy 342.122996 -285.922226)
			(xy 342.173848 -285.920177) (xy 342.224369 -285.926311) (xy 342.273253 -285.940471) (xy 342.319232 -285.962288)
			(xy 342.361116 -285.991198) (xy 342.39782 -286.026453) (xy 342.428393 -286.067139) (xy 342.452044 -286.112202)
			(xy 342.46816 -286.160476) (xy 342.476324 -286.21071) (xy 342.476836 -286.236156) (xy 342.795364 -286.236156)
			(xy 342.799324 -286.187102) (xy 342.811101 -286.139318) (xy 342.830392 -286.094042) (xy 342.856695 -286.052446)
			(xy 342.88933 -286.015609) (xy 342.927451 -285.984484) (xy 342.970072 -285.959877) (xy 343.016088 -285.942425)
			(xy 343.064307 -285.932581) (xy 343.113482 -285.9306) (xy 343.162337 -285.936532) (xy 343.209608 -285.950224)
			(xy 343.25407 -285.971322) (xy 343.294573 -285.999278) (xy 343.330066 -286.03337) (xy 343.359631 -286.072714)
			(xy 343.382502 -286.116291) (xy 343.398086 -286.162972) (xy 343.405981 -286.211549) (xy 343.406476 -286.236156)
			(xy 343.724987 -286.236156) (xy 343.729082 -286.185428) (xy 343.741261 -286.136014) (xy 343.761209 -286.089194)
			(xy 343.78841 -286.04618) (xy 343.822158 -286.008086) (xy 343.86158 -285.975899) (xy 343.905654 -285.950453)
			(xy 343.95324 -285.932406) (xy 344.003104 -285.922226) (xy 344.053956 -285.920177) (xy 344.104477 -285.926311)
			(xy 344.153361 -285.940471) (xy 344.19934 -285.962288) (xy 344.241224 -285.991198) (xy 344.277928 -286.026453)
			(xy 344.308501 -286.067139) (xy 344.332152 -286.112202) (xy 344.348268 -286.160476) (xy 344.356432 -286.21071)
			(xy 344.356944 -286.236156) (xy 344.356432 -286.261602) (xy 344.348268 -286.311836) (xy 344.332152 -286.36011)
			(xy 344.308501 -286.405173) (xy 344.277928 -286.445859) (xy 344.241224 -286.481114) (xy 344.19934 -286.510024)
			(xy 344.153361 -286.531841) (xy 344.104477 -286.546001) (xy 344.053956 -286.552135) (xy 344.003104 -286.550086)
			(xy 343.95324 -286.539906) (xy 343.905654 -286.521859) (xy 343.86158 -286.496413) (xy 343.822158 -286.464226)
			(xy 343.78841 -286.426132) (xy 343.761209 -286.383118) (xy 343.741261 -286.336298) (xy 343.729082 -286.286884)
			(xy 343.724987 -286.236156) (xy 343.406476 -286.236156) (xy 343.405981 -286.260763) (xy 343.398086 -286.30934)
			(xy 343.382502 -286.356021) (xy 343.359631 -286.399598) (xy 343.330066 -286.438942) (xy 343.294573 -286.473034)
			(xy 343.25407 -286.50099) (xy 343.209608 -286.522088) (xy 343.162337 -286.53578) (xy 343.113482 -286.541712)
			(xy 343.064307 -286.539731) (xy 343.016088 -286.529887) (xy 342.970072 -286.512435) (xy 342.927451 -286.487828)
			(xy 342.88933 -286.456703) (xy 342.856695 -286.419866) (xy 342.830392 -286.37827) (xy 342.811101 -286.332994)
			(xy 342.799324 -286.28521) (xy 342.795364 -286.236156) (xy 342.476836 -286.236156) (xy 342.476324 -286.261602)
			(xy 342.46816 -286.311836) (xy 342.452044 -286.36011) (xy 342.428393 -286.405173) (xy 342.39782 -286.445859)
			(xy 342.361116 -286.481114) (xy 342.319232 -286.510024) (xy 342.273253 -286.531841) (xy 342.224369 -286.546001)
			(xy 342.173848 -286.552135) (xy 342.122996 -286.550086) (xy 342.073132 -286.539906) (xy 342.025546 -286.521859)
			(xy 341.981472 -286.496413) (xy 341.94205 -286.464226) (xy 341.908302 -286.426132) (xy 341.881101 -286.383118)
			(xy 341.861153 -286.336298) (xy 341.848974 -286.286884) (xy 341.844879 -286.236156) (xy 341.525996 -286.236156)
			(xy 341.525997 -286.260264) (xy 341.518444 -286.307808) (xy 341.503524 -286.353579) (xy 341.481607 -286.396441)
			(xy 341.453236 -286.435333) (xy 341.419114 -286.469292) (xy 341.380085 -286.497475) (xy 341.337118 -286.519186)
			(xy 341.291277 -286.533885) (xy 341.267542 -286.537908) (xy 341.258652 -286.539178) (xy 341.24265 -286.548068)
			(xy 341.236808 -286.554926) (xy 341.231226 -286.562014) (xy 341.224992 -286.578931) (xy 341.224616 -286.587946)
			(xy 341.224616 -286.740346) (xy 341.224752 -286.745237) (xy 341.22667 -286.754829) (xy 341.228426 -286.759396)
			(xy 341.232236 -286.767016) (xy 341.232998 -286.768286) (xy 341.238995 -286.778864) (xy 341.250175 -286.800462)
			(xy 341.25535 -286.811466) (xy 341.268558 -286.842454) (xy 341.268558 -286.842708) (xy 341.271252 -286.848909)
			(xy 341.279361 -286.859722) (xy 341.28456 -286.864044) (xy 341.28964 -286.868108) (xy 341.30234 -286.873442)
			(xy 341.397844 -286.885634) (xy 341.406973 -286.886434) (xy 341.4248 -286.88225) (xy 341.432642 -286.877506)
			(xy 341.436187 -286.875009) (xy 341.442446 -286.869007) (xy 341.445088 -286.865568) (xy 341.445088 -286.865314)
			(xy 341.459582 -286.846343) (xy 341.493471 -286.812719) (xy 341.53218 -286.784778) (xy 341.574765 -286.7632)
			(xy 341.620188 -286.748511) (xy 341.667344 -286.74107) (xy 341.691214 -286.7406) (xy 341.716468 -286.741123)
			(xy 341.766287 -286.749438) (xy 341.814057 -286.76584) (xy 341.858477 -286.78988) (xy 341.898334 -286.820904)
			(xy 341.932541 -286.858064) (xy 341.960165 -286.900348) (xy 341.980454 -286.946602) (xy 341.992852 -286.995565)
			(xy 341.997023 -287.0459) (xy 341.997022 -287.045908) (xy 342.314779 -287.045908) (xy 342.318874 -286.99518)
			(xy 342.331053 -286.945766) (xy 342.351001 -286.898946) (xy 342.378202 -286.855932) (xy 342.41195 -286.817838)
			(xy 342.451372 -286.785651) (xy 342.495446 -286.760205) (xy 342.543032 -286.742158) (xy 342.592896 -286.731978)
			(xy 342.643748 -286.729929) (xy 342.694269 -286.736063) (xy 342.743153 -286.750223) (xy 342.789132 -286.77204)
			(xy 342.831016 -286.80095) (xy 342.86772 -286.836205) (xy 342.898293 -286.876891) (xy 342.921944 -286.921954)
			(xy 342.93806 -286.970228) (xy 342.946224 -287.020462) (xy 342.946736 -287.045908) (xy 343.254833 -287.045908)
			(xy 343.258928 -286.99518) (xy 343.271107 -286.945766) (xy 343.291055 -286.898946) (xy 343.318256 -286.855932)
			(xy 343.352004 -286.817838) (xy 343.391426 -286.785651) (xy 343.4355 -286.760205) (xy 343.483086 -286.742158)
			(xy 343.53295 -286.731978) (xy 343.583802 -286.729929) (xy 343.634323 -286.736063) (xy 343.683207 -286.750223)
			(xy 343.729186 -286.77204) (xy 343.77107 -286.80095) (xy 343.807774 -286.836205) (xy 343.838347 -286.876891)
			(xy 343.861998 -286.921954) (xy 343.878114 -286.970228) (xy 343.886278 -287.020462) (xy 343.88679 -287.045908)
			(xy 344.205318 -287.045908) (xy 344.209278 -286.996854) (xy 344.221055 -286.94907) (xy 344.240346 -286.903794)
			(xy 344.266649 -286.862198) (xy 344.299284 -286.825361) (xy 344.337405 -286.794236) (xy 344.380026 -286.769629)
			(xy 344.426042 -286.752177) (xy 344.474261 -286.742333) (xy 344.523436 -286.740352) (xy 344.572291 -286.746284)
			(xy 344.619562 -286.759976) (xy 344.664024 -286.781074) (xy 344.704527 -286.80903) (xy 344.74002 -286.843122)
			(xy 344.769585 -286.882466) (xy 344.792456 -286.926043) (xy 344.80804 -286.972724) (xy 344.815935 -287.021301)
			(xy 344.81643 -287.045908) (xy 344.815935 -287.070515) (xy 344.80804 -287.119092) (xy 344.792456 -287.165773)
			(xy 344.769585 -287.20935) (xy 344.74002 -287.248694) (xy 344.704527 -287.282786) (xy 344.664024 -287.310742)
			(xy 344.619562 -287.33184) (xy 344.572291 -287.345532) (xy 344.523436 -287.351464) (xy 344.474261 -287.349483)
			(xy 344.426042 -287.339639) (xy 344.380026 -287.322187) (xy 344.337405 -287.29758) (xy 344.299284 -287.266455)
			(xy 344.266649 -287.229618) (xy 344.240346 -287.188022) (xy 344.221055 -287.142746) (xy 344.209278 -287.094962)
			(xy 344.205318 -287.045908) (xy 343.88679 -287.045908) (xy 343.886278 -287.071354) (xy 343.878114 -287.121588)
			(xy 343.861998 -287.169862) (xy 343.838347 -287.214925) (xy 343.807774 -287.255611) (xy 343.77107 -287.290866)
			(xy 343.729186 -287.319776) (xy 343.683207 -287.341593) (xy 343.634323 -287.355753) (xy 343.583802 -287.361887)
			(xy 343.53295 -287.359838) (xy 343.483086 -287.349658) (xy 343.4355 -287.331611) (xy 343.391426 -287.306165)
			(xy 343.352004 -287.273978) (xy 343.318256 -287.235884) (xy 343.291055 -287.19287) (xy 343.271107 -287.14605)
			(xy 343.258928 -287.096636) (xy 343.254833 -287.045908) (xy 342.946736 -287.045908) (xy 342.946224 -287.071354)
			(xy 342.93806 -287.121588) (xy 342.921944 -287.169862) (xy 342.898293 -287.214925) (xy 342.86772 -287.255611)
			(xy 342.831016 -287.290866) (xy 342.789132 -287.319776) (xy 342.743153 -287.341593) (xy 342.694269 -287.355753)
			(xy 342.643748 -287.361887) (xy 342.592896 -287.359838) (xy 342.543032 -287.349658) (xy 342.495446 -287.331611)
			(xy 342.451372 -287.306165) (xy 342.41195 -287.273978) (xy 342.378202 -287.235884) (xy 342.351001 -287.19287)
			(xy 342.331053 -287.14605) (xy 342.318874 -287.096636) (xy 342.314779 -287.045908) (xy 341.997022 -287.045908)
			(xy 341.992852 -287.096235) (xy 341.980454 -287.145198) (xy 341.960165 -287.191452) (xy 341.932541 -287.233736)
			(xy 341.898334 -287.270896) (xy 341.858477 -287.30192) (xy 341.814057 -287.32596) (xy 341.766287 -287.342362)
			(xy 341.716468 -287.350677) (xy 341.691214 -287.351216) (xy 341.667344 -287.350755) (xy 341.620186 -287.343322)
			(xy 341.574761 -287.328634) (xy 341.532178 -287.307051) (xy 341.493476 -287.2791) (xy 341.459599 -287.245461)
			(xy 341.445088 -287.226502) (xy 341.445088 -287.226248) (xy 341.442438 -287.222816) (xy 341.436183 -287.216812)
			(xy 341.432642 -287.21431) (xy 341.424814 -287.209535) (xy 341.406975 -287.205355) (xy 341.397844 -287.206182)
			(xy 341.309198 -287.217612) (xy 341.302437 -287.218683) (xy 341.289809 -287.223955) (xy 341.284306 -287.228026)
			(xy 341.278972 -287.23209) (xy 341.271098 -287.242758) (xy 341.268558 -287.249362) (xy 341.260585 -287.269079)
			(xy 341.242024 -287.307349) (xy 341.231474 -287.325816) (xy 341.231474 -287.32607) (xy 341.228363 -287.33189)
			(xy 341.224903 -287.344622) (xy 341.224616 -287.351216) (xy 341.224616 -287.504378) (xy 341.224972 -287.513396)
			(xy 341.231215 -287.530316) (xy 341.236808 -287.537398) (xy 341.24265 -287.544256) (xy 341.258652 -287.553146)
			(xy 341.267542 -287.554416) (xy 341.291263 -287.558524) (xy 341.337103 -287.573221) (xy 341.380069 -287.594929)
			(xy 341.419097 -287.62311) (xy 341.45322 -287.657066) (xy 341.481591 -287.695956) (xy 341.503509 -287.738815)
			(xy 341.51843 -287.784583) (xy 341.525984 -287.832126) (xy 341.525984 -287.856168) (xy 341.844879 -287.856168)
			(xy 341.848974 -287.80544) (xy 341.861153 -287.756026) (xy 341.881101 -287.709206) (xy 341.908302 -287.666192)
			(xy 341.94205 -287.628098) (xy 341.981472 -287.595911) (xy 342.025546 -287.570465) (xy 342.073132 -287.552418)
			(xy 342.122996 -287.542238) (xy 342.173848 -287.540189) (xy 342.224369 -287.546323) (xy 342.273253 -287.560483)
			(xy 342.319232 -287.5823) (xy 342.361116 -287.61121) (xy 342.39782 -287.646465) (xy 342.428393 -287.687151)
			(xy 342.452044 -287.732214) (xy 342.46816 -287.780488) (xy 342.476324 -287.830722) (xy 342.476836 -287.856168)
			(xy 342.795364 -287.856168) (xy 342.799324 -287.807114) (xy 342.811101 -287.75933) (xy 342.830392 -287.714054)
			(xy 342.856695 -287.672458) (xy 342.88933 -287.635621) (xy 342.927451 -287.604496) (xy 342.970072 -287.579889)
			(xy 343.016088 -287.562437) (xy 343.064307 -287.552593) (xy 343.113482 -287.550612) (xy 343.162337 -287.556544)
			(xy 343.209608 -287.570236) (xy 343.25407 -287.591334) (xy 343.294573 -287.61929) (xy 343.330066 -287.653382)
			(xy 343.359631 -287.692726) (xy 343.382502 -287.736303) (xy 343.398086 -287.782984) (xy 343.405981 -287.831561)
			(xy 343.406476 -287.856168) (xy 343.724987 -287.856168) (xy 343.729082 -287.80544) (xy 343.741261 -287.756026)
			(xy 343.761209 -287.709206) (xy 343.78841 -287.666192) (xy 343.822158 -287.628098) (xy 343.86158 -287.595911)
			(xy 343.905654 -287.570465) (xy 343.95324 -287.552418) (xy 344.003104 -287.542238) (xy 344.053956 -287.540189)
			(xy 344.104477 -287.546323) (xy 344.153361 -287.560483) (xy 344.19934 -287.5823) (xy 344.241224 -287.61121)
			(xy 344.277928 -287.646465) (xy 344.308501 -287.687151) (xy 344.332152 -287.732214) (xy 344.348268 -287.780488)
			(xy 344.356432 -287.830722) (xy 344.356944 -287.856168) (xy 344.356432 -287.881614) (xy 344.348268 -287.931848)
			(xy 344.332152 -287.980122) (xy 344.308501 -288.025185) (xy 344.277928 -288.065871) (xy 344.241224 -288.101126)
			(xy 344.19934 -288.130036) (xy 344.153361 -288.151853) (xy 344.104477 -288.166013) (xy 344.053956 -288.172147)
			(xy 344.003104 -288.170098) (xy 343.95324 -288.159918) (xy 343.905654 -288.141871) (xy 343.86158 -288.116425)
			(xy 343.822158 -288.084238) (xy 343.78841 -288.046144) (xy 343.761209 -288.00313) (xy 343.741261 -287.95631)
			(xy 343.729082 -287.906896) (xy 343.724987 -287.856168) (xy 343.406476 -287.856168) (xy 343.405981 -287.880775)
			(xy 343.398086 -287.929352) (xy 343.382502 -287.976033) (xy 343.359631 -288.01961) (xy 343.330066 -288.058954)
			(xy 343.294573 -288.093046) (xy 343.25407 -288.121002) (xy 343.209608 -288.1421) (xy 343.162337 -288.155792)
			(xy 343.113482 -288.161724) (xy 343.064307 -288.159743) (xy 343.016088 -288.149899) (xy 342.970072 -288.132447)
			(xy 342.927451 -288.10784) (xy 342.88933 -288.076715) (xy 342.856695 -288.039878) (xy 342.830392 -287.998282)
			(xy 342.811101 -287.953006) (xy 342.799324 -287.905222) (xy 342.795364 -287.856168) (xy 342.476836 -287.856168)
			(xy 342.476324 -287.881614) (xy 342.46816 -287.931848) (xy 342.452044 -287.980122) (xy 342.428393 -288.025185)
			(xy 342.39782 -288.065871) (xy 342.361116 -288.101126) (xy 342.319232 -288.130036) (xy 342.273253 -288.151853)
			(xy 342.224369 -288.166013) (xy 342.173848 -288.172147) (xy 342.122996 -288.170098) (xy 342.073132 -288.159918)
			(xy 342.025546 -288.141871) (xy 341.981472 -288.116425) (xy 341.94205 -288.084238) (xy 341.908302 -288.046144)
			(xy 341.881101 -288.00313) (xy 341.861153 -287.95631) (xy 341.848974 -287.906896) (xy 341.844879 -287.856168)
			(xy 341.525984 -287.856168) (xy 341.525985 -287.880265) (xy 341.518432 -287.927807) (xy 341.503513 -287.973576)
			(xy 341.481596 -288.016436) (xy 341.453226 -288.055327) (xy 341.419105 -288.089284) (xy 341.380078 -288.117466)
			(xy 341.337112 -288.139175) (xy 341.291272 -288.153874) (xy 341.267542 -288.15792) (xy 341.258652 -288.15919)
			(xy 341.24265 -288.16808) (xy 341.236808 -288.174938) (xy 341.231228 -288.182026) (xy 341.224997 -288.198944)
			(xy 341.224616 -288.207958) (xy 341.224616 -288.366962) (xy 341.224851 -288.373478) (xy 341.228193 -288.386078)
			(xy 341.23122 -288.391854) (xy 341.241161 -288.40962) (xy 341.258708 -288.446359) (xy 341.266272 -288.46526)
			(xy 341.266272 -288.465514) (xy 341.268901 -288.471702) (xy 341.276876 -288.482521) (xy 341.28202 -288.48685)
			(xy 341.293196 -288.495486) (xy 341.305642 -288.49701) (xy 341.395812 -288.50844) (xy 341.402691 -288.509037)
			(xy 341.41634 -288.506979) (xy 341.422736 -288.504376) (xy 341.428578 -288.501836) (xy 341.438992 -288.493454)
			(xy 341.44331 -288.487612) (xy 341.457773 -288.468308) (xy 341.491758 -288.434081) (xy 341.530696 -288.405615)
			(xy 341.573621 -288.383616) (xy 341.619467 -288.368629) (xy 341.667097 -288.361027) (xy 341.691214 -288.360612)
			(xy 341.716467 -288.361135) (xy 341.766284 -288.36945) (xy 341.814052 -288.385851) (xy 341.85847 -288.40989)
			(xy 341.898326 -288.440913) (xy 341.932531 -288.478072) (xy 341.960155 -288.520354) (xy 341.980442 -288.566606)
			(xy 341.99284 -288.615567) (xy 341.997011 -288.6659) (xy 341.997009 -288.66592) (xy 342.314779 -288.66592)
			(xy 342.318874 -288.615192) (xy 342.331053 -288.565778) (xy 342.351001 -288.518958) (xy 342.378202 -288.475944)
			(xy 342.41195 -288.43785) (xy 342.451372 -288.405663) (xy 342.495446 -288.380217) (xy 342.543032 -288.36217)
			(xy 342.592896 -288.35199) (xy 342.643748 -288.349941) (xy 342.694269 -288.356075) (xy 342.743153 -288.370235)
			(xy 342.789132 -288.392052) (xy 342.831016 -288.420962) (xy 342.86772 -288.456217) (xy 342.898293 -288.496903)
			(xy 342.921944 -288.541966) (xy 342.93806 -288.59024) (xy 342.946224 -288.640474) (xy 342.946736 -288.66592)
			(xy 343.254833 -288.66592) (xy 343.258928 -288.615192) (xy 343.271107 -288.565778) (xy 343.291055 -288.518958)
			(xy 343.318256 -288.475944) (xy 343.352004 -288.43785) (xy 343.391426 -288.405663) (xy 343.4355 -288.380217)
			(xy 343.483086 -288.36217) (xy 343.53295 -288.35199) (xy 343.583802 -288.349941) (xy 343.634323 -288.356075)
			(xy 343.683207 -288.370235) (xy 343.729186 -288.392052) (xy 343.77107 -288.420962) (xy 343.807774 -288.456217)
			(xy 343.838347 -288.496903) (xy 343.861998 -288.541966) (xy 343.878114 -288.59024) (xy 343.886278 -288.640474)
			(xy 343.88679 -288.66592) (xy 343.886278 -288.691366) (xy 343.878114 -288.7416) (xy 343.861998 -288.789874)
			(xy 343.838347 -288.834937) (xy 343.807774 -288.875623) (xy 343.77107 -288.910878) (xy 343.729186 -288.939788)
			(xy 343.683207 -288.961605) (xy 343.634323 -288.975765) (xy 343.583802 -288.981899) (xy 343.53295 -288.97985)
			(xy 343.483086 -288.96967) (xy 343.4355 -288.951623) (xy 343.391426 -288.926177) (xy 343.352004 -288.89399)
			(xy 343.318256 -288.855896) (xy 343.291055 -288.812882) (xy 343.271107 -288.766062) (xy 343.258928 -288.716648)
			(xy 343.254833 -288.66592) (xy 342.946736 -288.66592) (xy 342.946224 -288.691366) (xy 342.93806 -288.7416)
			(xy 342.921944 -288.789874) (xy 342.898293 -288.834937) (xy 342.86772 -288.875623) (xy 342.831016 -288.910878)
			(xy 342.789132 -288.939788) (xy 342.743153 -288.961605) (xy 342.694269 -288.975765) (xy 342.643748 -288.981899)
			(xy 342.592896 -288.97985) (xy 342.543032 -288.96967) (xy 342.495446 -288.951623) (xy 342.451372 -288.926177)
			(xy 342.41195 -288.89399) (xy 342.378202 -288.855896) (xy 342.351001 -288.812882) (xy 342.331053 -288.766062)
			(xy 342.318874 -288.716648) (xy 342.314779 -288.66592) (xy 341.997009 -288.66592) (xy 341.99284 -288.716233)
			(xy 341.980442 -288.765194) (xy 341.960155 -288.811446) (xy 341.932531 -288.853728) (xy 341.898326 -288.890887)
			(xy 341.85847 -288.92191) (xy 341.814052 -288.945949) (xy 341.766284 -288.96235) (xy 341.716467 -288.970665)
			(xy 341.691214 -288.971228) (xy 341.678451 -288.971092) (xy 341.653016 -288.968934) (xy 341.640414 -288.96691)
			(xy 341.640414 -288.967164) (xy 341.61696 -288.962737) (xy 341.571704 -288.947577) (xy 341.529351 -288.925575)
			(xy 341.490927 -288.897265) (xy 341.457363 -288.863333) (xy 341.443056 -288.844228) (xy 341.438992 -288.838386)
			(xy 341.428324 -288.82975) (xy 341.422482 -288.82721) (xy 341.416199 -288.824685) (xy 341.402805 -288.822743)
			(xy 341.396066 -288.8234) (xy 341.305642 -288.83483) (xy 341.293196 -288.836354) (xy 341.28202 -288.84499)
			(xy 341.276891 -288.849333) (xy 341.268911 -288.860144) (xy 341.266272 -288.866326) (xy 341.266272 -288.86658)
			(xy 341.258701 -288.885478) (xy 341.241157 -288.922218) (xy 341.23122 -288.939986) (xy 341.227918 -288.945828)
			(xy 341.226394 -288.951924) (xy 341.224616 -288.964878) (xy 341.224616 -289.124136) (xy 341.224982 -289.13315)
			(xy 341.23124 -289.150057) (xy 341.236808 -289.157156) (xy 341.24265 -289.164014) (xy 341.258652 -289.172904)
			(xy 341.267542 -289.174174) (xy 341.291258 -289.178282) (xy 341.337089 -289.192977) (xy 341.380047 -289.214682)
			(xy 341.419067 -289.242859) (xy 341.453182 -289.27681) (xy 341.481547 -289.315693) (xy 341.503459 -289.358545)
			(xy 341.518376 -289.404305) (xy 341.525928 -289.451839) (xy 341.525927 -289.475926) (xy 341.844879 -289.475926)
			(xy 341.848974 -289.425198) (xy 341.861153 -289.375784) (xy 341.881101 -289.328964) (xy 341.908302 -289.28595)
			(xy 341.94205 -289.247856) (xy 341.981472 -289.215669) (xy 342.025546 -289.190223) (xy 342.073132 -289.172176)
			(xy 342.122996 -289.161996) (xy 342.173848 -289.159947) (xy 342.224369 -289.166081) (xy 342.273253 -289.180241)
			(xy 342.319232 -289.202058) (xy 342.361116 -289.230968) (xy 342.39782 -289.266223) (xy 342.428393 -289.306909)
			(xy 342.452044 -289.351972) (xy 342.46816 -289.400246) (xy 342.476324 -289.45048) (xy 342.476836 -289.475926)
			(xy 342.795364 -289.475926) (xy 342.799324 -289.426872) (xy 342.811101 -289.379088) (xy 342.830392 -289.333812)
			(xy 342.856695 -289.292216) (xy 342.88933 -289.255379) (xy 342.927451 -289.224254) (xy 342.970072 -289.199647)
			(xy 343.016088 -289.182195) (xy 343.064307 -289.172351) (xy 343.113482 -289.17037) (xy 343.162337 -289.176302)
			(xy 343.209608 -289.189994) (xy 343.25407 -289.211092) (xy 343.294573 -289.239048) (xy 343.330066 -289.27314)
			(xy 343.359631 -289.312484) (xy 343.382502 -289.356061) (xy 343.398086 -289.402742) (xy 343.405981 -289.451319)
			(xy 343.406476 -289.475926) (xy 343.724987 -289.475926) (xy 343.729082 -289.425198) (xy 343.741261 -289.375784)
			(xy 343.761209 -289.328964) (xy 343.78841 -289.28595) (xy 343.822158 -289.247856) (xy 343.86158 -289.215669)
			(xy 343.905654 -289.190223) (xy 343.95324 -289.172176) (xy 344.003104 -289.161996) (xy 344.053956 -289.159947)
			(xy 344.104477 -289.166081) (xy 344.153361 -289.180241) (xy 344.19934 -289.202058) (xy 344.241224 -289.230968)
			(xy 344.277928 -289.266223) (xy 344.308501 -289.306909) (xy 344.332152 -289.351972) (xy 344.348268 -289.400246)
			(xy 344.356432 -289.45048) (xy 344.356944 -289.475926) (xy 344.356432 -289.501372) (xy 344.348268 -289.551606)
			(xy 344.332152 -289.59988) (xy 344.308501 -289.644943) (xy 344.277928 -289.685629) (xy 344.241224 -289.720884)
			(xy 344.19934 -289.749794) (xy 344.153361 -289.771611) (xy 344.104477 -289.785771) (xy 344.053956 -289.791905)
			(xy 344.003104 -289.789856) (xy 343.95324 -289.779676) (xy 343.905654 -289.761629) (xy 343.86158 -289.736183)
			(xy 343.822158 -289.703996) (xy 343.78841 -289.665902) (xy 343.761209 -289.622888) (xy 343.741261 -289.576068)
			(xy 343.729082 -289.526654) (xy 343.724987 -289.475926) (xy 343.406476 -289.475926) (xy 343.405981 -289.500533)
			(xy 343.398086 -289.54911) (xy 343.382502 -289.595791) (xy 343.359631 -289.639368) (xy 343.330066 -289.678712)
			(xy 343.294573 -289.712804) (xy 343.25407 -289.74076) (xy 343.209608 -289.761858) (xy 343.162337 -289.77555)
			(xy 343.113482 -289.781482) (xy 343.064307 -289.779501) (xy 343.016088 -289.769657) (xy 342.970072 -289.752205)
			(xy 342.927451 -289.727598) (xy 342.88933 -289.696473) (xy 342.856695 -289.659636) (xy 342.830392 -289.61804)
			(xy 342.811101 -289.572764) (xy 342.799324 -289.52498) (xy 342.795364 -289.475926) (xy 342.476836 -289.475926)
			(xy 342.476324 -289.501372) (xy 342.46816 -289.551606) (xy 342.452044 -289.59988) (xy 342.428393 -289.644943)
			(xy 342.39782 -289.685629) (xy 342.361116 -289.720884) (xy 342.319232 -289.749794) (xy 342.273253 -289.771611)
			(xy 342.224369 -289.785771) (xy 342.173848 -289.791905) (xy 342.122996 -289.789856) (xy 342.073132 -289.779676)
			(xy 342.025546 -289.761629) (xy 341.981472 -289.736183) (xy 341.94205 -289.703996) (xy 341.908302 -289.665902)
			(xy 341.881101 -289.622888) (xy 341.861153 -289.576068) (xy 341.848974 -289.526654) (xy 341.844879 -289.475926)
			(xy 341.525927 -289.475926) (xy 341.525927 -289.499969) (xy 341.518374 -289.547502) (xy 341.503456 -289.593262)
			(xy 341.481543 -289.636114) (xy 341.453177 -289.674996) (xy 341.419061 -289.708946) (xy 341.38004 -289.737122)
			(xy 341.337082 -289.758826) (xy 341.29125 -289.77352) (xy 341.267542 -289.777678) (xy 341.258652 -289.778948)
			(xy 341.24265 -289.787838) (xy 341.236808 -289.794696) (xy 341.231221 -289.801782) (xy 341.224977 -289.818699)
			(xy 341.224616 -289.827716) (xy 341.224616 -289.986974) (xy 341.224852 -289.99349) (xy 341.228197 -290.006089)
			(xy 341.23122 -290.011866) (xy 341.24116 -290.029632) (xy 341.258707 -290.066372) (xy 341.266272 -290.085272)
			(xy 341.266272 -290.085526) (xy 341.268902 -290.091713) (xy 341.276879 -290.10253) (xy 341.28202 -290.106862)
			(xy 341.293196 -290.115498) (xy 341.305642 -290.117022) (xy 341.395812 -290.128452) (xy 341.402691 -290.12905)
			(xy 341.416339 -290.126989) (xy 341.422736 -290.124388) (xy 341.428578 -290.121848) (xy 341.438992 -290.113466)
			(xy 341.44331 -290.107624) (xy 341.457772 -290.088319) (xy 341.491757 -290.054091) (xy 341.530695 -290.025624)
			(xy 341.573619 -290.003624) (xy 341.619466 -289.988636) (xy 341.667097 -289.981034) (xy 341.691214 -289.980624)
			(xy 341.716466 -289.981147) (xy 341.766281 -289.989461) (xy 341.814048 -290.005862) (xy 341.858464 -290.0299)
			(xy 341.898317 -290.060921) (xy 341.932522 -290.098079) (xy 341.960144 -290.14036) (xy 341.980431 -290.18661)
			(xy 341.992829 -290.235569) (xy 341.996999 -290.2859) (xy 341.996996 -290.285932) (xy 342.314779 -290.285932)
			(xy 342.318874 -290.235204) (xy 342.331053 -290.18579) (xy 342.351001 -290.13897) (xy 342.378202 -290.095956)
			(xy 342.41195 -290.057862) (xy 342.451372 -290.025675) (xy 342.495446 -290.000229) (xy 342.543032 -289.982182)
			(xy 342.592896 -289.972002) (xy 342.643748 -289.969953) (xy 342.694269 -289.976087) (xy 342.743153 -289.990247)
			(xy 342.789132 -290.012064) (xy 342.831016 -290.040974) (xy 342.86772 -290.076229) (xy 342.898293 -290.116915)
			(xy 342.921944 -290.161978) (xy 342.93806 -290.210252) (xy 342.946224 -290.260486) (xy 342.946736 -290.285932)
			(xy 343.254833 -290.285932) (xy 343.258928 -290.235204) (xy 343.271107 -290.18579) (xy 343.291055 -290.13897)
			(xy 343.318256 -290.095956) (xy 343.352004 -290.057862) (xy 343.391426 -290.025675) (xy 343.4355 -290.000229)
			(xy 343.483086 -289.982182) (xy 343.53295 -289.972002) (xy 343.583802 -289.969953) (xy 343.634323 -289.976087)
			(xy 343.683207 -289.990247) (xy 343.729186 -290.012064) (xy 343.77107 -290.040974) (xy 343.807774 -290.076229)
			(xy 343.838347 -290.116915) (xy 343.861998 -290.161978) (xy 343.878114 -290.210252) (xy 343.886278 -290.260486)
			(xy 343.88679 -290.285932) (xy 343.886278 -290.311378) (xy 343.878114 -290.361612) (xy 343.861998 -290.409886)
			(xy 343.838347 -290.454949) (xy 343.807774 -290.495635) (xy 343.77107 -290.53089) (xy 343.729186 -290.5598)
			(xy 343.683207 -290.581617) (xy 343.634323 -290.595777) (xy 343.583802 -290.601911) (xy 343.53295 -290.599862)
			(xy 343.483086 -290.589682) (xy 343.4355 -290.571635) (xy 343.391426 -290.546189) (xy 343.352004 -290.514002)
			(xy 343.318256 -290.475908) (xy 343.291055 -290.432894) (xy 343.271107 -290.386074) (xy 343.258928 -290.33666)
			(xy 343.254833 -290.285932) (xy 342.946736 -290.285932) (xy 342.946224 -290.311378) (xy 342.93806 -290.361612)
			(xy 342.921944 -290.409886) (xy 342.898293 -290.454949) (xy 342.86772 -290.495635) (xy 342.831016 -290.53089)
			(xy 342.789132 -290.5598) (xy 342.743153 -290.581617) (xy 342.694269 -290.595777) (xy 342.643748 -290.601911)
			(xy 342.592896 -290.599862) (xy 342.543032 -290.589682) (xy 342.495446 -290.571635) (xy 342.451372 -290.546189)
			(xy 342.41195 -290.514002) (xy 342.378202 -290.475908) (xy 342.351001 -290.432894) (xy 342.331053 -290.386074)
			(xy 342.318874 -290.33666) (xy 342.314779 -290.285932) (xy 341.996996 -290.285932) (xy 341.992829 -290.336231)
			(xy 341.980431 -290.38519) (xy 341.960144 -290.43144) (xy 341.932522 -290.473721) (xy 341.898317 -290.510879)
			(xy 341.858464 -290.5419) (xy 341.814048 -290.565938) (xy 341.766281 -290.582339) (xy 341.716466 -290.590653)
			(xy 341.691214 -290.59124) (xy 341.678451 -290.591104) (xy 341.653016 -290.588946) (xy 341.640414 -290.586922)
			(xy 341.640414 -290.587176) (xy 341.61696 -290.58275) (xy 341.571704 -290.567589) (xy 341.52935 -290.545588)
			(xy 341.490924 -290.517278) (xy 341.45736 -290.483347) (xy 341.443056 -290.46424) (xy 341.438992 -290.458398)
			(xy 341.428324 -290.449762) (xy 341.422482 -290.447222) (xy 341.416199 -290.4447) (xy 341.402805 -290.442762)
			(xy 341.396066 -290.443412) (xy 341.305642 -290.454842) (xy 341.293196 -290.456366) (xy 341.28202 -290.465002)
			(xy 341.276891 -290.469346) (xy 341.268914 -290.480158) (xy 341.266272 -290.486338) (xy 341.266272 -290.486592)
			(xy 341.258701 -290.50549) (xy 341.241156 -290.542229) (xy 341.23122 -290.559998) (xy 341.227918 -290.56584)
			(xy 341.226394 -290.571936) (xy 341.224616 -290.58489) (xy 341.224616 -290.744148) (xy 341.224984 -290.753161)
			(xy 341.231245 -290.770065) (xy 341.236808 -290.777168) (xy 341.24265 -290.784026) (xy 341.258652 -290.792916)
			(xy 341.267542 -290.794186) (xy 341.291257 -290.798294) (xy 341.337087 -290.812989) (xy 341.380043 -290.834693)
			(xy 341.419061 -290.86287) (xy 341.453174 -290.896819) (xy 341.481538 -290.935701) (xy 341.503449 -290.978552)
			(xy 341.518365 -291.02431) (xy 341.525916 -291.071842) (xy 341.525915 -291.095938) (xy 341.844879 -291.095938)
			(xy 341.848974 -291.04521) (xy 341.861153 -290.995796) (xy 341.881101 -290.948976) (xy 341.908302 -290.905962)
			(xy 341.94205 -290.867868) (xy 341.981472 -290.835681) (xy 342.025546 -290.810235) (xy 342.073132 -290.792188)
			(xy 342.122996 -290.782008) (xy 342.173848 -290.779959) (xy 342.224369 -290.786093) (xy 342.273253 -290.800253)
			(xy 342.319232 -290.82207) (xy 342.361116 -290.85098) (xy 342.39782 -290.886235) (xy 342.428393 -290.926921)
			(xy 342.452044 -290.971984) (xy 342.46816 -291.020258) (xy 342.476324 -291.070492) (xy 342.476836 -291.095938)
			(xy 342.795364 -291.095938) (xy 342.799324 -291.046884) (xy 342.811101 -290.9991) (xy 342.830392 -290.953824)
			(xy 342.856695 -290.912228) (xy 342.88933 -290.875391) (xy 342.927451 -290.844266) (xy 342.970072 -290.819659)
			(xy 343.016088 -290.802207) (xy 343.064307 -290.792363) (xy 343.113482 -290.790382) (xy 343.162337 -290.796314)
			(xy 343.209608 -290.810006) (xy 343.25407 -290.831104) (xy 343.294573 -290.85906) (xy 343.330066 -290.893152)
			(xy 343.359631 -290.932496) (xy 343.382502 -290.976073) (xy 343.398086 -291.022754) (xy 343.405981 -291.071331)
			(xy 343.406476 -291.095938) (xy 343.405981 -291.120545) (xy 343.398086 -291.169122) (xy 343.382502 -291.215803)
			(xy 343.359631 -291.25938) (xy 343.330066 -291.298724) (xy 343.294573 -291.332816) (xy 343.25407 -291.360772)
			(xy 343.209608 -291.38187) (xy 343.162337 -291.395562) (xy 343.113482 -291.401494) (xy 343.064307 -291.399513)
			(xy 343.016088 -291.389669) (xy 342.970072 -291.372217) (xy 342.927451 -291.34761) (xy 342.88933 -291.316485)
			(xy 342.856695 -291.279648) (xy 342.830392 -291.238052) (xy 342.811101 -291.192776) (xy 342.799324 -291.144992)
			(xy 342.795364 -291.095938) (xy 342.476836 -291.095938) (xy 342.476324 -291.121384) (xy 342.46816 -291.171618)
			(xy 342.452044 -291.219892) (xy 342.428393 -291.264955) (xy 342.39782 -291.305641) (xy 342.361116 -291.340896)
			(xy 342.319232 -291.369806) (xy 342.273253 -291.391623) (xy 342.224369 -291.405783) (xy 342.173848 -291.411917)
			(xy 342.122996 -291.409868) (xy 342.073132 -291.399688) (xy 342.025546 -291.381641) (xy 341.981472 -291.356195)
			(xy 341.94205 -291.324008) (xy 341.908302 -291.285914) (xy 341.881101 -291.2429) (xy 341.861153 -291.19608)
			(xy 341.848974 -291.146666) (xy 341.844879 -291.095938) (xy 341.525915 -291.095938) (xy 341.525915 -291.11997)
			(xy 341.518362 -291.167501) (xy 341.503445 -291.213259) (xy 341.481532 -291.256109) (xy 341.453166 -291.29499)
			(xy 341.419052 -291.328938) (xy 341.380033 -291.357113) (xy 341.337076 -291.378815) (xy 341.291246 -291.393509)
			(xy 341.267542 -291.39769) (xy 341.258652 -291.39896) (xy 341.24265 -291.40785) (xy 341.236808 -291.414708)
			(xy 341.231223 -291.421795) (xy 341.224983 -291.438712) (xy 341.224616 -291.447728) (xy 341.224616 -291.600382)
			(xy 341.224756 -291.605272) (xy 341.22668 -291.614862) (xy 341.228426 -291.619432) (xy 341.232236 -291.627052)
			(xy 341.232998 -291.628322) (xy 341.238995 -291.638901) (xy 341.250173 -291.660499) (xy 341.25535 -291.671502)
			(xy 341.268558 -291.70249) (xy 341.268558 -291.702744) (xy 341.271246 -291.70895) (xy 341.279346 -291.719774)
			(xy 341.28456 -291.72408) (xy 341.28964 -291.728144) (xy 341.30234 -291.733478) (xy 341.397844 -291.74567)
			(xy 341.406973 -291.74647) (xy 341.424801 -291.742289) (xy 341.432642 -291.737542) (xy 341.436185 -291.735042)
			(xy 341.442437 -291.729036) (xy 341.445088 -291.725604) (xy 341.445088 -291.72535) (xy 341.459584 -291.706382)
			(xy 341.493476 -291.672765) (xy 341.532186 -291.64483) (xy 341.57477 -291.623257) (xy 341.620192 -291.608572)
			(xy 341.667346 -291.601132) (xy 341.691214 -291.600636) (xy 341.716465 -291.601159) (xy 341.766278 -291.609473)
			(xy 341.814043 -291.625873) (xy 341.858457 -291.64991) (xy 341.898309 -291.68093) (xy 341.932513 -291.718086)
			(xy 341.960134 -291.760365) (xy 341.98042 -291.806614) (xy 341.992817 -291.855571) (xy 341.996987 -291.9059)
			(xy 341.996983 -291.905944) (xy 342.314779 -291.905944) (xy 342.318874 -291.855216) (xy 342.331053 -291.805802)
			(xy 342.351001 -291.758982) (xy 342.378202 -291.715968) (xy 342.41195 -291.677874) (xy 342.451372 -291.645687)
			(xy 342.495446 -291.620241) (xy 342.543032 -291.602194) (xy 342.592896 -291.592014) (xy 342.643748 -291.589965)
			(xy 342.694269 -291.596099) (xy 342.743153 -291.610259) (xy 342.789132 -291.632076) (xy 342.831016 -291.660986)
			(xy 342.86772 -291.696241) (xy 342.898293 -291.736927) (xy 342.921944 -291.78199) (xy 342.93806 -291.830264)
			(xy 342.946224 -291.880498) (xy 342.946736 -291.905944) (xy 343.254833 -291.905944) (xy 343.258928 -291.855216)
			(xy 343.271107 -291.805802) (xy 343.291055 -291.758982) (xy 343.318256 -291.715968) (xy 343.352004 -291.677874)
			(xy 343.391426 -291.645687) (xy 343.4355 -291.620241) (xy 343.483086 -291.602194) (xy 343.53295 -291.592014)
			(xy 343.583802 -291.589965) (xy 343.634323 -291.596099) (xy 343.683207 -291.610259) (xy 343.729186 -291.632076)
			(xy 343.77107 -291.660986) (xy 343.807774 -291.696241) (xy 343.838347 -291.736927) (xy 343.861998 -291.78199)
			(xy 343.878114 -291.830264) (xy 343.886278 -291.880498) (xy 343.88679 -291.905944) (xy 343.886278 -291.93139)
			(xy 343.878114 -291.981624) (xy 343.861998 -292.029898) (xy 343.838347 -292.074961) (xy 343.807774 -292.115647)
			(xy 343.77107 -292.150902) (xy 343.729186 -292.179812) (xy 343.683207 -292.201629) (xy 343.634323 -292.215789)
			(xy 343.583802 -292.221923) (xy 343.53295 -292.219874) (xy 343.483086 -292.209694) (xy 343.4355 -292.191647)
			(xy 343.391426 -292.166201) (xy 343.352004 -292.134014) (xy 343.318256 -292.09592) (xy 343.291055 -292.052906)
			(xy 343.271107 -292.006086) (xy 343.258928 -291.956672) (xy 343.254833 -291.905944) (xy 342.946736 -291.905944)
			(xy 342.946224 -291.93139) (xy 342.93806 -291.981624) (xy 342.921944 -292.029898) (xy 342.898293 -292.074961)
			(xy 342.86772 -292.115647) (xy 342.831016 -292.150902) (xy 342.789132 -292.179812) (xy 342.743153 -292.201629)
			(xy 342.694269 -292.215789) (xy 342.643748 -292.221923) (xy 342.592896 -292.219874) (xy 342.543032 -292.209694)
			(xy 342.495446 -292.191647) (xy 342.451372 -292.166201) (xy 342.41195 -292.134014) (xy 342.378202 -292.09592)
			(xy 342.351001 -292.052906) (xy 342.331053 -292.006086) (xy 342.318874 -291.956672) (xy 342.314779 -291.905944)
			(xy 341.996983 -291.905944) (xy 341.992817 -291.956229) (xy 341.98042 -292.005186) (xy 341.960134 -292.051435)
			(xy 341.932513 -292.093714) (xy 341.898309 -292.13087) (xy 341.858457 -292.16189) (xy 341.814043 -292.185927)
			(xy 341.766278 -292.202327) (xy 341.716465 -292.210641) (xy 341.691214 -292.211252) (xy 341.667343 -292.210791)
			(xy 341.620184 -292.203359) (xy 341.574758 -292.188673) (xy 341.532173 -292.167091) (xy 341.493469 -292.139142)
			(xy 341.459589 -292.105505) (xy 341.445088 -292.086538) (xy 341.445088 -292.086284) (xy 341.442435 -292.082855)
			(xy 341.436176 -292.076857) (xy 341.432642 -292.074346) (xy 341.424815 -292.069568) (xy 341.406975 -292.065385)
			(xy 341.397844 -292.066218) (xy 341.309198 -292.077648) (xy 341.302437 -292.078721) (xy 341.289812 -292.083995)
			(xy 341.284306 -292.088062) (xy 341.278972 -292.092126) (xy 341.271098 -292.102794) (xy 341.268558 -292.109398)
			(xy 341.260579 -292.129112) (xy 341.242016 -292.167381) (xy 341.231474 -292.185852) (xy 341.231474 -292.186106)
			(xy 341.228355 -292.191925) (xy 341.22488 -292.204656) (xy 341.224616 -292.211252) (xy 341.224616 -292.36416)
			(xy 341.224969 -292.373179) (xy 341.231208 -292.390103) (xy 341.236808 -292.39718) (xy 341.24265 -292.404038)
			(xy 341.258652 -292.412928) (xy 341.267542 -292.414198) (xy 341.291258 -292.418306) (xy 341.33709 -292.433003)
			(xy 341.380048 -292.454711) (xy 341.419067 -292.48289) (xy 341.45318 -292.516844) (xy 341.481542 -292.555731)
			(xy 341.503451 -292.598586) (xy 341.518362 -292.644349) (xy 341.525907 -292.691885) (xy 341.526368 -292.71595)
			(xy 341.844879 -292.71595) (xy 341.848974 -292.665222) (xy 341.861153 -292.615808) (xy 341.881101 -292.568988)
			(xy 341.908302 -292.525974) (xy 341.94205 -292.48788) (xy 341.981472 -292.455693) (xy 342.025546 -292.430247)
			(xy 342.073132 -292.4122) (xy 342.122996 -292.40202) (xy 342.173848 -292.399971) (xy 342.224369 -292.406105)
			(xy 342.273253 -292.420265) (xy 342.319232 -292.442082) (xy 342.361116 -292.470992) (xy 342.39782 -292.506247)
			(xy 342.428393 -292.546933) (xy 342.452044 -292.591996) (xy 342.46816 -292.64027) (xy 342.476324 -292.690504)
			(xy 342.476836 -292.71595) (xy 342.795364 -292.71595) (xy 342.799324 -292.666896) (xy 342.811101 -292.619112)
			(xy 342.830392 -292.573836) (xy 342.856695 -292.53224) (xy 342.88933 -292.495403) (xy 342.927451 -292.464278)
			(xy 342.970072 -292.439671) (xy 343.016088 -292.422219) (xy 343.064307 -292.412375) (xy 343.113482 -292.410394)
			(xy 343.162337 -292.416326) (xy 343.209608 -292.430018) (xy 343.25407 -292.451116) (xy 343.294573 -292.479072)
			(xy 343.330066 -292.513164) (xy 343.359631 -292.552508) (xy 343.382502 -292.596085) (xy 343.398086 -292.642766)
			(xy 343.405981 -292.691343) (xy 343.406476 -292.71595) (xy 343.724987 -292.71595) (xy 343.729082 -292.665222)
			(xy 343.741261 -292.615808) (xy 343.761209 -292.568988) (xy 343.78841 -292.525974) (xy 343.822158 -292.48788)
			(xy 343.86158 -292.455693) (xy 343.905654 -292.430247) (xy 343.95324 -292.4122) (xy 344.003104 -292.40202)
			(xy 344.053956 -292.399971) (xy 344.104477 -292.406105) (xy 344.153361 -292.420265) (xy 344.19934 -292.442082)
			(xy 344.241224 -292.470992) (xy 344.277928 -292.506247) (xy 344.308501 -292.546933) (xy 344.332152 -292.591996)
			(xy 344.348268 -292.64027) (xy 344.356432 -292.690504) (xy 344.356944 -292.71595) (xy 344.356432 -292.741396)
			(xy 344.348268 -292.79163) (xy 344.332152 -292.839904) (xy 344.308501 -292.884967) (xy 344.277928 -292.925653)
			(xy 344.241224 -292.960908) (xy 344.19934 -292.989818) (xy 344.153361 -293.011635) (xy 344.104477 -293.025795)
			(xy 344.053956 -293.031929) (xy 344.003104 -293.02988) (xy 343.95324 -293.0197) (xy 343.905654 -293.001653)
			(xy 343.86158 -292.976207) (xy 343.822158 -292.94402) (xy 343.78841 -292.905926) (xy 343.761209 -292.862912)
			(xy 343.741261 -292.816092) (xy 343.729082 -292.766678) (xy 343.724987 -292.71595) (xy 343.406476 -292.71595)
			(xy 343.405981 -292.740557) (xy 343.398086 -292.789134) (xy 343.382502 -292.835815) (xy 343.359631 -292.879392)
			(xy 343.330066 -292.918736) (xy 343.294573 -292.952828) (xy 343.25407 -292.980784) (xy 343.209608 -293.001882)
			(xy 343.162337 -293.015574) (xy 343.113482 -293.021506) (xy 343.064307 -293.019525) (xy 343.016088 -293.009681)
			(xy 342.970072 -292.992229) (xy 342.927451 -292.967622) (xy 342.88933 -292.936497) (xy 342.856695 -292.89966)
			(xy 342.830392 -292.858064) (xy 342.811101 -292.812788) (xy 342.799324 -292.765004) (xy 342.795364 -292.71595)
			(xy 342.476836 -292.71595) (xy 342.476324 -292.741396) (xy 342.46816 -292.79163) (xy 342.452044 -292.839904)
			(xy 342.428393 -292.884967) (xy 342.39782 -292.925653) (xy 342.361116 -292.960908) (xy 342.319232 -292.989818)
			(xy 342.273253 -293.011635) (xy 342.224369 -293.025795) (xy 342.173848 -293.031929) (xy 342.122996 -293.02988)
			(xy 342.073132 -293.0197) (xy 342.025546 -293.001653) (xy 341.981472 -292.976207) (xy 341.94205 -292.94402)
			(xy 341.908302 -292.905926) (xy 341.881101 -292.862912) (xy 341.861153 -292.816092) (xy 341.848974 -292.766678)
			(xy 341.844879 -292.71595) (xy 341.526368 -292.71595) (xy 341.525921 -292.739683) (xy 341.518579 -292.786578)
			(xy 341.504065 -292.831771) (xy 341.482729 -292.874172) (xy 341.455085 -292.912758) (xy 341.4218 -292.946598)
			(xy 341.383677 -292.974877) (xy 341.341635 -292.996911) (xy 341.296688 -293.012171) (xy 341.273384 -293.016686)
			(xy 341.26551 -293.017956) (xy 341.258398 -293.021766) (xy 341.255143 -293.023601) (xy 341.249146 -293.028059)
			(xy 341.24646 -293.030656) (xy 341.000334 -293.276782) (xy 340.994163 -293.283416) (xy 340.986561 -293.29985)
			(xy 340.985181 -293.317903) (xy 340.990198 -293.335301) (xy 340.995254 -293.342822) (xy 340.995508 -293.343076)
			(xy 341.009834 -293.362996) (xy 341.032605 -293.406454) (xy 341.048122 -293.452997) (xy 341.055986 -293.501425)
			(xy 341.056468 -293.525956) (xy 341.38541 -293.525956) (xy 341.38937 -293.476902) (xy 341.401147 -293.429118)
			(xy 341.420438 -293.383842) (xy 341.446741 -293.342246) (xy 341.479376 -293.305409) (xy 341.517497 -293.274284)
			(xy 341.560118 -293.249677) (xy 341.606134 -293.232225) (xy 341.654353 -293.222381) (xy 341.703528 -293.2204)
			(xy 341.752383 -293.226332) (xy 341.799654 -293.240024) (xy 341.844116 -293.261122) (xy 341.884619 -293.289078)
			(xy 341.920112 -293.32317) (xy 341.949677 -293.362514) (xy 341.972548 -293.406091) (xy 341.988132 -293.452772)
			(xy 341.996027 -293.501349) (xy 341.996522 -293.525956) (xy 342.32521 -293.525956) (xy 342.32917 -293.476902)
			(xy 342.340947 -293.429118) (xy 342.360238 -293.383842) (xy 342.386541 -293.342246) (xy 342.419176 -293.305409)
			(xy 342.457297 -293.274284) (xy 342.499918 -293.249677) (xy 342.545934 -293.232225) (xy 342.594153 -293.222381)
			(xy 342.643328 -293.2204) (xy 342.692183 -293.226332) (xy 342.739454 -293.240024) (xy 342.783916 -293.261122)
			(xy 342.824419 -293.289078) (xy 342.859912 -293.32317) (xy 342.889477 -293.362514) (xy 342.912348 -293.406091)
			(xy 342.927932 -293.452772) (xy 342.935827 -293.501349) (xy 342.936322 -293.525956) (xy 343.254833 -293.525956)
			(xy 343.258928 -293.475228) (xy 343.271107 -293.425814) (xy 343.291055 -293.378994) (xy 343.318256 -293.33598)
			(xy 343.352004 -293.297886) (xy 343.391426 -293.265699) (xy 343.4355 -293.240253) (xy 343.483086 -293.222206)
			(xy 343.53295 -293.212026) (xy 343.583802 -293.209977) (xy 343.634323 -293.216111) (xy 343.683207 -293.230271)
			(xy 343.729186 -293.252088) (xy 343.77107 -293.280998) (xy 343.807774 -293.316253) (xy 343.838347 -293.356939)
			(xy 343.861998 -293.402002) (xy 343.878114 -293.450276) (xy 343.886278 -293.50051) (xy 343.88679 -293.525956)
			(xy 343.886278 -293.551402) (xy 343.878114 -293.601636) (xy 343.861998 -293.64991) (xy 343.838347 -293.694973)
			(xy 343.807774 -293.735659) (xy 343.77107 -293.770914) (xy 343.729186 -293.799824) (xy 343.683207 -293.821641)
			(xy 343.634323 -293.835801) (xy 343.583802 -293.841935) (xy 343.53295 -293.839886) (xy 343.483086 -293.829706)
			(xy 343.4355 -293.811659) (xy 343.391426 -293.786213) (xy 343.352004 -293.754026) (xy 343.318256 -293.715932)
			(xy 343.291055 -293.672918) (xy 343.271107 -293.626098) (xy 343.258928 -293.576684) (xy 343.254833 -293.525956)
			(xy 342.936322 -293.525956) (xy 342.935827 -293.550563) (xy 342.927932 -293.59914) (xy 342.912348 -293.645821)
			(xy 342.889477 -293.689398) (xy 342.859912 -293.728742) (xy 342.824419 -293.762834) (xy 342.783916 -293.79079)
			(xy 342.739454 -293.811888) (xy 342.692183 -293.82558) (xy 342.643328 -293.831512) (xy 342.594153 -293.829531)
			(xy 342.545934 -293.819687) (xy 342.499918 -293.802235) (xy 342.457297 -293.777628) (xy 342.419176 -293.746503)
			(xy 342.386541 -293.709666) (xy 342.360238 -293.66807) (xy 342.340947 -293.622794) (xy 342.32917 -293.57501)
			(xy 342.32521 -293.525956) (xy 341.996522 -293.525956) (xy 341.996027 -293.550563) (xy 341.988132 -293.59914)
			(xy 341.972548 -293.645821) (xy 341.949677 -293.689398) (xy 341.920112 -293.728742) (xy 341.884619 -293.762834)
			(xy 341.844116 -293.79079) (xy 341.799654 -293.811888) (xy 341.752383 -293.82558) (xy 341.703528 -293.831512)
			(xy 341.654353 -293.829531) (xy 341.606134 -293.819687) (xy 341.560118 -293.802235) (xy 341.517497 -293.777628)
			(xy 341.479376 -293.746503) (xy 341.446741 -293.709666) (xy 341.420438 -293.66807) (xy 341.401147 -293.622794)
			(xy 341.38937 -293.57501) (xy 341.38541 -293.525956) (xy 341.056468 -293.525956) (xy 341.055999 -293.550194)
			(xy 341.048334 -293.598059) (xy 341.033206 -293.644113) (xy 341.010994 -293.6872) (xy 340.982256 -293.726238)
			(xy 340.947713 -293.760247) (xy 340.908232 -293.788374) (xy 340.864805 -293.809912) (xy 340.818521 -293.824322)
			(xy 340.794594 -293.828216) (xy 340.781386 -293.829994) (xy 340.75116 -293.831518) (xy 340.727586 -293.831086)
			(xy 340.680997 -293.823857) (xy 340.636069 -293.809561) (xy 340.593869 -293.788537) (xy 340.555396 -293.761284)
			(xy 340.521564 -293.728447) (xy 340.493174 -293.690806) (xy 340.481666 -293.670228) (xy 340.478618 -293.664386)
			(xy 340.469474 -293.654734) (xy 340.430104 -293.630096) (xy 340.428072 -293.630096) (xy 340.411562 -293.632382)
			(xy 340.368338 -293.638021) (xy 340.28126 -293.642124) (xy 340.194182 -293.638021) (xy 340.150958 -293.632382)
			(xy 340.15045 -293.632382) (xy 340.13394 -293.630096) (xy 340.131908 -293.630096) (xy 340.092284 -293.654988)
			(xy 340.083648 -293.664386) (xy 340.080854 -293.669212) (xy 340.069369 -293.689862) (xy 340.04102 -293.727662)
			(xy 340.007191 -293.760647) (xy 339.968687 -293.788032) (xy 339.926426 -293.809164) (xy 339.881417 -293.823538)
			(xy 339.834731 -293.830812) (xy 339.811106 -293.831264) (xy 339.78756 -293.83083) (xy 339.741024 -293.823608)
			(xy 339.696147 -293.809335) (xy 339.65399 -293.788347) (xy 339.61555 -293.761142) (xy 339.581738 -293.728363)
			(xy 339.553354 -293.690786) (xy 339.541866 -293.670228) (xy 339.541866 -293.66972) (xy 339.538818 -293.66464)
			(xy 339.530182 -293.655242) (xy 339.490812 -293.63035) (xy 339.485224 -293.630604) (xy 339.471508 -293.632636)
			(xy 339.46211 -293.633906) (xy 339.461856 -293.633906) (xy 339.454689 -293.635154) (xy 339.441416 -293.641095)
			(xy 339.435694 -293.64559) (xy 339.404452 -293.67226) (xy 339.40115 -293.683182) (xy 339.397848 -293.693342)
			(xy 339.397848 -293.69385) (xy 339.393391 -293.707539) (xy 339.383228 -293.734478) (xy 339.377528 -293.747698)
			(xy 339.363678 -293.778126) (xy 339.329676 -293.835691) (xy 339.30971 -293.862506) (xy 339.30463 -293.86911)
			(xy 339.293962 -293.899844) (xy 339.294088 -293.904126) (xy 339.295621 -293.912555) (xy 339.29701 -293.916608)
			(xy 339.332316 -294.001444) (xy 339.33758 -294.012347) (xy 339.356008 -294.027998) (xy 339.367622 -294.031416)
			(xy 339.373464 -294.032432) (xy 339.373972 -294.032432) (xy 339.39861 -294.035582) (xy 339.446478 -294.048835)
			(xy 339.491569 -294.069661) (xy 339.532694 -294.097511) (xy 339.56877 -294.13165) (xy 339.598845 -294.171177)
			(xy 339.622125 -294.215052) (xy 339.637997 -294.262116) (xy 339.646042 -294.311128) (xy 339.646514 -294.335962)
			(xy 339.975202 -294.335962) (xy 339.979162 -294.286908) (xy 339.990939 -294.239124) (xy 340.01023 -294.193848)
			(xy 340.036533 -294.152252) (xy 340.069168 -294.115415) (xy 340.107289 -294.08429) (xy 340.14991 -294.059683)
			(xy 340.195926 -294.042231) (xy 340.244145 -294.032387) (xy 340.29332 -294.030406) (xy 340.342175 -294.036338)
			(xy 340.389446 -294.05003) (xy 340.433908 -294.071128) (xy 340.474411 -294.099084) (xy 340.509904 -294.133176)
			(xy 340.539469 -294.17252) (xy 340.56234 -294.216097) (xy 340.577924 -294.262778) (xy 340.585819 -294.311355)
			(xy 340.586314 -294.335962) (xy 340.915256 -294.335962) (xy 340.919216 -294.286908) (xy 340.930993 -294.239124)
			(xy 340.950284 -294.193848) (xy 340.976587 -294.152252) (xy 341.009222 -294.115415) (xy 341.047343 -294.08429)
			(xy 341.089964 -294.059683) (xy 341.13598 -294.042231) (xy 341.184199 -294.032387) (xy 341.233374 -294.030406)
			(xy 341.282229 -294.036338) (xy 341.3295 -294.05003) (xy 341.373962 -294.071128) (xy 341.414465 -294.099084)
			(xy 341.449958 -294.133176) (xy 341.479523 -294.17252) (xy 341.502394 -294.216097) (xy 341.517978 -294.262778)
			(xy 341.525873 -294.311355) (xy 341.526368 -294.335962) (xy 342.795364 -294.335962) (xy 342.799324 -294.286908)
			(xy 342.811101 -294.239124) (xy 342.830392 -294.193848) (xy 342.856695 -294.152252) (xy 342.88933 -294.115415)
			(xy 342.927451 -294.08429) (xy 342.970072 -294.059683) (xy 343.016088 -294.042231) (xy 343.064307 -294.032387)
			(xy 343.113482 -294.030406) (xy 343.162337 -294.036338) (xy 343.209608 -294.05003) (xy 343.25407 -294.071128)
			(xy 343.294573 -294.099084) (xy 343.330066 -294.133176) (xy 343.359631 -294.17252) (xy 343.382502 -294.216097)
			(xy 343.398086 -294.262778) (xy 343.405981 -294.311355) (xy 343.406476 -294.335962) (xy 343.735418 -294.335962)
			(xy 343.739378 -294.286908) (xy 343.751155 -294.239124) (xy 343.770446 -294.193848) (xy 343.796749 -294.152252)
			(xy 343.829384 -294.115415) (xy 343.867505 -294.08429) (xy 343.910126 -294.059683) (xy 343.956142 -294.042231)
			(xy 344.004361 -294.032387) (xy 344.053536 -294.030406) (xy 344.102391 -294.036338) (xy 344.149662 -294.05003)
			(xy 344.194124 -294.071128) (xy 344.234627 -294.099084) (xy 344.27012 -294.133176) (xy 344.299685 -294.17252)
			(xy 344.322556 -294.216097) (xy 344.33814 -294.262778) (xy 344.346035 -294.311355) (xy 344.34653 -294.335962)
			(xy 344.346035 -294.360569) (xy 344.33814 -294.409146) (xy 344.322556 -294.455827) (xy 344.299685 -294.499404)
			(xy 344.27012 -294.538748) (xy 344.234627 -294.57284) (xy 344.194124 -294.600796) (xy 344.149662 -294.621894)
			(xy 344.102391 -294.635586) (xy 344.053536 -294.641518) (xy 344.004361 -294.639537) (xy 343.956142 -294.629693)
			(xy 343.910126 -294.612241) (xy 343.867505 -294.587634) (xy 343.829384 -294.556509) (xy 343.796749 -294.519672)
			(xy 343.770446 -294.478076) (xy 343.751155 -294.4328) (xy 343.739378 -294.385016) (xy 343.735418 -294.335962)
			(xy 343.406476 -294.335962) (xy 343.405981 -294.360569) (xy 343.398086 -294.409146) (xy 343.382502 -294.455827)
			(xy 343.359631 -294.499404) (xy 343.330066 -294.538748) (xy 343.294573 -294.57284) (xy 343.25407 -294.600796)
			(xy 343.209608 -294.621894) (xy 343.162337 -294.635586) (xy 343.113482 -294.641518) (xy 343.064307 -294.639537)
			(xy 343.016088 -294.629693) (xy 342.970072 -294.612241) (xy 342.927451 -294.587634) (xy 342.88933 -294.556509)
			(xy 342.856695 -294.519672) (xy 342.830392 -294.478076) (xy 342.811101 -294.4328) (xy 342.799324 -294.385016)
			(xy 342.795364 -294.335962) (xy 341.526368 -294.335962) (xy 341.525873 -294.360569) (xy 341.517978 -294.409146)
			(xy 341.502394 -294.455827) (xy 341.479523 -294.499404) (xy 341.449958 -294.538748) (xy 341.414465 -294.57284)
			(xy 341.373962 -294.600796) (xy 341.3295 -294.621894) (xy 341.282229 -294.635586) (xy 341.233374 -294.641518)
			(xy 341.184199 -294.639537) (xy 341.13598 -294.629693) (xy 341.089964 -294.612241) (xy 341.047343 -294.587634)
			(xy 341.009222 -294.556509) (xy 340.976587 -294.519672) (xy 340.950284 -294.478076) (xy 340.930993 -294.4328)
			(xy 340.919216 -294.385016) (xy 340.915256 -294.335962) (xy 340.586314 -294.335962) (xy 340.585819 -294.360569)
			(xy 340.577924 -294.409146) (xy 340.56234 -294.455827) (xy 340.539469 -294.499404) (xy 340.509904 -294.538748)
			(xy 340.474411 -294.57284) (xy 340.433908 -294.600796) (xy 340.389446 -294.621894) (xy 340.342175 -294.635586)
			(xy 340.29332 -294.641518) (xy 340.244145 -294.639537) (xy 340.195926 -294.629693) (xy 340.14991 -294.612241)
			(xy 340.107289 -294.587634) (xy 340.069168 -294.556509) (xy 340.036533 -294.519672) (xy 340.01023 -294.478076)
			(xy 339.990939 -294.4328) (xy 339.979162 -294.385016) (xy 339.975202 -294.335962) (xy 339.646514 -294.335962)
			(xy 339.646071 -294.359957) (xy 339.638569 -294.407358) (xy 339.623744 -294.453001) (xy 339.60196 -294.495763)
			(xy 339.573755 -294.53459) (xy 339.539824 -294.568527) (xy 339.501 -294.596737) (xy 339.458242 -294.618527)
			(xy 339.412601 -294.633358) (xy 339.365201 -294.640867) (xy 339.341206 -294.64127) (xy 339.317428 -294.640817)
			(xy 339.270448 -294.633446) (xy 339.225178 -294.618881) (xy 339.182713 -294.597474) (xy 339.144079 -294.569744)
			(xy 339.110212 -294.536359) (xy 339.081929 -294.498128) (xy 339.059915 -294.455975) (xy 339.044701 -294.410919)
			(xy 339.036656 -294.364049) (xy 339.035898 -294.34028) (xy 339.035898 -294.335454) (xy 339.036255 -294.314584)
			(xy 339.041975 -294.273238) (xy 339.053274 -294.233057) (xy 339.061298 -294.213788) (xy 339.061298 -294.213534)
			(xy 339.063788 -294.207374) (xy 339.065842 -294.194253) (xy 339.065362 -294.187626) (xy 339.0646 -294.180768)
			(xy 339.05952 -294.168068) (xy 339.036152 -294.137588) (xy 338.999322 -294.09009) (xy 338.993534 -294.083741)
			(xy 338.978743 -294.075021) (xy 338.961898 -294.071702) (xy 338.953348 -294.072564) (xy 338.953094 -294.072564)
			(xy 338.932767 -294.075415) (xy 338.891831 -294.078466) (xy 338.871306 -294.07866) (xy 338.871052 -294.07866)
			(xy 338.850531 -294.078525) (xy 338.809595 -294.075603) (xy 338.789264 -294.072818) (xy 338.782305 -294.071953)
			(xy 338.768388 -294.073631) (xy 338.761832 -294.07612) (xy 338.756244 -294.078406) (xy 338.74583 -294.08628)
			(xy 338.687156 -294.16248) (xy 338.683155 -294.168144) (xy 338.678017 -294.18102) (xy 338.676996 -294.18788)
			(xy 338.675472 -294.201088) (xy 338.68106 -294.213788) (xy 338.692599 -294.24216) (xy 338.705391 -294.302049)
			(xy 338.70646 -294.33266) (xy 338.70646 -294.34028) (xy 338.705673 -294.36405) (xy 338.69764 -294.410924)
			(xy 338.682437 -294.455985) (xy 338.660429 -294.498144) (xy 338.632151 -294.53638) (xy 338.598286 -294.569768)
			(xy 338.559652 -294.597502) (xy 338.517186 -294.618909) (xy 338.471914 -294.633473) (xy 338.424931 -294.64084)
			(xy 338.401152 -294.64127) (xy 338.377164 -294.640796) (xy 338.329781 -294.633283) (xy 338.284156 -294.618451)
			(xy 338.241412 -294.596665) (xy 338.202603 -294.56846) (xy 338.168684 -294.534531) (xy 338.14049 -294.495714)
			(xy 338.118716 -294.452965) (xy 338.103896 -294.407336) (xy 338.096397 -294.35995) (xy 338.095844 -294.335962)
			(xy 338.096332 -294.311142) (xy 338.104367 -294.262157) (xy 338.12022 -294.215117) (xy 338.143473 -294.171261)
			(xy 338.173513 -294.131743) (xy 338.20955 -294.097604) (xy 338.250634 -294.069744) (xy 338.295683 -294.048896)
			(xy 338.343512 -294.03561) (xy 338.368132 -294.032432) (xy 338.368386 -294.032432) (xy 338.375093 -294.031516)
			(xy 338.387714 -294.026634) (xy 338.393278 -294.02278) (xy 338.398358 -294.018716) (xy 338.40674 -294.008302)
			(xy 338.444078 -293.919656) (xy 338.446556 -293.913229) (xy 338.448366 -293.89958) (xy 338.447634 -293.892732)
			(xy 338.445856 -293.879524) (xy 338.43722 -293.868602) (xy 338.431886 -293.861744) (xy 338.42833 -293.857172)
			(xy 338.419948 -293.850314) (xy 338.395818 -293.837868) (xy 338.39068 -293.835418) (xy 338.379657 -293.832591)
			(xy 338.373974 -293.83228) (xy 338.326793 -293.830616) (xy 338.23294 -293.820318) (xy 338.186522 -293.811706)
			(xy 338.166373 -293.807654) (xy 338.126358 -293.798254) (xy 338.106512 -293.79291) (xy 338.098287 -293.791236)
			(xy 338.081574 -293.792672) (xy 338.073746 -293.795704) (xy 338.051628 -293.806881) (xy 338.004671 -293.822709)
			(xy 337.955774 -293.830745) (xy 337.930998 -293.831264) (xy 337.906222 -293.830758) (xy 337.857327 -293.822708)
			(xy 337.810373 -293.80687) (xy 337.78825 -293.795704) (xy 337.780063 -293.792483) (xy 337.76253 -293.791177)
			(xy 337.75396 -293.793164) (xy 337.70615 -293.805596) (xy 337.608901 -293.822992) (xy 337.510495 -293.831733)
			(xy 337.461098 -293.83228) (xy 337.4117 -293.831752) (xy 337.313291 -293.823023) (xy 337.216039 -293.805624)
			(xy 337.168236 -293.793164) (xy 337.159667 -293.791147) (xy 337.142126 -293.792451) (xy 337.133946 -293.795704)
			(xy 337.111828 -293.806881) (xy 337.064871 -293.822709) (xy 337.015974 -293.830745) (xy 336.991198 -293.831264)
			(xy 336.966422 -293.830758) (xy 336.917527 -293.822708) (xy 336.870573 -293.80687) (xy 336.84845 -293.795704)
			(xy 336.840263 -293.792483) (xy 336.82273 -293.791177) (xy 336.81416 -293.793164) (xy 336.76635 -293.805596)
			(xy 336.669101 -293.822992) (xy 336.570695 -293.831733) (xy 336.521298 -293.83228) (xy 336.521044 -293.83228)
			(xy 336.471646 -293.83175) (xy 336.373238 -293.823016) (xy 336.275988 -293.805613) (xy 336.228182 -293.793164)
			(xy 336.219612 -293.791139) (xy 336.202065 -293.792429) (xy 336.193892 -293.795704) (xy 336.171775 -293.806884)
			(xy 336.124819 -293.82272) (xy 336.075921 -293.830763) (xy 336.051144 -293.831264) (xy 336.026367 -293.830762)
			(xy 335.977469 -293.822719) (xy 335.930512 -293.806886) (xy 335.908396 -293.795704) (xy 335.900209 -293.792492)
			(xy 335.88268 -293.791204) (xy 335.874106 -293.793164) (xy 335.826296 -293.805594) (xy 335.729046 -293.822985)
			(xy 335.63064 -293.831722) (xy 335.581244 -293.83228) (xy 335.58099 -293.83228) (xy 335.531592 -293.831752)
			(xy 335.433183 -293.823022) (xy 335.335932 -293.805623) (xy 335.288128 -293.793164) (xy 335.279559 -293.791148)
			(xy 335.26202 -293.792455) (xy 335.253838 -293.795704) (xy 335.231722 -293.806887) (xy 335.184766 -293.82273)
			(xy 335.135868 -293.830781) (xy 335.11109 -293.831264) (xy 335.086312 -293.830765) (xy 335.037411 -293.822729)
			(xy 334.99045 -293.806903) (xy 334.968342 -293.795704) (xy 334.960155 -293.792484) (xy 334.942623 -293.791181)
			(xy 334.934052 -293.793164) (xy 334.886242 -293.805596) (xy 334.788992 -293.822991) (xy 334.690587 -293.831732)
			(xy 334.64119 -293.83228) (xy 334.640936 -293.83228) (xy 334.591539 -293.83175) (xy 334.49313 -293.823015)
			(xy 334.395881 -293.805611) (xy 334.348074 -293.793164) (xy 334.339505 -293.79114) (xy 334.321958 -293.792433)
			(xy 334.313784 -293.795704) (xy 334.291667 -293.806883) (xy 334.24471 -293.822718) (xy 334.195813 -293.83076)
			(xy 334.171036 -293.831264) (xy 334.146259 -293.830761) (xy 334.097362 -293.822717) (xy 334.050405 -293.806883)
			(xy 334.028288 -293.795704) (xy 334.020101 -293.792493) (xy 334.002573 -293.791208) (xy 333.993998 -293.793164)
			(xy 333.946188 -293.805594) (xy 333.848938 -293.822984) (xy 333.750532 -293.83172) (xy 333.701136 -293.83228)
			(xy 333.700882 -293.83228) (xy 333.651484 -293.831752) (xy 333.553075 -293.823021) (xy 333.455824 -293.805621)
			(xy 333.40802 -293.793164) (xy 333.399452 -293.79115) (xy 333.381913 -293.792459) (xy 333.37373 -293.795704)
			(xy 333.351614 -293.806887) (xy 333.304658 -293.822728) (xy 333.25576 -293.830778) (xy 333.230982 -293.831264)
			(xy 333.206204 -293.830765) (xy 333.157304 -293.822728) (xy 333.110343 -293.8069) (xy 333.088234 -293.795704)
			(xy 333.080047 -293.792486) (xy 333.062515 -293.791185) (xy 333.053944 -293.793164) (xy 333.006134 -293.805596)
			(xy 332.908884 -293.82299) (xy 332.810479 -293.83173) (xy 332.761082 -293.83228) (xy 332.760828 -293.83228)
			(xy 332.716895 -293.83186) (xy 332.629302 -293.824954) (xy 332.542525 -293.811174) (xy 332.499716 -293.801292)
			(xy 332.49235 -293.800022) (xy 332.481197 -293.799647) (xy 332.460256 -293.807286) (xy 332.451964 -293.814754)
			(xy 332.110588 -294.15613) (xy 332.107388 -294.159497) (xy 332.102146 -294.167164) (xy 332.100174 -294.17137)
			(xy 332.100174 -294.21201) (xy 332.103984 -294.221154) (xy 332.114378 -294.248645) (xy 332.125625 -294.306325)
			(xy 332.126336 -294.335708) (xy 332.126336 -294.335962) (xy 332.455278 -294.335962) (xy 332.459238 -294.286908)
			(xy 332.471015 -294.239124) (xy 332.490306 -294.193848) (xy 332.516609 -294.152252) (xy 332.549244 -294.115415)
			(xy 332.587365 -294.08429) (xy 332.629986 -294.059683) (xy 332.676002 -294.042231) (xy 332.724221 -294.032387)
			(xy 332.773396 -294.030406) (xy 332.822251 -294.036338) (xy 332.869522 -294.05003) (xy 332.913984 -294.071128)
			(xy 332.954487 -294.099084) (xy 332.98998 -294.133176) (xy 333.019545 -294.17252) (xy 333.042416 -294.216097)
			(xy 333.058 -294.262778) (xy 333.065895 -294.311355) (xy 333.06639 -294.335962) (xy 333.395332 -294.335962)
			(xy 333.399292 -294.286908) (xy 333.411069 -294.239124) (xy 333.43036 -294.193848) (xy 333.456663 -294.152252)
			(xy 333.489298 -294.115415) (xy 333.527419 -294.08429) (xy 333.57004 -294.059683) (xy 333.616056 -294.042231)
			(xy 333.664275 -294.032387) (xy 333.71345 -294.030406) (xy 333.762305 -294.036338) (xy 333.809576 -294.05003)
			(xy 333.854038 -294.071128) (xy 333.894541 -294.099084) (xy 333.930034 -294.133176) (xy 333.959599 -294.17252)
			(xy 333.98247 -294.216097) (xy 333.998054 -294.262778) (xy 334.005949 -294.311355) (xy 334.006444 -294.335962)
			(xy 334.335386 -294.335962) (xy 334.339346 -294.286908) (xy 334.351123 -294.239124) (xy 334.370414 -294.193848)
			(xy 334.396717 -294.152252) (xy 334.429352 -294.115415) (xy 334.467473 -294.08429) (xy 334.510094 -294.059683)
			(xy 334.55611 -294.042231) (xy 334.604329 -294.032387) (xy 334.653504 -294.030406) (xy 334.702359 -294.036338)
			(xy 334.74963 -294.05003) (xy 334.794092 -294.071128) (xy 334.834595 -294.099084) (xy 334.870088 -294.133176)
			(xy 334.899653 -294.17252) (xy 334.922524 -294.216097) (xy 334.938108 -294.262778) (xy 334.946003 -294.311355)
			(xy 334.946498 -294.335962) (xy 335.275186 -294.335962) (xy 335.279146 -294.286908) (xy 335.290923 -294.239124)
			(xy 335.310214 -294.193848) (xy 335.336517 -294.152252) (xy 335.369152 -294.115415) (xy 335.407273 -294.08429)
			(xy 335.449894 -294.059683) (xy 335.49591 -294.042231) (xy 335.544129 -294.032387) (xy 335.593304 -294.030406)
			(xy 335.642159 -294.036338) (xy 335.68943 -294.05003) (xy 335.733892 -294.071128) (xy 335.774395 -294.099084)
			(xy 335.809888 -294.133176) (xy 335.839453 -294.17252) (xy 335.862324 -294.216097) (xy 335.877908 -294.262778)
			(xy 335.885803 -294.311355) (xy 335.886298 -294.335962) (xy 336.21524 -294.335962) (xy 336.2192 -294.286908)
			(xy 336.230977 -294.239124) (xy 336.250268 -294.193848) (xy 336.276571 -294.152252) (xy 336.309206 -294.115415)
			(xy 336.347327 -294.08429) (xy 336.389948 -294.059683) (xy 336.435964 -294.042231) (xy 336.484183 -294.032387)
			(xy 336.533358 -294.030406) (xy 336.582213 -294.036338) (xy 336.629484 -294.05003) (xy 336.673946 -294.071128)
			(xy 336.714449 -294.099084) (xy 336.749942 -294.133176) (xy 336.779507 -294.17252) (xy 336.802378 -294.216097)
			(xy 336.817962 -294.262778) (xy 336.825857 -294.311355) (xy 336.826352 -294.335962) (xy 337.155294 -294.335962)
			(xy 337.159254 -294.286908) (xy 337.171031 -294.239124) (xy 337.190322 -294.193848) (xy 337.216625 -294.152252)
			(xy 337.24926 -294.115415) (xy 337.287381 -294.08429) (xy 337.330002 -294.059683) (xy 337.376018 -294.042231)
			(xy 337.424237 -294.032387) (xy 337.473412 -294.030406) (xy 337.522267 -294.036338) (xy 337.569538 -294.05003)
			(xy 337.614 -294.071128) (xy 337.654503 -294.099084) (xy 337.689996 -294.133176) (xy 337.719561 -294.17252)
			(xy 337.742432 -294.216097) (xy 337.758016 -294.262778) (xy 337.765911 -294.311355) (xy 337.766406 -294.335962)
			(xy 337.765911 -294.360569) (xy 337.758016 -294.409146) (xy 337.742432 -294.455827) (xy 337.719561 -294.499404)
			(xy 337.689996 -294.538748) (xy 337.654503 -294.57284) (xy 337.614 -294.600796) (xy 337.569538 -294.621894)
			(xy 337.522267 -294.635586) (xy 337.473412 -294.641518) (xy 337.424237 -294.639537) (xy 337.376018 -294.629693)
			(xy 337.330002 -294.612241) (xy 337.287381 -294.587634) (xy 337.24926 -294.556509) (xy 337.216625 -294.519672)
			(xy 337.190322 -294.478076) (xy 337.171031 -294.4328) (xy 337.159254 -294.385016) (xy 337.155294 -294.335962)
			(xy 336.826352 -294.335962) (xy 336.825857 -294.360569) (xy 336.817962 -294.409146) (xy 336.802378 -294.455827)
			(xy 336.779507 -294.499404) (xy 336.749942 -294.538748) (xy 336.714449 -294.57284) (xy 336.673946 -294.600796)
			(xy 336.629484 -294.621894) (xy 336.582213 -294.635586) (xy 336.533358 -294.641518) (xy 336.484183 -294.639537)
			(xy 336.435964 -294.629693) (xy 336.389948 -294.612241) (xy 336.347327 -294.587634) (xy 336.309206 -294.556509)
			(xy 336.276571 -294.519672) (xy 336.250268 -294.478076) (xy 336.230977 -294.4328) (xy 336.2192 -294.385016)
			(xy 336.21524 -294.335962) (xy 335.886298 -294.335962) (xy 335.885803 -294.360569) (xy 335.877908 -294.409146)
			(xy 335.862324 -294.455827) (xy 335.839453 -294.499404) (xy 335.809888 -294.538748) (xy 335.774395 -294.57284)
			(xy 335.733892 -294.600796) (xy 335.68943 -294.621894) (xy 335.642159 -294.635586) (xy 335.593304 -294.641518)
			(xy 335.544129 -294.639537) (xy 335.49591 -294.629693) (xy 335.449894 -294.612241) (xy 335.407273 -294.587634)
			(xy 335.369152 -294.556509) (xy 335.336517 -294.519672) (xy 335.310214 -294.478076) (xy 335.290923 -294.4328)
			(xy 335.279146 -294.385016) (xy 335.275186 -294.335962) (xy 334.946498 -294.335962) (xy 334.946003 -294.360569)
			(xy 334.938108 -294.409146) (xy 334.922524 -294.455827) (xy 334.899653 -294.499404) (xy 334.870088 -294.538748)
			(xy 334.834595 -294.57284) (xy 334.794092 -294.600796) (xy 334.74963 -294.621894) (xy 334.702359 -294.635586)
			(xy 334.653504 -294.641518) (xy 334.604329 -294.639537) (xy 334.55611 -294.629693) (xy 334.510094 -294.612241)
			(xy 334.467473 -294.587634) (xy 334.429352 -294.556509) (xy 334.396717 -294.519672) (xy 334.370414 -294.478076)
			(xy 334.351123 -294.4328) (xy 334.339346 -294.385016) (xy 334.335386 -294.335962) (xy 334.006444 -294.335962)
			(xy 334.005949 -294.360569) (xy 333.998054 -294.409146) (xy 333.98247 -294.455827) (xy 333.959599 -294.499404)
			(xy 333.930034 -294.538748) (xy 333.894541 -294.57284) (xy 333.854038 -294.600796) (xy 333.809576 -294.621894)
			(xy 333.762305 -294.635586) (xy 333.71345 -294.641518) (xy 333.664275 -294.639537) (xy 333.616056 -294.629693)
			(xy 333.57004 -294.612241) (xy 333.527419 -294.587634) (xy 333.489298 -294.556509) (xy 333.456663 -294.519672)
			(xy 333.43036 -294.478076) (xy 333.411069 -294.4328) (xy 333.399292 -294.385016) (xy 333.395332 -294.335962)
			(xy 333.06639 -294.335962) (xy 333.065895 -294.360569) (xy 333.058 -294.409146) (xy 333.042416 -294.455827)
			(xy 333.019545 -294.499404) (xy 332.98998 -294.538748) (xy 332.954487 -294.57284) (xy 332.913984 -294.600796)
			(xy 332.869522 -294.621894) (xy 332.822251 -294.635586) (xy 332.773396 -294.641518) (xy 332.724221 -294.639537)
			(xy 332.676002 -294.629693) (xy 332.629986 -294.612241) (xy 332.587365 -294.587634) (xy 332.549244 -294.556509)
			(xy 332.516609 -294.519672) (xy 332.490306 -294.478076) (xy 332.471015 -294.4328) (xy 332.459238 -294.385016)
			(xy 332.455278 -294.335962) (xy 332.126336 -294.335962) (xy 332.125893 -294.359958) (xy 332.118391 -294.40736)
			(xy 332.103566 -294.453004) (xy 332.081783 -294.495768) (xy 332.053579 -294.534597) (xy 332.019647 -294.568536)
			(xy 331.980824 -294.596749) (xy 331.938065 -294.618541) (xy 331.892424 -294.633375) (xy 331.845024 -294.640887)
			(xy 331.821028 -294.64127) (xy 331.799836 -294.64089) (xy 331.757863 -294.634996) (xy 331.717107 -294.623361)
			(xy 331.697584 -294.615108) (xy 331.69733 -294.615108) (xy 331.687854 -294.611467) (xy 331.667572 -294.611181)
			(xy 331.648748 -294.618736) (xy 331.641196 -294.625522) (xy 331.520292 -294.746426) (xy 331.512918 -294.754548)
			(xy 331.505268 -294.775085) (xy 331.50556 -294.78605) (xy 331.50556 -294.786304) (xy 331.511402 -294.864028)
			(xy 331.513006 -294.874559) (xy 331.5235 -294.89307) (xy 331.531722 -294.899842) (xy 331.531976 -294.900096)
			(xy 331.550916 -294.914581) (xy 331.584479 -294.948443) (xy 331.612365 -294.987116) (xy 331.633894 -295.029657)
			(xy 331.648541 -295.07503) (xy 331.655949 -295.122129) (xy 331.656436 -295.145968) (xy 331.985378 -295.145968)
			(xy 331.989338 -295.096914) (xy 332.001115 -295.04913) (xy 332.020406 -295.003854) (xy 332.046709 -294.962258)
			(xy 332.079344 -294.925421) (xy 332.117465 -294.894296) (xy 332.160086 -294.869689) (xy 332.206102 -294.852237)
			(xy 332.254321 -294.842393) (xy 332.303496 -294.840412) (xy 332.352351 -294.846344) (xy 332.399622 -294.860036)
			(xy 332.444084 -294.881134) (xy 332.484587 -294.90909) (xy 332.52008 -294.943182) (xy 332.549645 -294.982526)
			(xy 332.572516 -295.026103) (xy 332.5881 -295.072784) (xy 332.595995 -295.121361) (xy 332.59649 -295.145968)
			(xy 332.925178 -295.145968) (xy 332.929138 -295.096914) (xy 332.940915 -295.04913) (xy 332.960206 -295.003854)
			(xy 332.986509 -294.962258) (xy 333.019144 -294.925421) (xy 333.057265 -294.894296) (xy 333.099886 -294.869689)
			(xy 333.145902 -294.852237) (xy 333.194121 -294.842393) (xy 333.243296 -294.840412) (xy 333.292151 -294.846344)
			(xy 333.339422 -294.860036) (xy 333.383884 -294.881134) (xy 333.424387 -294.90909) (xy 333.45988 -294.943182)
			(xy 333.489445 -294.982526) (xy 333.512316 -295.026103) (xy 333.5279 -295.072784) (xy 333.535795 -295.121361)
			(xy 333.53629 -295.145968) (xy 333.865232 -295.145968) (xy 333.869192 -295.096914) (xy 333.880969 -295.04913)
			(xy 333.90026 -295.003854) (xy 333.926563 -294.962258) (xy 333.959198 -294.925421) (xy 333.997319 -294.894296)
			(xy 334.03994 -294.869689) (xy 334.085956 -294.852237) (xy 334.134175 -294.842393) (xy 334.18335 -294.840412)
			(xy 334.232205 -294.846344) (xy 334.279476 -294.860036) (xy 334.323938 -294.881134) (xy 334.364441 -294.90909)
			(xy 334.399934 -294.943182) (xy 334.429499 -294.982526) (xy 334.45237 -295.026103) (xy 334.467954 -295.072784)
			(xy 334.475849 -295.121361) (xy 334.476344 -295.145968) (xy 334.805286 -295.145968) (xy 334.809246 -295.096914)
			(xy 334.821023 -295.04913) (xy 334.840314 -295.003854) (xy 334.866617 -294.962258) (xy 334.899252 -294.925421)
			(xy 334.937373 -294.894296) (xy 334.979994 -294.869689) (xy 335.02601 -294.852237) (xy 335.074229 -294.842393)
			(xy 335.123404 -294.840412) (xy 335.172259 -294.846344) (xy 335.21953 -294.860036) (xy 335.263992 -294.881134)
			(xy 335.304495 -294.90909) (xy 335.339988 -294.943182) (xy 335.369553 -294.982526) (xy 335.392424 -295.026103)
			(xy 335.408008 -295.072784) (xy 335.415903 -295.121361) (xy 335.416398 -295.145968) (xy 335.74534 -295.145968)
			(xy 335.7493 -295.096914) (xy 335.761077 -295.04913) (xy 335.780368 -295.003854) (xy 335.806671 -294.962258)
			(xy 335.839306 -294.925421) (xy 335.877427 -294.894296) (xy 335.920048 -294.869689) (xy 335.966064 -294.852237)
			(xy 336.014283 -294.842393) (xy 336.063458 -294.840412) (xy 336.112313 -294.846344) (xy 336.159584 -294.860036)
			(xy 336.204046 -294.881134) (xy 336.244549 -294.90909) (xy 336.280042 -294.943182) (xy 336.309607 -294.982526)
			(xy 336.332478 -295.026103) (xy 336.348062 -295.072784) (xy 336.355957 -295.121361) (xy 336.356452 -295.145968)
			(xy 337.625194 -295.145968) (xy 337.629154 -295.096914) (xy 337.640931 -295.04913) (xy 337.660222 -295.003854)
			(xy 337.686525 -294.962258) (xy 337.71916 -294.925421) (xy 337.757281 -294.894296) (xy 337.799902 -294.869689)
			(xy 337.845918 -294.852237) (xy 337.894137 -294.842393) (xy 337.943312 -294.840412) (xy 337.992167 -294.846344)
			(xy 338.039438 -294.860036) (xy 338.0839 -294.881134) (xy 338.124403 -294.90909) (xy 338.159896 -294.943182)
			(xy 338.189461 -294.982526) (xy 338.212332 -295.026103) (xy 338.227916 -295.072784) (xy 338.235811 -295.121361)
			(xy 338.236306 -295.145968) (xy 338.565248 -295.145968) (xy 338.569208 -295.096914) (xy 338.580985 -295.04913)
			(xy 338.600276 -295.003854) (xy 338.626579 -294.962258) (xy 338.659214 -294.925421) (xy 338.697335 -294.894296)
			(xy 338.739956 -294.869689) (xy 338.785972 -294.852237) (xy 338.834191 -294.842393) (xy 338.883366 -294.840412)
			(xy 338.932221 -294.846344) (xy 338.979492 -294.860036) (xy 339.023954 -294.881134) (xy 339.064457 -294.90909)
			(xy 339.09995 -294.943182) (xy 339.129515 -294.982526) (xy 339.152386 -295.026103) (xy 339.16797 -295.072784)
			(xy 339.175865 -295.121361) (xy 339.17636 -295.145968) (xy 339.505302 -295.145968) (xy 339.509262 -295.096914)
			(xy 339.521039 -295.04913) (xy 339.54033 -295.003854) (xy 339.566633 -294.962258) (xy 339.599268 -294.925421)
			(xy 339.637389 -294.894296) (xy 339.68001 -294.869689) (xy 339.726026 -294.852237) (xy 339.774245 -294.842393)
			(xy 339.82342 -294.840412) (xy 339.872275 -294.846344) (xy 339.919546 -294.860036) (xy 339.964008 -294.881134)
			(xy 340.004511 -294.90909) (xy 340.040004 -294.943182) (xy 340.069569 -294.982526) (xy 340.09244 -295.026103)
			(xy 340.108024 -295.072784) (xy 340.115919 -295.121361) (xy 340.116414 -295.145968) (xy 340.445356 -295.145968)
			(xy 340.449316 -295.096914) (xy 340.461093 -295.04913) (xy 340.480384 -295.003854) (xy 340.506687 -294.962258)
			(xy 340.539322 -294.925421) (xy 340.577443 -294.894296) (xy 340.620064 -294.869689) (xy 340.66608 -294.852237)
			(xy 340.714299 -294.842393) (xy 340.763474 -294.840412) (xy 340.812329 -294.846344) (xy 340.8596 -294.860036)
			(xy 340.904062 -294.881134) (xy 340.944565 -294.90909) (xy 340.980058 -294.943182) (xy 341.009623 -294.982526)
			(xy 341.032494 -295.026103) (xy 341.048078 -295.072784) (xy 341.055973 -295.121361) (xy 341.056468 -295.145968)
			(xy 343.265264 -295.145968) (xy 343.269224 -295.096914) (xy 343.281001 -295.04913) (xy 343.300292 -295.003854)
			(xy 343.326595 -294.962258) (xy 343.35923 -294.925421) (xy 343.397351 -294.894296) (xy 343.439972 -294.869689)
			(xy 343.485988 -294.852237) (xy 343.534207 -294.842393) (xy 343.583382 -294.840412) (xy 343.632237 -294.846344)
			(xy 343.679508 -294.860036) (xy 343.72397 -294.881134) (xy 343.764473 -294.90909) (xy 343.799966 -294.943182)
			(xy 343.829531 -294.982526) (xy 343.852402 -295.026103) (xy 343.867986 -295.072784) (xy 343.875881 -295.121361)
			(xy 343.876376 -295.145968) (xy 343.875881 -295.170575) (xy 343.867986 -295.219152) (xy 343.852402 -295.265833)
			(xy 343.829531 -295.30941) (xy 343.799966 -295.348754) (xy 343.764473 -295.382846) (xy 343.72397 -295.410802)
			(xy 343.679508 -295.4319) (xy 343.632237 -295.445592) (xy 343.583382 -295.451524) (xy 343.534207 -295.449543)
			(xy 343.485988 -295.439699) (xy 343.439972 -295.422247) (xy 343.397351 -295.39764) (xy 343.35923 -295.366515)
			(xy 343.326595 -295.329678) (xy 343.300292 -295.288082) (xy 343.281001 -295.242806) (xy 343.269224 -295.195022)
			(xy 343.265264 -295.145968) (xy 341.056468 -295.145968) (xy 341.055973 -295.170575) (xy 341.048078 -295.219152)
			(xy 341.032494 -295.265833) (xy 341.009623 -295.30941) (xy 340.980058 -295.348754) (xy 340.944565 -295.382846)
			(xy 340.904062 -295.410802) (xy 340.8596 -295.4319) (xy 340.812329 -295.445592) (xy 340.763474 -295.451524)
			(xy 340.714299 -295.449543) (xy 340.66608 -295.439699) (xy 340.620064 -295.422247) (xy 340.577443 -295.39764)
			(xy 340.539322 -295.366515) (xy 340.506687 -295.329678) (xy 340.480384 -295.288082) (xy 340.461093 -295.242806)
			(xy 340.449316 -295.195022) (xy 340.445356 -295.145968) (xy 340.116414 -295.145968) (xy 340.115919 -295.170575)
			(xy 340.108024 -295.219152) (xy 340.09244 -295.265833) (xy 340.069569 -295.30941) (xy 340.040004 -295.348754)
			(xy 340.004511 -295.382846) (xy 339.964008 -295.410802) (xy 339.919546 -295.4319) (xy 339.872275 -295.445592)
			(xy 339.82342 -295.451524) (xy 339.774245 -295.449543) (xy 339.726026 -295.439699) (xy 339.68001 -295.422247)
			(xy 339.637389 -295.39764) (xy 339.599268 -295.366515) (xy 339.566633 -295.329678) (xy 339.54033 -295.288082)
			(xy 339.521039 -295.242806) (xy 339.509262 -295.195022) (xy 339.505302 -295.145968) (xy 339.17636 -295.145968)
			(xy 339.175865 -295.170575) (xy 339.16797 -295.219152) (xy 339.152386 -295.265833) (xy 339.129515 -295.30941)
			(xy 339.09995 -295.348754) (xy 339.064457 -295.382846) (xy 339.023954 -295.410802) (xy 338.979492 -295.4319)
			(xy 338.932221 -295.445592) (xy 338.883366 -295.451524) (xy 338.834191 -295.449543) (xy 338.785972 -295.439699)
			(xy 338.739956 -295.422247) (xy 338.697335 -295.39764) (xy 338.659214 -295.366515) (xy 338.626579 -295.329678)
			(xy 338.600276 -295.288082) (xy 338.580985 -295.242806) (xy 338.569208 -295.195022) (xy 338.565248 -295.145968)
			(xy 338.236306 -295.145968) (xy 338.235811 -295.170575) (xy 338.227916 -295.219152) (xy 338.212332 -295.265833)
			(xy 338.189461 -295.30941) (xy 338.159896 -295.348754) (xy 338.124403 -295.382846) (xy 338.0839 -295.410802)
			(xy 338.039438 -295.4319) (xy 337.992167 -295.445592) (xy 337.943312 -295.451524) (xy 337.894137 -295.449543)
			(xy 337.845918 -295.439699) (xy 337.799902 -295.422247) (xy 337.757281 -295.39764) (xy 337.71916 -295.366515)
			(xy 337.686525 -295.329678) (xy 337.660222 -295.288082) (xy 337.640931 -295.242806) (xy 337.629154 -295.195022)
			(xy 337.625194 -295.145968) (xy 336.356452 -295.145968) (xy 336.355957 -295.170575) (xy 336.348062 -295.219152)
			(xy 336.332478 -295.265833) (xy 336.309607 -295.30941) (xy 336.280042 -295.348754) (xy 336.244549 -295.382846)
			(xy 336.204046 -295.410802) (xy 336.159584 -295.4319) (xy 336.112313 -295.445592) (xy 336.063458 -295.451524)
			(xy 336.014283 -295.449543) (xy 335.966064 -295.439699) (xy 335.920048 -295.422247) (xy 335.877427 -295.39764)
			(xy 335.839306 -295.366515) (xy 335.806671 -295.329678) (xy 335.780368 -295.288082) (xy 335.761077 -295.242806)
			(xy 335.7493 -295.195022) (xy 335.74534 -295.145968) (xy 335.416398 -295.145968) (xy 335.415903 -295.170575)
			(xy 335.408008 -295.219152) (xy 335.392424 -295.265833) (xy 335.369553 -295.30941) (xy 335.339988 -295.348754)
			(xy 335.304495 -295.382846) (xy 335.263992 -295.410802) (xy 335.21953 -295.4319) (xy 335.172259 -295.445592)
			(xy 335.123404 -295.451524) (xy 335.074229 -295.449543) (xy 335.02601 -295.439699) (xy 334.979994 -295.422247)
			(xy 334.937373 -295.39764) (xy 334.899252 -295.366515) (xy 334.866617 -295.329678) (xy 334.840314 -295.288082)
			(xy 334.821023 -295.242806) (xy 334.809246 -295.195022) (xy 334.805286 -295.145968) (xy 334.476344 -295.145968)
			(xy 334.475849 -295.170575) (xy 334.467954 -295.219152) (xy 334.45237 -295.265833) (xy 334.429499 -295.30941)
			(xy 334.399934 -295.348754) (xy 334.364441 -295.382846) (xy 334.323938 -295.410802) (xy 334.279476 -295.4319)
			(xy 334.232205 -295.445592) (xy 334.18335 -295.451524) (xy 334.134175 -295.449543) (xy 334.085956 -295.439699)
			(xy 334.03994 -295.422247) (xy 333.997319 -295.39764) (xy 333.959198 -295.366515) (xy 333.926563 -295.329678)
			(xy 333.90026 -295.288082) (xy 333.880969 -295.242806) (xy 333.869192 -295.195022) (xy 333.865232 -295.145968)
			(xy 333.53629 -295.145968) (xy 333.535795 -295.170575) (xy 333.5279 -295.219152) (xy 333.512316 -295.265833)
			(xy 333.489445 -295.30941) (xy 333.45988 -295.348754) (xy 333.424387 -295.382846) (xy 333.383884 -295.410802)
			(xy 333.339422 -295.4319) (xy 333.292151 -295.445592) (xy 333.243296 -295.451524) (xy 333.194121 -295.449543)
			(xy 333.145902 -295.439699) (xy 333.099886 -295.422247) (xy 333.057265 -295.39764) (xy 333.019144 -295.366515)
			(xy 332.986509 -295.329678) (xy 332.960206 -295.288082) (xy 332.940915 -295.242806) (xy 332.929138 -295.195022)
			(xy 332.925178 -295.145968) (xy 332.59649 -295.145968) (xy 332.595995 -295.170575) (xy 332.5881 -295.219152)
			(xy 332.572516 -295.265833) (xy 332.549645 -295.30941) (xy 332.52008 -295.348754) (xy 332.484587 -295.382846)
			(xy 332.444084 -295.410802) (xy 332.399622 -295.4319) (xy 332.352351 -295.445592) (xy 332.303496 -295.451524)
			(xy 332.254321 -295.449543) (xy 332.206102 -295.439699) (xy 332.160086 -295.422247) (xy 332.117465 -295.39764)
			(xy 332.079344 -295.366515) (xy 332.046709 -295.329678) (xy 332.020406 -295.288082) (xy 332.001115 -295.242806)
			(xy 331.989338 -295.195022) (xy 331.985378 -295.145968) (xy 331.656436 -295.145968) (xy 331.655992 -295.169964)
			(xy 331.64849 -295.217365) (xy 331.633664 -295.263008) (xy 331.611881 -295.305771) (xy 331.583677 -295.344599)
			(xy 331.549745 -295.378537) (xy 331.510922 -295.40675) (xy 331.468164 -295.428541) (xy 331.422523 -295.443376)
			(xy 331.375124 -295.450888) (xy 331.351128 -295.451276) (xy 331.327287 -295.450818) (xy 331.280186 -295.443404)
			(xy 331.234811 -295.428753) (xy 331.192269 -295.407221) (xy 331.153594 -295.379332) (xy 331.119729 -295.345766)
			(xy 331.105256 -295.326816) (xy 331.105002 -295.326562) (xy 331.098294 -295.318265) (xy 331.079751 -295.307749)
			(xy 331.069188 -295.306242) (xy 330.991464 -295.3004) (xy 330.99121 -295.3004) (xy 330.980245 -295.300111)
			(xy 330.959711 -295.307761) (xy 330.951586 -295.315132) (xy 330.789026 -295.477692) (xy 330.783692 -295.484042)
			(xy 330.781406 -295.487344) (xy 330.77912 -295.491408) (xy 330.774726 -295.50166) (xy 330.774324 -295.523936)
			(xy 330.778358 -295.534334) (xy 330.816966 -295.620948) (xy 330.82032 -295.627716) (xy 330.83026 -295.639079)
			(xy 330.836524 -295.6433) (xy 330.843382 -295.647618) (xy 330.85786 -295.651428) (xy 330.865734 -295.65092)
			(xy 330.88072 -295.650666) (xy 330.881228 -295.650666) (xy 330.906484 -295.65119) (xy 330.956306 -295.659508)
			(xy 331.00408 -295.675913) (xy 331.048503 -295.699956) (xy 331.088362 -295.730984) (xy 331.122571 -295.768148)
			(xy 331.150197 -295.810436) (xy 331.170487 -295.856694) (xy 331.182886 -295.905661) (xy 331.187055 -295.955974)
			(xy 331.515224 -295.955974) (xy 331.519184 -295.90692) (xy 331.530961 -295.859136) (xy 331.550252 -295.81386)
			(xy 331.576555 -295.772264) (xy 331.60919 -295.735427) (xy 331.647311 -295.704302) (xy 331.689932 -295.679695)
			(xy 331.735948 -295.662243) (xy 331.784167 -295.652399) (xy 331.833342 -295.650418) (xy 331.882197 -295.65635)
			(xy 331.929468 -295.670042) (xy 331.97393 -295.69114) (xy 332.014433 -295.719096) (xy 332.049926 -295.753188)
			(xy 332.079491 -295.792532) (xy 332.102362 -295.836109) (xy 332.117946 -295.88279) (xy 332.125841 -295.931367)
			(xy 332.126336 -295.955974) (xy 332.455278 -295.955974) (xy 332.459238 -295.90692) (xy 332.471015 -295.859136)
			(xy 332.490306 -295.81386) (xy 332.516609 -295.772264) (xy 332.549244 -295.735427) (xy 332.587365 -295.704302)
			(xy 332.629986 -295.679695) (xy 332.676002 -295.662243) (xy 332.724221 -295.652399) (xy 332.773396 -295.650418)
			(xy 332.822251 -295.65635) (xy 332.869522 -295.670042) (xy 332.913984 -295.69114) (xy 332.954487 -295.719096)
			(xy 332.98998 -295.753188) (xy 333.019545 -295.792532) (xy 333.042416 -295.836109) (xy 333.058 -295.88279)
			(xy 333.065895 -295.931367) (xy 333.06639 -295.955974) (xy 333.395332 -295.955974) (xy 333.399292 -295.90692)
			(xy 333.411069 -295.859136) (xy 333.43036 -295.81386) (xy 333.456663 -295.772264) (xy 333.489298 -295.735427)
			(xy 333.527419 -295.704302) (xy 333.57004 -295.679695) (xy 333.616056 -295.662243) (xy 333.664275 -295.652399)
			(xy 333.71345 -295.650418) (xy 333.762305 -295.65635) (xy 333.809576 -295.670042) (xy 333.854038 -295.69114)
			(xy 333.894541 -295.719096) (xy 333.930034 -295.753188) (xy 333.959599 -295.792532) (xy 333.98247 -295.836109)
			(xy 333.998054 -295.88279) (xy 334.005949 -295.931367) (xy 334.006444 -295.955974) (xy 334.335386 -295.955974)
			(xy 334.339346 -295.90692) (xy 334.351123 -295.859136) (xy 334.370414 -295.81386) (xy 334.396717 -295.772264)
			(xy 334.429352 -295.735427) (xy 334.467473 -295.704302) (xy 334.510094 -295.679695) (xy 334.55611 -295.662243)
			(xy 334.604329 -295.652399) (xy 334.653504 -295.650418) (xy 334.702359 -295.65635) (xy 334.74963 -295.670042)
			(xy 334.794092 -295.69114) (xy 334.834595 -295.719096) (xy 334.870088 -295.753188) (xy 334.899653 -295.792532)
			(xy 334.922524 -295.836109) (xy 334.938108 -295.88279) (xy 334.946003 -295.931367) (xy 334.946498 -295.955974)
			(xy 336.21524 -295.955974) (xy 336.2192 -295.90692) (xy 336.230977 -295.859136) (xy 336.250268 -295.81386)
			(xy 336.276571 -295.772264) (xy 336.309206 -295.735427) (xy 336.347327 -295.704302) (xy 336.389948 -295.679695)
			(xy 336.435964 -295.662243) (xy 336.484183 -295.652399) (xy 336.533358 -295.650418) (xy 336.582213 -295.65635)
			(xy 336.629484 -295.670042) (xy 336.673946 -295.69114) (xy 336.714449 -295.719096) (xy 336.749942 -295.753188)
			(xy 336.779507 -295.792532) (xy 336.802378 -295.836109) (xy 336.817962 -295.88279) (xy 336.825857 -295.931367)
			(xy 336.826352 -295.955974) (xy 338.095348 -295.955974) (xy 338.099308 -295.90692) (xy 338.111085 -295.859136)
			(xy 338.130376 -295.81386) (xy 338.156679 -295.772264) (xy 338.189314 -295.735427) (xy 338.227435 -295.704302)
			(xy 338.270056 -295.679695) (xy 338.316072 -295.662243) (xy 338.364291 -295.652399) (xy 338.413466 -295.650418)
			(xy 338.462321 -295.65635) (xy 338.509592 -295.670042) (xy 338.554054 -295.69114) (xy 338.594557 -295.719096)
			(xy 338.63005 -295.753188) (xy 338.659615 -295.792532) (xy 338.682486 -295.836109) (xy 338.69807 -295.88279)
			(xy 338.705965 -295.931367) (xy 338.70646 -295.955974) (xy 339.035402 -295.955974) (xy 339.039362 -295.90692)
			(xy 339.051139 -295.859136) (xy 339.07043 -295.81386) (xy 339.096733 -295.772264) (xy 339.129368 -295.735427)
			(xy 339.167489 -295.704302) (xy 339.21011 -295.679695) (xy 339.256126 -295.662243) (xy 339.304345 -295.652399)
			(xy 339.35352 -295.650418) (xy 339.402375 -295.65635) (xy 339.449646 -295.670042) (xy 339.494108 -295.69114)
			(xy 339.534611 -295.719096) (xy 339.570104 -295.753188) (xy 339.599669 -295.792532) (xy 339.62254 -295.836109)
			(xy 339.638124 -295.88279) (xy 339.646019 -295.931367) (xy 339.646514 -295.955974) (xy 339.975202 -295.955974)
			(xy 339.979162 -295.90692) (xy 339.990939 -295.859136) (xy 340.01023 -295.81386) (xy 340.036533 -295.772264)
			(xy 340.069168 -295.735427) (xy 340.107289 -295.704302) (xy 340.14991 -295.679695) (xy 340.195926 -295.662243)
			(xy 340.244145 -295.652399) (xy 340.29332 -295.650418) (xy 340.342175 -295.65635) (xy 340.389446 -295.670042)
			(xy 340.433908 -295.69114) (xy 340.474411 -295.719096) (xy 340.509904 -295.753188) (xy 340.539469 -295.792532)
			(xy 340.56234 -295.836109) (xy 340.577924 -295.88279) (xy 340.585819 -295.931367) (xy 340.586314 -295.955974)
			(xy 340.585819 -295.980581) (xy 340.577924 -296.029158) (xy 340.56234 -296.075839) (xy 340.539469 -296.119416)
			(xy 340.509904 -296.15876) (xy 340.474411 -296.192852) (xy 340.433908 -296.220808) (xy 340.389446 -296.241906)
			(xy 340.342175 -296.255598) (xy 340.29332 -296.26153) (xy 340.244145 -296.259549) (xy 340.195926 -296.249705)
			(xy 340.14991 -296.232253) (xy 340.107289 -296.207646) (xy 340.069168 -296.176521) (xy 340.036533 -296.139684)
			(xy 340.01023 -296.098088) (xy 339.990939 -296.052812) (xy 339.979162 -296.005028) (xy 339.975202 -295.955974)
			(xy 339.646514 -295.955974) (xy 339.646019 -295.980581) (xy 339.638124 -296.029158) (xy 339.62254 -296.075839)
			(xy 339.599669 -296.119416) (xy 339.570104 -296.15876) (xy 339.534611 -296.192852) (xy 339.494108 -296.220808)
			(xy 339.449646 -296.241906) (xy 339.402375 -296.255598) (xy 339.35352 -296.26153) (xy 339.304345 -296.259549)
			(xy 339.256126 -296.249705) (xy 339.21011 -296.232253) (xy 339.167489 -296.207646) (xy 339.129368 -296.176521)
			(xy 339.096733 -296.139684) (xy 339.07043 -296.098088) (xy 339.051139 -296.052812) (xy 339.039362 -296.005028)
			(xy 339.035402 -295.955974) (xy 338.70646 -295.955974) (xy 338.705965 -295.980581) (xy 338.69807 -296.029158)
			(xy 338.682486 -296.075839) (xy 338.659615 -296.119416) (xy 338.63005 -296.15876) (xy 338.594557 -296.192852)
			(xy 338.554054 -296.220808) (xy 338.509592 -296.241906) (xy 338.462321 -296.255598) (xy 338.413466 -296.26153)
			(xy 338.364291 -296.259549) (xy 338.316072 -296.249705) (xy 338.270056 -296.232253) (xy 338.227435 -296.207646)
			(xy 338.189314 -296.176521) (xy 338.156679 -296.139684) (xy 338.130376 -296.098088) (xy 338.111085 -296.052812)
			(xy 338.099308 -296.005028) (xy 338.095348 -295.955974) (xy 336.826352 -295.955974) (xy 336.825857 -295.980581)
			(xy 336.817962 -296.029158) (xy 336.802378 -296.075839) (xy 336.779507 -296.119416) (xy 336.749942 -296.15876)
			(xy 336.714449 -296.192852) (xy 336.673946 -296.220808) (xy 336.629484 -296.241906) (xy 336.582213 -296.255598)
			(xy 336.533358 -296.26153) (xy 336.484183 -296.259549) (xy 336.435964 -296.249705) (xy 336.389948 -296.232253)
			(xy 336.347327 -296.207646) (xy 336.309206 -296.176521) (xy 336.276571 -296.139684) (xy 336.250268 -296.098088)
			(xy 336.230977 -296.052812) (xy 336.2192 -296.005028) (xy 336.21524 -295.955974) (xy 334.946498 -295.955974)
			(xy 334.946003 -295.980581) (xy 334.938108 -296.029158) (xy 334.922524 -296.075839) (xy 334.899653 -296.119416)
			(xy 334.870088 -296.15876) (xy 334.834595 -296.192852) (xy 334.794092 -296.220808) (xy 334.74963 -296.241906)
			(xy 334.702359 -296.255598) (xy 334.653504 -296.26153) (xy 334.604329 -296.259549) (xy 334.55611 -296.249705)
			(xy 334.510094 -296.232253) (xy 334.467473 -296.207646) (xy 334.429352 -296.176521) (xy 334.396717 -296.139684)
			(xy 334.370414 -296.098088) (xy 334.351123 -296.052812) (xy 334.339346 -296.005028) (xy 334.335386 -295.955974)
			(xy 334.006444 -295.955974) (xy 334.005949 -295.980581) (xy 333.998054 -296.029158) (xy 333.98247 -296.075839)
			(xy 333.959599 -296.119416) (xy 333.930034 -296.15876) (xy 333.894541 -296.192852) (xy 333.854038 -296.220808)
			(xy 333.809576 -296.241906) (xy 333.762305 -296.255598) (xy 333.71345 -296.26153) (xy 333.664275 -296.259549)
			(xy 333.616056 -296.249705) (xy 333.57004 -296.232253) (xy 333.527419 -296.207646) (xy 333.489298 -296.176521)
			(xy 333.456663 -296.139684) (xy 333.43036 -296.098088) (xy 333.411069 -296.052812) (xy 333.399292 -296.005028)
			(xy 333.395332 -295.955974) (xy 333.06639 -295.955974) (xy 333.065895 -295.980581) (xy 333.058 -296.029158)
			(xy 333.042416 -296.075839) (xy 333.019545 -296.119416) (xy 332.98998 -296.15876) (xy 332.954487 -296.192852)
			(xy 332.913984 -296.220808) (xy 332.869522 -296.241906) (xy 332.822251 -296.255598) (xy 332.773396 -296.26153)
			(xy 332.724221 -296.259549) (xy 332.676002 -296.249705) (xy 332.629986 -296.232253) (xy 332.587365 -296.207646)
			(xy 332.549244 -296.176521) (xy 332.516609 -296.139684) (xy 332.490306 -296.098088) (xy 332.471015 -296.052812)
			(xy 332.459238 -296.005028) (xy 332.455278 -295.955974) (xy 332.126336 -295.955974) (xy 332.125841 -295.980581)
			(xy 332.117946 -296.029158) (xy 332.102362 -296.075839) (xy 332.079491 -296.119416) (xy 332.049926 -296.15876)
			(xy 332.014433 -296.192852) (xy 331.97393 -296.220808) (xy 331.929468 -296.241906) (xy 331.882197 -296.255598)
			(xy 331.833342 -296.26153) (xy 331.784167 -296.259549) (xy 331.735948 -296.249705) (xy 331.689932 -296.232253)
			(xy 331.647311 -296.207646) (xy 331.60919 -296.176521) (xy 331.576555 -296.139684) (xy 331.550252 -296.098088)
			(xy 331.530961 -296.052812) (xy 331.519184 -296.005028) (xy 331.515224 -295.955974) (xy 331.187055 -295.955974)
			(xy 331.187057 -295.956) (xy 331.182886 -296.006339) (xy 331.170487 -296.055306) (xy 331.150197 -296.101564)
			(xy 331.122571 -296.143852) (xy 331.088362 -296.181016) (xy 331.048503 -296.212044) (xy 331.00408 -296.236087)
			(xy 330.956306 -296.252492) (xy 330.906484 -296.26081) (xy 330.881228 -296.261282) (xy 330.880974 -296.261282)
			(xy 330.856998 -296.26081) (xy 330.809635 -296.253309) (xy 330.764028 -296.238494) (xy 330.721298 -296.216731)
			(xy 330.682496 -296.188555) (xy 330.648577 -296.154658) (xy 330.620375 -296.115875) (xy 330.598583 -296.073159)
			(xy 330.583738 -296.027562) (xy 330.576206 -295.980204) (xy 330.575666 -295.956228) (xy 330.575666 -295.95572)
			(xy 330.57592 -295.940734) (xy 330.576428 -295.93286) (xy 330.572618 -295.918382) (xy 330.5683 -295.911524)
			(xy 330.564127 -295.905216) (xy 330.552761 -295.895248) (xy 330.545948 -295.891966) (xy 330.459334 -295.853358)
			(xy 330.448926 -295.849375) (xy 330.426669 -295.849772) (xy 330.416408 -295.85412) (xy 330.412344 -295.856406)
			(xy 330.409042 -295.858692) (xy 330.402692 -295.864026) (xy 327.027772 -299.238946) (xy 339.464724 -299.238946)
			(xy 339.464724 -299.184454) (xy 339.472478 -299.130518) (xy 339.487829 -299.078233) (xy 339.510464 -299.028665)
			(xy 339.539922 -298.982823) (xy 339.575604 -298.941639) (xy 339.616783 -298.905952) (xy 339.662621 -298.876488)
			(xy 339.712186 -298.853847) (xy 339.764469 -298.838489) (xy 339.818404 -298.830728) (xy 339.84565 -298.830238)
			(xy 339.845904 -298.830238) (xy 339.871292 -298.830645) (xy 339.921618 -298.837392) (xy 339.970601 -298.850766)
			(xy 340.017373 -298.87053) (xy 340.039452 -298.88307) (xy 340.048088 -298.88815) (xy 340.067138 -298.891198)
			(xy 340.154768 -298.870624) (xy 340.17077 -298.859702) (xy 340.176104 -298.851828) (xy 340.176104 -298.85132)
			(xy 340.193797 -298.825344) (xy 340.234563 -298.777507) (xy 340.280915 -298.735059) (xy 340.332145 -298.698649)
			(xy 340.387473 -298.668831) (xy 340.446054 -298.64606) (xy 340.506995 -298.630683) (xy 340.569366 -298.622935)
			(xy 340.600792 -298.622466) (xy 340.631522 -298.622964) (xy 340.692533 -298.630371) (xy 340.752208 -298.645078)
			(xy 340.809674 -298.66687) (xy 340.864094 -298.69543) (xy 340.914676 -298.730342) (xy 340.96068 -298.771096)
			(xy 341.001437 -298.817098) (xy 341.036352 -298.867676) (xy 341.064916 -298.922095) (xy 341.086712 -298.97956)
			(xy 341.101423 -299.039233) (xy 341.108834 -299.100244) (xy 341.1093 -299.130974) (xy 341.108709 -299.165939)
			(xy 341.099111 -299.235208) (xy 341.080105 -299.302507) (xy 341.052051 -299.366564) (xy 341.01548 -299.42617)
			(xy 340.99373 -299.453554) (xy 340.988471 -299.46056) (xy 340.982619 -299.477058) (xy 340.9823 -299.485812)
			(xy 340.9823 -299.792136) (xy 340.982648 -299.800884) (xy 340.988495 -299.817376) (xy 340.99373 -299.824394)
			(xy 341.015469 -299.851784) (xy 341.052022 -299.911397) (xy 341.080068 -299.975454) (xy 341.099079 -300.042748)
			(xy 341.108698 -300.112011) (xy 341.1093 -300.146974) (xy 341.108838 -300.177706) (xy 341.101432 -300.238722)
			(xy 341.086725 -300.2984) (xy 341.064932 -300.35587) (xy 341.03637 -300.410295) (xy 341.001456 -300.460879)
			(xy 340.960699 -300.506886) (xy 340.914693 -300.547645) (xy 340.86411 -300.582561) (xy 340.809687 -300.611125)
			(xy 340.752217 -300.63292) (xy 340.692539 -300.647629) (xy 340.631524 -300.655037) (xy 340.600792 -300.655482)
			(xy 340.56828 -300.654953) (xy 340.503784 -300.646678) (xy 340.440868 -300.63025) (xy 340.380559 -300.605939)
			(xy 340.323841 -300.57414) (xy 340.271637 -300.535371) (xy 340.2248 -300.490266) (xy 340.204044 -300.465236)
			(xy 340.197754 -300.458065) (xy 340.181169 -300.44867) (xy 340.171786 -300.446948) (xy 340.140798 -300.442376)
			(xy 340.131308 -300.441455) (xy 340.112779 -300.4459) (xy 340.10473 -300.451012) (xy 340.080718 -300.466961)
			(xy 340.028902 -300.492213) (xy 339.973874 -300.509373) (xy 339.916889 -300.518049) (xy 339.888068 -300.518576)
			(xy 339.860816 -300.518152) (xy 339.806867 -300.510391) (xy 339.754572 -300.495032) (xy 339.704995 -300.472387)
			(xy 339.659144 -300.442917) (xy 339.617954 -300.407223) (xy 339.582263 -300.36603) (xy 339.552798 -300.320177)
			(xy 339.530157 -300.270598) (xy 339.514802 -300.218302) (xy 339.507046 -300.164352) (xy 339.507046 -300.109848)
			(xy 339.514802 -300.055898) (xy 339.530157 -300.003602) (xy 339.552798 -299.954023) (xy 339.582263 -299.90817)
			(xy 339.617954 -299.866977) (xy 339.659144 -299.831283) (xy 339.704995 -299.801813) (xy 339.754572 -299.779168)
			(xy 339.806867 -299.763809) (xy 339.860816 -299.756048) (xy 339.888068 -299.75556) (xy 339.918245 -299.756119)
			(xy 339.977849 -299.765595) (xy 340.035221 -299.784331) (xy 340.088929 -299.811862) (xy 340.11362 -299.82922)
			(xy 340.121498 -299.834459) (xy 340.139736 -299.839419) (xy 340.14918 -299.838872) (xy 340.200742 -299.83303)
			(xy 340.2076 -299.824648) (xy 340.212917 -299.817586) (xy 340.218898 -299.800967) (xy 340.219284 -299.792136)
			(xy 340.219284 -299.611288) (xy 340.218888 -299.602056) (xy 340.212339 -299.584794) (xy 340.200095 -299.570974)
			(xy 340.192106 -299.56633) (xy 340.112604 -299.524166) (xy 340.104349 -299.520193) (xy 340.086198 -299.517807)
			(xy 340.068366 -299.521952) (xy 340.060534 -299.526706) (xy 340.060534 -299.52696) (xy 340.060026 -299.52696)
			(xy 340.036195 -299.54257) (xy 339.984878 -299.567304) (xy 339.930454 -299.584134) (xy 339.874133 -299.592685)
			(xy 339.84565 -299.593254) (xy 339.818404 -299.592672) (xy 339.764469 -299.584911) (xy 339.712186 -299.569553)
			(xy 339.662621 -299.546912) (xy 339.616783 -299.517448) (xy 339.575604 -299.481761) (xy 339.539922 -299.440577)
			(xy 339.510464 -299.394735) (xy 339.487829 -299.345167) (xy 339.472478 -299.292882) (xy 339.464724 -299.238946)
			(xy 327.027772 -299.238946) (xy 326.173338 -300.09338) (xy 326.170631 -300.09623) (xy 326.166036 -300.102607)
			(xy 326.164194 -300.10608) (xy 326.161615 -300.111508) (xy 326.1588 -300.123187) (xy 326.158606 -300.129194)
			(xy 326.158606 -301.745353) (xy 340.488772 -301.745353) (xy 340.488772 -301.681431) (xy 340.496783 -301.618013)
			(xy 340.51268 -301.556099) (xy 340.536212 -301.496666) (xy 340.567006 -301.440651) (xy 340.604579 -301.388936)
			(xy 340.648336 -301.342339) (xy 340.697589 -301.301594) (xy 340.75156 -301.267343) (xy 340.809399 -301.240126)
			(xy 340.870192 -301.220373) (xy 340.932982 -301.208395) (xy 340.996778 -301.204382) (xy 341.060574 -301.208395)
			(xy 341.123364 -301.220373) (xy 341.184157 -301.240126) (xy 341.241996 -301.267343) (xy 341.295967 -301.301594)
			(xy 341.34522 -301.342339) (xy 341.388977 -301.388936) (xy 341.42655 -301.440651) (xy 341.457344 -301.496666)
			(xy 341.480876 -301.556099) (xy 341.496773 -301.618013) (xy 341.504784 -301.681431) (xy 341.505286 -301.713392)
			(xy 341.504784 -301.745353) (xy 341.496773 -301.808771) (xy 341.480876 -301.870685) (xy 341.457344 -301.930118)
			(xy 341.42655 -301.986133) (xy 341.388977 -302.037848) (xy 341.34522 -302.084445) (xy 341.295967 -302.12519)
			(xy 341.241996 -302.159441) (xy 341.184157 -302.186658) (xy 341.123364 -302.206411) (xy 341.060574 -302.218389)
			(xy 340.996778 -302.222403) (xy 340.932982 -302.218389) (xy 340.870192 -302.206411) (xy 340.809399 -302.186658)
			(xy 340.75156 -302.159441) (xy 340.697589 -302.12519) (xy 340.648336 -302.084445) (xy 340.604579 -302.037848)
			(xy 340.567006 -301.986133) (xy 340.536212 -301.930118) (xy 340.51268 -301.870685) (xy 340.496783 -301.808771)
			(xy 340.488772 -301.745353) (xy 326.158606 -301.745353) (xy 326.158606 -301.864522) (xy 326.158179 -301.874591)
			(xy 326.15046 -301.89319) (xy 326.14362 -301.90059) (xy 323.263981 -304.780188) (xy 326.752208 -304.780188)
			(xy 326.756238 -304.637853) (xy 326.768313 -304.495973) (xy 326.788396 -304.355005) (xy 326.816423 -304.215398)
			(xy 326.852303 -304.0776) (xy 326.895921 -303.942053) (xy 326.947138 -303.809191) (xy 327.005789 -303.679439)
			(xy 327.071687 -303.553213) (xy 327.144621 -303.430917) (xy 327.224358 -303.312944) (xy 327.31064 -303.199671)
			(xy 327.403193 -303.09146) (xy 327.50172 -302.988659) (xy 327.605905 -302.891597) (xy 327.715414 -302.800585)
			(xy 327.829897 -302.715913) (xy 327.948987 -302.637855) (xy 328.072302 -302.566659) (xy 328.199448 -302.502553)
			(xy 328.330017 -302.445744) (xy 328.463591 -302.396412) (xy 328.599742 -302.354716) (xy 328.738033 -302.32079)
			(xy 328.878023 -302.294742) (xy 329.019262 -302.276656) (xy 329.161298 -302.266589) (xy 329.303676 -302.264574)
			(xy 329.44594 -302.270617) (xy 329.587634 -302.284699) (xy 329.728304 -302.306775) (xy 329.867501 -302.336775)
			(xy 330.004777 -302.374601) (xy 330.139693 -302.420133) (xy 330.271817 -302.473224) (xy 330.400726 -302.533706)
			(xy 330.526007 -302.601384) (xy 330.647258 -302.676041) (xy 330.764091 -302.757439) (xy 330.876132 -302.845316)
			(xy 330.983022 -302.939391) (xy 331.084419 -303.039363) (xy 331.179997 -303.144911) (xy 331.269451 -303.255697)
			(xy 331.352493 -303.371366) (xy 331.428859 -303.491549) (xy 331.498303 -303.615859) (xy 331.560603 -303.7439)
			(xy 331.615559 -303.875259) (xy 331.662996 -304.009518) (xy 331.70276 -304.146245) (xy 331.734726 -304.285003)
			(xy 331.758791 -304.425347) (xy 331.774877 -304.566828) (xy 331.782932 -304.708992) (xy 331.783436 -304.780188)
			(xy 331.782932 -304.851384) (xy 331.774877 -304.993548) (xy 331.76785 -305.055351) (xy 333.14867 -305.055351)
			(xy 333.14867 -305.000849) (xy 333.156426 -304.946901) (xy 333.171781 -304.894606) (xy 333.194421 -304.845029)
			(xy 333.223887 -304.799178) (xy 333.259578 -304.757988) (xy 333.300767 -304.722295) (xy 333.346617 -304.692828)
			(xy 333.396193 -304.670186) (xy 333.448487 -304.654829) (xy 333.502435 -304.647071) (xy 333.529686 -304.646584)
			(xy 333.539931 -304.646673) (xy 333.560389 -304.647819) (xy 333.57058 -304.64887) (xy 333.579856 -304.649494)
			(xy 333.597831 -304.644786) (xy 333.605632 -304.639726) (xy 333.668116 -304.594768) (xy 333.67853 -304.57902)
			(xy 333.680562 -304.569876) (xy 333.687473 -304.541019) (xy 333.707125 -304.485027) (xy 333.733149 -304.431698)
			(xy 333.765193 -304.381754) (xy 333.783686 -304.358548) (xy 333.788903 -304.35159) (xy 333.794762 -304.335232)
			(xy 333.795116 -304.326544) (xy 333.795116 -304.172112) (xy 333.794731 -304.163429) (xy 333.788888 -304.147071)
			(xy 333.783686 -304.140108) (xy 333.764796 -304.116355) (xy 333.732197 -304.065163) (xy 333.718662 -304.038)
			(xy 333.714459 -304.030064) (xy 333.70158 -304.017567) (xy 333.693516 -304.013616) (xy 333.66583 -304.00117)
			(xy 333.657665 -303.997859) (xy 333.640104 -303.996559) (xy 333.63154 -303.99863) (xy 333.606578 -304.005128)
			(xy 333.555476 -304.012138) (xy 333.529686 -304.0126) (xy 333.502435 -304.012129) (xy 333.448487 -304.004371)
			(xy 333.396193 -303.989014) (xy 333.346617 -303.966372) (xy 333.300767 -303.936905) (xy 333.259578 -303.901212)
			(xy 333.223887 -303.860022) (xy 333.194421 -303.814171) (xy 333.171781 -303.764594) (xy 333.156426 -303.712299)
			(xy 333.14867 -303.658351) (xy 333.14867 -303.603849) (xy 333.156426 -303.549901) (xy 333.171781 -303.497606)
			(xy 333.194421 -303.448029) (xy 333.223887 -303.402178) (xy 333.259578 -303.360988) (xy 333.300767 -303.325295)
			(xy 333.346617 -303.295828) (xy 333.396193 -303.273186) (xy 333.448487 -303.257829) (xy 333.502435 -303.250071)
			(xy 333.529686 -303.249584) (xy 333.556134 -303.250062) (xy 333.608525 -303.257356) (xy 333.659405 -303.27182)
			(xy 333.707797 -303.293177) (xy 333.752775 -303.321016) (xy 333.793473 -303.354804) (xy 333.811626 -303.374044)
			(xy 333.817845 -303.380324) (xy 333.833425 -303.388641) (xy 333.842106 -303.3903) (xy 333.871824 -303.394364)
			(xy 333.880749 -303.395331) (xy 333.898316 -303.391699) (xy 333.906114 -303.387252) (xy 333.936647 -303.368716)
			(xy 334.001821 -303.339487) (xy 334.070443 -303.319665) (xy 334.141164 -303.30964) (xy 334.176878 -303.30902)
			(xy 334.207611 -303.309458) (xy 334.268628 -303.316865) (xy 334.328308 -303.331573) (xy 334.38578 -303.353368)
			(xy 334.440205 -303.381931) (xy 334.49079 -303.416847) (xy 334.536798 -303.457607) (xy 334.577556 -303.503615)
			(xy 334.612472 -303.5542) (xy 334.641035 -303.608626) (xy 334.662829 -303.666098) (xy 334.677536 -303.725778)
			(xy 334.684942 -303.786795) (xy 334.685386 -303.817528) (xy 334.684824 -303.852484) (xy 334.675258 -303.921738)
			(xy 334.656296 -303.989029) (xy 334.628297 -304.053089) (xy 334.591787 -304.112711) (xy 334.57007 -304.140108)
			(xy 334.564825 -304.147048) (xy 334.558984 -304.16342) (xy 334.55864 -304.172112) (xy 334.55864 -304.326544)
			(xy 334.559034 -304.335226) (xy 334.56487 -304.351585) (xy 334.57007 -304.358548) (xy 334.591755 -304.385969)
			(xy 334.628258 -304.445588) (xy 334.656256 -304.509643) (xy 334.675223 -304.576927) (xy 334.684802 -304.646175)
			(xy 334.685386 -304.681128) (xy 334.68497 -304.71186) (xy 334.677558 -304.772877) (xy 334.662845 -304.832555)
			(xy 334.641047 -304.890024) (xy 334.61248 -304.944447) (xy 334.591765 -304.974455) (xy 343.718382 -304.974455)
			(xy 343.718382 -304.910533) (xy 343.726393 -304.847115) (xy 343.74229 -304.785201) (xy 343.765822 -304.725768)
			(xy 343.796616 -304.669753) (xy 343.834189 -304.618038) (xy 343.877946 -304.571441) (xy 343.927199 -304.530696)
			(xy 343.98117 -304.496445) (xy 344.039009 -304.469228) (xy 344.099802 -304.449475) (xy 344.162592 -304.437497)
			(xy 344.226388 -304.433484) (xy 344.290184 -304.437497) (xy 344.352974 -304.449475) (xy 344.413767 -304.469228)
			(xy 344.471606 -304.496445) (xy 344.525577 -304.530696) (xy 344.57483 -304.571441) (xy 344.618587 -304.618038)
			(xy 344.65616 -304.669753) (xy 344.686954 -304.725768) (xy 344.710486 -304.785201) (xy 344.726383 -304.847115)
			(xy 344.734394 -304.910533) (xy 344.734896 -304.942494) (xy 344.734394 -304.974455) (xy 344.726383 -305.037873)
			(xy 344.710486 -305.099787) (xy 344.686954 -305.15922) (xy 344.65616 -305.215235) (xy 344.618587 -305.26695)
			(xy 344.57483 -305.313547) (xy 344.525577 -305.354292) (xy 344.471606 -305.388543) (xy 344.413767 -305.41576)
			(xy 344.352974 -305.435513) (xy 344.290184 -305.447491) (xy 344.226388 -305.451505) (xy 344.162592 -305.447491)
			(xy 344.099802 -305.435513) (xy 344.039009 -305.41576) (xy 343.98117 -305.388543) (xy 343.927199 -305.354292)
			(xy 343.877946 -305.313547) (xy 343.834189 -305.26695) (xy 343.796616 -305.215235) (xy 343.765822 -305.15922)
			(xy 343.74229 -305.099787) (xy 343.726393 -305.037873) (xy 343.718382 -304.974455) (xy 334.591765 -304.974455)
			(xy 334.577561 -304.99503) (xy 334.5368 -305.041035) (xy 334.490791 -305.081792) (xy 334.440205 -305.116706)
			(xy 334.385779 -305.145267) (xy 334.328307 -305.16706) (xy 334.268628 -305.181767) (xy 334.20761 -305.189173)
			(xy 334.176878 -305.189636) (xy 334.145823 -305.189181) (xy 334.084176 -305.181607) (xy 334.023915 -305.166562)
			(xy 333.99476 -305.155854) (xy 333.98587 -305.152552) (xy 333.967582 -305.152552) (xy 333.886302 -305.183286)
			(xy 333.872586 -305.195732) (xy 333.868268 -305.20386) (xy 333.855857 -305.226764) (xy 333.825796 -305.269308)
			(xy 333.790225 -305.307365) (xy 333.749805 -305.340226) (xy 333.705288 -305.367279) (xy 333.657503 -305.388023)
			(xy 333.60734 -305.402069) (xy 333.555732 -305.409157) (xy 333.529686 -305.4096) (xy 333.502435 -305.409129)
			(xy 333.448487 -305.401371) (xy 333.396193 -305.386014) (xy 333.346617 -305.363372) (xy 333.300767 -305.333905)
			(xy 333.259578 -305.298212) (xy 333.223887 -305.257022) (xy 333.194421 -305.211171) (xy 333.171781 -305.161594)
			(xy 333.156426 -305.109299) (xy 333.14867 -305.055351) (xy 331.76785 -305.055351) (xy 331.758791 -305.135029)
			(xy 331.734726 -305.275373) (xy 331.703678 -305.410147) (xy 339.849008 -305.410147) (xy 339.849008 -305.355653)
			(xy 339.856763 -305.301714) (xy 339.872114 -305.249427) (xy 339.89475 -305.199857) (xy 339.924209 -305.154013)
			(xy 339.959893 -305.112827) (xy 340.001074 -305.077138) (xy 340.046915 -305.047673) (xy 340.096482 -305.025031)
			(xy 340.148767 -305.009673) (xy 340.202705 -305.001911) (xy 340.229952 -305.001422) (xy 340.256402 -305.001843)
			(xy 340.308796 -305.009147) (xy 340.359677 -305.023622) (xy 340.40807 -305.044989) (xy 340.453046 -305.072839)
			(xy 340.493741 -305.106637) (xy 340.511892 -305.125882) (xy 340.518099 -305.132176) (xy 340.533688 -305.140486)
			(xy 340.542372 -305.142138) (xy 340.57209 -305.146202) (xy 340.581014 -305.147211) (xy 340.598585 -305.143552)
			(xy 340.60638 -305.13909) (xy 340.636917 -305.120561) (xy 340.70209 -305.091332) (xy 340.770711 -305.071509)
			(xy 340.841431 -305.06148) (xy 340.877144 -305.060858) (xy 340.907875 -305.061314) (xy 340.968887 -305.068727)
			(xy 341.028562 -305.083439) (xy 341.086028 -305.105237) (xy 341.140448 -305.133802) (xy 341.191029 -305.168717)
			(xy 341.237033 -305.209474) (xy 341.277789 -305.255479) (xy 341.312704 -305.30606) (xy 341.341267 -305.360481)
			(xy 341.363063 -305.417948) (xy 341.377775 -305.477623) (xy 341.385186 -305.538635) (xy 341.385652 -305.569366)
			(xy 341.385068 -305.604332) (xy 341.375469 -305.673601) (xy 341.356463 -305.740901) (xy 341.328407 -305.804958)
			(xy 341.291833 -305.864563) (xy 341.270082 -305.891946) (xy 341.264832 -305.898959) (xy 341.258973 -305.915451)
			(xy 341.258652 -305.924204) (xy 341.258652 -306.062634) (xy 342.14054 -306.062634) (xy 342.141042 -306.030119)
			(xy 342.149316 -305.965619) (xy 342.165747 -305.9027) (xy 342.190065 -305.842389) (xy 342.221875 -305.785671)
			(xy 342.260657 -305.733472) (xy 342.305777 -305.686643) (xy 342.356501 -305.64595) (xy 342.411998 -305.612056)
			(xy 342.471364 -305.585514) (xy 342.53363 -305.566758) (xy 342.597779 -305.556095) (xy 342.630252 -305.55438)
			(xy 342.64092 -305.554126) (xy 342.660224 -305.544728) (xy 342.722708 -305.47056) (xy 342.72855 -305.450494)
			(xy 342.72728 -305.44008) (xy 342.72728 -305.439572) (xy 342.725746 -305.427247) (xy 342.724094 -305.402462)
			(xy 342.723978 -305.390042) (xy 342.724464 -305.362791) (xy 342.73222 -305.308843) (xy 342.747575 -305.256548)
			(xy 342.770217 -305.206971) (xy 342.799683 -305.161121) (xy 342.835374 -305.11993) (xy 342.876565 -305.084239)
			(xy 342.922415 -305.054773) (xy 342.971992 -305.032131) (xy 343.024287 -305.016776) (xy 343.078235 -305.00902)
			(xy 343.132737 -305.00902) (xy 343.186685 -305.016776) (xy 343.23898 -305.032131) (xy 343.288557 -305.054773)
			(xy 343.334407 -305.084239) (xy 343.375598 -305.11993) (xy 343.411289 -305.161121) (xy 343.440755 -305.206971)
			(xy 343.463397 -305.256548) (xy 343.478752 -305.308843) (xy 343.486508 -305.362791) (xy 343.486994 -305.390042)
			(xy 343.486505 -305.418099) (xy 343.478267 -305.473605) (xy 343.46199 -305.527306) (xy 343.438024 -305.578044)
			(xy 343.406885 -305.624726) (xy 343.369247 -305.666344) (xy 343.325919 -305.702002) (xy 343.277837 -305.730931)
			(xy 343.226037 -305.752506) (xy 343.198958 -305.759866) (xy 343.188924 -305.763025) (xy 343.172404 -305.776014)
			(xy 343.166954 -305.785012) (xy 343.12606 -305.861212) (xy 343.124536 -305.88204) (xy 343.128092 -305.8922)
			(xy 343.128092 -305.892708) (xy 343.137394 -305.920063) (xy 343.150474 -305.976345) (xy 343.157105 -306.033744)
			(xy 343.157556 -306.062634) (xy 343.157054 -306.094595) (xy 343.149043 -306.158013) (xy 343.133146 -306.219927)
			(xy 343.109614 -306.27936) (xy 343.07882 -306.335375) (xy 343.041247 -306.38709) (xy 342.99749 -306.433687)
			(xy 342.948237 -306.474432) (xy 342.894266 -306.508683) (xy 342.836427 -306.5359) (xy 342.775634 -306.555653)
			(xy 342.712844 -306.567631) (xy 342.649048 -306.571645) (xy 342.585252 -306.567631) (xy 342.522462 -306.555653)
			(xy 342.461669 -306.5359) (xy 342.40383 -306.508683) (xy 342.349859 -306.474432) (xy 342.300606 -306.433687)
			(xy 342.256849 -306.38709) (xy 342.219276 -306.335375) (xy 342.188482 -306.27936) (xy 342.16495 -306.219927)
			(xy 342.149053 -306.158013) (xy 342.141042 -306.094595) (xy 342.14054 -306.062634) (xy 341.258652 -306.062634)
			(xy 341.258652 -306.078128) (xy 341.258993 -306.086877) (xy 341.264844 -306.103369) (xy 341.270082 -306.110386)
			(xy 341.291811 -306.137784) (xy 341.328366 -306.197395) (xy 341.356415 -306.261449) (xy 341.375429 -306.328741)
			(xy 341.385049 -306.398003) (xy 341.385652 -306.432966) (xy 341.385137 -306.466018) (xy 341.376563 -306.531564)
			(xy 341.359569 -306.595447) (xy 341.334441 -306.65659) (xy 341.301603 -306.713961) (xy 341.261608 -306.766594)
			(xy 341.215131 -306.813601) (xy 341.162955 -306.85419) (xy 341.10596 -306.887676) (xy 341.045106 -306.913496)
			(xy 340.98142 -306.931213) (xy 340.948772 -306.936394) (xy 340.93912 -306.937664) (xy 340.921848 -306.94757)
			(xy 340.866476 -307.018944) (xy 340.861142 -307.037994) (xy 340.862158 -307.047646) (xy 340.863117 -307.057588)
			(xy 340.864136 -307.077536) (xy 340.86419 -307.087524) (xy 340.863704 -307.114775) (xy 340.855948 -307.168723)
			(xy 340.840593 -307.221018) (xy 340.817951 -307.270595) (xy 340.788485 -307.316445) (xy 340.752794 -307.357636)
			(xy 340.711603 -307.393327) (xy 340.665753 -307.422793) (xy 340.616176 -307.445435) (xy 340.563881 -307.46079)
			(xy 340.509933 -307.468546) (xy 340.455431 -307.468546) (xy 340.401483 -307.46079) (xy 340.349188 -307.445435)
			(xy 340.299611 -307.422793) (xy 340.253761 -307.393327) (xy 340.21257 -307.357636) (xy 340.176879 -307.316445)
			(xy 340.147413 -307.270595) (xy 340.124771 -307.221018) (xy 340.109416 -307.168723) (xy 340.10166 -307.114775)
			(xy 340.101174 -307.087524) (xy 340.101665 -307.05915) (xy 340.110081 -307.003028) (xy 340.126717 -306.948772)
			(xy 340.151204 -306.897579) (xy 340.183005 -306.850577) (xy 340.221416 -306.808803) (xy 340.26559 -306.773179)
			(xy 340.314553 -306.744491) (xy 340.340696 -306.733448) (xy 340.350094 -306.729638) (xy 340.364064 -306.71643)
			(xy 340.397084 -306.642516) (xy 340.400681 -306.633455) (xy 340.401465 -306.613991) (xy 340.398608 -306.60467)
			(xy 340.389101 -306.577055) (xy 340.375772 -306.520189) (xy 340.369054 -306.462169) (xy 340.368636 -306.432966)
			(xy 340.369241 -306.398001) (xy 340.378835 -306.328732) (xy 340.397837 -306.261433) (xy 340.425887 -306.197376)
			(xy 340.462457 -306.13777) (xy 340.484206 -306.110386) (xy 340.489483 -306.103391) (xy 340.495326 -306.086885)
			(xy 340.495636 -306.078128) (xy 340.495636 -305.924204) (xy 340.495263 -305.915458) (xy 340.489432 -305.898967)
			(xy 340.484206 -305.891946) (xy 340.465259 -305.868195) (xy 340.432531 -305.817005) (xy 340.418928 -305.789838)
			(xy 340.41472 -305.781905) (xy 340.401843 -305.769408) (xy 340.393782 -305.765454) (xy 340.366096 -305.753008)
			(xy 340.357925 -305.749727) (xy 340.340376 -305.748441) (xy 340.331806 -305.750468) (xy 340.306845 -305.756971)
			(xy 340.255742 -305.763978) (xy 340.229952 -305.764438) (xy 340.202705 -305.763889) (xy 340.148767 -305.756127)
			(xy 340.096482 -305.740769) (xy 340.046915 -305.718127) (xy 340.001074 -305.688662) (xy 339.959893 -305.652973)
			(xy 339.924209 -305.611787) (xy 339.89475 -305.565943) (xy 339.872114 -305.516373) (xy 339.856763 -305.464086)
			(xy 339.849008 -305.410147) (xy 331.703678 -305.410147) (xy 331.70276 -305.414131) (xy 331.662996 -305.550858)
			(xy 331.615559 -305.685117) (xy 331.560603 -305.816476) (xy 331.498303 -305.944517) (xy 331.428859 -306.068827)
			(xy 331.352493 -306.18901) (xy 331.269451 -306.304679) (xy 331.179997 -306.415465) (xy 331.084419 -306.521013)
			(xy 330.983022 -306.620985) (xy 330.876132 -306.71506) (xy 330.764091 -306.802937) (xy 330.647258 -306.884335)
			(xy 330.526007 -306.958992) (xy 330.400726 -307.02667) (xy 330.271817 -307.087152) (xy 330.139693 -307.140243)
			(xy 330.004777 -307.185775) (xy 329.867501 -307.223601) (xy 329.728304 -307.253601) (xy 329.587634 -307.275677)
			(xy 329.44594 -307.289759) (xy 329.303676 -307.295802) (xy 329.161298 -307.293787) (xy 329.019262 -307.28372)
			(xy 328.878023 -307.265634) (xy 328.738033 -307.239586) (xy 328.599742 -307.20566) (xy 328.463591 -307.163964)
			(xy 328.330017 -307.114632) (xy 328.199448 -307.057823) (xy 328.072302 -306.993717) (xy 327.948987 -306.922521)
			(xy 327.829897 -306.844463) (xy 327.715414 -306.759791) (xy 327.605905 -306.668779) (xy 327.50172 -306.571717)
			(xy 327.403193 -306.468916) (xy 327.31064 -306.360705) (xy 327.224358 -306.247432) (xy 327.144621 -306.129459)
			(xy 327.071687 -306.007163) (xy 327.005789 -305.880937) (xy 326.947138 -305.751185) (xy 326.895921 -305.618323)
			(xy 326.852303 -305.482776) (xy 326.816423 -305.344978) (xy 326.788396 -305.205371) (xy 326.768313 -305.064403)
			(xy 326.756238 -304.922523) (xy 326.752208 -304.780188) (xy 323.263981 -304.780188) (xy 317.867463 -310.176629)
			(xy 332.667604 -310.176629) (xy 332.667604 -310.112707) (xy 332.675615 -310.049289) (xy 332.691512 -309.987375)
			(xy 332.715044 -309.927942) (xy 332.745838 -309.871927) (xy 332.783411 -309.820212) (xy 332.827168 -309.773615)
			(xy 332.876421 -309.73287) (xy 332.930392 -309.698619) (xy 332.988231 -309.671402) (xy 333.049024 -309.651649)
			(xy 333.111814 -309.639671) (xy 333.17561 -309.635658) (xy 333.239406 -309.639671) (xy 333.302196 -309.651649)
			(xy 333.362989 -309.671402) (xy 333.420828 -309.698619) (xy 333.474799 -309.73287) (xy 333.506735 -309.759289)
			(xy 334.460162 -309.759289) (xy 334.465371 -309.696417) (xy 334.478316 -309.634671) (xy 334.4988 -309.575002)
			(xy 334.526507 -309.518324) (xy 334.561012 -309.465509) (xy 334.601786 -309.417368) (xy 334.6482 -309.374639)
			(xy 334.699544 -309.337981) (xy 334.755028 -309.307954) (xy 334.8138 -309.285021) (xy 334.874957 -309.269535)
			(xy 334.93756 -309.261732) (xy 334.969104 -309.261256) (xy 335.004096 -309.261834) (xy 335.073421 -309.271427)
			(xy 335.140775 -309.290432) (xy 335.173066 -309.303928) (xy 335.184935 -309.308312) (xy 335.210115 -309.30619)
			(xy 335.221072 -309.299864) (xy 335.292192 -309.253382) (xy 335.302419 -309.245873) (xy 335.314551 -309.223628)
			(xy 335.315306 -309.210964) (xy 335.315306 -309.21071) (xy 335.315747 -309.179978) (xy 335.323155 -309.118961)
			(xy 335.337864 -309.059282) (xy 335.359659 -309.001811) (xy 335.388223 -308.947386) (xy 335.423139 -308.896802)
			(xy 335.463897 -308.850795) (xy 335.509905 -308.810036) (xy 335.56049 -308.775121) (xy 335.614915 -308.746557)
			(xy 335.672386 -308.724762) (xy 335.732065 -308.710054) (xy 335.793082 -308.702647) (xy 335.823814 -308.702202)
			(xy 335.824068 -308.702202) (xy 335.854441 -308.702636) (xy 335.914755 -308.709857) (xy 335.973777 -308.724223)
			(xy 336.002376 -308.73446) (xy 336.010708 -308.73723) (xy 336.028253 -308.737483) (xy 336.036666 -308.734968)
			(xy 336.06486 -308.725316) (xy 336.073047 -308.722122) (xy 336.08682 -308.71123) (xy 336.091784 -308.70398)
			(xy 336.10951 -308.676098) (xy 336.151114 -308.624769) (xy 336.199019 -308.579265) (xy 336.252418 -308.540353)
			(xy 336.310409 -308.50869) (xy 336.372014 -308.484809) (xy 336.436195 -308.469114) (xy 336.468974 -308.464966)
			(xy 336.477527 -308.463631) (xy 336.493109 -308.45612) (xy 336.499454 -308.450234) (xy 336.520536 -308.428898)
			(xy 336.526255 -308.422634) (xy 336.53352 -308.407317) (xy 336.53476 -308.398926) (xy 336.53864 -308.369149)
			(xy 336.554497 -308.311235) (xy 336.579231 -308.256519) (xy 336.612231 -308.206354) (xy 336.632042 -308.183788)
			(xy 336.638251 -308.176383) (xy 336.645087 -308.158322) (xy 336.644768 -308.139013) (xy 336.64144 -308.12994)
			(xy 336.606388 -308.045104) (xy 336.602255 -308.036402) (xy 336.588828 -308.022614) (xy 336.571277 -308.014719)
			(xy 336.561684 -308.013862) (xy 336.529231 -308.011815) (xy 336.465183 -308.00058) (xy 336.40309 -307.981274)
			(xy 336.343963 -307.954212) (xy 336.288767 -307.919836) (xy 336.238403 -307.878705) (xy 336.193691 -307.831491)
			(xy 336.155361 -307.778963) (xy 336.124038 -307.721979) (xy 336.100233 -307.661468) (xy 336.091784 -307.630068)
			(xy 336.088668 -307.619885) (xy 336.075625 -307.60309) (xy 336.056882 -307.593044) (xy 336.046318 -307.591714)
			(xy 336.014763 -307.588842) (xy 335.952666 -307.576231) (xy 335.892618 -307.556) (xy 335.835549 -307.528464)
			(xy 335.782345 -307.494049) (xy 335.73383 -307.453288) (xy 335.690757 -307.406815) (xy 335.653794 -307.355349)
			(xy 335.623512 -307.299689) (xy 335.600383 -307.240696) (xy 335.584764 -307.179287) (xy 335.576898 -307.116412)
			(xy 335.576418 -307.08473) (xy 335.576866 -307.053998) (xy 335.584272 -306.99298) (xy 335.598979 -306.933301)
			(xy 335.620772 -306.87583) (xy 335.649335 -306.821404) (xy 335.68425 -306.770819) (xy 335.725009 -306.724812)
			(xy 335.771016 -306.684053) (xy 335.821601 -306.649137) (xy 335.876026 -306.620574) (xy 335.933497 -306.59878)
			(xy 335.993176 -306.584072) (xy 336.054194 -306.576666) (xy 336.084926 -306.576222) (xy 336.115533 -306.57669)
			(xy 336.176303 -306.584063) (xy 336.235748 -306.598677) (xy 336.29301 -306.620319) (xy 336.34726 -306.648677)
			(xy 336.397715 -306.683341) (xy 336.443645 -306.723809) (xy 336.484387 -306.769497) (xy 336.519351 -306.819745)
			(xy 336.548031 -306.873825) (xy 336.570014 -306.930957) (xy 336.57794 -306.960524) (xy 336.581042 -306.970713)
			(xy 336.59409 -306.98751) (xy 336.61284 -306.997552) (xy 336.623406 -306.998878) (xy 336.644318 -307.000687)
			(xy 336.685773 -307.007296) (xy 336.70621 -307.012086) (xy 336.709004 -307.012594) (xy 336.719775 -307.014056)
			(xy 336.740851 -307.008829) (xy 336.757897 -306.995376) (xy 336.76788 -306.976092) (xy 336.769024 -306.954407)
			(xy 336.761124 -306.93418) (xy 336.753708 -306.926234) (xy 336.749898 -306.922932) (xy 336.724514 -306.902221)
			(xy 336.678772 -306.855319) (xy 336.639434 -306.802929) (xy 336.607153 -306.74592) (xy 336.582464 -306.685235)
			(xy 336.565776 -306.621882) (xy 336.557365 -306.556909) (xy 336.556858 -306.524152) (xy 336.55731 -306.493421)
			(xy 336.564724 -306.432408) (xy 336.579437 -306.372734) (xy 336.601234 -306.315268) (xy 336.6298 -306.260847)
			(xy 336.664715 -306.210267) (xy 336.705473 -306.164263) (xy 336.751478 -306.123507) (xy 336.802059 -306.088592)
			(xy 336.85648 -306.060029) (xy 336.913947 -306.038232) (xy 336.973622 -306.023521) (xy 337.034635 -306.01611)
			(xy 337.065366 -306.015644) (xy 337.096619 -306.016114) (xy 337.158653 -306.023783) (xy 337.219279 -306.038996)
			(xy 337.277584 -306.061525) (xy 337.332688 -306.09103) (xy 337.383761 -306.127066) (xy 337.430032 -306.16909)
			(xy 337.470804 -306.216468) (xy 337.48853 -306.242212) (xy 337.493803 -306.249464) (xy 337.508303 -306.259994)
			(xy 337.525543 -306.264886) (xy 337.534504 -306.264564) (xy 337.636612 -306.257198) (xy 337.659218 -306.241704)
			(xy 337.66506 -306.229258) (xy 337.679112 -306.200524) (xy 337.713341 -306.146488) (xy 337.754078 -306.097172)
			(xy 337.800679 -306.053356) (xy 337.852408 -306.015732) (xy 337.908448 -305.984893) (xy 337.967914 -305.961328)
			(xy 338.029866 -305.945409) (xy 338.093326 -305.937386) (xy 338.125308 -305.936904) (xy 338.156041 -305.93733)
			(xy 338.217058 -305.94474) (xy 338.276737 -305.959451) (xy 338.334208 -305.981248) (xy 338.388632 -306.009813)
			(xy 338.439217 -306.04473) (xy 338.485224 -306.08549) (xy 338.525982 -306.131499) (xy 338.560897 -306.182085)
			(xy 338.589461 -306.23651) (xy 338.611255 -306.293982) (xy 338.625964 -306.353662) (xy 338.633371 -306.414679)
			(xy 338.633816 -306.445412) (xy 338.63329 -306.47859) (xy 338.624658 -306.544382) (xy 338.607541 -306.608492)
			(xy 338.582231 -306.669831) (xy 338.549158 -306.727357) (xy 338.508884 -306.780093) (xy 338.462092 -306.827142)
			(xy 338.409578 -306.867705) (xy 338.352234 -306.901093) (xy 338.291035 -306.926739) (xy 338.22702 -306.944207)
			(xy 338.161276 -306.9532) (xy 338.128102 -306.95392) (xy 338.115629 -306.954663) (xy 338.093662 -306.966511)
			(xy 338.086192 -306.976526) (xy 338.032344 -307.057044) (xy 338.029804 -307.08219) (xy 338.03463 -307.093874)
			(xy 338.045381 -307.121376) (xy 338.061219 -307.178263) (xy 338.070372 -307.236601) (xy 338.071968 -307.266086)
			(xy 338.072743 -307.275619) (xy 338.080451 -307.293108) (xy 338.086954 -307.300122) (xy 338.12353 -307.336444)
			(xy 338.125308 -307.336444) (xy 338.152555 -307.337027) (xy 338.206495 -307.344783) (xy 338.258783 -307.360137)
			(xy 338.308353 -307.382776) (xy 338.354196 -307.412239) (xy 338.39538 -307.447926) (xy 338.431066 -307.48911)
			(xy 338.460528 -307.534955) (xy 338.464274 -307.543157) (xy 343.824808 -307.543157) (xy 343.824808 -307.479235)
			(xy 343.832819 -307.415817) (xy 343.848716 -307.353903) (xy 343.872248 -307.29447) (xy 343.903042 -307.238455)
			(xy 343.940615 -307.18674) (xy 343.984372 -307.140143) (xy 344.033625 -307.099398) (xy 344.087596 -307.065147)
			(xy 344.145435 -307.03793) (xy 344.206228 -307.018177) (xy 344.269018 -307.006199) (xy 344.332814 -307.002186)
			(xy 344.39661 -307.006199) (xy 344.4594 -307.018177) (xy 344.520193 -307.03793) (xy 344.578032 -307.065147)
			(xy 344.632003 -307.099398) (xy 344.681256 -307.140143) (xy 344.725013 -307.18674) (xy 344.762586 -307.238455)
			(xy 344.79338 -307.29447) (xy 344.816912 -307.353903) (xy 344.832809 -307.415817) (xy 344.84082 -307.479235)
			(xy 344.841322 -307.511196) (xy 344.84082 -307.543157) (xy 344.832809 -307.606575) (xy 344.816912 -307.668489)
			(xy 344.79338 -307.727922) (xy 344.762586 -307.783937) (xy 344.725013 -307.835652) (xy 344.681256 -307.882249)
			(xy 344.632003 -307.922994) (xy 344.578032 -307.957245) (xy 344.520193 -307.984462) (xy 344.4594 -308.004215)
			(xy 344.39661 -308.016193) (xy 344.332814 -308.020207) (xy 344.269018 -308.016193) (xy 344.206228 -308.004215)
			(xy 344.145435 -307.984462) (xy 344.087596 -307.957245) (xy 344.033625 -307.922994) (xy 343.984372 -307.882249)
			(xy 343.940615 -307.835652) (xy 343.903042 -307.783937) (xy 343.872248 -307.727922) (xy 343.848716 -307.668489)
			(xy 343.832819 -307.606575) (xy 343.824808 -307.543157) (xy 338.464274 -307.543157) (xy 338.483166 -307.584525)
			(xy 338.498519 -307.636812) (xy 338.506274 -307.690753) (xy 338.506274 -307.745247) (xy 338.498519 -307.799188)
			(xy 338.483166 -307.851475) (xy 338.460528 -307.901045) (xy 338.431066 -307.94689) (xy 338.39538 -307.988074)
			(xy 338.354196 -308.023761) (xy 338.308353 -308.053224) (xy 338.258783 -308.075863) (xy 338.206495 -308.091217)
			(xy 338.152555 -308.098973) (xy 338.125308 -308.09946) (xy 338.098454 -308.098958) (xy 338.045277 -308.091426)
			(xy 337.993681 -308.076512) (xy 337.944688 -308.054508) (xy 337.899264 -308.025851) (xy 337.858309 -307.991106)
			(xy 337.822631 -307.950961) (xy 337.792936 -307.906209) (xy 337.769811 -307.857734) (xy 337.761326 -307.832252)
			(xy 337.758161 -307.823418) (xy 337.746405 -307.808808) (xy 337.738466 -307.803804) (xy 337.711796 -307.788056)
			(xy 337.703331 -307.783555) (xy 337.684409 -307.780554) (xy 337.674966 -307.782214) (xy 337.647584 -307.788018)
			(xy 337.591956 -307.794251) (xy 337.563968 -307.79466) (xy 337.532396 -307.794194) (xy 337.469736 -307.786382)
			(xy 337.408527 -307.77087) (xy 337.34971 -307.747897) (xy 337.294191 -307.717816) (xy 337.242825 -307.681091)
			(xy 337.21929 -307.66004) (xy 337.209892 -307.651404) (xy 337.186016 -307.645054) (xy 337.079844 -307.66893)
			(xy 337.060794 -307.684932) (xy 337.056222 -307.696616) (xy 337.044755 -307.723791) (xy 337.016464 -307.775549)
			(xy 336.982372 -307.823684) (xy 336.942937 -307.867549) (xy 336.921094 -307.88737) (xy 336.914142 -307.89404)
			(xy 336.905375 -307.911176) (xy 336.903558 -307.930338) (xy 336.905854 -307.939694) (xy 336.931762 -308.027832)
			(xy 336.934847 -308.036921) (xy 336.946544 -308.052116) (xy 336.963006 -308.06195) (xy 336.972402 -308.0639)
			(xy 336.972656 -308.0639) (xy 336.999301 -308.068469) (xy 337.051011 -308.084241) (xy 337.099977 -308.107155)
			(xy 337.145217 -308.136752) (xy 337.185826 -308.17244) (xy 337.22099 -308.213504) (xy 337.250004 -308.25912)
			(xy 337.272288 -308.308376) (xy 337.287395 -308.360284) (xy 337.295022 -308.413805) (xy 337.29549 -308.440836)
			(xy 337.295021 -308.468432) (xy 337.28705 -308.523047) (xy 337.271295 -308.575943) (xy 337.248085 -308.626018)
			(xy 337.217902 -308.672227) (xy 337.181378 -308.713606) (xy 337.139274 -308.749292) (xy 337.092468 -308.77854)
			(xy 337.067398 -308.790086) (xy 337.059656 -308.793824) (xy 337.047054 -308.805499) (xy 337.04276 -308.812946)
			(xy 337.02879 -308.839362) (xy 337.025092 -308.847197) (xy 337.02262 -308.864332) (xy 337.023964 -308.87289)
			(xy 337.028378 -308.897031) (xy 337.033082 -308.945886) (xy 337.033362 -308.970426) (xy 337.032987 -309.00116)
			(xy 337.025574 -309.062181) (xy 337.01086 -309.121863) (xy 336.98906 -309.179336) (xy 336.96049 -309.233762)
			(xy 336.925568 -309.284348) (xy 336.908895 -309.303166) (xy 341.391494 -309.303166) (xy 341.392058 -309.26821)
			(xy 341.401624 -309.198956) (xy 341.420585 -309.131665) (xy 341.448584 -309.067605) (xy 341.485093 -309.007984)
			(xy 341.50681 -308.980586) (xy 341.512055 -308.973646) (xy 341.517896 -308.957274) (xy 341.51824 -308.948582)
			(xy 341.51824 -308.79415) (xy 341.517853 -308.785467) (xy 341.512013 -308.769108) (xy 341.50681 -308.762146)
			(xy 341.48512 -308.73473) (xy 341.448618 -308.675109) (xy 341.420621 -308.611053) (xy 341.401655 -308.543768)
			(xy 341.392077 -308.47452) (xy 341.391494 -308.439566) (xy 341.391924 -308.408834) (xy 341.399336 -308.347819)
			(xy 341.414049 -308.288142) (xy 341.435847 -308.230674) (xy 341.464413 -308.176252) (xy 341.499331 -308.12567)
			(xy 341.54009 -308.079665) (xy 341.586098 -308.038909) (xy 341.636683 -308.003995) (xy 341.691107 -307.975432)
			(xy 341.748577 -307.953638) (xy 341.808255 -307.93893) (xy 341.86927 -307.931521) (xy 341.900002 -307.931058)
			(xy 341.931057 -307.931519) (xy 341.992704 -307.939091) (xy 342.052965 -307.954134) (xy 342.08212 -307.96484)
			(xy 342.09101 -307.968142) (xy 342.109298 -307.968142) (xy 342.190578 -307.937408) (xy 342.204294 -307.924962)
			(xy 342.208612 -307.916834) (xy 342.221035 -307.893937) (xy 342.251095 -307.851394) (xy 342.286665 -307.813337)
			(xy 342.327083 -307.780476) (xy 342.371598 -307.753421) (xy 342.41938 -307.732677) (xy 342.469542 -307.718629)
			(xy 342.521148 -307.711538) (xy 342.547194 -307.711094) (xy 342.574447 -307.711553) (xy 342.628399 -307.719309)
			(xy 342.680698 -307.734665) (xy 342.730279 -307.757307) (xy 342.776133 -307.786775) (xy 342.817327 -307.822469)
			(xy 342.853021 -307.863662) (xy 342.88249 -307.909516) (xy 342.905133 -307.959096) (xy 342.920489 -308.011395)
			(xy 342.928247 -308.065347) (xy 342.928247 -308.119853) (xy 342.920489 -308.173805) (xy 342.905133 -308.226104)
			(xy 342.88249 -308.275684) (xy 342.853021 -308.321538) (xy 342.817327 -308.362731) (xy 342.776133 -308.398425)
			(xy 342.730279 -308.427893) (xy 342.680698 -308.450535) (xy 342.628399 -308.465891) (xy 342.574447 -308.473647)
			(xy 342.547194 -308.47411) (xy 342.536949 -308.474015) (xy 342.516491 -308.472873) (xy 342.5063 -308.471824)
			(xy 342.497024 -308.471242) (xy 342.479052 -308.475921) (xy 342.471248 -308.480968) (xy 342.408764 -308.525926)
			(xy 342.39835 -308.541674) (xy 342.396318 -308.550818) (xy 342.389409 -308.579675) (xy 342.369756 -308.635667)
			(xy 342.343732 -308.688996) (xy 342.311687 -308.738941) (xy 342.293194 -308.762146) (xy 342.287978 -308.769105)
			(xy 342.282119 -308.785462) (xy 342.281764 -308.79415) (xy 342.281764 -308.948582) (xy 342.282156 -308.957264)
			(xy 342.287995 -308.973622) (xy 342.293194 -308.980586) (xy 342.312082 -309.004341) (xy 342.344682 -309.055532)
			(xy 342.358218 -309.082694) (xy 342.362401 -309.090642) (xy 342.375295 -309.103131) (xy 342.383364 -309.107078)
			(xy 342.41105 -309.119524) (xy 342.419218 -309.122825) (xy 342.436776 -309.124131) (xy 342.44534 -309.122064)
			(xy 342.470303 -309.11557) (xy 342.521404 -309.108557) (xy 342.547194 -309.108094) (xy 342.574447 -309.108553)
			(xy 342.628399 -309.116309) (xy 342.680698 -309.131665) (xy 342.730279 -309.154307) (xy 342.776133 -309.183775)
			(xy 342.817327 -309.219469) (xy 342.853021 -309.260662) (xy 342.88249 -309.306516) (xy 342.905133 -309.356096)
			(xy 342.920489 -309.408395) (xy 342.928247 -309.462347) (xy 342.928247 -309.516853) (xy 342.920489 -309.570805)
			(xy 342.905133 -309.623104) (xy 342.88249 -309.672684) (xy 342.853021 -309.718538) (xy 342.817327 -309.759731)
			(xy 342.776133 -309.795425) (xy 342.730279 -309.824893) (xy 342.680698 -309.847535) (xy 342.628399 -309.862891)
			(xy 342.574447 -309.870647) (xy 342.547194 -309.87111) (xy 342.520745 -309.870648) (xy 342.468354 -309.863351)
			(xy 342.417474 -309.848884) (xy 342.369081 -309.827524) (xy 342.324104 -309.799682) (xy 342.283406 -309.765891)
			(xy 342.265254 -309.74665) (xy 342.259042 -309.740362) (xy 342.243456 -309.73205) (xy 342.234774 -309.730394)
			(xy 342.205056 -309.72633) (xy 342.196131 -309.725354) (xy 342.178563 -309.728992) (xy 342.170766 -309.733442)
			(xy 342.140214 -309.751945) (xy 342.075047 -309.781182) (xy 342.006431 -309.801013) (xy 341.935714 -309.811048)
			(xy 341.900002 -309.811674) (xy 341.869269 -309.81126) (xy 341.80825 -309.803851) (xy 341.74857 -309.789141)
			(xy 341.691097 -309.767344) (xy 341.636672 -309.738778) (xy 341.586086 -309.70386) (xy 341.540079 -309.663098)
			(xy 341.499321 -309.617088) (xy 341.464406 -309.566501) (xy 341.435843 -309.512073) (xy 341.41405 -309.4546)
			(xy 341.399343 -309.394918) (xy 341.391938 -309.333899) (xy 341.391494 -309.303166) (xy 336.908895 -309.303166)
			(xy 336.884804 -309.330355) (xy 336.838791 -309.371113) (xy 336.7882 -309.406027) (xy 336.73377 -309.434589)
			(xy 336.676294 -309.456382) (xy 336.61661 -309.471087) (xy 336.555588 -309.478491) (xy 336.524854 -309.478934)
			(xy 336.5246 -309.478934) (xy 336.494227 -309.478514) (xy 336.433912 -309.471288) (xy 336.37489 -309.456916)
			(xy 336.346292 -309.446676) (xy 336.33795 -309.443942) (xy 336.320415 -309.443668) (xy 336.312002 -309.446168)
			(xy 336.283808 -309.45582) (xy 336.275611 -309.458992) (xy 336.261843 -309.469899) (xy 336.256884 -309.477156)
			(xy 336.239492 -309.504503) (xy 336.198801 -309.554947) (xy 336.152028 -309.599811) (xy 336.099932 -309.638364)
			(xy 336.043358 -309.669983) (xy 335.983224 -309.694155) (xy 335.920505 -309.710487) (xy 335.856219 -309.718714)
			(xy 335.823814 -309.719218) (xy 335.788822 -309.718636) (xy 335.719498 -309.709045) (xy 335.652143 -309.690041)
			(xy 335.619852 -309.676546) (xy 335.607981 -309.672166) (xy 335.582801 -309.674282) (xy 335.571846 -309.68061)
			(xy 335.500726 -309.727092) (xy 335.490469 -309.734568) (xy 335.478352 -309.756838) (xy 335.477612 -309.76951)
			(xy 335.477612 -309.769764) (xy 335.47717 -309.801308) (xy 335.469371 -309.863911) (xy 335.453888 -309.92507)
			(xy 335.430959 -309.983843) (xy 335.400936 -310.039329) (xy 335.364281 -310.090675) (xy 335.321555 -310.137092)
			(xy 335.273417 -310.177868) (xy 335.220604 -310.212377) (xy 335.163928 -310.240088) (xy 335.104259 -310.260575)
			(xy 335.042515 -310.273525) (xy 334.979643 -310.278737) (xy 334.916609 -310.276133) (xy 334.854382 -310.265752)
			(xy 334.793916 -310.247753) (xy 334.736141 -310.222413) (xy 334.681945 -310.190121) (xy 334.632158 -310.151374)
			(xy 334.587547 -310.106766) (xy 334.548797 -310.056982) (xy 334.516502 -310.002787) (xy 334.491158 -309.945014)
			(xy 334.473156 -309.884549) (xy 334.46277 -309.822322) (xy 334.460162 -309.759289) (xy 333.506735 -309.759289)
			(xy 333.524052 -309.773615) (xy 333.567809 -309.820212) (xy 333.605382 -309.871927) (xy 333.636176 -309.927942)
			(xy 333.659708 -309.987375) (xy 333.675605 -310.049289) (xy 333.683616 -310.112707) (xy 333.684118 -310.144668)
			(xy 333.683616 -310.176629) (xy 333.675605 -310.240047) (xy 333.659708 -310.301961) (xy 333.636176 -310.361394)
			(xy 333.605382 -310.417409) (xy 333.597591 -310.428132) (xy 337.30514 -310.428132) (xy 337.309211 -310.37251)
			(xy 337.321337 -310.318073) (xy 337.34126 -310.265982) (xy 337.368556 -310.217347) (xy 337.402642 -310.173204)
			(xy 337.442791 -310.134495) (xy 337.488149 -310.102044) (xy 337.537749 -310.076543) (xy 337.590533 -310.058536)
			(xy 337.645376 -310.048406) (xy 337.70111 -310.046369) (xy 337.756547 -310.052469) (xy 337.810504 -310.066575)
			(xy 337.861833 -310.088387) (xy 337.909439 -310.117441) (xy 337.952307 -310.153116) (xy 337.989524 -310.194653)
			(xy 338.020297 -310.241166) (xy 338.043969 -310.291663) (xy 338.060037 -310.34507) (xy 338.068157 -310.400246)
			(xy 338.068665 -310.4281) (xy 338.321221 -310.4281) (xy 338.325235 -310.364311) (xy 338.33721 -310.301529)
			(xy 338.35696 -310.240742) (xy 338.384172 -310.18291) (xy 338.418418 -310.128944) (xy 338.459157 -310.079695)
			(xy 338.505747 -310.03594) (xy 338.557453 -309.99837) (xy 338.61346 -309.967575) (xy 338.672885 -309.944043)
			(xy 338.734791 -309.928144) (xy 338.798201 -309.920128) (xy 338.830158 -309.919624) (xy 338.860799 -309.920055)
			(xy 338.921636 -309.92743) (xy 338.981144 -309.942067) (xy 339.038462 -309.963751) (xy 339.092756 -309.99217)
			(xy 339.143239 -310.026911) (xy 339.18918 -310.067469) (xy 339.209888 -310.090058) (xy 339.210142 -310.090312)
			(xy 339.216542 -310.096765) (xy 339.232669 -310.105109) (xy 339.241638 -310.106568) (xy 339.318346 -310.115458)
			(xy 339.33638 -310.110886) (xy 339.344 -310.105552) (xy 339.368184 -310.089318) (xy 339.420443 -310.063598)
			(xy 339.476002 -310.046113) (xy 339.533571 -310.037267) (xy 339.562694 -310.036718) (xy 339.589949 -310.037128)
			(xy 339.643904 -310.044885) (xy 339.696207 -310.060242) (xy 339.745791 -310.082886) (xy 339.791648 -310.112355)
			(xy 339.832844 -310.148052) (xy 339.868541 -310.189247) (xy 339.898012 -310.235104) (xy 339.920656 -310.284688)
			(xy 339.936013 -310.33699) (xy 339.943771 -310.390945) (xy 339.943771 -310.445455) (xy 339.936013 -310.49941)
			(xy 339.920656 -310.551712) (xy 339.898012 -310.601296) (xy 339.868541 -310.647153) (xy 339.832844 -310.688348)
			(xy 339.791648 -310.724045) (xy 339.745791 -310.753514) (xy 339.696207 -310.776158) (xy 339.643904 -310.791515)
			(xy 339.589949 -310.799272) (xy 339.562694 -310.799734) (xy 339.534878 -310.799218) (xy 339.479835 -310.791143)
			(xy 339.426546 -310.775167) (xy 339.376141 -310.751626) (xy 339.352636 -310.736742) (xy 339.352382 -310.736488)
			(xy 339.344452 -310.731821) (xy 339.326483 -310.727922) (xy 339.31733 -310.728868) (xy 339.241384 -310.739536)
			(xy 339.225128 -310.74868) (xy 339.219032 -310.756046) (xy 339.198257 -310.779871) (xy 339.151827 -310.822768)
			(xy 339.100437 -310.859578) (xy 339.04488 -310.889732) (xy 338.986012 -310.912764) (xy 338.924743 -310.92832)
			(xy 338.862018 -310.936159) (xy 338.830412 -310.93664) (xy 338.830158 -310.93664) (xy 338.798201 -310.936072)
			(xy 338.734791 -310.928056) (xy 338.672885 -310.912157) (xy 338.61346 -310.888625) (xy 338.557453 -310.85783)
			(xy 338.505747 -310.82026) (xy 338.459157 -310.776505) (xy 338.418418 -310.727256) (xy 338.384172 -310.67329)
			(xy 338.35696 -310.615458) (xy 338.33721 -310.554671) (xy 338.325235 -310.491889) (xy 338.321221 -310.4281)
			(xy 338.068665 -310.4281) (xy 338.068666 -310.428132) (xy 338.068157 -310.456018) (xy 338.060037 -310.511194)
			(xy 338.043969 -310.564601) (xy 338.020297 -310.615098) (xy 337.989524 -310.661611) (xy 337.952307 -310.703148)
			(xy 337.909439 -310.738823) (xy 337.861833 -310.767877) (xy 337.810504 -310.789689) (xy 337.756547 -310.803795)
			(xy 337.70111 -310.809895) (xy 337.645376 -310.807858) (xy 337.590533 -310.797728) (xy 337.537749 -310.779721)
			(xy 337.488149 -310.75422) (xy 337.442791 -310.721769) (xy 337.402642 -310.68306) (xy 337.368556 -310.638917)
			(xy 337.34126 -310.590282) (xy 337.321337 -310.538191) (xy 337.309211 -310.483754) (xy 337.30514 -310.428132)
			(xy 333.597591 -310.428132) (xy 333.567809 -310.469124) (xy 333.524052 -310.515721) (xy 333.474799 -310.556466)
			(xy 333.420828 -310.590717) (xy 333.362989 -310.617934) (xy 333.302196 -310.637687) (xy 333.239406 -310.649665)
			(xy 333.17561 -310.653679) (xy 333.111814 -310.649665) (xy 333.049024 -310.637687) (xy 332.988231 -310.617934)
			(xy 332.930392 -310.590717) (xy 332.876421 -310.556466) (xy 332.827168 -310.515721) (xy 332.783411 -310.469124)
			(xy 332.745838 -310.417409) (xy 332.715044 -310.361394) (xy 332.691512 -310.301961) (xy 332.675615 -310.240047)
			(xy 332.667604 -310.176629) (xy 317.867463 -310.176629) (xy 308.376574 -319.667382) (xy 308.369175 -319.674226)
			(xy 308.350577 -319.681954) (xy 308.340506 -319.682368) (xy 305.625754 -319.682368) (xy 305.619744 -319.682535)
			(xy 305.608061 -319.685356) (xy 305.60264 -319.687956) (xy 305.599165 -319.689794) (xy 305.592784 -319.694386)
			(xy 305.58994 -319.6971) (xy 304.796952 -320.490088) (xy 304.794245 -320.492938) (xy 304.789649 -320.499315)
			(xy 304.787808 -320.502788) (xy 304.785229 -320.508216) (xy 304.782415 -320.519895) (xy 304.78222 -320.525902)
			(xy 304.78222 -323.493384) (xy 304.782637 -323.503406) (xy 304.790305 -323.521925) (xy 304.804479 -323.536097)
			(xy 304.822998 -323.543763) (xy 304.83302 -323.544184) (xy 306.19446 -323.544184) (xy 306.238937 -323.544666)
			(xy 306.327533 -323.552637) (xy 306.415058 -323.568517) (xy 306.500807 -323.592179) (xy 306.58409 -323.623433)
			(xy 306.664236 -323.662026) (xy 306.7406 -323.707649) (xy 306.812566 -323.759933) (xy 306.879556 -323.818458)
			(xy 306.94103 -323.882752) (xy 306.996493 -323.952298) (xy 307.045499 -324.026536) (xy 307.087653 -324.104868)
			(xy 307.122615 -324.186663) (xy 307.150103 -324.271263) (xy 307.169898 -324.357987) (xy 307.181839 -324.446136)
			(xy 307.18583 -324.535) (xy 307.181839 -324.623864) (xy 307.169898 -324.712013) (xy 307.150103 -324.798737)
			(xy 307.122615 -324.883337) (xy 307.087653 -324.965132) (xy 307.045499 -325.043464) (xy 306.996493 -325.117702)
			(xy 306.94103 -325.187248) (xy 306.879556 -325.251542) (xy 306.812566 -325.310067) (xy 306.7406 -325.362351)
			(xy 306.664236 -325.407974) (xy 306.58409 -325.446567) (xy 306.500807 -325.477821) (xy 306.415058 -325.501483)
			(xy 306.327533 -325.517363) (xy 306.238937 -325.525334) (xy 306.19446 -325.525892) (xy 304.83302 -325.525892)
			(xy 304.822995 -325.526308) (xy 304.80447 -325.533974) (xy 304.79029 -325.548147) (xy 304.782614 -325.566668)
			(xy 304.78222 -325.576692) (xy 304.78222 -334.880458) (xy 304.783236 -334.89011) (xy 304.784858 -334.897357)
			(xy 304.791693 -334.910533) (xy 304.796698 -334.916018) (xy 304.976022 -335.095342) (xy 304.981522 -335.100327)
			(xy 304.99469 -335.107166) (xy 305.00193 -335.108804) (xy 305.011582 -335.10982)
		)
		(stroke
			(width 0)
			(type solid)
		)
		(fill yes)
		(layer "In4.Cu")
		(net "PVDDCR_CPU1_P0")
	)
	(gr_arc
		(start 0.508 -77.67193)
		(mid 0.621601 -78.242658)
		(end 0.94488 -78.726538)
		(stroke
			(width 0.2)
			(type default)
		)
		(layer "In4.Cu")
	)
	(gr_line
		(start 0.508 -13.780008)
		(end 0.508 -77.67193)
		(stroke
			(width 0.2)
			(type default)
		)
		(layer "In4.Cu")
	)
	(gr_arc
		(start 0.508 -7.78002)
		(mid 0.944996 -8.83502)
		(end 1.999996 -9.272016)
		(stroke
			(width 0.2)
			(type default)
		)
		(layer "In4.Cu")
	)
	(gr_line
		(start 0.508 10.40003)
		(end 0.508 -7.78002)
		(stroke
			(width 0.2)
			(type default)
		)
		(layer "In4.Cu")
	)
	(gr_line
		(start 0.94488 -78.726538)
		(end 1.773428 -79.555086)
		(stroke
			(width 0.2)
			(type default)
		)
		(layer "In4.Cu")
	)
	(gr_arc
		(start 1.999996 -12.288012)
		(mid 0.944996 -12.725008)
		(end 0.508 -13.780008)
		(stroke
			(width 0.2)
			(type default)
		)
		(layer "In4.Cu")
	)
	(gr_line
		(start 1.999996 -9.272016)
		(end 9.10209 -9.272016)
		(stroke
			(width 0.2)
			(type default)
		)
		(layer "In4.Cu")
	)
	(gr_arc
		(start 1.999996 11.892026)
		(mid 0.944996 11.45503)
		(end 0.508 10.40003)
		(stroke
			(width 0.2)
			(type default)
		)
		(layer "In4.Cu")
	)
	(gr_arc
		(start 2.507996 -403.371812)
		(mid 2.621533 -403.942691)
		(end 2.944876 -404.426674)
		(stroke
			(width 0.2)
			(type default)
		)
		(layer "In4.Cu")
	)
	(gr_arc
		(start 2.507996 -81.32826)
		(mid 2.317045 -80.368624)
		(end 1.773428 -79.555086)
		(stroke
			(width 0.2)
			(type default)
		)
		(layer "In4.Cu")
	)
	(gr_line
		(start 2.507996 -81.32826)
		(end 2.507996 -403.371812)
		(stroke
			(width 0.2)
			(type default)
		)
		(layer "In4.Cu")
	)
	(gr_line
		(start 2.944876 -404.426674)
		(end 6.273292 -407.75509)
		(stroke
			(width 0.2)
			(type default)
		)
		(layer "In4.Cu")
	)
	(gr_arc
		(start 7.008114 -439.989976)
		(mid 7.44511 -441.044976)
		(end 8.50011 -441.481972)
		(stroke
			(width 0.2)
			(type default)
		)
		(layer "In4.Cu")
	)
	(gr_arc
		(start 7.008114 -409.528518)
		(mid 6.817049 -408.568734)
		(end 6.273292 -407.75509)
		(stroke
			(width 0.2)
			(type default)
		)
		(layer "In4.Cu")
	)
	(gr_line
		(start 7.008114 -409.528518)
		(end 7.008114 -439.989976)
		(stroke
			(width 0.2)
			(type default)
		)
		(layer "In4.Cu")
	)
	(gr_line
		(start 8.50011 -441.481972)
		(end 194.496944 -441.481972)
		(stroke
			(width 0.2)
			(type default)
		)
		(layer "In4.Cu")
	)
	(gr_arc
		(start 9.10209 -9.272016)
		(mid 10.15709 -8.83502)
		(end 10.594086 -7.78002)
		(stroke
			(width 0.2)
			(type default)
		)
		(layer "In4.Cu")
	)
	(gr_line
		(start 10.594086 -7.78002)
		(end 10.594086 0.40005)
		(stroke
			(width 0.2)
			(type default)
		)
		(layer "In4.Cu")
	)
	(gr_line
		(start 11.102086 -12.288012)
		(end 1.999996 -12.288012)
		(stroke
			(width 0.2)
			(type default)
		)
		(layer "In4.Cu")
	)
	(gr_arc
		(start 11.102086 -12.288012)
		(mid 12.875508 -11.553438)
		(end 13.610082 -9.780016)
		(stroke
			(width 0.2)
			(type default)
		)
		(layer "In4.Cu")
	)
	(gr_arc
		(start 13.102082 2.908046)
		(mid 11.32866 2.173472)
		(end 10.594086 0.40005)
		(stroke
			(width 0.2)
			(type default)
		)
		(layer "In4.Cu")
	)
	(gr_line
		(start 13.102082 2.908046)
		(end 81.701894 2.908046)
		(stroke
			(width 0.2)
			(type default)
		)
		(layer "In4.Cu")
	)
	(gr_line
		(start 13.610082 -0.508)
		(end 13.610082 -9.780016)
		(stroke
			(width 0.2)
			(type default)
		)
		(layer "In4.Cu")
	)
	(gr_line
		(start 57.020206 -420.17823)
		(end 57.020206 -420.87927)
		(stroke
			(width 0.07112)
			(type default)
		)
		(layer "In4.Cu")
	)
	(gr_line
		(start 57.020206 -419.05047)
		(end 57.020206 -419.75151)
		(stroke
			(width 0.07112)
			(type default)
		)
		(layer "In4.Cu")
	)
	(gr_line
		(start 57.303416 -420.1795)
		(end 57.439306 -420.31539)
		(stroke
			(width 0.07112)
			(type default)
		)
		(layer "In4.Cu")
	)
	(gr_line
		(start 57.303416 -419.05174)
		(end 57.439306 -419.18763)
		(stroke
			(width 0.07112)
			(type default)
		)
		(layer "In4.Cu")
	)
	(gr_line
		(start 57.439306 -420.74211)
		(end 57.303416 -420.878)
		(stroke
			(width 0.07112)
			(type default)
		)
		(layer "In4.Cu")
	)
	(gr_line
		(start 57.439306 -420.31539)
		(end 57.439306 -420.74211)
		(stroke
			(width 0.07112)
			(type default)
		)
		(layer "In4.Cu")
	)
	(gr_line
		(start 57.439306 -419.61435)
		(end 57.303416 -419.75024)
		(stroke
			(width 0.07112)
			(type default)
		)
		(layer "In4.Cu")
	)
	(gr_line
		(start 57.439306 -419.18763)
		(end 57.439306 -419.61435)
		(stroke
			(width 0.07112)
			(type default)
		)
		(layer "In4.Cu")
	)
	(gr_line
		(start 58.067956 -414.942274)
		(end 57.875932 -414.942274)
		(stroke
			(width 0.07112)
			(type default)
		)
		(layer "In4.Cu")
	)
	(gr_line
		(start 58.170572 -414.247076)
		(end 57.674764 -414.742884)
		(stroke
			(width 0.07112)
			(type default)
		)
		(layer "In4.Cu")
	)
	(gr_line
		(start 58.190892 -423.230802)
		(end 58.64987 -423.68978)
		(stroke
			(width 0.07112)
			(type default)
		)
		(layer "In4.Cu")
	)
	(gr_line
		(start 58.190892 -422.948862)
		(end 58.64987 -422.489884)
		(stroke
			(width 0.07112)
			(type default)
		)
		(layer "In4.Cu")
	)
	(gr_line
		(start 58.369962 -414.640268)
		(end 58.067956 -414.942274)
		(stroke
			(width 0.07112)
			(type default)
		)
		(layer "In4.Cu")
	)
	(gr_line
		(start 58.369962 -414.448244)
		(end 58.369962 -414.640268)
		(stroke
			(width 0.07112)
			(type default)
		)
		(layer "In4.Cu")
	)
	(gr_line
		(start 63.10884 -423.230802)
		(end 62.649862 -423.68978)
		(stroke
			(width 0.07112)
			(type default)
		)
		(layer "In4.Cu")
	)
	(gr_line
		(start 63.10884 -422.948862)
		(end 62.649862 -422.489884)
		(stroke
			(width 0.07112)
			(type default)
		)
		(layer "In4.Cu")
	)
	(gr_line
		(start 65.108836 -424.2308)
		(end 64.649858 -424.689778)
		(stroke
			(width 0.07112)
			(type default)
		)
		(layer "In4.Cu")
	)
	(gr_line
		(start 65.108836 -423.94886)
		(end 64.649858 -423.489882)
		(stroke
			(width 0.07112)
			(type default)
		)
		(layer "In4.Cu")
	)
	(gr_line
		(start 71.108824 -419.63086)
		(end 70.649846 -420.089838)
		(stroke
			(width 0.07112)
			(type default)
		)
		(layer "In4.Cu")
	)
	(gr_line
		(start 71.108824 -419.34892)
		(end 70.649846 -418.889942)
		(stroke
			(width 0.07112)
			(type default)
		)
		(layer "In4.Cu")
	)
	(gr_line
		(start 72.457818 -377.960128)
		(end 72.457818 -378.661168)
		(stroke
			(width 0.07112)
			(type default)
		)
		(layer "In4.Cu")
	)
	(gr_line
		(start 72.457818 -374.884442)
		(end 72.457818 -375.585482)
		(stroke
			(width 0.07112)
			(type default)
		)
		(layer "In4.Cu")
	)
	(gr_line
		(start 72.457818 -373.756682)
		(end 72.457818 -374.457722)
		(stroke
			(width 0.07112)
			(type default)
		)
		(layer "In4.Cu")
	)
	(gr_line
		(start 72.457818 -371.69598)
		(end 72.457818 -372.39702)
		(stroke
			(width 0.07112)
			(type default)
		)
		(layer "In4.Cu")
	)
	(gr_line
		(start 72.741028 -377.961398)
		(end 72.876918 -378.097288)
		(stroke
			(width 0.07112)
			(type default)
		)
		(layer "In4.Cu")
	)
	(gr_line
		(start 72.741028 -374.885712)
		(end 72.876918 -375.021602)
		(stroke
			(width 0.07112)
			(type default)
		)
		(layer "In4.Cu")
	)
	(gr_line
		(start 72.741028 -373.757952)
		(end 72.876918 -373.893842)
		(stroke
			(width 0.07112)
			(type default)
		)
		(layer "In4.Cu")
	)
	(gr_line
		(start 72.741028 -371.69725)
		(end 72.876918 -371.83314)
		(stroke
			(width 0.07112)
			(type default)
		)
		(layer "In4.Cu")
	)
	(gr_line
		(start 72.876918 -378.524008)
		(end 72.741028 -378.659898)
		(stroke
			(width 0.07112)
			(type default)
		)
		(layer "In4.Cu")
	)
	(gr_line
		(start 72.876918 -378.097288)
		(end 72.876918 -378.524008)
		(stroke
			(width 0.07112)
			(type default)
		)
		(layer "In4.Cu")
	)
	(gr_line
		(start 72.876918 -375.448322)
		(end 72.741028 -375.584212)
		(stroke
			(width 0.07112)
			(type default)
		)
		(layer "In4.Cu")
	)
	(gr_line
		(start 72.876918 -375.021602)
		(end 72.876918 -375.448322)
		(stroke
			(width 0.07112)
			(type default)
		)
		(layer "In4.Cu")
	)
	(gr_line
		(start 72.876918 -374.320562)
		(end 72.741028 -374.456452)
		(stroke
			(width 0.07112)
			(type default)
		)
		(layer "In4.Cu")
	)
	(gr_line
		(start 72.876918 -373.893842)
		(end 72.876918 -374.320562)
		(stroke
			(width 0.07112)
			(type default)
		)
		(layer "In4.Cu")
	)
	(gr_line
		(start 72.876918 -372.25986)
		(end 72.741028 -372.39575)
		(stroke
			(width 0.07112)
			(type default)
		)
		(layer "In4.Cu")
	)
	(gr_line
		(start 72.876918 -371.83314)
		(end 72.876918 -372.25986)
		(stroke
			(width 0.07112)
			(type default)
		)
		(layer "In4.Cu")
	)
	(gr_line
		(start 73.10882 -420.630858)
		(end 72.649842 -421.089836)
		(stroke
			(width 0.07112)
			(type default)
		)
		(layer "In4.Cu")
	)
	(gr_line
		(start 73.10882 -420.348918)
		(end 72.649842 -419.88994)
		(stroke
			(width 0.07112)
			(type default)
		)
		(layer "In4.Cu")
	)
	(gr_line
		(start 73.66762 -382.07823)
		(end 73.95845 -382.36906)
		(stroke
			(width 0.07112)
			(type default)
		)
		(layer "In4.Cu")
	)
	(gr_line
		(start 73.66762 -381.79629)
		(end 73.95845 -381.50546)
		(stroke
			(width 0.07112)
			(type default)
		)
		(layer "In4.Cu")
	)
	(gr_line
		(start 73.769982 -420.768018)
		(end 73.634092 -420.632128)
		(stroke
			(width 0.07112)
			(type default)
		)
		(layer "In4.Cu")
	)
	(gr_line
		(start 73.90511 -372.352316)
		(end 74.041 -372.488206)
		(stroke
			(width 0.07112)
			(type default)
		)
		(layer "In4.Cu")
	)
	(gr_line
		(start 73.90511 -371.925596)
		(end 73.90511 -372.352316)
		(stroke
			(width 0.07112)
			(type default)
		)
		(layer "In4.Cu")
	)
	(gr_line
		(start 73.90511 -371.224556)
		(end 74.041 -371.360446)
		(stroke
			(width 0.07112)
			(type default)
		)
		(layer "In4.Cu")
	)
	(gr_line
		(start 73.90511 -370.797836)
		(end 73.90511 -371.224556)
		(stroke
			(width 0.07112)
			(type default)
		)
		(layer "In4.Cu")
	)
	(gr_line
		(start 73.90511 -370.096796)
		(end 74.041 -370.232686)
		(stroke
			(width 0.07112)
			(type default)
		)
		(layer "In4.Cu")
	)
	(gr_line
		(start 73.90511 -369.670076)
		(end 73.90511 -370.096796)
		(stroke
			(width 0.07112)
			(type default)
		)
		(layer "In4.Cu")
	)
	(gr_line
		(start 74.041 -371.789706)
		(end 73.90511 -371.925596)
		(stroke
			(width 0.07112)
			(type default)
		)
		(layer "In4.Cu")
	)
	(gr_line
		(start 74.041 -370.661946)
		(end 73.90511 -370.797836)
		(stroke
			(width 0.07112)
			(type default)
		)
		(layer "In4.Cu")
	)
	(gr_line
		(start 74.041 -369.534186)
		(end 73.90511 -369.670076)
		(stroke
			(width 0.07112)
			(type default)
		)
		(layer "In4.Cu")
	)
	(gr_line
		(start 74.196702 -420.768018)
		(end 73.769982 -420.768018)
		(stroke
			(width 0.07112)
			(type default)
		)
		(layer "In4.Cu")
	)
	(gr_line
		(start 74.24928 -376.54103)
		(end 73.95845 -376.83186)
		(stroke
			(width 0.07112)
			(type default)
		)
		(layer "In4.Cu")
	)
	(gr_line
		(start 74.24928 -376.25909)
		(end 73.95845 -375.96826)
		(stroke
			(width 0.07112)
			(type default)
		)
		(layer "In4.Cu")
	)
	(gr_line
		(start 74.32421 -371.788436)
		(end 74.32421 -372.489476)
		(stroke
			(width 0.07112)
			(type default)
		)
		(layer "In4.Cu")
	)
	(gr_line
		(start 74.32421 -370.660676)
		(end 74.32421 -371.361716)
		(stroke
			(width 0.07112)
			(type default)
		)
		(layer "In4.Cu")
	)
	(gr_line
		(start 74.32421 -369.532916)
		(end 74.32421 -370.233956)
		(stroke
			(width 0.07112)
			(type default)
		)
		(layer "In4.Cu")
	)
	(gr_line
		(start 74.329036 -416.9537)
		(end 74.193146 -416.81781)
		(stroke
			(width 0.07112)
			(type default)
		)
		(layer "In4.Cu")
	)
	(gr_line
		(start 74.332592 -420.632128)
		(end 74.196702 -420.768018)
		(stroke
			(width 0.07112)
			(type default)
		)
		(layer "In4.Cu")
	)
	(gr_line
		(start 74.333862 -420.348918)
		(end 73.632822 -420.348918)
		(stroke
			(width 0.07112)
			(type default)
		)
		(layer "In4.Cu")
	)
	(gr_line
		(start 74.755756 -416.9537)
		(end 74.329036 -416.9537)
		(stroke
			(width 0.07112)
			(type default)
		)
		(layer "In4.Cu")
	)
	(gr_line
		(start 74.891646 -416.81781)
		(end 74.755756 -416.9537)
		(stroke
			(width 0.07112)
			(type default)
		)
		(layer "In4.Cu")
	)
	(gr_line
		(start 74.892916 -416.5346)
		(end 74.191876 -416.5346)
		(stroke
			(width 0.07112)
			(type default)
		)
		(layer "In4.Cu")
	)
	(gr_line
		(start 75.043792 -375.377964)
		(end 75.153266 -375.487438)
		(stroke
			(width 0.07112)
			(type default)
		)
		(layer "In4.Cu")
	)
	(gr_line
		(start 75.043792 -374.951244)
		(end 75.043792 -375.377964)
		(stroke
			(width 0.07112)
			(type default)
		)
		(layer "In4.Cu")
	)
	(gr_line
		(start 75.153266 -374.84177)
		(end 75.043792 -374.951244)
		(stroke
			(width 0.07112)
			(type default)
		)
		(layer "In4.Cu")
	)
	(gr_line
		(start 75.436476 -374.8405)
		(end 75.436476 -375.488708)
		(stroke
			(width 0.07112)
			(type default)
		)
		(layer "In4.Cu")
	)
	(gr_line
		(start 75.520042 -420.921688)
		(end 75.229212 -420.630858)
		(stroke
			(width 0.07112)
			(type default)
		)
		(layer "In4.Cu")
	)
	(gr_line
		(start 75.520042 -420.058088)
		(end 75.229212 -420.348918)
		(stroke
			(width 0.07112)
			(type default)
		)
		(layer "In4.Cu")
	)
	(gr_line
		(start 75.833732 -371.2083)
		(end 75.542902 -371.49913)
		(stroke
			(width 0.07112)
			(type default)
		)
		(layer "In4.Cu")
	)
	(gr_line
		(start 76.115672 -371.2083)
		(end 76.406502 -371.49913)
		(stroke
			(width 0.07112)
			(type default)
		)
		(layer "In4.Cu")
	)
	(gr_line
		(start 77.535532 -368.7445)
		(end 77.244702 -369.03533)
		(stroke
			(width 0.07112)
			(type default)
		)
		(layer "In4.Cu")
	)
	(gr_line
		(start 77.817472 -368.7445)
		(end 78.108302 -369.03533)
		(stroke
			(width 0.07112)
			(type default)
		)
		(layer "In4.Cu")
	)
	(gr_line
		(start 78.04277 -418.3761)
		(end 77.75194 -418.08527)
		(stroke
			(width 0.07112)
			(type default)
		)
		(layer "In4.Cu")
	)
	(gr_line
		(start 78.04277 -417.5125)
		(end 77.75194 -417.80333)
		(stroke
			(width 0.07112)
			(type default)
		)
		(layer "In4.Cu")
	)
	(gr_line
		(start 79.985362 -361.723686)
		(end 79.985362 -361.72394)
		(stroke
			(width 0.07112)
			(type default)
		)
		(layer "In4.Cu")
	)
	(gr_line
		(start 80.939132 -373.6721)
		(end 80.648302 -373.96293)
		(stroke
			(width 0.07112)
			(type default)
		)
		(layer "In4.Cu")
	)
	(gr_line
		(start 81.193894 -9.780016)
		(end 81.193894 -0.508)
		(stroke
			(width 0.2)
			(type default)
		)
		(layer "In4.Cu")
	)
	(gr_arc
		(start 81.193894 -9.780016)
		(mid 81.928474 -11.55343)
		(end 83.70189 -12.288012)
		(stroke
			(width 0.2)
			(type default)
		)
		(layer "In4.Cu")
	)
	(gr_line
		(start 81.193894 -0.508)
		(end 13.610082 -0.508)
		(stroke
			(width 0.2)
			(type default)
		)
		(layer "In4.Cu")
	)
	(gr_line
		(start 81.221072 -373.6721)
		(end 81.511902 -373.96293)
		(stroke
			(width 0.07112)
			(type default)
		)
		(layer "In4.Cu")
	)
	(gr_line
		(start 82.640932 -371.2083)
		(end 82.350102 -371.49913)
		(stroke
			(width 0.07112)
			(type default)
		)
		(layer "In4.Cu")
	)
	(gr_line
		(start 82.922872 -371.2083)
		(end 83.213702 -371.49913)
		(stroke
			(width 0.07112)
			(type default)
		)
		(layer "In4.Cu")
	)
	(gr_arc
		(start 84.20989 -7.78002)
		(mid 84.646886 -8.83502)
		(end 85.701886 -9.272016)
		(stroke
			(width 0.2)
			(type default)
		)
		(layer "In4.Cu")
	)
	(gr_arc
		(start 84.20989 0.40005)
		(mid 83.475332 2.173501)
		(end 81.701894 2.908046)
		(stroke
			(width 0.2)
			(type default)
		)
		(layer "In4.Cu")
	)
	(gr_line
		(start 84.20989 0.40005)
		(end 84.20989 -7.78002)
		(stroke
			(width 0.2)
			(type default)
		)
		(layer "In4.Cu")
	)
	(gr_line
		(start 84.342732 -368.7445)
		(end 84.051902 -369.03533)
		(stroke
			(width 0.07112)
			(type default)
		)
		(layer "In4.Cu")
	)
	(gr_line
		(start 84.624672 -368.7445)
		(end 84.915502 -369.03533)
		(stroke
			(width 0.07112)
			(type default)
		)
		(layer "In4.Cu")
	)
	(gr_line
		(start 85.701886 -9.272016)
		(end 122.102118 -9.272016)
		(stroke
			(width 0.2)
			(type default)
		)
		(layer "In4.Cu")
	)
	(gr_line
		(start 87.746332 -373.6721)
		(end 87.455502 -373.96293)
		(stroke
			(width 0.07112)
			(type default)
		)
		(layer "In4.Cu")
	)
	(gr_line
		(start 88.028272 -373.6721)
		(end 88.319102 -373.96293)
		(stroke
			(width 0.07112)
			(type default)
		)
		(layer "In4.Cu")
	)
	(gr_line
		(start 88.049354 -363.89437)
		(end 88.049354 -363.894624)
		(stroke
			(width 0.07112)
			(type default)
		)
		(layer "In4.Cu")
	)
	(gr_line
		(start 88.159336 -364.708694)
		(end 88.15578 -364.711234)
		(stroke
			(width 0.07112)
			(type default)
		)
		(layer "In4.Cu")
	)
	(gr_arc
		(start 88.159336 -364.708694)
		(mid 88.161241 -364.707424)
		(end 88.163146 -364.706154)
		(stroke
			(width 0.07112)
			(type default)
		)
		(layer "In4.Cu")
	)
	(gr_line
		(start 88.316308 -364.94339)
		(end 88.312498 -364.945676)
		(stroke
			(width 0.07112)
			(type default)
		)
		(layer "In4.Cu")
	)
	(gr_line
		(start 89.448132 -371.2083)
		(end 89.157302 -371.49913)
		(stroke
			(width 0.07112)
			(type default)
		)
		(layer "In4.Cu")
	)
	(gr_line
		(start 89.730072 -371.2083)
		(end 90.020902 -371.49913)
		(stroke
			(width 0.07112)
			(type default)
		)
		(layer "In4.Cu")
	)
	(gr_line
		(start 91.149932 -368.7445)
		(end 90.859102 -369.03533)
		(stroke
			(width 0.07112)
			(type default)
		)
		(layer "In4.Cu")
	)
	(gr_line
		(start 91.431872 -368.7445)
		(end 91.722702 -369.03533)
		(stroke
			(width 0.07112)
			(type default)
		)
		(layer "In4.Cu")
	)
	(gr_line
		(start 94.553532 -373.6721)
		(end 94.262702 -373.96293)
		(stroke
			(width 0.07112)
			(type default)
		)
		(layer "In4.Cu")
	)
	(gr_line
		(start 94.835472 -373.6721)
		(end 95.126302 -373.96293)
		(stroke
			(width 0.07112)
			(type default)
		)
		(layer "In4.Cu")
	)
	(gr_line
		(start 96.255332 -371.2083)
		(end 95.964502 -371.49913)
		(stroke
			(width 0.07112)
			(type default)
		)
		(layer "In4.Cu")
	)
	(gr_line
		(start 96.430084 -296.20591)
		(end 96.430084 -296.234358)
		(stroke
			(width 0.05715)
			(type default)
		)
		(layer "In4.Cu")
	)
	(gr_line
		(start 96.475804 -296.16019)
		(end 96.430084 -296.20591)
		(stroke
			(width 0.05715)
			(type default)
		)
		(layer "In4.Cu")
	)
	(gr_line
		(start 96.537272 -371.2083)
		(end 96.828102 -371.49913)
		(stroke
			(width 0.07112)
			(type default)
		)
		(layer "In4.Cu")
	)
	(gr_line
		(start 96.666304 -296.16019)
		(end 96.712024 -296.20591)
		(stroke
			(width 0.05715)
			(type default)
		)
		(layer "In4.Cu")
	)
	(gr_line
		(start 96.712024 -296.20591)
		(end 96.712024 -296.234358)
		(stroke
			(width 0.05715)
			(type default)
		)
		(layer "In4.Cu")
	)
	(gr_line
		(start 97.131886 -291.866574)
		(end 97.131886 -291.867336)
		(stroke
			(width 0.05715)
			(type default)
		)
		(layer "In4.Cu")
	)
	(gr_line
		(start 97.136458 -295.146222)
		(end 97.136204 -295.145968)
		(stroke
			(width 0.05715)
			(type default)
		)
		(layer "In4.Cu")
	)
	(gr_line
		(start 97.136458 -291.916866)
		(end 97.136458 -291.917374)
		(stroke
			(width 0.05715)
			(type default)
		)
		(layer "In4.Cu")
	)
	(gr_line
		(start 97.370138 -296.07891)
		(end 97.370138 -296.107358)
		(stroke
			(width 0.05715)
			(type default)
		)
		(layer "In4.Cu")
	)
	(gr_line
		(start 97.415858 -296.03319)
		(end 97.370138 -296.07891)
		(stroke
			(width 0.05715)
			(type default)
		)
		(layer "In4.Cu")
	)
	(gr_line
		(start 97.606358 -296.03319)
		(end 97.652078 -296.07891)
		(stroke
			(width 0.05715)
			(type default)
		)
		(layer "In4.Cu")
	)
	(gr_line
		(start 97.652078 -296.07891)
		(end 97.652078 -296.107358)
		(stroke
			(width 0.05715)
			(type default)
		)
		(layer "In4.Cu")
	)
	(gr_line
		(start 97.698052 -290.608766)
		(end 97.697036 -290.609274)
		(stroke
			(width 0.05715)
			(type default)
		)
		(layer "In4.Cu")
	)
	(gr_line
		(start 97.698814 -291.584126)
		(end 97.699322 -291.58438)
		(stroke
			(width 0.05715)
			(type default)
		)
		(layer "In4.Cu")
	)
	(gr_line
		(start 97.698814 -290.608258)
		(end 97.698052 -290.608766)
		(stroke
			(width 0.05715)
			(type default)
		)
		(layer "In4.Cu")
	)
	(gr_line
		(start 97.700084 -290.607496)
		(end 97.698814 -290.608258)
		(stroke
			(width 0.05715)
			(type default)
		)
		(layer "In4.Cu")
	)
	(gr_line
		(start 97.701608 -291.58565)
		(end 97.70237 -291.586158)
		(stroke
			(width 0.05715)
			(type default)
		)
		(layer "In4.Cu")
	)
	(gr_line
		(start 97.70237 -291.586158)
		(end 97.703894 -291.58692)
		(stroke
			(width 0.05715)
			(type default)
		)
		(layer "In4.Cu")
	)
	(gr_line
		(start 97.703894 -291.58692)
		(end 97.704656 -291.587428)
		(stroke
			(width 0.05715)
			(type default)
		)
		(layer "In4.Cu")
	)
	(gr_line
		(start 97.704656 -291.587428)
		(end 97.705672 -291.587936)
		(stroke
			(width 0.05715)
			(type default)
		)
		(layer "In4.Cu")
	)
	(gr_line
		(start 97.793302 -290.77412)
		(end 97.792032 -290.774882)
		(stroke
			(width 0.05715)
			(type default)
		)
		(layer "In4.Cu")
	)
	(gr_line
		(start 97.793556 -291.418518)
		(end 97.794064 -291.418772)
		(stroke
			(width 0.05715)
			(type default)
		)
		(layer "In4.Cu")
	)
	(gr_line
		(start 97.794064 -291.418772)
		(end 97.79508 -291.41928)
		(stroke
			(width 0.05715)
			(type default)
		)
		(layer "In4.Cu")
	)
	(gr_line
		(start 97.794064 -290.773612)
		(end 97.793302 -290.77412)
		(stroke
			(width 0.05715)
			(type default)
		)
		(layer "In4.Cu")
	)
	(gr_line
		(start 97.79508 -291.41928)
		(end 97.796604 -291.420296)
		(stroke
			(width 0.05715)
			(type default)
		)
		(layer "In4.Cu")
	)
	(gr_line
		(start 97.79508 -290.773104)
		(end 97.794064 -290.773612)
		(stroke
			(width 0.05715)
			(type default)
		)
		(layer "In4.Cu")
	)
	(gr_line
		(start 97.796604 -291.420296)
		(end 97.79762 -291.420804)
		(stroke
			(width 0.05715)
			(type default)
		)
		(layer "In4.Cu")
	)
	(gr_line
		(start 97.79762 -291.420804)
		(end 97.80016 -291.422328)
		(stroke
			(width 0.05715)
			(type default)
		)
		(layer "In4.Cu")
	)
	(gr_line
		(start 97.80016 -291.422328)
		(end 97.801176 -291.42309)
		(stroke
			(width 0.05715)
			(type default)
		)
		(layer "In4.Cu")
	)
	(gr_line
		(start 97.957132 -368.7445)
		(end 97.666302 -369.03533)
		(stroke
			(width 0.07112)
			(type default)
		)
		(layer "In4.Cu")
	)
	(gr_line
		(start 97.981008 -291.096192)
		(end 98.27895 -291.096192)
		(stroke
			(width 0.05715)
			(type default)
		)
		(layer "In4.Cu")
	)
	(gr_line
		(start 97.981008 -289.47618)
		(end 98.27895 -289.47618)
		(stroke
			(width 0.05715)
			(type default)
		)
		(layer "In4.Cu")
	)
	(gr_line
		(start 97.981008 -287.856422)
		(end 98.27895 -287.856422)
		(stroke
			(width 0.05715)
			(type default)
		)
		(layer "In4.Cu")
	)
	(gr_line
		(start 97.981008 -286.23641)
		(end 98.27895 -286.23641)
		(stroke
			(width 0.05715)
			(type default)
		)
		(layer "In4.Cu")
	)
	(gr_line
		(start 98.076512 -295.146222)
		(end 98.076258 -295.145968)
		(stroke
			(width 0.05715)
			(type default)
		)
		(layer "In4.Cu")
	)
	(gr_line
		(start 98.239072 -368.7445)
		(end 98.529902 -369.03533)
		(stroke
			(width 0.07112)
			(type default)
		)
		(layer "In4.Cu")
	)
	(gr_line
		(start 98.27895 -291.096192)
		(end 98.361754 -291.178996)
		(stroke
			(width 0.05715)
			(type default)
		)
		(layer "In4.Cu")
	)
	(gr_line
		(start 98.27895 -289.47618)
		(end 98.348292 -289.545522)
		(stroke
			(width 0.05715)
			(type default)
		)
		(layer "In4.Cu")
	)
	(gr_line
		(start 98.27895 -287.856422)
		(end 98.361754 -287.939226)
		(stroke
			(width 0.05715)
			(type default)
		)
		(layer "In4.Cu")
	)
	(gr_line
		(start 98.27895 -286.23641)
		(end 98.348292 -286.305752)
		(stroke
			(width 0.05715)
			(type default)
		)
		(layer "In4.Cu")
	)
	(gr_line
		(start 98.310192 -296.07891)
		(end 98.310192 -296.107358)
		(stroke
			(width 0.05715)
			(type default)
		)
		(layer "In4.Cu")
	)
	(gr_line
		(start 98.355912 -296.03319)
		(end 98.310192 -296.07891)
		(stroke
			(width 0.05715)
			(type default)
		)
		(layer "In4.Cu")
	)
	(gr_arc
		(start 98.361754 -291.178996)
		(mid 98.363547 -291.190318)
		(end 98.365564 -291.201602)
		(stroke
			(width 0.05715)
			(type default)
		)
		(layer "In4.Cu")
	)
	(gr_arc
		(start 98.361754 -287.939226)
		(mid 98.363542 -287.950676)
		(end 98.365564 -287.962086)
		(stroke
			(width 0.05715)
			(type default)
		)
		(layer "In4.Cu")
	)
	(gr_arc
		(start 98.536506 -289.581844)
		(mid 98.538528 -289.570434)
		(end 98.540316 -289.558984)
		(stroke
			(width 0.05715)
			(type default)
		)
		(layer "In4.Cu")
	)
	(gr_arc
		(start 98.536506 -286.342074)
		(mid 98.538529 -286.330664)
		(end 98.540316 -286.319214)
		(stroke
			(width 0.05715)
			(type default)
		)
		(layer "In4.Cu")
	)
	(gr_line
		(start 98.546412 -296.03319)
		(end 98.592132 -296.07891)
		(stroke
			(width 0.05715)
			(type default)
		)
		(layer "In4.Cu")
	)
	(gr_arc
		(start 98.590862 -291.55517)
		(mid 98.594914 -291.557982)
		(end 98.59899 -291.560758)
		(stroke
			(width 0.05715)
			(type default)
		)
		(layer "In4.Cu")
	)
	(gr_line
		(start 98.592132 -296.07891)
		(end 98.592132 -296.107358)
		(stroke
			(width 0.05715)
			(type default)
		)
		(layer "In4.Cu")
	)
	(gr_line
		(start 98.59899 -291.560758)
		(end 98.605848 -291.564822)
		(stroke
			(width 0.05715)
			(type default)
		)
		(layer "In4.Cu")
	)
	(gr_line
		(start 98.605848 -291.564822)
		(end 98.60661 -291.56533)
		(stroke
			(width 0.05715)
			(type default)
		)
		(layer "In4.Cu")
	)
	(gr_line
		(start 98.60661 -291.56533)
		(end 98.607372 -291.565838)
		(stroke
			(width 0.05715)
			(type default)
		)
		(layer "In4.Cu")
	)
	(gr_line
		(start 98.62312 -291.096192)
		(end 98.553778 -291.165534)
		(stroke
			(width 0.05715)
			(type default)
		)
		(layer "In4.Cu")
	)
	(gr_line
		(start 98.62312 -289.47618)
		(end 98.540316 -289.558984)
		(stroke
			(width 0.05715)
			(type default)
		)
		(layer "In4.Cu")
	)
	(gr_line
		(start 98.62312 -287.856422)
		(end 98.553778 -287.925764)
		(stroke
			(width 0.05715)
			(type default)
		)
		(layer "In4.Cu")
	)
	(gr_line
		(start 98.62312 -286.23641)
		(end 98.540316 -286.319214)
		(stroke
			(width 0.05715)
			(type default)
		)
		(layer "In4.Cu")
	)
	(gr_line
		(start 98.64725 -291.588952)
		(end 98.649028 -291.589968)
		(stroke
			(width 0.05715)
			(type default)
		)
		(layer "In4.Cu")
	)
	(gr_line
		(start 98.921062 -291.096192)
		(end 98.62312 -291.096192)
		(stroke
			(width 0.05715)
			(type default)
		)
		(layer "In4.Cu")
	)
	(gr_line
		(start 98.921062 -289.47618)
		(end 98.62312 -289.47618)
		(stroke
			(width 0.05715)
			(type default)
		)
		(layer "In4.Cu")
	)
	(gr_line
		(start 98.921062 -287.856422)
		(end 98.62312 -287.856422)
		(stroke
			(width 0.05715)
			(type default)
		)
		(layer "In4.Cu")
	)
	(gr_line
		(start 98.921062 -286.23641)
		(end 98.62312 -286.23641)
		(stroke
			(width 0.05715)
			(type default)
		)
		(layer "In4.Cu")
	)
	(gr_line
		(start 99.087432 -293.050722)
		(end 99.08667 -293.05123)
		(stroke
			(width 0.05715)
			(type default)
		)
		(layer "In4.Cu")
	)
	(gr_line
		(start 99.182174 -293.836344)
		(end 99.182682 -293.836344)
		(stroke
			(width 0.05715)
			(type default)
		)
		(layer "In4.Cu")
	)
	(gr_line
		(start 99.182682 -293.216076)
		(end 99.182428 -293.216076)
		(stroke
			(width 0.05715)
			(type default)
		)
		(layer "In4.Cu")
	)
	(gr_line
		(start 99.18319 -293.215822)
		(end 99.182682 -293.216076)
		(stroke
			(width 0.05715)
			(type default)
		)
		(layer "In4.Cu")
	)
	(gr_line
		(start 99.211638 -289.005518)
		(end 99.211892 -289.005772)
		(stroke
			(width 0.05715)
			(type default)
		)
		(layer "In4.Cu")
	)
	(gr_line
		(start 99.23272 -293.865554)
		(end 99.242372 -293.871142)
		(stroke
			(width 0.05715)
			(type default)
		)
		(layer "In4.Cu")
	)
	(gr_line
		(start 99.234752 -292.246812)
		(end 99.242372 -292.25113)
		(stroke
			(width 0.05715)
			(type default)
		)
		(layer "In4.Cu")
	)
	(gr_arc
		(start 99.242372 -293.871142)
		(mid 99.242753 -293.871396)
		(end 99.243134 -293.87165)
		(stroke
			(width 0.05715)
			(type default)
		)
		(layer "In4.Cu")
	)
	(gr_arc
		(start 99.242372 -292.25113)
		(mid 99.242753 -292.251384)
		(end 99.243134 -292.251638)
		(stroke
			(width 0.05715)
			(type default)
		)
		(layer "In4.Cu")
	)
	(gr_line
		(start 99.243134 -293.87165)
		(end 99.245166 -293.873174)
		(stroke
			(width 0.05715)
			(type default)
		)
		(layer "In4.Cu")
	)
	(gr_arc
		(start 99.245166 -293.873174)
		(mid 99.245547 -293.873428)
		(end 99.245928 -293.873682)
		(stroke
			(width 0.05715)
			(type default)
		)
		(layer "In4.Cu")
	)
	(gr_line
		(start 99.2505 -296.07891)
		(end 99.2505 -296.107358)
		(stroke
			(width 0.05715)
			(type default)
		)
		(layer "In4.Cu")
	)
	(gr_arc
		(start 99.251008 -292.257226)
		(mid 99.247083 -292.254415)
		(end 99.243134 -292.251638)
		(stroke
			(width 0.05715)
			(type default)
		)
		(layer "In4.Cu")
	)
	(gr_line
		(start 99.29622 -296.03319)
		(end 99.2505 -296.07891)
		(stroke
			(width 0.05715)
			(type default)
		)
		(layer "In4.Cu")
	)
	(gr_line
		(start 99.48672 -296.03319)
		(end 99.53244 -296.07891)
		(stroke
			(width 0.05715)
			(type default)
		)
		(layer "In4.Cu")
	)
	(gr_line
		(start 99.53244 -296.07891)
		(end 99.53244 -296.107358)
		(stroke
			(width 0.05715)
			(type default)
		)
		(layer "In4.Cu")
	)
	(gr_line
		(start 99.956366 -295.146222)
		(end 99.956112 -295.145968)
		(stroke
			(width 0.05715)
			(type default)
		)
		(layer "In4.Cu")
	)
	(gr_line
		(start 100.18522 -296.07891)
		(end 100.18522 -296.107358)
		(stroke
			(width 0.05715)
			(type default)
		)
		(layer "In4.Cu")
	)
	(gr_line
		(start 100.23094 -296.03319)
		(end 100.18522 -296.07891)
		(stroke
			(width 0.05715)
			(type default)
		)
		(layer "In4.Cu")
	)
	(gr_line
		(start 100.42144 -296.03319)
		(end 100.46716 -296.07891)
		(stroke
			(width 0.05715)
			(type default)
		)
		(layer "In4.Cu")
	)
	(gr_line
		(start 100.46716 -296.07891)
		(end 100.46716 -296.107358)
		(stroke
			(width 0.05715)
			(type default)
		)
		(layer "In4.Cu")
	)
	(gr_arc
		(start 100.471224 -291.55517)
		(mid 100.475149 -291.557981)
		(end 100.479098 -291.560758)
		(stroke
			(width 0.05715)
			(type default)
		)
		(layer "In4.Cu")
	)
	(gr_line
		(start 100.479098 -291.560758)
		(end 100.485956 -291.564822)
		(stroke
			(width 0.05715)
			(type default)
		)
		(layer "In4.Cu")
	)
	(gr_line
		(start 100.485956 -291.564822)
		(end 100.486718 -291.56533)
		(stroke
			(width 0.05715)
			(type default)
		)
		(layer "In4.Cu")
	)
	(gr_line
		(start 100.486718 -291.56533)
		(end 100.48748 -291.565838)
		(stroke
			(width 0.05715)
			(type default)
		)
		(layer "In4.Cu")
	)
	(gr_line
		(start 100.518214 -290.608766)
		(end 100.517198 -290.609274)
		(stroke
			(width 0.05715)
			(type default)
		)
		(layer "In4.Cu")
	)
	(gr_line
		(start 100.518468 -291.583872)
		(end 100.518976 -291.584126)
		(stroke
			(width 0.05715)
			(type default)
		)
		(layer "In4.Cu")
	)
	(gr_line
		(start 100.518722 -290.608512)
		(end 100.518214 -290.608766)
		(stroke
			(width 0.05715)
			(type default)
		)
		(layer "In4.Cu")
	)
	(gr_line
		(start 100.518976 -291.584126)
		(end 100.519484 -291.58438)
		(stroke
			(width 0.05715)
			(type default)
		)
		(layer "In4.Cu")
	)
	(gr_line
		(start 100.52177 -291.58565)
		(end 100.522532 -291.586158)
		(stroke
			(width 0.05715)
			(type default)
		)
		(layer "In4.Cu")
	)
	(gr_line
		(start 100.522532 -291.586158)
		(end 100.524056 -291.58692)
		(stroke
			(width 0.05715)
			(type default)
		)
		(layer "In4.Cu")
	)
	(gr_line
		(start 100.524056 -291.58692)
		(end 100.524818 -291.587428)
		(stroke
			(width 0.05715)
			(type default)
		)
		(layer "In4.Cu")
	)
	(gr_line
		(start 100.524818 -291.587428)
		(end 100.525834 -291.587936)
		(stroke
			(width 0.05715)
			(type default)
		)
		(layer "In4.Cu")
	)
	(gr_line
		(start 100.613464 -290.77412)
		(end 100.612194 -290.774882)
		(stroke
			(width 0.05715)
			(type default)
		)
		(layer "In4.Cu")
	)
	(gr_line
		(start 100.613972 -290.773866)
		(end 100.613464 -290.77412)
		(stroke
			(width 0.05715)
			(type default)
		)
		(layer "In4.Cu")
	)
	(gr_line
		(start 100.614226 -291.418772)
		(end 100.615242 -291.41928)
		(stroke
			(width 0.05715)
			(type default)
		)
		(layer "In4.Cu")
	)
	(gr_line
		(start 100.615242 -291.41928)
		(end 100.616766 -291.420296)
		(stroke
			(width 0.05715)
			(type default)
		)
		(layer "In4.Cu")
	)
	(gr_line
		(start 100.616766 -291.420296)
		(end 100.617782 -291.420804)
		(stroke
			(width 0.05715)
			(type default)
		)
		(layer "In4.Cu")
	)
	(gr_line
		(start 100.617782 -291.420804)
		(end 100.620322 -291.422328)
		(stroke
			(width 0.05715)
			(type default)
		)
		(layer "In4.Cu")
	)
	(gr_line
		(start 100.620322 -291.422328)
		(end 100.621338 -291.42309)
		(stroke
			(width 0.05715)
			(type default)
		)
		(layer "In4.Cu")
	)
	(gr_line
		(start 100.80117 -291.096192)
		(end 101.099112 -291.096192)
		(stroke
			(width 0.05715)
			(type default)
		)
		(layer "In4.Cu")
	)
	(gr_line
		(start 100.80117 -289.47618)
		(end 101.099112 -289.47618)
		(stroke
			(width 0.05715)
			(type default)
		)
		(layer "In4.Cu")
	)
	(gr_line
		(start 100.80117 -287.856422)
		(end 101.099112 -287.856422)
		(stroke
			(width 0.05715)
			(type default)
		)
		(layer "In4.Cu")
	)
	(gr_line
		(start 100.84816 -294.752014)
		(end 100.842826 -294.75557)
		(stroke
			(width 0.05715)
			(type default)
		)
		(layer "In4.Cu")
	)
	(gr_line
		(start 100.891086 -294.722042)
		(end 100.87356 -294.734234)
		(stroke
			(width 0.05715)
			(type default)
		)
		(layer "In4.Cu")
	)
	(gr_line
		(start 100.892102 -294.722296)
		(end 100.891086 -294.722042)
		(stroke
			(width 0.05715)
			(type default)
		)
		(layer "In4.Cu")
	)
	(gr_line
		(start 100.896928 -295.016682)
		(end 100.896674 -295.016428)
		(stroke
			(width 0.05715)
			(type default)
		)
		(layer "In4.Cu")
	)
	(gr_line
		(start 100.951792 -294.912034)
		(end 100.951538 -294.912288)
		(stroke
			(width 0.05715)
			(type default)
		)
		(layer "In4.Cu")
	)
	(gr_line
		(start 101.073458 -294.599614)
		(end 101.07295 -294.600122)
		(stroke
			(width 0.05715)
			(type default)
		)
		(layer "In4.Cu")
	)
	(gr_line
		(start 101.099112 -291.096192)
		(end 101.181916 -291.178996)
		(stroke
			(width 0.05715)
			(type default)
		)
		(layer "In4.Cu")
	)
	(gr_line
		(start 101.099112 -289.47618)
		(end 101.168454 -289.545522)
		(stroke
			(width 0.05715)
			(type default)
		)
		(layer "In4.Cu")
	)
	(gr_line
		(start 101.099112 -287.856422)
		(end 101.181916 -287.939226)
		(stroke
			(width 0.05715)
			(type default)
		)
		(layer "In4.Cu")
	)
	(gr_line
		(start 101.130354 -296.20591)
		(end 101.130354 -296.234358)
		(stroke
			(width 0.05715)
			(type default)
		)
		(layer "In4.Cu")
	)
	(gr_line
		(start 101.14788 -294.784526)
		(end 101.148134 -294.784272)
		(stroke
			(width 0.05715)
			(type default)
		)
		(layer "In4.Cu")
	)
	(gr_line
		(start 101.148134 -294.784272)
		(end 101.14026 -294.789352)
		(stroke
			(width 0.05715)
			(type default)
		)
		(layer "In4.Cu")
	)
	(gr_line
		(start 101.156262 -294.777922)
		(end 101.14788 -294.784526)
		(stroke
			(width 0.05715)
			(type default)
		)
		(layer "In4.Cu")
	)
	(gr_line
		(start 101.176074 -296.16019)
		(end 101.130354 -296.20591)
		(stroke
			(width 0.05715)
			(type default)
		)
		(layer "In4.Cu")
	)
	(gr_arc
		(start 101.181916 -291.178996)
		(mid 101.183707 -291.190318)
		(end 101.185726 -291.201602)
		(stroke
			(width 0.05715)
			(type default)
		)
		(layer "In4.Cu")
	)
	(gr_arc
		(start 101.181916 -287.939226)
		(mid 101.183707 -287.950548)
		(end 101.185726 -287.961832)
		(stroke
			(width 0.05715)
			(type default)
		)
		(layer "In4.Cu")
	)
	(gr_line
		(start 101.354382 -368.75085)
		(end 101.069902 -369.03533)
		(stroke
			(width 0.07112)
			(type default)
		)
		(layer "In4.Cu")
	)
	(gr_line
		(start 101.354382 -368.73815)
		(end 101.354382 -368.75085)
		(stroke
			(width 0.07112)
			(type default)
		)
		(layer "In4.Cu")
	)
	(gr_arc
		(start 101.356668 -289.581844)
		(mid 101.35869 -289.570433)
		(end 101.360478 -289.558984)
		(stroke
			(width 0.05715)
			(type default)
		)
		(layer "In4.Cu")
	)
	(gr_line
		(start 101.366574 -296.16019)
		(end 101.412294 -296.20591)
		(stroke
			(width 0.05715)
			(type default)
		)
		(layer "In4.Cu")
	)
	(gr_line
		(start 101.412294 -296.20591)
		(end 101.412294 -296.234358)
		(stroke
			(width 0.05715)
			(type default)
		)
		(layer "In4.Cu")
	)
	(gr_line
		(start 101.443028 -291.096192)
		(end 101.37394 -291.16528)
		(stroke
			(width 0.05715)
			(type default)
		)
		(layer "In4.Cu")
	)
	(gr_line
		(start 101.443282 -289.47618)
		(end 101.360478 -289.558984)
		(stroke
			(width 0.05715)
			(type default)
		)
		(layer "In4.Cu")
	)
	(gr_line
		(start 101.443282 -287.856422)
		(end 101.37394 -287.925764)
		(stroke
			(width 0.05715)
			(type default)
		)
		(layer "In4.Cu")
	)
	(gr_arc
		(start 101.462332 -291.586158)
		(mid 101.461444 -291.585649)
		(end 101.460554 -291.585142)
		(stroke
			(width 0.05715)
			(type default)
		)
		(layer "In4.Cu")
	)
	(gr_line
		(start 101.553772 -291.418772)
		(end 101.555296 -291.419534)
		(stroke
			(width 0.05715)
			(type default)
		)
		(layer "In4.Cu")
	)
	(gr_line
		(start 101.637592 -368.73942)
		(end 101.933502 -369.03533)
		(stroke
			(width 0.07112)
			(type default)
		)
		(layer "In4.Cu")
	)
	(gr_line
		(start 101.74097 -291.096192)
		(end 101.443028 -291.096192)
		(stroke
			(width 0.05715)
			(type default)
		)
		(layer "In4.Cu")
	)
	(gr_line
		(start 101.74097 -289.47618)
		(end 101.443282 -289.47618)
		(stroke
			(width 0.05715)
			(type default)
		)
		(layer "In4.Cu")
	)
	(gr_line
		(start 101.74097 -287.856422)
		(end 101.443282 -287.856422)
		(stroke
			(width 0.05715)
			(type default)
		)
		(layer "In4.Cu")
	)
	(gr_arc
		(start 101.881178 -289.125152)
		(mid 101.885103 -289.127963)
		(end 101.889052 -289.13074)
		(stroke
			(width 0.05715)
			(type default)
		)
		(layer "In4.Cu")
	)
	(gr_line
		(start 101.889052 -289.13074)
		(end 101.89591 -289.134804)
		(stroke
			(width 0.05715)
			(type default)
		)
		(layer "In4.Cu")
	)
	(gr_line
		(start 101.89591 -289.134804)
		(end 101.896672 -289.135312)
		(stroke
			(width 0.05715)
			(type default)
		)
		(layer "In4.Cu")
	)
	(gr_line
		(start 101.896672 -289.135312)
		(end 101.897434 -289.13582)
		(stroke
			(width 0.05715)
			(type default)
		)
		(layer "In4.Cu")
	)
	(gr_line
		(start 101.910388 -293.049198)
		(end 101.906832 -293.05123)
		(stroke
			(width 0.05715)
			(type default)
		)
		(layer "In4.Cu")
	)
	(gr_line
		(start 101.923342 -292.39083)
		(end 101.922326 -292.390322)
		(stroke
			(width 0.05715)
			(type default)
		)
		(layer "In4.Cu")
	)
	(gr_line
		(start 101.92766 -293.039038)
		(end 101.926136 -293.0398)
		(stroke
			(width 0.05715)
			(type default)
		)
		(layer "In4.Cu")
	)
	(gr_line
		(start 102.002336 -293.836344)
		(end 102.002844 -293.836344)
		(stroke
			(width 0.05715)
			(type default)
		)
		(layer "In4.Cu")
	)
	(gr_line
		(start 102.052882 -293.865554)
		(end 102.062534 -293.871142)
		(stroke
			(width 0.05715)
			(type default)
		)
		(layer "In4.Cu")
	)
	(gr_line
		(start 102.054406 -292.246558)
		(end 102.061518 -292.250622)
		(stroke
			(width 0.05715)
			(type default)
		)
		(layer "In4.Cu")
	)
	(gr_arc
		(start 102.062534 -293.871142)
		(mid 102.062915 -293.871396)
		(end 102.063296 -293.87165)
		(stroke
			(width 0.05715)
			(type default)
		)
		(layer "In4.Cu")
	)
	(gr_arc
		(start 102.063042 -292.251638)
		(mid 102.06228 -292.251129)
		(end 102.061518 -292.250622)
		(stroke
			(width 0.05715)
			(type default)
		)
		(layer "In4.Cu")
	)
	(gr_line
		(start 102.063296 -293.87165)
		(end 102.065328 -293.873174)
		(stroke
			(width 0.05715)
			(type default)
		)
		(layer "In4.Cu")
	)
	(gr_arc
		(start 102.065328 -293.873174)
		(mid 102.065709 -293.873428)
		(end 102.06609 -293.873682)
		(stroke
			(width 0.05715)
			(type default)
		)
		(layer "In4.Cu")
	)
	(gr_arc
		(start 102.069392 -292.25621)
		(mid 102.066225 -292.253913)
		(end 102.063042 -292.251638)
		(stroke
			(width 0.05715)
			(type default)
		)
		(layer "In4.Cu")
	)
	(gr_line
		(start 102.075234 -296.21988)
		(end 102.075234 -296.234358)
		(stroke
			(width 0.05715)
			(type default)
		)
		(layer "In4.Cu")
	)
	(gr_line
		(start 102.120954 -296.17416)
		(end 102.075234 -296.21988)
		(stroke
			(width 0.05715)
			(type default)
		)
		(layer "In4.Cu")
	)
	(gr_line
		(start 102.120954 -296.16019)
		(end 102.120954 -296.17416)
		(stroke
			(width 0.05715)
			(type default)
		)
		(layer "In4.Cu")
	)
	(gr_line
		(start 102.312724 -296.16146)
		(end 102.357174 -296.20591)
		(stroke
			(width 0.05715)
			(type default)
		)
		(layer "In4.Cu")
	)
	(gr_line
		(start 102.357174 -296.20591)
		(end 102.357174 -296.234358)
		(stroke
			(width 0.05715)
			(type default)
		)
		(layer "In4.Cu")
	)
	(gr_line
		(start 102.386638 -291.57676)
		(end 102.390956 -291.5793)
		(stroke
			(width 0.05715)
			(type default)
		)
		(layer "In4.Cu")
	)
	(gr_line
		(start 102.405942 -291.58819)
		(end 102.406958 -291.588698)
		(stroke
			(width 0.05715)
			(type default)
		)
		(layer "In4.Cu")
	)
	(gr_line
		(start 102.493826 -290.773612)
		(end 102.493318 -290.773866)
		(stroke
			(width 0.05715)
			(type default)
		)
		(layer "In4.Cu")
	)
	(gr_line
		(start 102.502208 -351.801176)
		(end 102.501954 -351.801176)
		(stroke
			(width 0.07112)
			(type default)
		)
		(layer "In4.Cu")
	)
	(gr_line
		(start 102.525322 -291.43706)
		(end 102.532434 -291.441124)
		(stroke
			(width 0.05715)
			(type default)
		)
		(layer "In4.Cu")
	)
	(gr_line
		(start 102.530402 -289.819842)
		(end 102.53345 -289.821874)
		(stroke
			(width 0.05715)
			(type default)
		)
		(layer "In4.Cu")
	)
	(gr_arc
		(start 102.532434 -291.441124)
		(mid 102.532815 -291.441378)
		(end 102.533196 -291.441632)
		(stroke
			(width 0.05715)
			(type default)
		)
		(layer "In4.Cu")
	)
	(gr_line
		(start 102.53345 -289.821874)
		(end 102.533958 -289.822382)
		(stroke
			(width 0.05715)
			(type default)
		)
		(layer "In4.Cu")
	)
	(gr_arc
		(start 102.540816 -291.446966)
		(mid 102.537017 -291.444284)
		(end 102.533196 -291.441632)
		(stroke
			(width 0.05715)
			(type default)
		)
		(layer "In4.Cu")
	)
	(gr_line
		(start 103.016812 -352.629978)
		(end 103.016558 -352.629978)
		(stroke
			(width 0.07112)
			(type default)
		)
		(layer "In4.Cu")
	)
	(gr_line
		(start 103.020114 -296.07891)
		(end 103.020114 -296.107358)
		(stroke
			(width 0.05715)
			(type default)
		)
		(layer "In4.Cu")
	)
	(gr_line
		(start 103.065834 -296.03319)
		(end 103.020114 -296.07891)
		(stroke
			(width 0.05715)
			(type default)
		)
		(layer "In4.Cu")
	)
	(gr_line
		(start 103.167688 -372.220998)
		(end 103.167942 -372.220998)
		(stroke
			(width 0.07112)
			(type default)
		)
		(layer "In4.Cu")
	)
	(gr_line
		(start 103.256334 -296.03319)
		(end 103.302054 -296.07891)
		(stroke
			(width 0.05715)
			(type default)
		)
		(layer "In4.Cu")
	)
	(gr_arc
		(start 103.291132 -291.55517)
		(mid 103.295057 -291.557981)
		(end 103.299006 -291.560758)
		(stroke
			(width 0.05715)
			(type default)
		)
		(layer "In4.Cu")
	)
	(gr_line
		(start 103.299006 -291.560758)
		(end 103.305864 -291.564822)
		(stroke
			(width 0.05715)
			(type default)
		)
		(layer "In4.Cu")
	)
	(gr_arc
		(start 103.299006 -290.631626)
		(mid 103.295057 -290.634403)
		(end 103.291132 -290.637214)
		(stroke
			(width 0.05715)
			(type default)
		)
		(layer "In4.Cu")
	)
	(gr_arc
		(start 103.299006 -290.631626)
		(mid 103.299387 -290.631372)
		(end 103.299768 -290.631118)
		(stroke
			(width 0.05715)
			(type default)
		)
		(layer "In4.Cu")
	)
	(gr_line
		(start 103.302054 -296.07891)
		(end 103.302054 -296.107358)
		(stroke
			(width 0.05715)
			(type default)
		)
		(layer "In4.Cu")
	)
	(gr_line
		(start 103.305864 -291.564822)
		(end 103.306626 -291.56533)
		(stroke
			(width 0.05715)
			(type default)
		)
		(layer "In4.Cu")
	)
	(gr_line
		(start 103.306626 -291.56533)
		(end 103.307388 -291.565838)
		(stroke
			(width 0.05715)
			(type default)
		)
		(layer "In4.Cu")
	)
	(gr_line
		(start 103.30688 -290.627054)
		(end 103.299768 -290.631118)
		(stroke
			(width 0.05715)
			(type default)
		)
		(layer "In4.Cu")
	)
	(gr_line
		(start 103.32339 -371.48135)
		(end 102.9335 -372.06428)
		(stroke
			(width 0.07112)
			(type default)
		)
		(layer "In4.Cu")
	)
	(gr_line
		(start 103.338376 -291.583872)
		(end 103.338884 -291.584126)
		(stroke
			(width 0.05715)
			(type default)
		)
		(layer "In4.Cu")
	)
	(gr_line
		(start 103.33863 -290.608512)
		(end 103.337868 -290.60902)
		(stroke
			(width 0.05715)
			(type default)
		)
		(layer "In4.Cu")
	)
	(gr_line
		(start 103.340154 -290.60775)
		(end 103.33863 -290.608512)
		(stroke
			(width 0.05715)
			(type default)
		)
		(layer "In4.Cu")
	)
	(gr_line
		(start 103.357934 -372.183406)
		(end 103.169466 -372.220744)
		(stroke
			(width 0.07112)
			(type default)
		)
		(layer "In4.Cu")
	)
	(gr_line
		(start 103.434134 -290.773612)
		(end 103.433118 -290.77412)
		(stroke
			(width 0.05715)
			(type default)
		)
		(layer "In4.Cu")
	)
	(gr_line
		(start 103.435658 -290.772596)
		(end 103.434134 -290.773612)
		(stroke
			(width 0.05715)
			(type default)
		)
		(layer "In4.Cu")
	)
	(gr_line
		(start 103.464868 -291.436298)
		(end 103.470456 -291.4396)
		(stroke
			(width 0.05715)
			(type default)
		)
		(layer "In4.Cu")
	)
	(gr_line
		(start 103.470456 -291.4396)
		(end 103.47325 -291.441632)
		(stroke
			(width 0.05715)
			(type default)
		)
		(layer "In4.Cu")
	)
	(gr_arc
		(start 103.481124 -291.44722)
		(mid 103.477199 -291.444409)
		(end 103.47325 -291.441632)
		(stroke
			(width 0.05715)
			(type default)
		)
		(layer "In4.Cu")
	)
	(gr_line
		(start 103.514652 -376.665998)
		(end 103.805482 -376.956828)
		(stroke
			(width 0.07112)
			(type default)
		)
		(layer "In4.Cu")
	)
	(gr_line
		(start 103.514652 -376.384058)
		(end 103.805482 -376.093228)
		(stroke
			(width 0.07112)
			(type default)
		)
		(layer "In4.Cu")
	)
	(gr_line
		(start 103.558086 -371.639592)
		(end 103.595424 -371.828314)
		(stroke
			(width 0.07112)
			(type default)
		)
		(layer "In4.Cu")
	)
	(gr_line
		(start 103.595424 -371.828314)
		(end 103.357934 -372.183406)
		(stroke
			(width 0.07112)
			(type default)
		)
		(layer "In4.Cu")
	)
	(gr_line
		(start 103.621078 -291.096192)
		(end 103.91902 -291.096192)
		(stroke
			(width 0.05715)
			(type default)
		)
		(layer "In4.Cu")
	)
	(gr_line
		(start 103.621078 -289.47618)
		(end 103.91902 -289.47618)
		(stroke
			(width 0.05715)
			(type default)
		)
		(layer "In4.Cu")
	)
	(gr_line
		(start 103.621078 -287.856422)
		(end 103.91902 -287.856422)
		(stroke
			(width 0.05715)
			(type default)
		)
		(layer "In4.Cu")
	)
	(gr_line
		(start 103.716582 -295.146222)
		(end 103.716328 -295.145968)
		(stroke
			(width 0.05715)
			(type default)
		)
		(layer "In4.Cu")
	)
	(gr_arc
		(start 103.808276 -289.79876)
		(mid 103.807132 -289.799394)
		(end 103.80599 -289.80003)
		(stroke
			(width 0.05715)
			(type default)
		)
		(layer "In4.Cu")
	)
	(gr_line
		(start 103.820976 -355.567742)
		(end 103.82123 -355.567996)
		(stroke
			(width 0.07112)
			(type default)
		)
		(layer "In4.Cu")
	)
	(gr_line
		(start 103.91902 -291.096192)
		(end 104.001824 -291.178996)
		(stroke
			(width 0.05715)
			(type default)
		)
		(layer "In4.Cu")
	)
	(gr_line
		(start 103.91902 -289.47618)
		(end 103.988362 -289.545522)
		(stroke
			(width 0.05715)
			(type default)
		)
		(layer "In4.Cu")
	)
	(gr_line
		(start 103.91902 -287.856422)
		(end 104.001824 -287.939226)
		(stroke
			(width 0.05715)
			(type default)
		)
		(layer "In4.Cu")
	)
	(gr_line
		(start 103.950262 -370.543836)
		(end 103.560372 -371.126766)
		(stroke
			(width 0.07112)
			(type default)
		)
		(layer "In4.Cu")
	)
	(gr_line
		(start 103.98506 -371.245638)
		(end 103.796592 -371.28323)
		(stroke
			(width 0.07112)
			(type default)
		)
		(layer "In4.Cu")
	)
	(gr_arc
		(start 104.001824 -291.178996)
		(mid 104.003617 -291.190318)
		(end 104.005634 -291.201602)
		(stroke
			(width 0.05715)
			(type default)
		)
		(layer "In4.Cu")
	)
	(gr_arc
		(start 104.001824 -287.939226)
		(mid 104.003615 -287.950548)
		(end 104.005634 -287.961832)
		(stroke
			(width 0.05715)
			(type default)
		)
		(layer "In4.Cu")
	)
	(gr_line
		(start 104.026716 -296.07891)
		(end 104.026716 -296.107358)
		(stroke
			(width 0.05715)
			(type default)
		)
		(layer "In4.Cu")
	)
	(gr_line
		(start 104.072436 -296.03319)
		(end 104.026716 -296.07891)
		(stroke
			(width 0.05715)
			(type default)
		)
		(layer "In4.Cu")
	)
	(gr_line
		(start 104.096312 -380.069598)
		(end 103.805482 -380.360428)
		(stroke
			(width 0.07112)
			(type default)
		)
		(layer "In4.Cu")
	)
	(gr_line
		(start 104.096312 -379.787658)
		(end 103.805482 -379.496828)
		(stroke
			(width 0.07112)
			(type default)
		)
		(layer "In4.Cu")
	)
	(gr_arc
		(start 104.176576 -289.581844)
		(mid 104.178598 -289.570433)
		(end 104.180386 -289.558984)
		(stroke
			(width 0.05715)
			(type default)
		)
		(layer "In4.Cu")
	)
	(gr_line
		(start 104.185212 -370.701824)
		(end 104.22255 -370.8908)
		(stroke
			(width 0.07112)
			(type default)
		)
		(layer "In4.Cu")
	)
	(gr_line
		(start 104.22255 -370.8908)
		(end 103.98506 -371.245638)
		(stroke
			(width 0.07112)
			(type default)
		)
		(layer "In4.Cu")
	)
	(gr_arc
		(start 104.229408 -288.31413)
		(mid 104.234216 -288.317585)
		(end 104.23906 -288.320988)
		(stroke
			(width 0.05715)
			(type default)
		)
		(layer "In4.Cu")
	)
	(gr_arc
		(start 104.230932 -291.55517)
		(mid 104.234984 -291.557982)
		(end 104.23906 -291.560758)
		(stroke
			(width 0.05715)
			(type default)
		)
		(layer "In4.Cu")
	)
	(gr_line
		(start 104.23906 -291.560758)
		(end 104.245918 -291.564822)
		(stroke
			(width 0.05715)
			(type default)
		)
		(layer "In4.Cu")
	)
	(gr_line
		(start 104.23906 -288.320988)
		(end 104.241092 -288.322512)
		(stroke
			(width 0.05715)
			(type default)
		)
		(layer "In4.Cu")
	)
	(gr_line
		(start 104.241092 -288.322512)
		(end 104.245918 -288.325306)
		(stroke
			(width 0.05715)
			(type default)
		)
		(layer "In4.Cu")
	)
	(gr_line
		(start 104.245918 -291.564822)
		(end 104.24668 -291.56533)
		(stroke
			(width 0.05715)
			(type default)
		)
		(layer "In4.Cu")
	)
	(gr_line
		(start 104.24668 -291.56533)
		(end 104.247442 -291.565838)
		(stroke
			(width 0.05715)
			(type default)
		)
		(layer "In4.Cu")
	)
	(gr_line
		(start 104.262936 -296.03319)
		(end 104.308656 -296.07891)
		(stroke
			(width 0.05715)
			(type default)
		)
		(layer "In4.Cu")
	)
	(gr_line
		(start 104.26319 -291.096192)
		(end 104.193848 -291.165534)
		(stroke
			(width 0.05715)
			(type default)
		)
		(layer "In4.Cu")
	)
	(gr_line
		(start 104.26319 -289.47618)
		(end 104.180386 -289.558984)
		(stroke
			(width 0.05715)
			(type default)
		)
		(layer "In4.Cu")
	)
	(gr_line
		(start 104.26319 -287.856422)
		(end 104.193848 -287.925764)
		(stroke
			(width 0.05715)
			(type default)
		)
		(layer "In4.Cu")
	)
	(gr_line
		(start 104.308656 -296.07891)
		(end 104.308656 -296.107358)
		(stroke
			(width 0.05715)
			(type default)
		)
		(layer "In4.Cu")
	)
	(gr_line
		(start 104.373426 -288.178494)
		(end 104.373934 -288.178748)
		(stroke
			(width 0.05715)
			(type default)
		)
		(layer "In4.Cu")
	)
	(gr_line
		(start 104.561132 -291.096192)
		(end 104.26319 -291.096192)
		(stroke
			(width 0.05715)
			(type default)
		)
		(layer "In4.Cu")
	)
	(gr_line
		(start 104.561132 -289.47618)
		(end 104.26319 -289.47618)
		(stroke
			(width 0.05715)
			(type default)
		)
		(layer "In4.Cu")
	)
	(gr_line
		(start 104.561132 -287.856422)
		(end 104.26319 -287.856422)
		(stroke
			(width 0.05715)
			(type default)
		)
		(layer "In4.Cu")
	)
	(gr_line
		(start 104.577388 -369.606068)
		(end 104.187498 -370.189252)
		(stroke
			(width 0.07112)
			(type default)
		)
		(layer "In4.Cu")
	)
	(gr_line
		(start 104.612186 -370.308124)
		(end 104.423464 -370.345716)
		(stroke
			(width 0.07112)
			(type default)
		)
		(layer "In4.Cu")
	)
	(gr_line
		(start 104.652572 -291.869876)
		(end 104.652826 -291.8714)
		(stroke
			(width 0.05715)
			(type default)
		)
		(layer "In4.Cu")
	)
	(gr_line
		(start 104.656382 -291.91458)
		(end 104.656382 -291.91585)
		(stroke
			(width 0.05715)
			(type default)
		)
		(layer "In4.Cu")
	)
	(gr_arc
		(start 104.701086 -289.125152)
		(mid 104.705011 -289.127963)
		(end 104.70896 -289.13074)
		(stroke
			(width 0.05715)
			(type default)
		)
		(layer "In4.Cu")
	)
	(gr_line
		(start 104.70896 -289.13074)
		(end 104.715818 -289.134804)
		(stroke
			(width 0.05715)
			(type default)
		)
		(layer "In4.Cu")
	)
	(gr_line
		(start 104.715818 -289.134804)
		(end 104.71658 -289.135312)
		(stroke
			(width 0.05715)
			(type default)
		)
		(layer "In4.Cu")
	)
	(gr_line
		(start 104.71658 -289.135312)
		(end 104.717596 -289.13582)
		(stroke
			(width 0.05715)
			(type default)
		)
		(layer "In4.Cu")
	)
	(gr_line
		(start 104.727502 -293.050722)
		(end 104.72674 -293.05123)
		(stroke
			(width 0.05715)
			(type default)
		)
		(layer "In4.Cu")
	)
	(gr_line
		(start 104.74198 -289.150044)
		(end 104.748076 -289.1536)
		(stroke
			(width 0.05715)
			(type default)
		)
		(layer "In4.Cu")
	)
	(gr_line
		(start 104.748076 -289.1536)
		(end 104.748076 -289.153346)
		(stroke
			(width 0.05715)
			(type default)
		)
		(layer "In4.Cu")
	)
	(gr_line
		(start 104.748076 -289.153346)
		(end 104.751632 -289.155124)
		(stroke
			(width 0.05715)
			(type default)
		)
		(layer "In4.Cu")
	)
	(gr_line
		(start 104.812338 -369.76431)
		(end 104.849676 -369.953286)
		(stroke
			(width 0.07112)
			(type default)
		)
		(layer "In4.Cu")
	)
	(gr_line
		(start 104.822244 -293.836344)
		(end 104.822752 -293.836344)
		(stroke
			(width 0.05715)
			(type default)
		)
		(layer "In4.Cu")
	)
	(gr_line
		(start 104.822752 -293.216076)
		(end 104.822498 -293.216076)
		(stroke
			(width 0.05715)
			(type default)
		)
		(layer "In4.Cu")
	)
	(gr_line
		(start 104.82326 -293.215822)
		(end 104.822752 -293.216076)
		(stroke
			(width 0.05715)
			(type default)
		)
		(layer "In4.Cu")
	)
	(gr_line
		(start 104.849676 -369.953286)
		(end 104.612186 -370.308124)
		(stroke
			(width 0.07112)
			(type default)
		)
		(layer "In4.Cu")
	)
	(gr_line
		(start 104.87279 -293.865554)
		(end 104.882442 -293.871142)
		(stroke
			(width 0.05715)
			(type default)
		)
		(layer "In4.Cu")
	)
	(gr_arc
		(start 104.882442 -293.871142)
		(mid 104.882823 -293.871396)
		(end 104.883204 -293.87165)
		(stroke
			(width 0.05715)
			(type default)
		)
		(layer "In4.Cu")
	)
	(gr_line
		(start 104.883204 -293.87165)
		(end 104.885236 -293.873174)
		(stroke
			(width 0.05715)
			(type default)
		)
		(layer "In4.Cu")
	)
	(gr_arc
		(start 104.885236 -293.873174)
		(mid 104.885617 -293.873428)
		(end 104.885998 -293.873682)
		(stroke
			(width 0.05715)
			(type default)
		)
		(layer "In4.Cu")
	)
	(gr_line
		(start 104.97185 -296.07891)
		(end 104.97185 -296.107358)
		(stroke
			(width 0.05715)
			(type default)
		)
		(layer "In4.Cu")
	)
	(gr_line
		(start 105.01757 -296.03319)
		(end 104.97185 -296.07891)
		(stroke
			(width 0.05715)
			(type default)
		)
		(layer "In4.Cu")
	)
	(gr_arc
		(start 105.206546 -291.577014)
		(mid 105.208702 -291.578289)
		(end 105.210864 -291.579554)
		(stroke
			(width 0.05715)
			(type default)
		)
		(layer "In4.Cu")
	)
	(gr_line
		(start 105.20807 -296.03319)
		(end 105.25379 -296.07891)
		(stroke
			(width 0.05715)
			(type default)
		)
		(layer "In4.Cu")
	)
	(gr_line
		(start 105.217722 -291.583618)
		(end 105.217976 -291.583618)
		(stroke
			(width 0.05715)
			(type default)
		)
		(layer "In4.Cu")
	)
	(gr_line
		(start 105.217976 -290.608766)
		(end 105.217722 -290.60902)
		(stroke
			(width 0.05715)
			(type default)
		)
		(layer "In4.Cu")
	)
	(gr_line
		(start 105.22585 -291.58819)
		(end 105.226612 -291.588444)
		(stroke
			(width 0.05715)
			(type default)
		)
		(layer "In4.Cu")
	)
	(gr_line
		(start 105.25379 -296.07891)
		(end 105.25379 -296.107358)
		(stroke
			(width 0.05715)
			(type default)
		)
		(layer "In4.Cu")
	)
	(gr_line
		(start 105.290112 -378.659136)
		(end 105.426002 -378.795026)
		(stroke
			(width 0.07112)
			(type default)
		)
		(layer "In4.Cu")
	)
	(gr_line
		(start 105.290112 -378.232416)
		(end 105.290112 -378.659136)
		(stroke
			(width 0.07112)
			(type default)
		)
		(layer "In4.Cu")
	)
	(gr_line
		(start 105.290112 -377.531376)
		(end 105.426002 -377.667266)
		(stroke
			(width 0.07112)
			(type default)
		)
		(layer "In4.Cu")
	)
	(gr_line
		(start 105.290112 -377.104656)
		(end 105.290112 -377.531376)
		(stroke
			(width 0.07112)
			(type default)
		)
		(layer "In4.Cu")
	)
	(gr_line
		(start 105.290112 -376.403616)
		(end 105.426002 -376.539506)
		(stroke
			(width 0.07112)
			(type default)
		)
		(layer "In4.Cu")
	)
	(gr_line
		(start 105.290112 -375.976896)
		(end 105.290112 -376.403616)
		(stroke
			(width 0.07112)
			(type default)
		)
		(layer "In4.Cu")
	)
	(gr_line
		(start 105.290112 -375.264934)
		(end 105.426002 -375.400824)
		(stroke
			(width 0.07112)
			(type default)
		)
		(layer "In4.Cu")
	)
	(gr_line
		(start 105.290112 -374.838214)
		(end 105.290112 -375.264934)
		(stroke
			(width 0.07112)
			(type default)
		)
		(layer "In4.Cu")
	)
	(gr_line
		(start 105.301288 -289.791394)
		(end 105.302558 -289.792156)
		(stroke
			(width 0.05715)
			(type default)
		)
		(layer "In4.Cu")
	)
	(gr_line
		(start 105.31348 -291.418518)
		(end 105.3211 -291.422836)
		(stroke
			(width 0.05715)
			(type default)
		)
		(layer "In4.Cu")
	)
	(gr_line
		(start 105.3211 -291.422836)
		(end 105.322624 -291.423852)
		(stroke
			(width 0.05715)
			(type default)
		)
		(layer "In4.Cu")
	)
	(gr_line
		(start 105.33507 -290.76142)
		(end 105.334816 -290.76142)
		(stroke
			(width 0.05715)
			(type default)
		)
		(layer "In4.Cu")
	)
	(gr_line
		(start 105.344976 -290.755578)
		(end 105.343452 -290.756594)
		(stroke
			(width 0.05715)
			(type default)
		)
		(layer "In4.Cu")
	)
	(gr_line
		(start 105.345738 -291.437314)
		(end 105.352342 -291.441124)
		(stroke
			(width 0.05715)
			(type default)
		)
		(layer "In4.Cu")
	)
	(gr_arc
		(start 105.352342 -291.441124)
		(mid 105.352723 -291.441378)
		(end 105.353104 -291.441632)
		(stroke
			(width 0.05715)
			(type default)
		)
		(layer "In4.Cu")
	)
	(gr_arc
		(start 105.360978 -291.44722)
		(mid 105.357053 -291.444409)
		(end 105.353104 -291.441632)
		(stroke
			(width 0.05715)
			(type default)
		)
		(layer "In4.Cu")
	)
	(gr_line
		(start 105.426002 -378.096526)
		(end 105.290112 -378.232416)
		(stroke
			(width 0.07112)
			(type default)
		)
		(layer "In4.Cu")
	)
	(gr_line
		(start 105.426002 -376.968766)
		(end 105.290112 -377.104656)
		(stroke
			(width 0.07112)
			(type default)
		)
		(layer "In4.Cu")
	)
	(gr_line
		(start 105.426002 -375.841006)
		(end 105.290112 -375.976896)
		(stroke
			(width 0.07112)
			(type default)
		)
		(layer "In4.Cu")
	)
	(gr_line
		(start 105.426002 -374.702324)
		(end 105.290112 -374.838214)
		(stroke
			(width 0.07112)
			(type default)
		)
		(layer "In4.Cu")
	)
	(gr_line
		(start 105.596436 -295.146222)
		(end 105.596182 -295.145968)
		(stroke
			(width 0.05715)
			(type default)
		)
		(layer "In4.Cu")
	)
	(gr_line
		(start 105.709212 -378.095256)
		(end 105.709212 -378.796296)
		(stroke
			(width 0.07112)
			(type default)
		)
		(layer "In4.Cu")
	)
	(gr_line
		(start 105.709212 -376.967496)
		(end 105.709212 -377.668536)
		(stroke
			(width 0.07112)
			(type default)
		)
		(layer "In4.Cu")
	)
	(gr_line
		(start 105.709212 -375.839736)
		(end 105.709212 -376.540776)
		(stroke
			(width 0.07112)
			(type default)
		)
		(layer "In4.Cu")
	)
	(gr_line
		(start 105.709212 -374.701054)
		(end 105.709212 -375.402094)
		(stroke
			(width 0.07112)
			(type default)
		)
		(layer "In4.Cu")
	)
	(gr_line
		(start 105.916984 -296.07891)
		(end 105.916984 -296.107358)
		(stroke
			(width 0.05715)
			(type default)
		)
		(layer "In4.Cu")
	)
	(gr_line
		(start 105.962704 -296.03319)
		(end 105.916984 -296.07891)
		(stroke
			(width 0.05715)
			(type default)
		)
		(layer "In4.Cu")
	)
	(gr_arc
		(start 106.11104 -291.55517)
		(mid 106.114965 -291.557981)
		(end 106.118914 -291.560758)
		(stroke
			(width 0.05715)
			(type default)
		)
		(layer "In4.Cu")
	)
	(gr_line
		(start 106.118914 -291.560758)
		(end 106.125772 -291.564822)
		(stroke
			(width 0.05715)
			(type default)
		)
		(layer "In4.Cu")
	)
	(gr_line
		(start 106.125772 -291.564822)
		(end 106.126534 -291.56533)
		(stroke
			(width 0.05715)
			(type default)
		)
		(layer "In4.Cu")
	)
	(gr_line
		(start 106.126534 -291.56533)
		(end 106.127296 -291.565838)
		(stroke
			(width 0.05715)
			(type default)
		)
		(layer "In4.Cu")
	)
	(gr_line
		(start 106.153204 -296.03319)
		(end 106.198924 -296.07891)
		(stroke
			(width 0.05715)
			(type default)
		)
		(layer "In4.Cu")
	)
	(gr_line
		(start 106.15803 -290.608766)
		(end 106.157014 -290.609274)
		(stroke
			(width 0.05715)
			(type default)
		)
		(layer "In4.Cu")
	)
	(gr_line
		(start 106.158284 -291.583872)
		(end 106.158792 -291.584126)
		(stroke
			(width 0.05715)
			(type default)
		)
		(layer "In4.Cu")
	)
	(gr_line
		(start 106.158792 -291.584126)
		(end 106.1593 -291.58438)
		(stroke
			(width 0.05715)
			(type default)
		)
		(layer "In4.Cu")
	)
	(gr_line
		(start 106.158792 -290.608258)
		(end 106.15803 -290.608766)
		(stroke
			(width 0.05715)
			(type default)
		)
		(layer "In4.Cu")
	)
	(gr_line
		(start 106.160062 -290.607496)
		(end 106.158792 -290.608258)
		(stroke
			(width 0.05715)
			(type default)
		)
		(layer "In4.Cu")
	)
	(gr_line
		(start 106.161586 -291.58565)
		(end 106.162348 -291.586158)
		(stroke
			(width 0.05715)
			(type default)
		)
		(layer "In4.Cu")
	)
	(gr_line
		(start 106.162348 -291.586158)
		(end 106.163872 -291.58692)
		(stroke
			(width 0.05715)
			(type default)
		)
		(layer "In4.Cu")
	)
	(gr_line
		(start 106.163872 -291.58692)
		(end 106.164634 -291.587428)
		(stroke
			(width 0.05715)
			(type default)
		)
		(layer "In4.Cu")
	)
	(gr_line
		(start 106.164634 -291.587428)
		(end 106.16565 -291.587936)
		(stroke
			(width 0.05715)
			(type default)
		)
		(layer "In4.Cu")
	)
	(gr_line
		(start 106.198924 -296.07891)
		(end 106.198924 -296.107358)
		(stroke
			(width 0.05715)
			(type default)
		)
		(layer "In4.Cu")
	)
	(gr_line
		(start 106.25328 -290.77412)
		(end 106.25201 -290.774882)
		(stroke
			(width 0.05715)
			(type default)
		)
		(layer "In4.Cu")
	)
	(gr_line
		(start 106.254042 -291.418772)
		(end 106.255058 -291.41928)
		(stroke
			(width 0.05715)
			(type default)
		)
		(layer "In4.Cu")
	)
	(gr_line
		(start 106.254042 -290.773612)
		(end 106.25328 -290.77412)
		(stroke
			(width 0.05715)
			(type default)
		)
		(layer "In4.Cu")
	)
	(gr_line
		(start 106.255058 -291.41928)
		(end 106.256582 -291.420296)
		(stroke
			(width 0.05715)
			(type default)
		)
		(layer "In4.Cu")
	)
	(gr_line
		(start 106.255058 -290.773104)
		(end 106.254042 -290.773612)
		(stroke
			(width 0.05715)
			(type default)
		)
		(layer "In4.Cu")
	)
	(gr_line
		(start 106.256582 -291.420296)
		(end 106.257598 -291.420804)
		(stroke
			(width 0.05715)
			(type default)
		)
		(layer "In4.Cu")
	)
	(gr_line
		(start 106.257598 -291.420804)
		(end 106.260138 -291.422328)
		(stroke
			(width 0.05715)
			(type default)
		)
		(layer "In4.Cu")
	)
	(gr_line
		(start 106.260138 -291.422328)
		(end 106.261154 -291.42309)
		(stroke
			(width 0.05715)
			(type default)
		)
		(layer "In4.Cu")
	)
	(gr_line
		(start 106.440986 -291.096192)
		(end 106.738928 -291.096192)
		(stroke
			(width 0.05715)
			(type default)
		)
		(layer "In4.Cu")
	)
	(gr_line
		(start 106.440986 -289.47618)
		(end 106.738928 -289.47618)
		(stroke
			(width 0.05715)
			(type default)
		)
		(layer "In4.Cu")
	)
	(gr_line
		(start 106.440986 -287.856422)
		(end 106.738928 -287.856422)
		(stroke
			(width 0.05715)
			(type default)
		)
		(layer "In4.Cu")
	)
	(gr_line
		(start 106.53649 -295.146222)
		(end 106.536236 -295.145968)
		(stroke
			(width 0.05715)
			(type default)
		)
		(layer "In4.Cu")
	)
	(gr_line
		(start 106.738928 -291.096192)
		(end 106.821732 -291.178996)
		(stroke
			(width 0.05715)
			(type default)
		)
		(layer "In4.Cu")
	)
	(gr_line
		(start 106.738928 -289.47618)
		(end 106.80827 -289.545522)
		(stroke
			(width 0.05715)
			(type default)
		)
		(layer "In4.Cu")
	)
	(gr_line
		(start 106.738928 -287.856422)
		(end 106.821732 -287.939226)
		(stroke
			(width 0.05715)
			(type default)
		)
		(layer "In4.Cu")
	)
	(gr_arc
		(start 106.821732 -291.178996)
		(mid 106.823525 -291.190318)
		(end 106.825542 -291.201602)
		(stroke
			(width 0.05715)
			(type default)
		)
		(layer "In4.Cu")
	)
	(gr_arc
		(start 106.821732 -287.939226)
		(mid 106.82352 -287.950676)
		(end 106.825542 -287.962086)
		(stroke
			(width 0.05715)
			(type default)
		)
		(layer "In4.Cu")
	)
	(gr_line
		(start 106.960162 -295.585134)
		(end 106.960416 -295.58488)
		(stroke
			(width 0.05715)
			(type default)
		)
		(layer "In4.Cu")
	)
	(gr_arc
		(start 106.996484 -289.581844)
		(mid 106.998506 -289.570433)
		(end 107.000294 -289.558984)
		(stroke
			(width 0.05715)
			(type default)
		)
		(layer "In4.Cu")
	)
	(gr_line
		(start 107.014264 -296.584116)
		(end 107.014264 -296.612564)
		(stroke
			(width 0.05715)
			(type default)
		)
		(layer "In4.Cu")
	)
	(gr_arc
		(start 107.05084 -291.55517)
		(mid 107.054892 -291.557982)
		(end 107.058968 -291.560758)
		(stroke
			(width 0.05715)
			(type default)
		)
		(layer "In4.Cu")
	)
	(gr_line
		(start 107.058968 -291.560758)
		(end 107.065826 -291.564822)
		(stroke
			(width 0.05715)
			(type default)
		)
		(layer "In4.Cu")
	)
	(gr_line
		(start 107.059984 -296.538396)
		(end 107.014264 -296.584116)
		(stroke
			(width 0.05715)
			(type default)
		)
		(layer "In4.Cu")
	)
	(gr_line
		(start 107.065826 -291.564822)
		(end 107.066588 -291.56533)
		(stroke
			(width 0.05715)
			(type default)
		)
		(layer "In4.Cu")
	)
	(gr_line
		(start 107.066588 -291.56533)
		(end 107.06735 -291.565838)
		(stroke
			(width 0.05715)
			(type default)
		)
		(layer "In4.Cu")
	)
	(gr_line
		(start 107.083098 -291.096192)
		(end 107.013756 -291.165534)
		(stroke
			(width 0.05715)
			(type default)
		)
		(layer "In4.Cu")
	)
	(gr_line
		(start 107.083098 -289.47618)
		(end 107.000294 -289.558984)
		(stroke
			(width 0.05715)
			(type default)
		)
		(layer "In4.Cu")
	)
	(gr_line
		(start 107.083098 -287.856422)
		(end 107.013756 -287.925764)
		(stroke
			(width 0.05715)
			(type default)
		)
		(layer "In4.Cu")
	)
	(gr_line
		(start 107.098338 -291.583872)
		(end 107.098846 -291.584126)
		(stroke
			(width 0.05715)
			(type default)
		)
		(layer "In4.Cu")
	)
	(gr_line
		(start 107.098846 -291.584126)
		(end 107.10164 -291.58565)
		(stroke
			(width 0.05715)
			(type default)
		)
		(layer "In4.Cu")
	)
	(gr_arc
		(start 107.0991 -295.469056)
		(mid 107.088077 -295.474841)
		(end 107.077256 -295.480994)
		(stroke
			(width 0.05715)
			(type default)
		)
		(layer "In4.Cu")
	)
	(gr_line
		(start 107.121706 -295.455086)
		(end 107.116626 -295.458896)
		(stroke
			(width 0.05715)
			(type default)
		)
		(layer "In4.Cu")
	)
	(gr_line
		(start 107.122468 -295.454578)
		(end 107.121706 -295.455086)
		(stroke
			(width 0.05715)
			(type default)
		)
		(layer "In4.Cu")
	)
	(gr_arc
		(start 107.168188 -295.648634)
		(mid 107.167425 -295.64914)
		(end 107.166664 -295.64965)
		(stroke
			(width 0.05715)
			(type default)
		)
		(layer "In4.Cu")
	)
	(gr_line
		(start 107.17784 -295.64711)
		(end 107.174538 -295.646348)
		(stroke
			(width 0.05715)
			(type default)
		)
		(layer "In4.Cu")
	)
	(gr_line
		(start 107.17911 -295.646348)
		(end 107.17784 -295.64711)
		(stroke
			(width 0.05715)
			(type default)
		)
		(layer "In4.Cu")
	)
	(gr_line
		(start 107.211114 -295.625012)
		(end 107.17911 -295.646348)
		(stroke
			(width 0.05715)
			(type default)
		)
		(layer "In4.Cu")
	)
	(gr_line
		(start 107.222544 -295.617392)
		(end 107.221528 -295.618154)
		(stroke
			(width 0.05715)
			(type default)
		)
		(layer "In4.Cu")
	)
	(gr_line
		(start 107.22864 -295.613836)
		(end 107.222544 -295.617392)
		(stroke
			(width 0.05715)
			(type default)
		)
		(layer "In4.Cu")
	)
	(gr_line
		(start 107.228894 -295.613582)
		(end 107.22864 -295.613836)
		(stroke
			(width 0.05715)
			(type default)
		)
		(layer "In4.Cu")
	)
	(gr_line
		(start 107.230164 -295.61282)
		(end 107.228894 -295.613582)
		(stroke
			(width 0.05715)
			(type default)
		)
		(layer "In4.Cu")
	)
	(gr_line
		(start 107.250484 -296.538396)
		(end 107.296204 -296.584116)
		(stroke
			(width 0.05715)
			(type default)
		)
		(layer "In4.Cu")
	)
	(gr_line
		(start 107.28579 -291.912802)
		(end 107.28579 -291.907214)
		(stroke
			(width 0.05715)
			(type default)
		)
		(layer "In4.Cu")
	)
	(gr_arc
		(start 107.28579 -291.912802)
		(mid 107.285914 -291.914707)
		(end 107.286044 -291.916612)
		(stroke
			(width 0.05715)
			(type default)
		)
		(layer "In4.Cu")
	)
	(gr_line
		(start 107.296204 -296.584116)
		(end 107.296204 -296.612564)
		(stroke
			(width 0.05715)
			(type default)
		)
		(layer "In4.Cu")
	)
	(gr_line
		(start 107.38104 -291.096192)
		(end 107.083098 -291.096192)
		(stroke
			(width 0.05715)
			(type default)
		)
		(layer "In4.Cu")
	)
	(gr_line
		(start 107.38104 -289.47618)
		(end 107.083098 -289.47618)
		(stroke
			(width 0.05715)
			(type default)
		)
		(layer "In4.Cu")
	)
	(gr_line
		(start 107.38104 -287.856422)
		(end 107.083098 -287.856422)
		(stroke
			(width 0.05715)
			(type default)
		)
		(layer "In4.Cu")
	)
	(gr_line
		(start 107.525566 -377.9647)
		(end 107.525312 -377.9647)
		(stroke
			(width 0.07112)
			(type default)
		)
		(layer "In4.Cu")
	)
	(gr_line
		(start 107.547156 -293.050976)
		(end 107.546648 -293.05123)
		(stroke
			(width 0.05715)
			(type default)
		)
		(layer "In4.Cu")
	)
	(gr_arc
		(start 107.572302 -289.15614)
		(mid 107.571414 -289.155631)
		(end 107.570524 -289.155124)
		(stroke
			(width 0.05715)
			(type default)
		)
		(layer "In4.Cu")
	)
	(gr_line
		(start 107.60456 -294.036242)
		(end 107.606592 -294.037512)
		(stroke
			(width 0.05715)
			(type default)
		)
		(layer "In4.Cu")
	)
	(gr_line
		(start 107.642152 -293.836344)
		(end 107.64266 -293.836344)
		(stroke
			(width 0.05715)
			(type default)
		)
		(layer "In4.Cu")
	)
	(gr_line
		(start 107.663742 -288.988754)
		(end 107.665266 -288.989516)
		(stroke
			(width 0.05715)
			(type default)
		)
		(layer "In4.Cu")
	)
	(gr_line
		(start 107.692698 -293.865554)
		(end 107.70235 -293.871142)
		(stroke
			(width 0.05715)
			(type default)
		)
		(layer "In4.Cu")
	)
	(gr_arc
		(start 107.70235 -293.871142)
		(mid 107.702731 -293.871396)
		(end 107.703112 -293.87165)
		(stroke
			(width 0.05715)
			(type default)
		)
		(layer "In4.Cu")
	)
	(gr_line
		(start 107.703112 -293.87165)
		(end 107.7087 -293.875714)
		(stroke
			(width 0.05715)
			(type default)
		)
		(layer "In4.Cu")
	)
	(gr_line
		(start 107.71124 -293.877492)
		(end 107.712002 -293.878254)
		(stroke
			(width 0.05715)
			(type default)
		)
		(layer "In4.Cu")
	)
	(gr_line
		(start 107.716574 -293.881302)
		(end 107.717336 -293.882064)
		(stroke
			(width 0.05715)
			(type default)
		)
		(layer "In4.Cu")
	)
	(gr_line
		(start 107.717336 -293.882064)
		(end 107.721146 -293.885112)
		(stroke
			(width 0.05715)
			(type default)
		)
		(layer "In4.Cu")
	)
	(gr_line
		(start 107.720892 -301.83455)
		(end 107.721146 -301.834804)
		(stroke
			(width 0.07112)
			(type default)
		)
		(layer "In4.Cu")
	)
	(gr_line
		(start 108.034328 -289.96132)
		(end 108.0389 -289.964114)
		(stroke
			(width 0.05715)
			(type default)
		)
		(layer "In4.Cu")
	)
	(gr_line
		(start 108.0389 -289.964114)
		(end 108.039408 -289.964368)
		(stroke
			(width 0.05715)
			(type default)
		)
		(layer "In4.Cu")
	)
	(gr_line
		(start 108.06938 -319.792096)
		(end 108.06938 -319.791842)
		(stroke
			(width 0.07112)
			(type default)
		)
		(layer "In4.Cu")
	)
	(gr_line
		(start 108.130594 -312.799476)
		(end 108.130594 -312.79973)
		(stroke
			(width 0.07112)
			(type default)
		)
		(layer "In4.Cu")
	)
	(gr_line
		(start 108.164376 -289.81654)
		(end 108.171488 -289.820604)
		(stroke
			(width 0.05715)
			(type default)
		)
		(layer "In4.Cu")
	)
	(gr_arc
		(start 108.173012 -289.82162)
		(mid 108.17225 -289.821111)
		(end 108.171488 -289.820604)
		(stroke
			(width 0.05715)
			(type default)
		)
		(layer "In4.Cu")
	)
	(gr_arc
		(start 108.179362 -289.826192)
		(mid 108.176195 -289.823895)
		(end 108.173012 -289.82162)
		(stroke
			(width 0.05715)
			(type default)
		)
		(layer "In4.Cu")
	)
	(gr_line
		(start 108.17987 -295.529)
		(end 108.17987 -295.557448)
		(stroke
			(width 0.05715)
			(type default)
		)
		(layer "In4.Cu")
	)
	(gr_line
		(start 108.22559 -295.48328)
		(end 108.17987 -295.529)
		(stroke
			(width 0.05715)
			(type default)
		)
		(layer "In4.Cu")
	)
	(gr_line
		(start 108.35132 -320.580258)
		(end 108.35132 -320.580004)
		(stroke
			(width 0.07112)
			(type default)
		)
		(layer "In4.Cu")
	)
	(gr_line
		(start 108.41609 -295.48328)
		(end 108.46181 -295.529)
		(stroke
			(width 0.05715)
			(type default)
		)
		(layer "In4.Cu")
	)
	(gr_arc
		(start 108.461048 -293.985188)
		(mid 108.464973 -293.987999)
		(end 108.468922 -293.990776)
		(stroke
			(width 0.05715)
			(type default)
		)
		(layer "In4.Cu")
	)
	(gr_arc
		(start 108.461048 -292.365176)
		(mid 108.464973 -292.367987)
		(end 108.468922 -292.370764)
		(stroke
			(width 0.05715)
			(type default)
		)
		(layer "In4.Cu")
	)
	(gr_arc
		(start 108.461048 -290.745164)
		(mid 108.464973 -290.747975)
		(end 108.468922 -290.750752)
		(stroke
			(width 0.05715)
			(type default)
		)
		(layer "In4.Cu")
	)
	(gr_line
		(start 108.46181 -295.529)
		(end 108.46181 -295.557448)
		(stroke
			(width 0.05715)
			(type default)
		)
		(layer "In4.Cu")
	)
	(gr_arc
		(start 108.468922 -294.681656)
		(mid 108.464973 -294.684433)
		(end 108.461048 -294.687244)
		(stroke
			(width 0.05715)
			(type default)
		)
		(layer "In4.Cu")
	)
	(gr_line
		(start 108.468922 -293.990776)
		(end 108.47578 -293.99484)
		(stroke
			(width 0.05715)
			(type default)
		)
		(layer "In4.Cu")
	)
	(gr_arc
		(start 108.468922 -293.061644)
		(mid 108.464973 -293.064421)
		(end 108.461048 -293.067232)
		(stroke
			(width 0.05715)
			(type default)
		)
		(layer "In4.Cu")
	)
	(gr_line
		(start 108.468922 -292.370764)
		(end 108.47578 -292.374828)
		(stroke
			(width 0.05715)
			(type default)
		)
		(layer "In4.Cu")
	)
	(gr_arc
		(start 108.468922 -291.441632)
		(mid 108.464973 -291.444409)
		(end 108.461048 -291.44722)
		(stroke
			(width 0.05715)
			(type default)
		)
		(layer "In4.Cu")
	)
	(gr_line
		(start 108.468922 -290.750752)
		(end 108.47578 -290.754816)
		(stroke
			(width 0.05715)
			(type default)
		)
		(layer "In4.Cu")
	)
	(gr_line
		(start 108.47578 -293.99484)
		(end 108.476542 -293.995348)
		(stroke
			(width 0.05715)
			(type default)
		)
		(layer "In4.Cu")
	)
	(gr_line
		(start 108.47578 -292.374828)
		(end 108.476542 -292.375336)
		(stroke
			(width 0.05715)
			(type default)
		)
		(layer "In4.Cu")
	)
	(gr_line
		(start 108.47578 -290.754816)
		(end 108.476542 -290.755324)
		(stroke
			(width 0.05715)
			(type default)
		)
		(layer "In4.Cu")
	)
	(gr_line
		(start 108.476542 -293.995348)
		(end 108.477304 -293.995856)
		(stroke
			(width 0.05715)
			(type default)
		)
		(layer "In4.Cu")
	)
	(gr_line
		(start 108.476542 -292.375336)
		(end 108.477304 -292.375844)
		(stroke
			(width 0.05715)
			(type default)
		)
		(layer "In4.Cu")
	)
	(gr_line
		(start 108.476542 -290.755324)
		(end 108.477304 -290.755832)
		(stroke
			(width 0.05715)
			(type default)
		)
		(layer "In4.Cu")
	)
	(gr_line
		(start 108.477558 -294.676576)
		(end 108.468922 -294.681656)
		(stroke
			(width 0.05715)
			(type default)
		)
		(layer "In4.Cu")
	)
	(gr_line
		(start 108.477558 -293.056564)
		(end 108.468922 -293.061644)
		(stroke
			(width 0.05715)
			(type default)
		)
		(layer "In4.Cu")
	)
	(gr_line
		(start 108.477558 -291.436552)
		(end 108.468922 -291.441632)
		(stroke
			(width 0.05715)
			(type default)
		)
		(layer "In4.Cu")
	)
	(gr_line
		(start 108.48213 -294.673782)
		(end 108.479336 -294.67556)
		(stroke
			(width 0.05715)
			(type default)
		)
		(layer "In4.Cu")
	)
	(gr_line
		(start 108.48213 -293.05377)
		(end 108.479336 -293.055548)
		(stroke
			(width 0.05715)
			(type default)
		)
		(layer "In4.Cu")
	)
	(gr_line
		(start 108.48213 -291.433758)
		(end 108.479336 -291.435536)
		(stroke
			(width 0.05715)
			(type default)
		)
		(layer "In4.Cu")
	)
	(gr_line
		(start 108.490004 -294.66921)
		(end 108.489242 -294.669718)
		(stroke
			(width 0.05715)
			(type default)
		)
		(layer "In4.Cu")
	)
	(gr_line
		(start 108.490004 -293.049198)
		(end 108.489242 -293.049706)
		(stroke
			(width 0.05715)
			(type default)
		)
		(layer "In4.Cu")
	)
	(gr_line
		(start 108.490004 -291.429186)
		(end 108.489242 -291.429694)
		(stroke
			(width 0.05715)
			(type default)
		)
		(layer "In4.Cu")
	)
	(gr_line
		(start 108.491528 -294.668194)
		(end 108.490004 -294.66921)
		(stroke
			(width 0.05715)
			(type default)
		)
		(layer "In4.Cu")
	)
	(gr_line
		(start 108.491528 -293.048182)
		(end 108.490004 -293.049198)
		(stroke
			(width 0.05715)
			(type default)
		)
		(layer "In4.Cu")
	)
	(gr_line
		(start 108.491528 -291.42817)
		(end 108.490004 -291.429186)
		(stroke
			(width 0.05715)
			(type default)
		)
		(layer "In4.Cu")
	)
	(gr_line
		(start 108.494322 -294.66667)
		(end 108.493052 -294.667432)
		(stroke
			(width 0.05715)
			(type default)
		)
		(layer "In4.Cu")
	)
	(gr_line
		(start 108.494322 -293.046658)
		(end 108.493052 -293.04742)
		(stroke
			(width 0.05715)
			(type default)
		)
		(layer "In4.Cu")
	)
	(gr_line
		(start 108.494322 -291.426646)
		(end 108.493052 -291.427408)
		(stroke
			(width 0.05715)
			(type default)
		)
		(layer "In4.Cu")
	)
	(gr_line
		(start 108.495084 -294.666162)
		(end 108.494322 -294.66667)
		(stroke
			(width 0.05715)
			(type default)
		)
		(layer "In4.Cu")
	)
	(gr_line
		(start 108.495084 -293.04615)
		(end 108.494322 -293.046658)
		(stroke
			(width 0.05715)
			(type default)
		)
		(layer "In4.Cu")
	)
	(gr_line
		(start 108.495084 -291.426138)
		(end 108.494322 -291.426646)
		(stroke
			(width 0.05715)
			(type default)
		)
		(layer "In4.Cu")
	)
	(gr_line
		(start 108.496354 -294.6654)
		(end 108.495084 -294.666162)
		(stroke
			(width 0.05715)
			(type default)
		)
		(layer "In4.Cu")
	)
	(gr_line
		(start 108.496354 -293.045388)
		(end 108.495084 -293.04615)
		(stroke
			(width 0.05715)
			(type default)
		)
		(layer "In4.Cu")
	)
	(gr_line
		(start 108.496354 -291.425376)
		(end 108.495084 -291.426138)
		(stroke
			(width 0.05715)
			(type default)
		)
		(layer "In4.Cu")
	)
	(gr_line
		(start 108.503212 -294.66159)
		(end 108.502196 -294.662098)
		(stroke
			(width 0.05715)
			(type default)
		)
		(layer "In4.Cu")
	)
	(gr_line
		(start 108.503212 -293.041578)
		(end 108.502196 -293.042086)
		(stroke
			(width 0.05715)
			(type default)
		)
		(layer "In4.Cu")
	)
	(gr_line
		(start 108.503212 -291.421566)
		(end 108.502196 -291.422074)
		(stroke
			(width 0.05715)
			(type default)
		)
		(layer "In4.Cu")
	)
	(gr_line
		(start 108.50372 -294.661336)
		(end 108.503212 -294.66159)
		(stroke
			(width 0.05715)
			(type default)
		)
		(layer "In4.Cu")
	)
	(gr_line
		(start 108.50372 -293.041324)
		(end 108.503212 -293.041578)
		(stroke
			(width 0.05715)
			(type default)
		)
		(layer "In4.Cu")
	)
	(gr_line
		(start 108.50372 -291.421312)
		(end 108.503212 -291.421566)
		(stroke
			(width 0.05715)
			(type default)
		)
		(layer "In4.Cu")
	)
	(gr_line
		(start 108.507022 -294.659304)
		(end 108.505498 -294.66032)
		(stroke
			(width 0.05715)
			(type default)
		)
		(layer "In4.Cu")
	)
	(gr_line
		(start 108.507022 -293.039292)
		(end 108.505498 -293.040308)
		(stroke
			(width 0.05715)
			(type default)
		)
		(layer "In4.Cu")
	)
	(gr_line
		(start 108.507022 -291.41928)
		(end 108.505498 -291.420296)
		(stroke
			(width 0.05715)
			(type default)
		)
		(layer "In4.Cu")
	)
	(gr_line
		(start 108.508038 -294.658796)
		(end 108.507022 -294.659304)
		(stroke
			(width 0.05715)
			(type default)
		)
		(layer "In4.Cu")
	)
	(gr_line
		(start 108.508038 -293.038784)
		(end 108.507022 -293.039292)
		(stroke
			(width 0.05715)
			(type default)
		)
		(layer "In4.Cu")
	)
	(gr_line
		(start 108.508038 -291.418772)
		(end 108.507022 -291.41928)
		(stroke
			(width 0.05715)
			(type default)
		)
		(layer "In4.Cu")
	)
	(gr_line
		(start 108.508292 -294.01389)
		(end 108.5088 -294.014144)
		(stroke
			(width 0.05715)
			(type default)
		)
		(layer "In4.Cu")
	)
	(gr_line
		(start 108.508292 -292.393878)
		(end 108.5088 -292.394132)
		(stroke
			(width 0.05715)
			(type default)
		)
		(layer "In4.Cu")
	)
	(gr_line
		(start 108.508292 -290.773866)
		(end 108.5088 -290.77412)
		(stroke
			(width 0.05715)
			(type default)
		)
		(layer "In4.Cu")
	)
	(gr_line
		(start 108.5088 -294.658288)
		(end 108.508038 -294.658796)
		(stroke
			(width 0.05715)
			(type default)
		)
		(layer "In4.Cu")
	)
	(gr_line
		(start 108.5088 -294.014144)
		(end 108.511594 -294.015668)
		(stroke
			(width 0.05715)
			(type default)
		)
		(layer "In4.Cu")
	)
	(gr_line
		(start 108.5088 -293.038276)
		(end 108.508038 -293.038784)
		(stroke
			(width 0.05715)
			(type default)
		)
		(layer "In4.Cu")
	)
	(gr_line
		(start 108.5088 -292.394132)
		(end 108.511594 -292.395656)
		(stroke
			(width 0.05715)
			(type default)
		)
		(layer "In4.Cu")
	)
	(gr_line
		(start 108.5088 -291.418264)
		(end 108.508038 -291.418772)
		(stroke
			(width 0.05715)
			(type default)
		)
		(layer "In4.Cu")
	)
	(gr_line
		(start 108.5088 -290.77412)
		(end 108.511594 -290.775644)
		(stroke
			(width 0.05715)
			(type default)
		)
		(layer "In4.Cu")
	)
	(gr_line
		(start 108.510578 -294.657272)
		(end 108.5088 -294.658288)
		(stroke
			(width 0.05715)
			(type default)
		)
		(layer "In4.Cu")
	)
	(gr_line
		(start 108.510578 -293.03726)
		(end 108.5088 -293.038276)
		(stroke
			(width 0.05715)
			(type default)
		)
		(layer "In4.Cu")
	)
	(gr_line
		(start 108.510578 -291.417248)
		(end 108.5088 -291.418264)
		(stroke
			(width 0.05715)
			(type default)
		)
		(layer "In4.Cu")
	)
	(gr_line
		(start 108.59262 -294.8305)
		(end 108.591096 -294.831262)
		(stroke
			(width 0.05715)
			(type default)
		)
		(layer "In4.Cu")
	)
	(gr_line
		(start 108.59262 -293.210488)
		(end 108.591096 -293.21125)
		(stroke
			(width 0.05715)
			(type default)
		)
		(layer "In4.Cu")
	)
	(gr_line
		(start 108.59262 -291.590476)
		(end 108.591096 -291.591238)
		(stroke
			(width 0.05715)
			(type default)
		)
		(layer "In4.Cu")
	)
	(gr_line
		(start 108.59516 -294.828976)
		(end 108.594652 -294.82923)
		(stroke
			(width 0.05715)
			(type default)
		)
		(layer "In4.Cu")
	)
	(gr_line
		(start 108.59516 -293.208964)
		(end 108.594652 -293.209218)
		(stroke
			(width 0.05715)
			(type default)
		)
		(layer "In4.Cu")
	)
	(gr_line
		(start 108.59516 -291.588952)
		(end 108.594652 -291.589206)
		(stroke
			(width 0.05715)
			(type default)
		)
		(layer "In4.Cu")
	)
	(gr_line
		(start 108.5977 -294.827452)
		(end 108.596938 -294.82796)
		(stroke
			(width 0.05715)
			(type default)
		)
		(layer "In4.Cu")
	)
	(gr_line
		(start 108.5977 -293.20744)
		(end 108.596938 -293.207948)
		(stroke
			(width 0.05715)
			(type default)
		)
		(layer "In4.Cu")
	)
	(gr_line
		(start 108.5977 -291.587428)
		(end 108.596938 -291.587936)
		(stroke
			(width 0.05715)
			(type default)
		)
		(layer "In4.Cu")
	)
	(gr_line
		(start 108.599224 -294.826436)
		(end 108.5977 -294.827452)
		(stroke
			(width 0.05715)
			(type default)
		)
		(layer "In4.Cu")
	)
	(gr_line
		(start 108.599224 -293.206424)
		(end 108.5977 -293.20744)
		(stroke
			(width 0.05715)
			(type default)
		)
		(layer "In4.Cu")
	)
	(gr_line
		(start 108.599224 -291.586412)
		(end 108.5977 -291.587428)
		(stroke
			(width 0.05715)
			(type default)
		)
		(layer "In4.Cu")
	)
	(gr_line
		(start 108.60024 -294.825928)
		(end 108.599224 -294.826436)
		(stroke
			(width 0.05715)
			(type default)
		)
		(layer "In4.Cu")
	)
	(gr_line
		(start 108.60024 -293.205916)
		(end 108.599224 -293.206424)
		(stroke
			(width 0.05715)
			(type default)
		)
		(layer "In4.Cu")
	)
	(gr_line
		(start 108.60024 -291.585904)
		(end 108.599224 -291.586412)
		(stroke
			(width 0.05715)
			(type default)
		)
		(layer "In4.Cu")
	)
	(gr_line
		(start 108.60405 -294.823642)
		(end 108.603288 -294.82415)
		(stroke
			(width 0.05715)
			(type default)
		)
		(layer "In4.Cu")
	)
	(gr_line
		(start 108.60405 -293.84879)
		(end 108.605066 -293.849298)
		(stroke
			(width 0.05715)
			(type default)
		)
		(layer "In4.Cu")
	)
	(gr_line
		(start 108.60405 -293.20363)
		(end 108.603288 -293.204138)
		(stroke
			(width 0.05715)
			(type default)
		)
		(layer "In4.Cu")
	)
	(gr_line
		(start 108.60405 -292.228778)
		(end 108.605066 -292.229286)
		(stroke
			(width 0.05715)
			(type default)
		)
		(layer "In4.Cu")
	)
	(gr_line
		(start 108.60405 -291.583618)
		(end 108.603288 -291.584126)
		(stroke
			(width 0.05715)
			(type default)
		)
		(layer "In4.Cu")
	)
	(gr_line
		(start 108.60405 -290.608766)
		(end 108.605066 -290.609274)
		(stroke
			(width 0.05715)
			(type default)
		)
		(layer "In4.Cu")
	)
	(gr_line
		(start 108.605066 -294.823134)
		(end 108.60405 -294.823642)
		(stroke
			(width 0.05715)
			(type default)
		)
		(layer "In4.Cu")
	)
	(gr_line
		(start 108.605066 -293.849298)
		(end 108.60659 -293.850314)
		(stroke
			(width 0.05715)
			(type default)
		)
		(layer "In4.Cu")
	)
	(gr_line
		(start 108.605066 -293.203122)
		(end 108.60405 -293.20363)
		(stroke
			(width 0.05715)
			(type default)
		)
		(layer "In4.Cu")
	)
	(gr_line
		(start 108.605066 -292.229286)
		(end 108.60659 -292.230302)
		(stroke
			(width 0.05715)
			(type default)
		)
		(layer "In4.Cu")
	)
	(gr_line
		(start 108.605066 -291.58311)
		(end 108.60405 -291.583618)
		(stroke
			(width 0.05715)
			(type default)
		)
		(layer "In4.Cu")
	)
	(gr_line
		(start 108.605066 -290.609274)
		(end 108.60659 -290.61029)
		(stroke
			(width 0.05715)
			(type default)
		)
		(layer "In4.Cu")
	)
	(gr_line
		(start 108.60659 -293.850314)
		(end 108.607606 -293.850822)
		(stroke
			(width 0.05715)
			(type default)
		)
		(layer "In4.Cu")
	)
	(gr_line
		(start 108.60659 -292.230302)
		(end 108.607606 -292.23081)
		(stroke
			(width 0.05715)
			(type default)
		)
		(layer "In4.Cu")
	)
	(gr_line
		(start 108.60659 -290.61029)
		(end 108.607606 -290.610798)
		(stroke
			(width 0.05715)
			(type default)
		)
		(layer "In4.Cu")
	)
	(gr_line
		(start 108.607352 -294.82161)
		(end 108.60659 -294.822118)
		(stroke
			(width 0.05715)
			(type default)
		)
		(layer "In4.Cu")
	)
	(gr_line
		(start 108.607352 -293.201598)
		(end 108.60659 -293.202106)
		(stroke
			(width 0.05715)
			(type default)
		)
		(layer "In4.Cu")
	)
	(gr_line
		(start 108.607352 -291.581586)
		(end 108.60659 -291.582094)
		(stroke
			(width 0.05715)
			(type default)
		)
		(layer "In4.Cu")
	)
	(gr_line
		(start 108.607606 -293.850822)
		(end 108.612686 -293.85387)
		(stroke
			(width 0.05715)
			(type default)
		)
		(layer "In4.Cu")
	)
	(gr_line
		(start 108.607606 -292.23081)
		(end 108.612686 -292.233858)
		(stroke
			(width 0.05715)
			(type default)
		)
		(layer "In4.Cu")
	)
	(gr_line
		(start 108.607606 -290.610798)
		(end 108.612686 -290.613846)
		(stroke
			(width 0.05715)
			(type default)
		)
		(layer "In4.Cu")
	)
	(gr_line
		(start 108.790994 -290.286186)
		(end 109.088936 -290.286186)
		(stroke
			(width 0.05715)
			(type default)
		)
		(layer "In4.Cu")
	)
	(gr_line
		(start 108.790994 -288.666174)
		(end 109.088936 -288.666174)
		(stroke
			(width 0.05715)
			(type default)
		)
		(layer "In4.Cu")
	)
	(gr_line
		(start 108.790994 -287.046162)
		(end 109.088936 -287.046162)
		(stroke
			(width 0.05715)
			(type default)
		)
		(layer "In4.Cu")
	)
	(gr_line
		(start 109.088936 -290.286186)
		(end 109.17174 -290.36899)
		(stroke
			(width 0.05715)
			(type default)
		)
		(layer "In4.Cu")
	)
	(gr_line
		(start 109.088936 -288.666174)
		(end 109.17174 -288.748978)
		(stroke
			(width 0.05715)
			(type default)
		)
		(layer "In4.Cu")
	)
	(gr_line
		(start 109.088936 -287.046162)
		(end 109.17174 -287.128966)
		(stroke
			(width 0.05715)
			(type default)
		)
		(layer "In4.Cu")
	)
	(gr_line
		(start 109.094778 -319.992248)
		(end 109.094778 -319.991994)
		(stroke
			(width 0.07112)
			(type default)
		)
		(layer "In4.Cu")
	)
	(gr_line
		(start 109.094778 -319.991994)
		(end 109.154214 -320.064638)
		(stroke
			(width 0.07112)
			(type default)
		)
		(layer "In4.Cu")
	)
	(gr_line
		(start 109.119924 -295.529)
		(end 109.119924 -295.557448)
		(stroke
			(width 0.05715)
			(type default)
		)
		(layer "In4.Cu")
	)
	(gr_line
		(start 109.165644 -295.48328)
		(end 109.119924 -295.529)
		(stroke
			(width 0.05715)
			(type default)
		)
		(layer "In4.Cu")
	)
	(gr_arc
		(start 109.17174 -290.36899)
		(mid 109.173532 -290.380312)
		(end 109.17555 -290.391596)
		(stroke
			(width 0.05715)
			(type default)
		)
		(layer "In4.Cu")
	)
	(gr_arc
		(start 109.17174 -288.748978)
		(mid 109.173782 -288.760303)
		(end 109.176058 -288.771584)
		(stroke
			(width 0.05715)
			(type default)
		)
		(layer "In4.Cu")
	)
	(gr_arc
		(start 109.17174 -287.128966)
		(mid 109.173434 -287.13876)
		(end 109.175296 -287.148524)
		(stroke
			(width 0.05715)
			(type default)
		)
		(layer "In4.Cu")
	)
	(gr_arc
		(start 109.175296 -287.148524)
		(mid 109.175548 -287.149921)
		(end 109.175804 -287.151318)
		(stroke
			(width 0.05715)
			(type default)
		)
		(layer "In4.Cu")
	)
	(gr_line
		(start 109.31271 -319.813178)
		(end 109.3724 -319.885822)
		(stroke
			(width 0.07112)
			(type default)
		)
		(layer "In4.Cu")
	)
	(gr_line
		(start 109.356144 -295.48328)
		(end 109.401864 -295.529)
		(stroke
			(width 0.05715)
			(type default)
		)
		(layer "In4.Cu")
	)
	(gr_line
		(start 109.401864 -295.529)
		(end 109.401864 -295.557448)
		(stroke
			(width 0.05715)
			(type default)
		)
		(layer "In4.Cu")
	)
	(gr_arc
		(start 109.408976 -294.681656)
		(mid 109.405027 -294.684433)
		(end 109.401102 -294.687244)
		(stroke
			(width 0.05715)
			(type default)
		)
		(layer "In4.Cu")
	)
	(gr_line
		(start 109.413802 -294.678862)
		(end 109.408976 -294.681656)
		(stroke
			(width 0.05715)
			(type default)
		)
		(layer "In4.Cu")
	)
	(gr_line
		(start 109.41431 -294.678608)
		(end 109.413802 -294.678862)
		(stroke
			(width 0.05715)
			(type default)
		)
		(layer "In4.Cu")
	)
	(gr_line
		(start 109.421168 -294.67429)
		(end 109.41812 -294.676322)
		(stroke
			(width 0.05715)
			(type default)
		)
		(layer "In4.Cu")
	)
	(gr_arc
		(start 109.43209 -294.003984)
		(mid 109.434879 -294.00577)
		(end 109.437678 -294.00754)
		(stroke
			(width 0.05715)
			(type default)
		)
		(layer "In4.Cu")
	)
	(gr_line
		(start 109.433106 -290.286186)
		(end 109.363764 -290.355528)
		(stroke
			(width 0.05715)
			(type default)
		)
		(layer "In4.Cu")
	)
	(gr_line
		(start 109.433106 -288.666174)
		(end 109.363256 -288.736024)
		(stroke
			(width 0.05715)
			(type default)
		)
		(layer "In4.Cu")
	)
	(gr_line
		(start 109.433106 -287.046162)
		(end 109.364018 -287.11525)
		(stroke
			(width 0.05715)
			(type default)
		)
		(layer "In4.Cu")
	)
	(gr_arc
		(start 109.441742 -293.04234)
		(mid 109.439834 -293.043606)
		(end 109.437932 -293.04488)
		(stroke
			(width 0.05715)
			(type default)
		)
		(layer "In4.Cu")
	)
	(gr_line
		(start 109.448092 -293.038784)
		(end 109.447838 -293.038784)
		(stroke
			(width 0.05715)
			(type default)
		)
		(layer "In4.Cu")
	)
	(gr_line
		(start 109.44987 -294.014652)
		(end 109.450632 -294.01516)
		(stroke
			(width 0.05715)
			(type default)
		)
		(layer "In4.Cu")
	)
	(gr_line
		(start 109.452664 -293.036244)
		(end 109.450632 -293.03726)
		(stroke
			(width 0.05715)
			(type default)
		)
		(layer "In4.Cu")
	)
	(gr_line
		(start 109.453172 -291.415724)
		(end 109.448854 -291.418264)
		(stroke
			(width 0.05715)
			(type default)
		)
		(layer "In4.Cu")
	)
	(gr_line
		(start 109.499146 -290.805616)
		(end 109.499654 -290.806124)
		(stroke
			(width 0.05715)
			(type default)
		)
		(layer "In4.Cu")
	)
	(gr_line
		(start 109.543596 -293.848536)
		(end 109.545882 -293.849806)
		(stroke
			(width 0.05715)
			(type default)
		)
		(layer "In4.Cu")
	)
	(gr_line
		(start 109.544104 -291.583618)
		(end 109.543596 -291.583872)
		(stroke
			(width 0.05715)
			(type default)
		)
		(layer "In4.Cu")
	)
	(gr_line
		(start 109.545882 -293.849806)
		(end 109.54639 -293.850314)
		(stroke
			(width 0.05715)
			(type default)
		)
		(layer "In4.Cu")
	)
	(gr_arc
		(start 109.54639 -294.822372)
		(mid 109.547534 -294.821738)
		(end 109.548676 -294.821102)
		(stroke
			(width 0.05715)
			(type default)
		)
		(layer "In4.Cu")
	)
	(gr_line
		(start 109.548676 -293.200836)
		(end 109.54385 -293.203884)
		(stroke
			(width 0.05715)
			(type default)
		)
		(layer "In4.Cu")
	)
	(gr_arc
		(start 109.563408 -292.240462)
		(mid 109.563916 -292.240843)
		(end 109.564424 -292.241224)
		(stroke
			(width 0.05715)
			(type default)
		)
		(layer "In4.Cu")
	)
	(gr_line
		(start 109.731048 -290.286186)
		(end 109.433106 -290.286186)
		(stroke
			(width 0.05715)
			(type default)
		)
		(layer "In4.Cu")
	)
	(gr_line
		(start 109.731048 -288.666174)
		(end 109.433106 -288.666174)
		(stroke
			(width 0.05715)
			(type default)
		)
		(layer "In4.Cu")
	)
	(gr_line
		(start 109.731048 -287.046162)
		(end 109.433106 -287.046162)
		(stroke
			(width 0.05715)
			(type default)
		)
		(layer "In4.Cu")
	)
	(gr_arc
		(start 109.798104 -373.90705)
		(mid 109.79785 -373.906796)
		(end 109.797596 -373.906542)
		(stroke
			(width 0.07112)
			(type default)
		)
		(layer "In4.Cu")
	)
	(gr_line
		(start 109.822488 -289.440112)
		(end 109.822742 -289.441382)
		(stroke
			(width 0.05715)
			(type default)
		)
		(layer "In4.Cu")
	)
	(gr_line
		(start 109.822488 -287.819846)
		(end 109.822742 -287.821116)
		(stroke
			(width 0.05715)
			(type default)
		)
		(layer "In4.Cu")
	)
	(gr_line
		(start 109.826298 -289.484562)
		(end 109.826298 -289.485832)
		(stroke
			(width 0.05715)
			(type default)
		)
		(layer "In4.Cu")
	)
	(gr_line
		(start 109.826298 -287.864042)
		(end 109.826298 -287.86582)
		(stroke
			(width 0.05715)
			(type default)
		)
		(layer "In4.Cu")
	)
	(gr_line
		(start 110.01121 -288.177732)
		(end 110.017306 -288.181034)
		(stroke
			(width 0.05715)
			(type default)
		)
		(layer "In4.Cu")
	)
	(gr_line
		(start 110.059978 -297.179238)
		(end 110.059978 -297.880278)
		(stroke
			(width 0.07112)
			(type default)
		)
		(layer "In4.Cu")
	)
	(gr_line
		(start 110.059978 -295.529)
		(end 110.059978 -295.557448)
		(stroke
			(width 0.05715)
			(type default)
		)
		(layer "In4.Cu")
	)
	(gr_line
		(start 110.105698 -295.48328)
		(end 110.059978 -295.529)
		(stroke
			(width 0.05715)
			(type default)
		)
		(layer "In4.Cu")
	)
	(gr_line
		(start 110.296198 -295.48328)
		(end 110.341918 -295.529)
		(stroke
			(width 0.05715)
			(type default)
		)
		(layer "In4.Cu")
	)
	(gr_line
		(start 110.341918 -295.529)
		(end 110.341918 -295.557448)
		(stroke
			(width 0.05715)
			(type default)
		)
		(layer "In4.Cu")
	)
	(gr_line
		(start 110.343188 -297.180508)
		(end 110.479078 -297.316398)
		(stroke
			(width 0.07112)
			(type default)
		)
		(layer "In4.Cu")
	)
	(gr_arc
		(start 110.34903 -291.441632)
		(mid 110.345847 -291.443907)
		(end 110.34268 -291.446204)
		(stroke
			(width 0.05715)
			(type default)
		)
		(layer "In4.Cu")
	)
	(gr_arc
		(start 110.350554 -291.440616)
		(mid 110.349792 -291.441123)
		(end 110.34903 -291.441632)
		(stroke
			(width 0.05715)
			(type default)
		)
		(layer "In4.Cu")
	)
	(gr_line
		(start 110.357412 -291.436552)
		(end 110.350554 -291.440616)
		(stroke
			(width 0.05715)
			(type default)
		)
		(layer "In4.Cu")
	)
	(gr_arc
		(start 110.375446 -294.00627)
		(mid 110.377476 -294.007417)
		(end 110.37951 -294.008556)
		(stroke
			(width 0.05715)
			(type default)
		)
		(layer "In4.Cu")
	)
	(gr_line
		(start 110.38713 -290.773104)
		(end 110.387892 -290.773612)
		(stroke
			(width 0.05715)
			(type default)
		)
		(layer "In4.Cu")
	)
	(gr_line
		(start 110.387892 -294.013636)
		(end 110.388146 -294.013636)
		(stroke
			(width 0.05715)
			(type default)
		)
		(layer "In4.Cu")
	)
	(gr_line
		(start 110.387892 -289.1536)
		(end 110.388146 -289.1536)
		(stroke
			(width 0.05715)
			(type default)
		)
		(layer "In4.Cu")
	)
	(gr_line
		(start 110.388146 -293.038784)
		(end 110.387892 -293.039038)
		(stroke
			(width 0.05715)
			(type default)
		)
		(layer "In4.Cu")
	)
	(gr_line
		(start 110.479078 -297.743118)
		(end 110.343188 -297.879008)
		(stroke
			(width 0.07112)
			(type default)
		)
		(layer "In4.Cu")
	)
	(gr_line
		(start 110.479078 -297.316398)
		(end 110.479078 -297.743118)
		(stroke
			(width 0.07112)
			(type default)
		)
		(layer "In4.Cu")
	)
	(gr_line
		(start 110.483904 -290.608766)
		(end 110.484158 -290.60902)
		(stroke
			(width 0.05715)
			(type default)
		)
		(layer "In4.Cu")
	)
	(gr_line
		(start 110.483904 -288.988754)
		(end 110.484158 -288.989008)
		(stroke
			(width 0.05715)
			(type default)
		)
		(layer "In4.Cu")
	)
	(gr_line
		(start 110.484158 -291.583618)
		(end 110.483904 -291.583618)
		(stroke
			(width 0.05715)
			(type default)
		)
		(layer "In4.Cu")
	)
	(gr_arc
		(start 110.49254 -291.578538)
		(mid 110.494574 -291.577399)
		(end 110.496604 -291.576252)
		(stroke
			(width 0.05715)
			(type default)
		)
		(layer "In4.Cu")
	)
	(gr_line
		(start 110.505494 -293.191184)
		(end 110.50524 -293.191184)
		(stroke
			(width 0.05715)
			(type default)
		)
		(layer "In4.Cu")
	)
	(gr_line
		(start 110.516162 -293.867586)
		(end 110.521496 -293.870634)
		(stroke
			(width 0.05715)
			(type default)
		)
		(layer "In4.Cu")
	)
	(gr_line
		(start 110.516416 -293.18458)
		(end 110.515654 -293.185088)
		(stroke
			(width 0.05715)
			(type default)
		)
		(layer "In4.Cu")
	)
	(gr_arc
		(start 110.52302 -293.87165)
		(mid 110.522258 -293.871141)
		(end 110.521496 -293.870634)
		(stroke
			(width 0.05715)
			(type default)
		)
		(layer "In4.Cu")
	)
	(gr_line
		(start 110.52302 -293.87165)
		(end 110.528608 -293.87546)
		(stroke
			(width 0.05715)
			(type default)
		)
		(layer "In4.Cu")
	)
	(gr_line
		(start 110.52302 -293.18077)
		(end 110.516416 -293.18458)
		(stroke
			(width 0.05715)
			(type default)
		)
		(layer "In4.Cu")
	)
	(gr_arc
		(start 110.52302 -293.18077)
		(mid 110.524164 -293.18001)
		(end 110.525306 -293.179246)
		(stroke
			(width 0.05715)
			(type default)
		)
		(layer "In4.Cu")
	)
	(gr_arc
		(start 110.526068 -293.178738)
		(mid 110.528869 -293.176715)
		(end 110.531656 -293.174674)
		(stroke
			(width 0.05715)
			(type default)
		)
		(layer "In4.Cu")
	)
	(gr_line
		(start 110.575344 -292.729158)
		(end 110.575344 -292.730174)
		(stroke
			(width 0.05715)
			(type default)
		)
		(layer "In4.Cu")
	)
	(gr_arc
		(start 110.765844 -292.737286)
		(mid 110.765983 -292.73373)
		(end 110.766098 -292.730174)
		(stroke
			(width 0.05715)
			(type default)
		)
		(layer "In4.Cu")
	)
	(gr_line
		(start 110.766098 -292.716204)
		(end 110.766352 -292.716204)
		(stroke
			(width 0.05715)
			(type default)
		)
		(layer "In4.Cu")
	)
	(gr_line
		(start 111.199422 -290.253674)
		(end 111.199422 -290.282122)
		(stroke
			(width 0.05715)
			(type default)
		)
		(layer "In4.Cu")
	)
	(gr_line
		(start 111.245142 -290.207954)
		(end 111.199422 -290.253674)
		(stroke
			(width 0.05715)
			(type default)
		)
		(layer "In4.Cu")
	)
	(gr_line
		(start 111.435642 -290.207954)
		(end 111.481362 -290.253674)
		(stroke
			(width 0.05715)
			(type default)
		)
		(layer "In4.Cu")
	)
	(gr_line
		(start 111.481362 -290.253674)
		(end 111.481362 -290.282122)
		(stroke
			(width 0.05715)
			(type default)
		)
		(layer "In4.Cu")
	)
	(gr_line
		(start 111.512858 -379.764544)
		(end 111.438944 -379.586744)
		(stroke
			(width 0.07112)
			(type default)
		)
		(layer "In4.Cu")
	)
	(gr_line
		(start 111.869728 -350.54413)
		(end 111.869728 -350.543876)
		(stroke
			(width 0.07112)
			(type default)
		)
		(layer "In4.Cu")
	)
	(gr_line
		(start 111.90732 -379.927866)
		(end 111.512858 -379.764544)
		(stroke
			(width 0.07112)
			(type default)
		)
		(layer "In4.Cu")
	)
	(gr_line
		(start 112.08512 -379.854206)
		(end 111.90732 -379.927866)
		(stroke
			(width 0.07112)
			(type default)
		)
		(layer "In4.Cu")
	)
	(gr_line
		(start 112.19434 -379.59284)
		(end 111.546386 -379.324616)
		(stroke
			(width 0.07112)
			(type default)
		)
		(layer "In4.Cu")
	)
	(gr_line
		(start 112.554766 -380.196344)
		(end 112.48136 -380.01829)
		(stroke
			(width 0.07112)
			(type default)
		)
		(layer "In4.Cu")
	)
	(gr_line
		(start 112.652302 -377.354338)
		(end 112.652302 -377.16206)
		(stroke
			(width 0.07112)
			(type default)
		)
		(layer "In4.Cu")
	)
	(gr_line
		(start 112.949228 -380.359666)
		(end 112.554766 -380.196344)
		(stroke
			(width 0.07112)
			(type default)
		)
		(layer "In4.Cu")
	)
	(gr_line
		(start 112.954308 -377.656344)
		(end 112.652302 -377.354338)
		(stroke
			(width 0.07112)
			(type default)
		)
		(layer "In4.Cu")
	)
	(gr_line
		(start 112.956594 -296.000932)
		(end 112.95634 -296.001186)
		(stroke
			(width 0.07112)
			(type default)
		)
		(layer "In4.Cu")
	)
	(gr_line
		(start 113.021618 -289.54857)
		(end 113.041684 -289.528504)
		(stroke
			(width 0.05715)
			(type default)
		)
		(layer "In4.Cu")
	)
	(gr_line
		(start 113.021618 -289.548316)
		(end 113.021618 -289.54857)
		(stroke
			(width 0.05715)
			(type default)
		)
		(layer "In4.Cu")
	)
	(gr_line
		(start 113.041684 -289.528504)
		(end 113.105692 -289.528504)
		(stroke
			(width 0.05715)
			(type default)
		)
		(layer "In4.Cu")
	)
	(gr_line
		(start 113.105692 -289.528504)
		(end 113.1062 -289.527996)
		(stroke
			(width 0.05715)
			(type default)
		)
		(layer "In4.Cu")
	)
	(gr_line
		(start 113.127536 -380.286006)
		(end 112.949228 -380.359666)
		(stroke
			(width 0.07112)
			(type default)
		)
		(layer "In4.Cu")
	)
	(gr_line
		(start 113.146586 -377.656344)
		(end 112.954308 -377.656344)
		(stroke
			(width 0.07112)
			(type default)
		)
		(layer "In4.Cu")
	)
	(gr_line
		(start 113.221008 -289.747706)
		(end 113.241074 -289.72764)
		(stroke
			(width 0.05715)
			(type default)
		)
		(layer "In4.Cu")
	)
	(gr_line
		(start 113.236502 -380.02464)
		(end 112.588294 -379.756162)
		(stroke
			(width 0.07112)
			(type default)
		)
		(layer "In4.Cu")
	)
	(gr_line
		(start 113.241074 -289.72764)
		(end 113.241074 -289.663886)
		(stroke
			(width 0.05715)
			(type default)
		)
		(layer "In4.Cu")
	)
	(gr_line
		(start 113.347754 -377.456954)
		(end 112.851946 -376.961146)
		(stroke
			(width 0.07112)
			(type default)
		)
		(layer "In4.Cu")
	)
	(gr_line
		(start 113.449862 -378.151898)
		(end 113.449862 -377.95962)
		(stroke
			(width 0.07112)
			(type default)
		)
		(layer "In4.Cu")
	)
	(gr_line
		(start 113.671604 -288.989008)
		(end 113.671858 -288.988754)
		(stroke
			(width 0.05715)
			(type default)
		)
		(layer "In4.Cu")
	)
	(gr_line
		(start 113.751868 -378.453904)
		(end 113.449862 -378.151898)
		(stroke
			(width 0.07112)
			(type default)
		)
		(layer "In4.Cu")
	)
	(gr_line
		(start 113.755932 -352.11639)
		(end 113.755932 -352.116136)
		(stroke
			(width 0.07112)
			(type default)
		)
		(layer "In4.Cu")
	)
	(gr_line
		(start 113.846102 -360.929682)
		(end 113.845594 -360.929936)
		(stroke
			(width 0.07112)
			(type default)
		)
		(layer "In4.Cu")
	)
	(gr_line
		(start 113.85931 -288.666174)
		(end 113.859564 -288.666174)
		(stroke
			(width 0.05715)
			(type default)
		)
		(layer "In4.Cu")
	)
	(gr_line
		(start 113.944146 -378.453904)
		(end 113.751868 -378.453904)
		(stroke
			(width 0.07112)
			(type default)
		)
		(layer "In4.Cu")
	)
	(gr_arc
		(start 114.094768 -290.745164)
		(mid 114.098693 -290.747975)
		(end 114.102642 -290.750752)
		(stroke
			(width 0.05715)
			(type default)
		)
		(layer "In4.Cu")
	)
	(gr_arc
		(start 114.10061 -288.203132)
		(mid 114.096277 -288.206159)
		(end 114.091974 -288.209228)
		(stroke
			(width 0.05715)
			(type default)
		)
		(layer "In4.Cu")
	)
	(gr_line
		(start 114.10061 -288.203132)
		(end 114.102134 -288.202116)
		(stroke
			(width 0.05715)
			(type default)
		)
		(layer "In4.Cu")
	)
	(gr_line
		(start 114.102134 -288.202116)
		(end 114.103658 -288.201354)
		(stroke
			(width 0.05715)
			(type default)
		)
		(layer "In4.Cu")
	)
	(gr_arc
		(start 114.103404 -290.75126)
		(mid 114.103023 -290.751006)
		(end 114.102642 -290.750752)
		(stroke
			(width 0.05715)
			(type default)
		)
		(layer "In4.Cu")
	)
	(gr_line
		(start 114.103658 -288.201354)
		(end 114.10442 -288.200338)
		(stroke
			(width 0.05715)
			(type default)
		)
		(layer "In4.Cu")
	)
	(gr_line
		(start 114.10442 -288.200338)
		(end 114.107976 -288.198306)
		(stroke
			(width 0.05715)
			(type default)
		)
		(layer "In4.Cu")
	)
	(gr_line
		(start 114.107976 -288.198306)
		(end 114.10823 -288.198052)
		(stroke
			(width 0.05715)
			(type default)
		)
		(layer "In4.Cu")
	)
	(gr_line
		(start 114.111024 -290.755578)
		(end 114.103404 -290.75126)
		(stroke
			(width 0.05715)
			(type default)
		)
		(layer "In4.Cu")
	)
	(gr_line
		(start 114.118136 -376.856752)
		(end 114.118136 -376.664474)
		(stroke
			(width 0.07112)
			(type default)
		)
		(layer "In4.Cu")
	)
	(gr_line
		(start 114.141758 -288.178494)
		(end 114.142774 -288.177986)
		(stroke
			(width 0.05715)
			(type default)
		)
		(layer "In4.Cu")
	)
	(gr_line
		(start 114.145314 -378.254768)
		(end 113.649506 -377.758706)
		(stroke
			(width 0.07112)
			(type default)
		)
		(layer "In4.Cu")
	)
	(gr_line
		(start 114.200686 -378.309886)
		(end 114.145314 -378.254768)
		(stroke
			(width 0.07112)
			(type default)
		)
		(layer "In4.Cu")
	)
	(gr_line
		(start 114.23777 -288.343848)
		(end 114.238278 -288.343086)
		(stroke
			(width 0.05715)
			(type default)
		)
		(layer "In4.Cu")
	)
	(gr_arc
		(start 114.24158 -289.96132)
		(mid 114.242469 -289.960813)
		(end 114.243358 -289.960304)
		(stroke
			(width 0.05715)
			(type default)
		)
		(layer "In4.Cu")
	)
	(gr_line
		(start 114.247422 -378.949712)
		(end 114.247422 -378.75718)
		(stroke
			(width 0.07112)
			(type default)
		)
		(layer "In4.Cu")
	)
	(gr_line
		(start 114.283744 -296.358564)
		(end 114.283744 -296.330116)
		(stroke
			(width 0.05715)
			(type default)
		)
		(layer "In4.Cu")
	)
	(gr_line
		(start 114.283744 -296.330116)
		(end 114.329464 -296.284396)
		(stroke
			(width 0.05715)
			(type default)
		)
		(layer "In4.Cu")
	)
	(gr_line
		(start 114.329972 -287.852866)
		(end 114.329972 -287.852612)
		(stroke
			(width 0.05715)
			(type default)
		)
		(layer "In4.Cu")
	)
	(gr_line
		(start 114.393472 -380.503684)
		(end 114.392964 -380.50343)
		(stroke
			(width 0.07112)
			(type default)
		)
		(layer "In4.Cu")
	)
	(gr_line
		(start 114.39525 -287.590484)
		(end 114.395504 -287.589976)
		(stroke
			(width 0.05715)
			(type default)
		)
		(layer "In4.Cu")
	)
	(gr_line
		(start 114.420142 -377.158758)
		(end 114.118136 -376.856752)
		(stroke
			(width 0.07112)
			(type default)
		)
		(layer "In4.Cu")
	)
	(gr_line
		(start 114.520472 -287.853882)
		(end 114.520472 -287.852866)
		(stroke
			(width 0.05715)
			(type default)
		)
		(layer "In4.Cu")
	)
	(gr_arc
		(start 114.520472 -287.852866)
		(mid 114.520472 -287.852612)
		(end 114.520472 -287.852358)
		(stroke
			(width 0.05715)
			(type default)
		)
		(layer "In4.Cu")
	)
	(gr_line
		(start 114.520726 -291.101272)
		(end 114.52098 -291.101272)
		(stroke
			(width 0.05715)
			(type default)
		)
		(layer "In4.Cu")
	)
	(gr_line
		(start 114.549428 -379.251718)
		(end 114.247422 -378.949712)
		(stroke
			(width 0.07112)
			(type default)
		)
		(layer "In4.Cu")
	)
	(gr_line
		(start 114.565684 -296.358564)
		(end 114.565684 -296.330116)
		(stroke
			(width 0.05715)
			(type default)
		)
		(layer "In4.Cu")
	)
	(gr_line
		(start 114.565684 -296.330116)
		(end 114.519964 -296.284396)
		(stroke
			(width 0.05715)
			(type default)
		)
		(layer "In4.Cu")
	)
	(gr_line
		(start 114.6048 -390.8298)
		(end 114.522504 -390.912096)
		(stroke
			(width 0.07112)
			(type default)
		)
		(layer "In4.Cu")
	)
	(gr_line
		(start 114.605816 -292.232334)
		(end 114.609118 -292.230302)
		(stroke
			(width 0.05715)
			(type default)
		)
		(layer "In4.Cu")
	)
	(gr_line
		(start 114.60607 -295.472104)
		(end 114.60734 -295.471342)
		(stroke
			(width 0.05715)
			(type default)
		)
		(layer "In4.Cu")
	)
	(gr_line
		(start 114.60734 -295.471342)
		(end 114.609118 -295.470326)
		(stroke
			(width 0.05715)
			(type default)
		)
		(layer "In4.Cu")
	)
	(gr_line
		(start 114.608864 -288.990278)
		(end 114.61115 -288.989008)
		(stroke
			(width 0.05715)
			(type default)
		)
		(layer "In4.Cu")
	)
	(gr_line
		(start 114.609118 -295.470326)
		(end 114.610642 -295.46931)
		(stroke
			(width 0.05715)
			(type default)
		)
		(layer "In4.Cu")
	)
	(gr_line
		(start 114.609118 -292.230302)
		(end 114.610642 -292.229286)
		(stroke
			(width 0.05715)
			(type default)
		)
		(layer "In4.Cu")
	)
	(gr_line
		(start 114.610642 -295.46931)
		(end 114.611658 -295.468802)
		(stroke
			(width 0.05715)
			(type default)
		)
		(layer "In4.Cu")
	)
	(gr_line
		(start 114.610642 -292.229286)
		(end 114.611658 -292.228778)
		(stroke
			(width 0.05715)
			(type default)
		)
		(layer "In4.Cu")
	)
	(gr_line
		(start 114.610642 -291.58311)
		(end 114.60988 -291.582602)
		(stroke
			(width 0.05715)
			(type default)
		)
		(layer "In4.Cu")
	)
	(gr_line
		(start 114.611658 -295.468802)
		(end 114.612674 -295.468294)
		(stroke
			(width 0.05715)
			(type default)
		)
		(layer "In4.Cu")
	)
	(gr_line
		(start 114.611658 -293.84879)
		(end 114.612166 -293.848536)
		(stroke
			(width 0.05715)
			(type default)
		)
		(layer "In4.Cu")
	)
	(gr_line
		(start 114.611658 -292.228778)
		(end 114.612928 -292.228016)
		(stroke
			(width 0.05715)
			(type default)
		)
		(layer "In4.Cu")
	)
	(gr_line
		(start 114.611658 -291.583618)
		(end 114.610642 -291.58311)
		(stroke
			(width 0.05715)
			(type default)
		)
		(layer "In4.Cu")
	)
	(gr_line
		(start 114.61242 -377.158758)
		(end 114.420142 -377.158758)
		(stroke
			(width 0.07112)
			(type default)
		)
		(layer "In4.Cu")
	)
	(gr_line
		(start 114.61242 -294.82415)
		(end 114.611658 -294.823642)
		(stroke
			(width 0.05715)
			(type default)
		)
		(layer "In4.Cu")
	)
	(gr_line
		(start 114.61369 -293.2049)
		(end 114.61242 -293.204138)
		(stroke
			(width 0.05715)
			(type default)
		)
		(layer "In4.Cu")
	)
	(gr_line
		(start 114.6175 -294.826944)
		(end 114.61242 -294.82415)
		(stroke
			(width 0.05715)
			(type default)
		)
		(layer "In4.Cu")
	)
	(gr_arc
		(start 114.63909 -287.594294)
		(mid 114.638709 -287.594547)
		(end 114.638328 -287.594802)
		(stroke
			(width 0.05715)
			(type default)
		)
		(layer "In4.Cu")
	)
	(gr_line
		(start 114.70005 -295.63822)
		(end 114.701574 -295.637204)
		(stroke
			(width 0.05715)
			(type default)
		)
		(layer "In4.Cu")
	)
	(gr_line
		(start 114.701574 -295.637204)
		(end 114.702336 -295.636696)
		(stroke
			(width 0.05715)
			(type default)
		)
		(layer "In4.Cu")
	)
	(gr_line
		(start 114.703352 -295.636188)
		(end 114.704114 -295.63568)
		(stroke
			(width 0.05715)
			(type default)
		)
		(layer "In4.Cu")
	)
	(gr_arc
		(start 114.703352 -289.15614)
		(mid 114.701188 -289.157402)
		(end 114.699034 -289.15868)
		(stroke
			(width 0.05715)
			(type default)
		)
		(layer "In4.Cu")
	)
	(gr_line
		(start 114.704114 -295.63568)
		(end 114.7064 -295.63441)
		(stroke
			(width 0.05715)
			(type default)
		)
		(layer "In4.Cu")
	)
	(gr_line
		(start 114.70513 -292.395148)
		(end 114.706908 -292.394132)
		(stroke
			(width 0.05715)
			(type default)
		)
		(layer "In4.Cu")
	)
	(gr_line
		(start 114.706654 -291.418264)
		(end 114.706146 -291.41801)
		(stroke
			(width 0.05715)
			(type default)
		)
		(layer "In4.Cu")
	)
	(gr_line
		(start 114.706908 -292.394132)
		(end 114.70767 -292.393624)
		(stroke
			(width 0.05715)
			(type default)
		)
		(layer "In4.Cu")
	)
	(gr_line
		(start 114.70767 -293.038784)
		(end 114.707162 -293.03853)
		(stroke
			(width 0.05715)
			(type default)
		)
		(layer "In4.Cu")
	)
	(gr_line
		(start 114.70767 -292.393624)
		(end 114.70894 -292.392862)
		(stroke
			(width 0.05715)
			(type default)
		)
		(layer "In4.Cu")
	)
	(gr_line
		(start 114.708686 -293.039292)
		(end 114.70767 -293.038784)
		(stroke
			(width 0.05715)
			(type default)
		)
		(layer "In4.Cu")
	)
	(gr_line
		(start 114.711226 -295.631616)
		(end 114.711988 -295.631108)
		(stroke
			(width 0.05715)
			(type default)
		)
		(layer "In4.Cu")
	)
	(gr_line
		(start 114.72164 -390.829546)
		(end 114.6048 -390.8298)
		(stroke
			(width 0.07112)
			(type default)
		)
		(layer "In4.Cu")
	)
	(gr_line
		(start 114.72164 -390.829546)
		(end 114.72164 -390.8298)
		(stroke
			(width 0.07112)
			(type default)
		)
		(layer "In4.Cu")
	)
	(gr_line
		(start 114.722656 -290.286186)
		(end 114.424714 -290.286186)
		(stroke
			(width 0.05715)
			(type default)
		)
		(layer "In4.Cu")
	)
	(gr_line
		(start 114.722656 -288.666174)
		(end 114.424714 -288.666174)
		(stroke
			(width 0.05715)
			(type default)
		)
		(layer "In4.Cu")
	)
	(gr_line
		(start 114.722656 -287.046162)
		(end 114.424714 -287.046162)
		(stroke
			(width 0.05715)
			(type default)
		)
		(layer "In4.Cu")
	)
	(gr_line
		(start 114.74196 -379.251718)
		(end 114.549428 -379.251718)
		(stroke
			(width 0.07112)
			(type default)
		)
		(layer "In4.Cu")
	)
	(gr_line
		(start 114.791998 -288.735516)
		(end 114.722656 -288.666174)
		(stroke
			(width 0.05715)
			(type default)
		)
		(layer "In4.Cu")
	)
	(gr_line
		(start 114.791998 -287.115504)
		(end 114.722656 -287.046162)
		(stroke
			(width 0.05715)
			(type default)
		)
		(layer "In4.Cu")
	)
	(gr_line
		(start 114.80546 -290.36899)
		(end 114.722656 -290.286186)
		(stroke
			(width 0.05715)
			(type default)
		)
		(layer "In4.Cu")
	)
	(gr_arc
		(start 114.80546 -290.36899)
		(mid 114.807247 -290.38044)
		(end 114.80927 -290.39185)
		(stroke
			(width 0.05715)
			(type default)
		)
		(layer "In4.Cu")
	)
	(gr_line
		(start 114.813588 -376.959368)
		(end 114.317526 -376.463306)
		(stroke
			(width 0.07112)
			(type default)
		)
		(layer "In4.Cu")
	)
	(gr_line
		(start 114.891312 -385.31038)
		(end 115.244626 -385.405376)
		(stroke
			(width 0.07112)
			(type default)
		)
		(layer "In4.Cu")
	)
	(gr_line
		(start 114.915696 -377.654312)
		(end 114.915696 -377.462034)
		(stroke
			(width 0.07112)
			(type default)
		)
		(layer "In4.Cu")
	)
	(gr_line
		(start 114.942874 -379.052328)
		(end 114.447066 -378.556266)
		(stroke
			(width 0.07112)
			(type default)
		)
		(layer "In4.Cu")
	)
	(gr_line
		(start 114.961416 -375.802652)
		(end 114.961416 -375.610374)
		(stroke
			(width 0.07112)
			(type default)
		)
		(layer "In4.Cu")
	)
	(gr_line
		(start 114.979958 -287.151826)
		(end 114.980212 -287.151826)
		(stroke
			(width 0.05715)
			(type default)
		)
		(layer "In4.Cu")
	)
	(gr_arc
		(start 114.980212 -288.771838)
		(mid 114.982234 -288.760428)
		(end 114.984022 -288.748978)
		(stroke
			(width 0.05715)
			(type default)
		)
		(layer "In4.Cu")
	)
	(gr_arc
		(start 114.980212 -287.151826)
		(mid 114.982234 -287.140415)
		(end 114.984022 -287.128966)
		(stroke
			(width 0.05715)
			(type default)
		)
		(layer "In4.Cu")
	)
	(gr_line
		(start 114.984022 -288.748978)
		(end 115.066826 -288.666174)
		(stroke
			(width 0.05715)
			(type default)
		)
		(layer "In4.Cu")
	)
	(gr_line
		(start 114.984022 -287.128966)
		(end 115.066826 -287.046162)
		(stroke
			(width 0.05715)
			(type default)
		)
		(layer "In4.Cu")
	)
	(gr_line
		(start 114.997484 -290.355528)
		(end 115.066826 -290.286186)
		(stroke
			(width 0.05715)
			(type default)
		)
		(layer "In4.Cu")
	)
	(gr_line
		(start 115.066826 -290.286186)
		(end 115.364768 -290.286186)
		(stroke
			(width 0.05715)
			(type default)
		)
		(layer "In4.Cu")
	)
	(gr_line
		(start 115.066826 -288.666174)
		(end 115.364768 -288.666174)
		(stroke
			(width 0.05715)
			(type default)
		)
		(layer "In4.Cu")
	)
	(gr_line
		(start 115.066826 -287.046162)
		(end 115.364768 -287.046162)
		(stroke
			(width 0.05715)
			(type default)
		)
		(layer "In4.Cu")
	)
	(gr_arc
		(start 115.101624 -380.996698)
		(mid 115.100228 -380.995173)
		(end 115.09883 -380.99365)
		(stroke
			(width 0.07112)
			(type default)
		)
		(layer "In4.Cu")
	)
	(gr_arc
		(start 115.104926 -381.000508)
		(mid 115.103276 -380.998602)
		(end 115.101624 -380.996698)
		(stroke
			(width 0.07112)
			(type default)
		)
		(layer "In4.Cu")
	)
	(gr_line
		(start 115.184936 -404.17369)
		(end 114.894106 -404.46452)
		(stroke
			(width 0.07112)
			(type default)
		)
		(layer "In4.Cu")
	)
	(gr_line
		(start 115.187476 -363.67212)
		(end 115.187222 -363.67212)
		(stroke
			(width 0.07112)
			(type default)
		)
		(layer "In4.Cu")
	)
	(gr_line
		(start 115.217702 -377.956318)
		(end 114.915696 -377.654312)
		(stroke
			(width 0.07112)
			(type default)
		)
		(layer "In4.Cu")
	)
	(gr_line
		(start 115.223798 -296.358564)
		(end 115.223798 -296.330116)
		(stroke
			(width 0.05715)
			(type default)
		)
		(layer "In4.Cu")
	)
	(gr_line
		(start 115.223798 -296.330116)
		(end 115.269518 -296.284396)
		(stroke
			(width 0.05715)
			(type default)
		)
		(layer "In4.Cu")
	)
	(gr_line
		(start 115.244626 -385.405376)
		(end 115.245134 -385.404868)
		(stroke
			(width 0.07112)
			(type default)
		)
		(layer "In4.Cu")
	)
	(gr_line
		(start 115.263422 -376.104658)
		(end 114.961416 -375.802652)
		(stroke
			(width 0.07112)
			(type default)
		)
		(layer "In4.Cu")
	)
	(gr_line
		(start 115.291362 -386.003292)
		(end 115.386104 -385.649724)
		(stroke
			(width 0.07112)
			(type default)
		)
		(layer "In4.Cu")
	)
	(gr_line
		(start 115.358672 -382.45796)
		(end 115.358418 -382.458214)
		(stroke
			(width 0.07112)
			(type default)
		)
		(layer "In4.Cu")
	)
	(gr_line
		(start 115.40998 -377.956318)
		(end 115.217702 -377.956318)
		(stroke
			(width 0.07112)
			(type default)
		)
		(layer "In4.Cu")
	)
	(gr_line
		(start 115.4557 -376.104658)
		(end 115.263422 -376.104658)
		(stroke
			(width 0.07112)
			(type default)
		)
		(layer "In4.Cu")
	)
	(gr_line
		(start 115.466876 -404.17369)
		(end 115.757706 -404.46452)
		(stroke
			(width 0.07112)
			(type default)
		)
		(layer "In4.Cu")
	)
	(gr_line
		(start 115.505738 -296.358564)
		(end 115.505738 -296.330116)
		(stroke
			(width 0.05715)
			(type default)
		)
		(layer "In4.Cu")
	)
	(gr_line
		(start 115.505738 -296.330116)
		(end 115.460018 -296.284396)
		(stroke
			(width 0.05715)
			(type default)
		)
		(layer "In4.Cu")
	)
	(gr_line
		(start 115.50777 -385.579112)
		(end 115.560602 -385.548632)
		(stroke
			(width 0.07112)
			(type default)
		)
		(layer "In4.Cu")
	)
	(gr_arc
		(start 115.512596 -295.491662)
		(mid 115.508648 -295.49444)
		(end 115.504722 -295.49725)
		(stroke
			(width 0.05715)
			(type default)
		)
		(layer "In4.Cu")
	)
	(gr_line
		(start 115.512596 -295.491662)
		(end 115.519454 -295.487598)
		(stroke
			(width 0.05715)
			(type default)
		)
		(layer "In4.Cu")
	)
	(gr_line
		(start 115.519454 -295.487598)
		(end 115.520216 -295.48709)
		(stroke
			(width 0.05715)
			(type default)
		)
		(layer "In4.Cu")
	)
	(gr_line
		(start 115.520216 -295.48709)
		(end 115.520724 -295.486836)
		(stroke
			(width 0.05715)
			(type default)
		)
		(layer "In4.Cu")
	)
	(gr_line
		(start 115.542822 -294.818562)
		(end 115.541806 -294.818054)
		(stroke
			(width 0.05715)
			(type default)
		)
		(layer "In4.Cu")
	)
	(gr_line
		(start 115.542822 -293.19855)
		(end 115.541806 -293.198042)
		(stroke
			(width 0.05715)
			(type default)
		)
		(layer "In4.Cu")
	)
	(gr_line
		(start 115.542822 -291.578538)
		(end 115.541806 -291.57803)
		(stroke
			(width 0.05715)
			(type default)
		)
		(layer "In4.Cu")
	)
	(gr_line
		(start 115.544854 -293.852854)
		(end 115.552982 -293.848282)
		(stroke
			(width 0.05715)
			(type default)
		)
		(layer "In4.Cu")
	)
	(gr_line
		(start 115.544854 -292.232842)
		(end 115.552982 -292.22827)
		(stroke
			(width 0.05715)
			(type default)
		)
		(layer "In4.Cu")
	)
	(gr_line
		(start 115.545362 -295.472612)
		(end 115.547648 -295.471342)
		(stroke
			(width 0.05715)
			(type default)
		)
		(layer "In4.Cu")
	)
	(gr_line
		(start 115.548918 -295.47058)
		(end 115.553236 -295.46804)
		(stroke
			(width 0.05715)
			(type default)
		)
		(layer "In4.Cu")
	)
	(gr_line
		(start 115.553236 -295.46804)
		(end 115.553998 -295.467532)
		(stroke
			(width 0.05715)
			(type default)
		)
		(layer "In4.Cu")
	)
	(gr_line
		(start 115.560602 -385.548632)
		(end 115.64874 -385.460494)
		(stroke
			(width 0.07112)
			(type default)
		)
		(layer "In4.Cu")
	)
	(gr_line
		(start 115.560856 -294.828976)
		(end 115.559586 -294.828214)
		(stroke
			(width 0.05715)
			(type default)
		)
		(layer "In4.Cu")
	)
	(gr_line
		(start 115.560856 -293.208964)
		(end 115.559586 -293.208202)
		(stroke
			(width 0.05715)
			(type default)
		)
		(layer "In4.Cu")
	)
	(gr_line
		(start 115.560856 -291.588952)
		(end 115.559586 -291.58819)
		(stroke
			(width 0.05715)
			(type default)
		)
		(layer "In4.Cu")
	)
	(gr_line
		(start 115.561872 -294.829484)
		(end 115.560856 -294.828976)
		(stroke
			(width 0.05715)
			(type default)
		)
		(layer "In4.Cu")
	)
	(gr_line
		(start 115.561872 -293.209472)
		(end 115.560856 -293.208964)
		(stroke
			(width 0.05715)
			(type default)
		)
		(layer "In4.Cu")
	)
	(gr_line
		(start 115.561872 -291.58946)
		(end 115.560856 -291.588952)
		(stroke
			(width 0.05715)
			(type default)
		)
		(layer "In4.Cu")
	)
	(gr_line
		(start 115.611148 -377.756928)
		(end 115.115086 -377.260866)
		(stroke
			(width 0.07112)
			(type default)
		)
		(layer "In4.Cu")
	)
	(gr_line
		(start 115.644168 -294.656764)
		(end 115.642136 -294.655748)
		(stroke
			(width 0.05715)
			(type default)
		)
		(layer "In4.Cu")
	)
	(gr_line
		(start 115.644168 -293.036752)
		(end 115.642136 -293.035736)
		(stroke
			(width 0.05715)
			(type default)
		)
		(layer "In4.Cu")
	)
	(gr_line
		(start 115.644168 -291.41674)
		(end 115.642136 -291.415724)
		(stroke
			(width 0.05715)
			(type default)
		)
		(layer "In4.Cu")
	)
	(gr_line
		(start 115.6462 -294.658034)
		(end 115.64493 -294.657272)
		(stroke
			(width 0.05715)
			(type default)
		)
		(layer "In4.Cu")
	)
	(gr_line
		(start 115.6462 -293.038022)
		(end 115.64493 -293.03726)
		(stroke
			(width 0.05715)
			(type default)
		)
		(layer "In4.Cu")
	)
	(gr_line
		(start 115.6462 -291.41801)
		(end 115.64493 -291.417248)
		(stroke
			(width 0.05715)
			(type default)
		)
		(layer "In4.Cu")
	)
	(gr_line
		(start 115.64874 -385.460494)
		(end 115.64874 -385.334764)
		(stroke
			(width 0.07112)
			(type default)
		)
		(layer "In4.Cu")
	)
	(gr_line
		(start 115.64874 -295.63314)
		(end 115.650518 -295.632124)
		(stroke
			(width 0.05715)
			(type default)
		)
		(layer "In4.Cu")
	)
	(gr_line
		(start 115.650518 -295.632124)
		(end 115.654074 -295.630092)
		(stroke
			(width 0.05715)
			(type default)
		)
		(layer "In4.Cu")
	)
	(gr_line
		(start 115.650518 -294.660574)
		(end 115.647724 -294.658796)
		(stroke
			(width 0.05715)
			(type default)
		)
		(layer "In4.Cu")
	)
	(gr_line
		(start 115.650518 -293.040562)
		(end 115.647724 -293.038784)
		(stroke
			(width 0.05715)
			(type default)
		)
		(layer "In4.Cu")
	)
	(gr_line
		(start 115.650518 -291.42055)
		(end 115.647724 -291.418772)
		(stroke
			(width 0.05715)
			(type default)
		)
		(layer "In4.Cu")
	)
	(gr_line
		(start 115.65255 -294.66159)
		(end 115.652042 -294.661336)
		(stroke
			(width 0.05715)
			(type default)
		)
		(layer "In4.Cu")
	)
	(gr_line
		(start 115.65255 -293.041578)
		(end 115.652042 -293.041324)
		(stroke
			(width 0.05715)
			(type default)
		)
		(layer "In4.Cu")
	)
	(gr_line
		(start 115.65255 -291.421566)
		(end 115.652042 -291.421312)
		(stroke
			(width 0.05715)
			(type default)
		)
		(layer "In4.Cu")
	)
	(gr_line
		(start 115.65509 -294.663114)
		(end 115.654074 -294.662606)
		(stroke
			(width 0.05715)
			(type default)
		)
		(layer "In4.Cu")
	)
	(gr_line
		(start 115.65509 -293.043102)
		(end 115.654074 -293.042594)
		(stroke
			(width 0.05715)
			(type default)
		)
		(layer "In4.Cu")
	)
	(gr_line
		(start 115.65509 -291.42309)
		(end 115.654074 -291.422582)
		(stroke
			(width 0.05715)
			(type default)
		)
		(layer "In4.Cu")
	)
	(gr_line
		(start 115.656868 -375.905268)
		(end 115.160806 -375.409206)
		(stroke
			(width 0.07112)
			(type default)
		)
		(layer "In4.Cu")
	)
	(gr_line
		(start 115.65763 -294.664638)
		(end 115.657122 -294.664384)
		(stroke
			(width 0.05715)
			(type default)
		)
		(layer "In4.Cu")
	)
	(gr_line
		(start 115.65763 -293.044626)
		(end 115.657122 -293.044372)
		(stroke
			(width 0.05715)
			(type default)
		)
		(layer "In4.Cu")
	)
	(gr_line
		(start 115.65763 -291.424614)
		(end 115.657122 -291.42436)
		(stroke
			(width 0.05715)
			(type default)
		)
		(layer "In4.Cu")
	)
	(gr_arc
		(start 115.702842 -307.241194)
		(mid 115.703476 -307.242084)
		(end 115.704112 -307.242972)
		(stroke
			(width 0.07112)
			(type default)
		)
		(layer "In4.Cu")
	)
	(gr_arc
		(start 115.704112 -307.242972)
		(mid 115.71225 -307.254108)
		(end 115.720622 -307.26507)
		(stroke
			(width 0.07112)
			(type default)
		)
		(layer "In4.Cu")
	)
	(gr_line
		(start 115.713256 -378.451618)
		(end 115.713256 -378.259594)
		(stroke
			(width 0.07112)
			(type default)
		)
		(layer "In4.Cu")
	)
	(gr_arc
		(start 115.721384 -307.266086)
		(mid 115.721003 -307.265578)
		(end 115.720622 -307.26507)
		(stroke
			(width 0.07112)
			(type default)
		)
		(layer "In4.Cu")
	)
	(gr_line
		(start 115.758976 -376.600212)
		(end 115.758976 -376.407934)
		(stroke
			(width 0.07112)
			(type default)
		)
		(layer "In4.Cu")
	)
	(gr_line
		(start 115.935252 -307.081428)
		(end 115.938554 -307.086254)
		(stroke
			(width 0.07112)
			(type default)
		)
		(layer "In4.Cu")
	)
	(gr_line
		(start 115.938554 -307.086254)
		(end 115.94211 -307.090572)
		(stroke
			(width 0.07112)
			(type default)
		)
		(layer "In4.Cu")
	)
	(gr_line
		(start 115.951508 -336.055716)
		(end 115.951762 -336.056986)
		(stroke
			(width 0.07112)
			(type default)
		)
		(layer "In4.Cu")
	)
	(gr_arc
		(start 115.9764 -290.74618)
		(mid 115.979567 -290.748477)
		(end 115.98275 -290.750752)
		(stroke
			(width 0.05715)
			(type default)
		)
		(layer "In4.Cu")
	)
	(gr_arc
		(start 115.98275 -290.750752)
		(mid 115.983512 -290.751261)
		(end 115.984274 -290.751768)
		(stroke
			(width 0.05715)
			(type default)
		)
		(layer "In4.Cu")
	)
	(gr_line
		(start 115.990878 -290.755578)
		(end 115.984274 -290.751768)
		(stroke
			(width 0.05715)
			(type default)
		)
		(layer "In4.Cu")
	)
	(gr_line
		(start 116.015262 -378.753624)
		(end 115.713256 -378.451618)
		(stroke
			(width 0.07112)
			(type default)
		)
		(layer "In4.Cu")
	)
	(gr_line
		(start 116.029486 -290.778184)
		(end 116.028978 -290.77793)
		(stroke
			(width 0.05715)
			(type default)
		)
		(layer "In4.Cu")
	)
	(gr_line
		(start 116.060982 -376.902218)
		(end 115.758976 -376.600212)
		(stroke
			(width 0.07112)
			(type default)
		)
		(layer "In4.Cu")
	)
	(gr_line
		(start 116.091208 -385.31038)
		(end 116.444522 -385.405376)
		(stroke
			(width 0.07112)
			(type default)
		)
		(layer "In4.Cu")
	)
	(gr_line
		(start 116.125752 -290.613592)
		(end 116.125244 -290.613338)
		(stroke
			(width 0.05715)
			(type default)
		)
		(layer "In4.Cu")
	)
	(gr_line
		(start 116.164106 -296.358564)
		(end 116.164106 -296.330116)
		(stroke
			(width 0.05715)
			(type default)
		)
		(layer "In4.Cu")
	)
	(gr_line
		(start 116.164106 -296.330116)
		(end 116.209826 -296.284396)
		(stroke
			(width 0.05715)
			(type default)
		)
		(layer "In4.Cu")
	)
	(gr_line
		(start 116.207286 -378.753624)
		(end 116.015262 -378.753624)
		(stroke
			(width 0.07112)
			(type default)
		)
		(layer "In4.Cu")
	)
	(gr_line
		(start 116.209318 -295.952418)
		(end 116.209318 -295.947846)
		(stroke
			(width 0.05715)
			(type default)
		)
		(layer "In4.Cu")
	)
	(gr_arc
		(start 116.209572 -295.94302)
		(mid 116.20944 -295.945433)
		(end 116.209318 -295.947846)
		(stroke
			(width 0.05715)
			(type default)
		)
		(layer "In4.Cu")
	)
	(gr_line
		(start 116.25326 -376.902218)
		(end 116.060982 -376.902218)
		(stroke
			(width 0.07112)
			(type default)
		)
		(layer "In4.Cu")
	)
	(gr_line
		(start 116.400326 -295.978072)
		(end 116.400326 -295.96969)
		(stroke
			(width 0.05715)
			(type default)
		)
		(layer "In4.Cu")
	)
	(gr_line
		(start 116.408454 -378.554234)
		(end 115.912646 -378.058426)
		(stroke
			(width 0.07112)
			(type default)
		)
		(layer "In4.Cu")
	)
	(gr_line
		(start 116.444522 -385.405376)
		(end 116.44503 -385.404868)
		(stroke
			(width 0.07112)
			(type default)
		)
		(layer "In4.Cu")
	)
	(gr_arc
		(start 116.44503 -295.496996)
		(mid 116.441464 -295.499522)
		(end 116.437918 -295.502076)
		(stroke
			(width 0.05715)
			(type default)
		)
		(layer "In4.Cu")
	)
	(gr_line
		(start 116.446046 -296.358564)
		(end 116.446046 -296.330116)
		(stroke
			(width 0.05715)
			(type default)
		)
		(layer "In4.Cu")
	)
	(gr_line
		(start 116.446046 -296.330116)
		(end 116.400326 -296.284396)
		(stroke
			(width 0.05715)
			(type default)
		)
		(layer "In4.Cu")
	)
	(gr_arc
		(start 116.453158 -295.491154)
		(mid 116.450868 -295.4928)
		(end 116.448586 -295.494456)
		(stroke
			(width 0.05715)
			(type default)
		)
		(layer "In4.Cu")
	)
	(gr_line
		(start 116.454428 -376.702828)
		(end 115.958366 -376.206766)
		(stroke
			(width 0.07112)
			(type default)
		)
		(layer "In4.Cu")
	)
	(gr_line
		(start 116.48059 -293.855394)
		(end 116.481352 -293.854886)
		(stroke
			(width 0.05715)
			(type default)
		)
		(layer "In4.Cu")
	)
	(gr_line
		(start 116.48059 -292.235382)
		(end 116.481352 -292.234874)
		(stroke
			(width 0.05715)
			(type default)
		)
		(layer "In4.Cu")
	)
	(gr_line
		(start 116.48059 -288.995358)
		(end 116.481352 -288.99485)
		(stroke
			(width 0.05715)
			(type default)
		)
		(layer "In4.Cu")
	)
	(gr_line
		(start 116.484146 -291.579046)
		(end 116.482876 -291.578284)
		(stroke
			(width 0.05715)
			(type default)
		)
		(layer "In4.Cu")
	)
	(gr_line
		(start 116.4844 -293.853108)
		(end 116.48821 -293.850822)
		(stroke
			(width 0.05715)
			(type default)
		)
		(layer "In4.Cu")
	)
	(gr_line
		(start 116.4844 -292.233096)
		(end 116.48821 -292.23081)
		(stroke
			(width 0.05715)
			(type default)
		)
		(layer "In4.Cu")
	)
	(gr_line
		(start 116.4844 -288.993072)
		(end 116.48821 -288.990786)
		(stroke
			(width 0.05715)
			(type default)
		)
		(layer "In4.Cu")
	)
	(gr_line
		(start 116.484654 -291.5793)
		(end 116.484146 -291.579046)
		(stroke
			(width 0.05715)
			(type default)
		)
		(layer "In4.Cu")
	)
	(gr_line
		(start 116.48694 -291.580824)
		(end 116.48567 -291.580062)
		(stroke
			(width 0.05715)
			(type default)
		)
		(layer "In4.Cu")
	)
	(gr_line
		(start 116.48821 -293.850822)
		(end 116.489226 -293.850314)
		(stroke
			(width 0.05715)
			(type default)
		)
		(layer "In4.Cu")
	)
	(gr_line
		(start 116.48821 -292.23081)
		(end 116.489226 -292.230302)
		(stroke
			(width 0.05715)
			(type default)
		)
		(layer "In4.Cu")
	)
	(gr_line
		(start 116.48821 -288.990786)
		(end 116.489226 -288.990278)
		(stroke
			(width 0.05715)
			(type default)
		)
		(layer "In4.Cu")
	)
	(gr_line
		(start 116.489226 -293.850314)
		(end 116.49075 -293.849298)
		(stroke
			(width 0.05715)
			(type default)
		)
		(layer "In4.Cu")
	)
	(gr_line
		(start 116.489226 -292.230302)
		(end 116.49075 -292.229286)
		(stroke
			(width 0.05715)
			(type default)
		)
		(layer "In4.Cu")
	)
	(gr_line
		(start 116.489226 -288.990278)
		(end 116.49075 -288.989262)
		(stroke
			(width 0.05715)
			(type default)
		)
		(layer "In4.Cu")
	)
	(gr_line
		(start 116.49075 -291.58311)
		(end 116.489734 -291.582602)
		(stroke
			(width 0.05715)
			(type default)
		)
		(layer "In4.Cu")
	)
	(gr_line
		(start 116.491258 -386.003292)
		(end 116.586 -385.649724)
		(stroke
			(width 0.07112)
			(type default)
		)
		(layer "In4.Cu")
	)
	(gr_line
		(start 116.491766 -293.84879)
		(end 116.492528 -293.848282)
		(stroke
			(width 0.05715)
			(type default)
		)
		(layer "In4.Cu")
	)
	(gr_line
		(start 116.491766 -292.228778)
		(end 116.492528 -292.22827)
		(stroke
			(width 0.05715)
			(type default)
		)
		(layer "In4.Cu")
	)
	(gr_line
		(start 116.491766 -291.583618)
		(end 116.49075 -291.58311)
		(stroke
			(width 0.05715)
			(type default)
		)
		(layer "In4.Cu")
	)
	(gr_line
		(start 116.491766 -288.988754)
		(end 116.492528 -288.988246)
		(stroke
			(width 0.05715)
			(type default)
		)
		(layer "In4.Cu")
	)
	(gr_line
		(start 116.492528 -291.584126)
		(end 116.491766 -291.583618)
		(stroke
			(width 0.05715)
			(type default)
		)
		(layer "In4.Cu")
	)
	(gr_line
		(start 116.493798 -294.824912)
		(end 116.492528 -294.82415)
		(stroke
			(width 0.05715)
			(type default)
		)
		(layer "In4.Cu")
	)
	(gr_line
		(start 116.493798 -293.2049)
		(end 116.492528 -293.204138)
		(stroke
			(width 0.05715)
			(type default)
		)
		(layer "In4.Cu")
	)
	(gr_line
		(start 116.495576 -294.825928)
		(end 116.493798 -294.824912)
		(stroke
			(width 0.05715)
			(type default)
		)
		(layer "In4.Cu")
	)
	(gr_line
		(start 116.495576 -293.846504)
		(end 116.496084 -293.84625)
		(stroke
			(width 0.05715)
			(type default)
		)
		(layer "In4.Cu")
	)
	(gr_line
		(start 116.495576 -292.226492)
		(end 116.496084 -292.226238)
		(stroke
			(width 0.05715)
			(type default)
		)
		(layer "In4.Cu")
	)
	(gr_line
		(start 116.495576 -288.986468)
		(end 116.496084 -288.986214)
		(stroke
			(width 0.05715)
			(type default)
		)
		(layer "In4.Cu")
	)
	(gr_line
		(start 116.498878 -291.587682)
		(end 116.497862 -291.587174)
		(stroke
			(width 0.05715)
			(type default)
		)
		(layer "In4.Cu")
	)
	(gr_line
		(start 116.499386 -291.587936)
		(end 116.498878 -291.587682)
		(stroke
			(width 0.05715)
			(type default)
		)
		(layer "In4.Cu")
	)
	(gr_line
		(start 116.556536 -377.397518)
		(end 116.556536 -377.205494)
		(stroke
			(width 0.07112)
			(type default)
		)
		(layer "In4.Cu")
	)
	(gr_line
		(start 116.576094 -403.192488)
		(end 116.398294 -403.118828)
		(stroke
			(width 0.07112)
			(type default)
		)
		(layer "In4.Cu")
	)
	(gr_line
		(start 116.577618 -294.019478)
		(end 116.57838 -294.01897)
		(stroke
			(width 0.05715)
			(type default)
		)
		(layer "In4.Cu")
	)
	(gr_line
		(start 116.577618 -292.399466)
		(end 116.57838 -292.398958)
		(stroke
			(width 0.05715)
			(type default)
		)
		(layer "In4.Cu")
	)
	(gr_line
		(start 116.577618 -289.159442)
		(end 116.57838 -289.158934)
		(stroke
			(width 0.05715)
			(type default)
		)
		(layer "In4.Cu")
	)
	(gr_line
		(start 116.579396 -291.413946)
		(end 116.57838 -291.413438)
		(stroke
			(width 0.05715)
			(type default)
		)
		(layer "In4.Cu")
	)
	(gr_line
		(start 116.58346 -291.416232)
		(end 116.581936 -291.41547)
		(stroke
			(width 0.05715)
			(type default)
		)
		(layer "In4.Cu")
	)
	(gr_line
		(start 116.585492 -294.014906)
		(end 116.587016 -294.014144)
		(stroke
			(width 0.05715)
			(type default)
		)
		(layer "In4.Cu")
	)
	(gr_line
		(start 116.585492 -292.394894)
		(end 116.587016 -292.394132)
		(stroke
			(width 0.05715)
			(type default)
		)
		(layer "In4.Cu")
	)
	(gr_line
		(start 116.585492 -289.15487)
		(end 116.587016 -289.154108)
		(stroke
			(width 0.05715)
			(type default)
		)
		(layer "In4.Cu")
	)
	(gr_line
		(start 116.587016 -294.014144)
		(end 116.587778 -294.013636)
		(stroke
			(width 0.05715)
			(type default)
		)
		(layer "In4.Cu")
	)
	(gr_line
		(start 116.587016 -292.394132)
		(end 116.587778 -292.393624)
		(stroke
			(width 0.05715)
			(type default)
		)
		(layer "In4.Cu")
	)
	(gr_line
		(start 116.587016 -291.418264)
		(end 116.586508 -291.41801)
		(stroke
			(width 0.05715)
			(type default)
		)
		(layer "In4.Cu")
	)
	(gr_line
		(start 116.587016 -289.154108)
		(end 116.587778 -289.1536)
		(stroke
			(width 0.05715)
			(type default)
		)
		(layer "In4.Cu")
	)
	(gr_line
		(start 116.587778 -294.658796)
		(end 116.58727 -294.658542)
		(stroke
			(width 0.05715)
			(type default)
		)
		(layer "In4.Cu")
	)
	(gr_line
		(start 116.587778 -294.013636)
		(end 116.588794 -294.013128)
		(stroke
			(width 0.05715)
			(type default)
		)
		(layer "In4.Cu")
	)
	(gr_line
		(start 116.587778 -293.038784)
		(end 116.58727 -293.03853)
		(stroke
			(width 0.05715)
			(type default)
		)
		(layer "In4.Cu")
	)
	(gr_line
		(start 116.587778 -292.393624)
		(end 116.588794 -292.393116)
		(stroke
			(width 0.05715)
			(type default)
		)
		(layer "In4.Cu")
	)
	(gr_line
		(start 116.587778 -291.418772)
		(end 116.587016 -291.418264)
		(stroke
			(width 0.05715)
			(type default)
		)
		(layer "In4.Cu")
	)
	(gr_line
		(start 116.587778 -289.1536)
		(end 116.588794 -289.153092)
		(stroke
			(width 0.05715)
			(type default)
		)
		(layer "In4.Cu")
	)
	(gr_line
		(start 116.58854 -294.65905)
		(end 116.587778 -294.658796)
		(stroke
			(width 0.05715)
			(type default)
		)
		(layer "In4.Cu")
	)
	(gr_line
		(start 116.588794 -294.013128)
		(end 116.590318 -294.012112)
		(stroke
			(width 0.05715)
			(type default)
		)
		(layer "In4.Cu")
	)
	(gr_line
		(start 116.588794 -293.039292)
		(end 116.587778 -293.038784)
		(stroke
			(width 0.05715)
			(type default)
		)
		(layer "In4.Cu")
	)
	(gr_line
		(start 116.588794 -292.393116)
		(end 116.590318 -292.3921)
		(stroke
			(width 0.05715)
			(type default)
		)
		(layer "In4.Cu")
	)
	(gr_line
		(start 116.588794 -291.41928)
		(end 116.587778 -291.418772)
		(stroke
			(width 0.05715)
			(type default)
		)
		(layer "In4.Cu")
	)
	(gr_line
		(start 116.588794 -289.153092)
		(end 116.590318 -289.152076)
		(stroke
			(width 0.05715)
			(type default)
		)
		(layer "In4.Cu")
	)
	(gr_line
		(start 116.590572 -294.660574)
		(end 116.590318 -294.66032)
		(stroke
			(width 0.05715)
			(type default)
		)
		(layer "In4.Cu")
	)
	(gr_line
		(start 116.590572 -291.420296)
		(end 116.588794 -291.41928)
		(stroke
			(width 0.05715)
			(type default)
		)
		(layer "In4.Cu")
	)
	(gr_line
		(start 116.592096 -294.011096)
		(end 116.594128 -294.009826)
		(stroke
			(width 0.05715)
			(type default)
		)
		(layer "In4.Cu")
	)
	(gr_line
		(start 116.592096 -292.391084)
		(end 116.594128 -292.389814)
		(stroke
			(width 0.05715)
			(type default)
		)
		(layer "In4.Cu")
	)
	(gr_line
		(start 116.592096 -289.15106)
		(end 116.594128 -289.14979)
		(stroke
			(width 0.05715)
			(type default)
		)
		(layer "In4.Cu")
	)
	(gr_line
		(start 116.593112 -291.42182)
		(end 116.592096 -291.421312)
		(stroke
			(width 0.05715)
			(type default)
		)
		(layer "In4.Cu")
	)
	(gr_line
		(start 116.594128 -291.422582)
		(end 116.593112 -291.42182)
		(stroke
			(width 0.05715)
			(type default)
		)
		(layer "In4.Cu")
	)
	(gr_line
		(start 116.619274 -291.43706)
		(end 116.618766 -291.436806)
		(stroke
			(width 0.05715)
			(type default)
		)
		(layer "In4.Cu")
	)
	(gr_line
		(start 116.620036 -291.437568)
		(end 116.619274 -291.43706)
		(stroke
			(width 0.05715)
			(type default)
		)
		(layer "In4.Cu")
	)
	(gr_line
		(start 116.626894 -291.441632)
		(end 116.620036 -291.437568)
		(stroke
			(width 0.05715)
			(type default)
		)
		(layer "In4.Cu")
	)
	(gr_arc
		(start 116.634768 -291.44722)
		(mid 116.630843 -291.444409)
		(end 116.626894 -291.441632)
		(stroke
			(width 0.05715)
			(type default)
		)
		(layer "In4.Cu")
	)
	(gr_line
		(start 116.707666 -385.579112)
		(end 116.760498 -385.548632)
		(stroke
			(width 0.07112)
			(type default)
		)
		(layer "In4.Cu")
	)
	(gr_line
		(start 116.760498 -385.548632)
		(end 116.848636 -385.460494)
		(stroke
			(width 0.07112)
			(type default)
		)
		(layer "In4.Cu")
	)
	(gr_line
		(start 116.848636 -385.460494)
		(end 116.848636 -385.334764)
		(stroke
			(width 0.07112)
			(type default)
		)
		(layer "In4.Cu")
	)
	(gr_line
		(start 116.858542 -377.699524)
		(end 116.556536 -377.397518)
		(stroke
			(width 0.07112)
			(type default)
		)
		(layer "In4.Cu")
	)
	(gr_line
		(start 116.88953 -372.720616)
		(end 116.890038 -372.72087)
		(stroke
			(width 0.07112)
			(type default)
		)
		(layer "In4.Cu")
	)
	(gr_line
		(start 116.937028 -402.589238)
		(end 116.289074 -402.857716)
		(stroke
			(width 0.07112)
			(type default)
		)
		(layer "In4.Cu")
	)
	(gr_line
		(start 116.970556 -403.02942)
		(end 116.576094 -403.192488)
		(stroke
			(width 0.07112)
			(type default)
		)
		(layer "In4.Cu")
	)
	(gr_line
		(start 116.971318 -373.137176)
		(end 116.971064 -373.137176)
		(stroke
			(width 0.07112)
			(type default)
		)
		(layer "In4.Cu")
	)
	(gr_line
		(start 117.043962 -402.851366)
		(end 116.970556 -403.02942)
		(stroke
			(width 0.07112)
			(type default)
		)
		(layer "In4.Cu")
	)
	(gr_line
		(start 117.050566 -377.699524)
		(end 116.858542 -377.699524)
		(stroke
			(width 0.07112)
			(type default)
		)
		(layer "In4.Cu")
	)
	(gr_line
		(start 117.072664 -291.096192)
		(end 116.774722 -291.096192)
		(stroke
			(width 0.05715)
			(type default)
		)
		(layer "In4.Cu")
	)
	(gr_line
		(start 117.072664 -289.47618)
		(end 116.774722 -289.47618)
		(stroke
			(width 0.05715)
			(type default)
		)
		(layer "In4.Cu")
	)
	(gr_line
		(start 117.072664 -287.856422)
		(end 116.774722 -287.856422)
		(stroke
			(width 0.05715)
			(type default)
		)
		(layer "In4.Cu")
	)
	(gr_line
		(start 117.11178 -296.362882)
		(end 117.11178 -296.334434)
		(stroke
			(width 0.05715)
			(type default)
		)
		(layer "In4.Cu")
	)
	(gr_line
		(start 117.11178 -296.334434)
		(end 117.1575 -296.288714)
		(stroke
			(width 0.05715)
			(type default)
		)
		(layer "In4.Cu")
	)
	(gr_line
		(start 117.142006 -287.925764)
		(end 117.072664 -287.856422)
		(stroke
			(width 0.05715)
			(type default)
		)
		(layer "In4.Cu")
	)
	(gr_line
		(start 117.155468 -291.178996)
		(end 117.072664 -291.096192)
		(stroke
			(width 0.05715)
			(type default)
		)
		(layer "In4.Cu")
	)
	(gr_line
		(start 117.155468 -289.558984)
		(end 117.072664 -289.47618)
		(stroke
			(width 0.05715)
			(type default)
		)
		(layer "In4.Cu")
	)
	(gr_arc
		(start 117.155468 -289.558984)
		(mid 117.15726 -289.570306)
		(end 117.159278 -289.58159)
		(stroke
			(width 0.05715)
			(type default)
		)
		(layer "In4.Cu")
	)
	(gr_line
		(start 117.155722 -291.178996)
		(end 117.155468 -291.178996)
		(stroke
			(width 0.05715)
			(type default)
		)
		(layer "In4.Cu")
	)
	(gr_arc
		(start 117.155722 -291.178996)
		(mid 117.157514 -291.190191)
		(end 117.159532 -291.201348)
		(stroke
			(width 0.05715)
			(type default)
		)
		(layer "In4.Cu")
	)
	(gr_line
		(start 117.251734 -377.500134)
		(end 116.755926 -377.004326)
		(stroke
			(width 0.07112)
			(type default)
		)
		(layer "In4.Cu")
	)
	(gr_line
		(start 117.260878 -337.822286)
		(end 117.382544 -338.523834)
		(stroke
			(width 0.07112)
			(type default)
		)
		(layer "In4.Cu")
	)
	(gr_line
		(start 117.291358 -385.31038)
		(end 117.644418 -385.405376)
		(stroke
			(width 0.07112)
			(type default)
		)
		(layer "In4.Cu")
	)
	(gr_arc
		(start 117.33022 -287.962086)
		(mid 117.332243 -287.950676)
		(end 117.33403 -287.939226)
		(stroke
			(width 0.05715)
			(type default)
		)
		(layer "In4.Cu")
	)
	(gr_line
		(start 117.33403 -287.939226)
		(end 117.416834 -287.856422)
		(stroke
			(width 0.05715)
			(type default)
		)
		(layer "In4.Cu")
	)
	(gr_line
		(start 117.347492 -289.545522)
		(end 117.416834 -289.47618)
		(stroke
			(width 0.05715)
			(type default)
		)
		(layer "In4.Cu")
	)
	(gr_line
		(start 117.347746 -291.16528)
		(end 117.416834 -291.096192)
		(stroke
			(width 0.05715)
			(type default)
		)
		(layer "In4.Cu")
	)
	(gr_line
		(start 117.348 -295.964356)
		(end 117.348 -295.885362)
		(stroke
			(width 0.05715)
			(type default)
		)
		(layer "In4.Cu")
	)
	(gr_arc
		(start 117.382036 -294.793162)
		(mid 117.381528 -294.792781)
		(end 117.38102 -294.7924)
		(stroke
			(width 0.05715)
			(type default)
		)
		(layer "In4.Cu")
	)
	(gr_line
		(start 117.382798 -338.523834)
		(end 117.389402 -338.562696)
		(stroke
			(width 0.07112)
			(type default)
		)
		(layer "In4.Cu")
	)
	(gr_arc
		(start 117.384576 -289.935158)
		(mid 117.388628 -289.93797)
		(end 117.392704 -289.940746)
		(stroke
			(width 0.05715)
			(type default)
		)
		(layer "In4.Cu")
	)
	(gr_line
		(start 117.389402 -338.562696)
		(end 117.389402 -338.601812)
		(stroke
			(width 0.07112)
			(type default)
		)
		(layer "In4.Cu")
	)
	(gr_arc
		(start 117.393466 -289.941254)
		(mid 117.393085 -289.941)
		(end 117.392704 -289.940746)
		(stroke
			(width 0.05715)
			(type default)
		)
		(layer "In4.Cu")
	)
	(gr_line
		(start 117.39372 -296.362882)
		(end 117.39372 -296.334434)
		(stroke
			(width 0.05715)
			(type default)
		)
		(layer "In4.Cu")
	)
	(gr_line
		(start 117.39372 -296.334434)
		(end 117.348 -296.288714)
		(stroke
			(width 0.05715)
			(type default)
		)
		(layer "In4.Cu")
	)
	(gr_line
		(start 117.400578 -289.945318)
		(end 117.393466 -289.941254)
		(stroke
			(width 0.05715)
			(type default)
		)
		(layer "In4.Cu")
	)
	(gr_line
		(start 117.416834 -291.096192)
		(end 117.714776 -291.096192)
		(stroke
			(width 0.05715)
			(type default)
		)
		(layer "In4.Cu")
	)
	(gr_line
		(start 117.416834 -289.47618)
		(end 117.714776 -289.47618)
		(stroke
			(width 0.05715)
			(type default)
		)
		(layer "In4.Cu")
	)
	(gr_line
		(start 117.416834 -287.856422)
		(end 117.714776 -287.856422)
		(stroke
			(width 0.05715)
			(type default)
		)
		(layer "In4.Cu")
	)
	(gr_line
		(start 117.42547 -293.8526)
		(end 117.432582 -293.848536)
		(stroke
			(width 0.05715)
			(type default)
		)
		(layer "In4.Cu")
	)
	(gr_line
		(start 117.432328 -289.96386)
		(end 117.431566 -289.963352)
		(stroke
			(width 0.05715)
			(type default)
		)
		(layer "In4.Cu")
	)
	(gr_line
		(start 117.432582 -293.203884)
		(end 117.43182 -293.20363)
		(stroke
			(width 0.05715)
			(type default)
		)
		(layer "In4.Cu")
	)
	(gr_line
		(start 117.435122 -289.965384)
		(end 117.432328 -289.96386)
		(stroke
			(width 0.05715)
			(type default)
		)
		(layer "In4.Cu")
	)
	(gr_line
		(start 117.521228 -294.017192)
		(end 117.521736 -294.016938)
		(stroke
			(width 0.05715)
			(type default)
		)
		(layer "In4.Cu")
	)
	(gr_line
		(start 117.523006 -293.03599)
		(end 117.517672 -293.032942)
		(stroke
			(width 0.05715)
			(type default)
		)
		(layer "In4.Cu")
	)
	(gr_line
		(start 117.527832 -289.79876)
		(end 117.526816 -289.798252)
		(stroke
			(width 0.05715)
			(type default)
		)
		(layer "In4.Cu")
	)
	(gr_line
		(start 117.530626 -289.800538)
		(end 117.527832 -289.79876)
		(stroke
			(width 0.05715)
			(type default)
		)
		(layer "In4.Cu")
	)
	(gr_line
		(start 117.538754 -337.774026)
		(end 117.66042 -338.475574)
		(stroke
			(width 0.07112)
			(type default)
		)
		(layer "In4.Cu")
	)
	(gr_arc
		(start 117.53977 -294.006778)
		(mid 117.542186 -294.005387)
		(end 117.544596 -294.003984)
		(stroke
			(width 0.05715)
			(type default)
		)
		(layer "In4.Cu")
	)
	(gr_arc
		(start 117.545612 -293.049198)
		(mid 117.54257 -293.047283)
		(end 117.539516 -293.045388)
		(stroke
			(width 0.05715)
			(type default)
		)
		(layer "In4.Cu")
	)
	(gr_line
		(start 117.618002 -402.760942)
		(end 117.440456 -402.687282)
		(stroke
			(width 0.07112)
			(type default)
		)
		(layer "In4.Cu")
	)
	(gr_line
		(start 117.644418 -385.405376)
		(end 117.644926 -385.404868)
		(stroke
			(width 0.07112)
			(type default)
		)
		(layer "In4.Cu")
	)
	(gr_line
		(start 117.652292 -314.060078)
		(end 117.652546 -314.060078)
		(stroke
			(width 0.07112)
			(type default)
		)
		(layer "In4.Cu")
	)
	(gr_arc
		(start 117.666262 -338.51469)
		(mid 117.663606 -338.495092)
		(end 117.66042 -338.475574)
		(stroke
			(width 0.07112)
			(type default)
		)
		(layer "In4.Cu")
	)
	(gr_arc
		(start 117.670326 -338.562696)
		(mid 117.668684 -338.53866)
		(end 117.666262 -338.51469)
		(stroke
			(width 0.07112)
			(type default)
		)
		(layer "In4.Cu")
	)
	(gr_arc
		(start 117.671342 -338.601812)
		(mid 117.67109 -338.582247)
		(end 117.670326 -338.562696)
		(stroke
			(width 0.07112)
			(type default)
		)
		(layer "In4.Cu")
	)
	(gr_line
		(start 117.691154 -386.003292)
		(end 117.785896 -385.649724)
		(stroke
			(width 0.07112)
			(type default)
		)
		(layer "In4.Cu")
	)
	(gr_line
		(start 117.719856 -329.478386)
		(end 117.72011 -329.478386)
		(stroke
			(width 0.07112)
			(type default)
		)
		(layer "In4.Cu")
	)
	(gr_line
		(start 117.758464 -382.81229)
		(end 117.75821 -382.812544)
		(stroke
			(width 0.07112)
			(type default)
		)
		(layer "In4.Cu")
	)
	(gr_line
		(start 117.902482 -290.77412)
		(end 117.90172 -290.773612)
		(stroke
			(width 0.05715)
			(type default)
		)
		(layer "In4.Cu")
	)
	(gr_line
		(start 117.903752 -290.774882)
		(end 117.902482 -290.77412)
		(stroke
			(width 0.05715)
			(type default)
		)
		(layer "In4.Cu")
	)
	(gr_line
		(start 117.907562 -385.579112)
		(end 117.960394 -385.548632)
		(stroke
			(width 0.07112)
			(type default)
		)
		(layer "In4.Cu")
	)
	(gr_line
		(start 117.907816 -290.777168)
		(end 117.906292 -290.776152)
		(stroke
			(width 0.05715)
			(type default)
		)
		(layer "In4.Cu")
	)
	(gr_line
		(start 117.908832 -290.777676)
		(end 117.907816 -290.777168)
		(stroke
			(width 0.05715)
			(type default)
		)
		(layer "In4.Cu")
	)
	(gr_line
		(start 117.90934 -290.77793)
		(end 117.908832 -290.777676)
		(stroke
			(width 0.05715)
			(type default)
		)
		(layer "In4.Cu")
	)
	(gr_line
		(start 117.960394 -385.548632)
		(end 118.048532 -385.460494)
		(stroke
			(width 0.07112)
			(type default)
		)
		(layer "In4.Cu")
	)
	(gr_line
		(start 117.97919 -402.157692)
		(end 117.330982 -402.42617)
		(stroke
			(width 0.07112)
			(type default)
		)
		(layer "In4.Cu")
	)
	(gr_line
		(start 118.003066 -290.611814)
		(end 118.00205 -290.611306)
		(stroke
			(width 0.05715)
			(type default)
		)
		(layer "In4.Cu")
	)
	(gr_line
		(start 118.004082 -290.612576)
		(end 118.003066 -290.611814)
		(stroke
			(width 0.05715)
			(type default)
		)
		(layer "In4.Cu")
	)
	(gr_line
		(start 118.012464 -402.59762)
		(end 117.618002 -402.760942)
		(stroke
			(width 0.07112)
			(type default)
		)
		(layer "In4.Cu")
	)
	(gr_line
		(start 118.029228 -290.627054)
		(end 118.02872 -290.6268)
		(stroke
			(width 0.05715)
			(type default)
		)
		(layer "In4.Cu")
	)
	(gr_line
		(start 118.02999 -290.627562)
		(end 118.029228 -290.627054)
		(stroke
			(width 0.05715)
			(type default)
		)
		(layer "In4.Cu")
	)
	(gr_line
		(start 118.036848 -290.631626)
		(end 118.02999 -290.627562)
		(stroke
			(width 0.05715)
			(type default)
		)
		(layer "In4.Cu")
	)
	(gr_line
		(start 118.04396 -296.358564)
		(end 118.04396 -296.330116)
		(stroke
			(width 0.05715)
			(type default)
		)
		(layer "In4.Cu")
	)
	(gr_line
		(start 118.04396 -296.330116)
		(end 118.08968 -296.284396)
		(stroke
			(width 0.05715)
			(type default)
		)
		(layer "In4.Cu")
	)
	(gr_arc
		(start 118.044722 -290.637214)
		(mid 118.040797 -290.634403)
		(end 118.036848 -290.631626)
		(stroke
			(width 0.05715)
			(type default)
		)
		(layer "In4.Cu")
	)
	(gr_line
		(start 118.048532 -385.460494)
		(end 118.048532 -385.334764)
		(stroke
			(width 0.07112)
			(type default)
		)
		(layer "In4.Cu")
	)
	(gr_line
		(start 118.086124 -402.41982)
		(end 118.012464 -402.59762)
		(stroke
			(width 0.07112)
			(type default)
		)
		(layer "In4.Cu")
	)
	(gr_line
		(start 118.248176 -404.17369)
		(end 117.957346 -404.46452)
		(stroke
			(width 0.07112)
			(type default)
		)
		(layer "In4.Cu")
	)
	(gr_line
		(start 118.3259 -296.358564)
		(end 118.3259 -296.330116)
		(stroke
			(width 0.05715)
			(type default)
		)
		(layer "In4.Cu")
	)
	(gr_line
		(start 118.3259 -296.330116)
		(end 118.28018 -296.284396)
		(stroke
			(width 0.05715)
			(type default)
		)
		(layer "In4.Cu")
	)
	(gr_line
		(start 118.467886 -313.579764)
		(end 118.46814 -313.57951)
		(stroke
			(width 0.07112)
			(type default)
		)
		(layer "In4.Cu")
	)
	(gr_line
		(start 118.46814 -313.57951)
		(end 118.737888 -313.908186)
		(stroke
			(width 0.07112)
			(type default)
		)
		(layer "In4.Cu")
	)
	(gr_line
		(start 118.491254 -385.31038)
		(end 118.844568 -385.405376)
		(stroke
			(width 0.07112)
			(type default)
		)
		(layer "In4.Cu")
	)
	(gr_line
		(start 118.530116 -404.17369)
		(end 118.820946 -404.46452)
		(stroke
			(width 0.07112)
			(type default)
		)
		(layer "In4.Cu")
	)
	(gr_line
		(start 118.62181 -329.096878)
		(end 118.622064 -329.096878)
		(stroke
			(width 0.07112)
			(type default)
		)
		(layer "In4.Cu")
	)
	(gr_line
		(start 118.65356 -402.31949)
		(end 118.491 -402.25218)
		(stroke
			(width 0.07112)
			(type default)
		)
		(layer "In4.Cu")
	)
	(gr_line
		(start 118.686072 -313.400694)
		(end 118.95582 -313.72937)
		(stroke
			(width 0.07112)
			(type default)
		)
		(layer "In4.Cu")
	)
	(gr_line
		(start 118.844568 -385.405376)
		(end 118.845076 -385.404868)
		(stroke
			(width 0.07112)
			(type default)
		)
		(layer "In4.Cu")
	)
	(gr_line
		(start 118.891304 -386.003292)
		(end 118.986046 -385.649724)
		(stroke
			(width 0.07112)
			(type default)
		)
		(layer "In4.Cu")
	)
	(gr_line
		(start 118.983506 -296.457116)
		(end 118.983506 -296.428668)
		(stroke
			(width 0.05715)
			(type default)
		)
		(layer "In4.Cu")
	)
	(gr_line
		(start 118.983506 -296.428668)
		(end 119.029226 -296.382948)
		(stroke
			(width 0.05715)
			(type default)
		)
		(layer "In4.Cu")
	)
	(gr_line
		(start 119.008144 -401.73148)
		(end 118.38178 -401.990814)
		(stroke
			(width 0.07112)
			(type default)
		)
		(layer "In4.Cu")
	)
	(gr_line
		(start 119.029226 -295.952418)
		(end 119.029226 -295.948354)
		(stroke
			(width 0.05715)
			(type default)
		)
		(layer "In4.Cu")
	)
	(gr_arc
		(start 119.02948 -295.943274)
		(mid 119.029348 -295.945814)
		(end 119.029226 -295.948354)
		(stroke
			(width 0.05715)
			(type default)
		)
		(layer "In4.Cu")
	)
	(gr_line
		(start 119.048022 -402.156168)
		(end 118.65356 -402.31949)
		(stroke
			(width 0.07112)
			(type default)
		)
		(layer "In4.Cu")
	)
	(gr_line
		(start 119.107712 -385.579112)
		(end 119.160544 -385.548632)
		(stroke
			(width 0.07112)
			(type default)
		)
		(layer "In4.Cu")
	)
	(gr_line
		(start 119.115586 -401.993608)
		(end 119.048022 -402.156168)
		(stroke
			(width 0.07112)
			(type default)
		)
		(layer "In4.Cu")
	)
	(gr_line
		(start 119.160544 -385.548632)
		(end 119.248682 -385.460494)
		(stroke
			(width 0.07112)
			(type default)
		)
		(layer "In4.Cu")
	)
	(gr_line
		(start 119.215662 -313.002422)
		(end 119.215662 -313.002168)
		(stroke
			(width 0.07112)
			(type default)
		)
		(layer "In4.Cu")
	)
	(gr_line
		(start 119.248682 -385.460494)
		(end 119.248682 -385.334764)
		(stroke
			(width 0.07112)
			(type default)
		)
		(layer "In4.Cu")
	)
	(gr_line
		(start 119.265446 -296.457116)
		(end 119.265446 -296.428668)
		(stroke
			(width 0.05715)
			(type default)
		)
		(layer "In4.Cu")
	)
	(gr_line
		(start 119.265446 -296.428668)
		(end 119.219726 -296.382948)
		(stroke
			(width 0.05715)
			(type default)
		)
		(layer "In4.Cu")
	)
	(gr_arc
		(start 119.273066 -295.491154)
		(mid 119.265529 -295.496427)
		(end 119.25808 -295.501822)
		(stroke
			(width 0.05715)
			(type default)
		)
		(layer "In4.Cu")
	)
	(gr_arc
		(start 119.273066 -295.491154)
		(mid 119.273447 -295.4909)
		(end 119.273828 -295.490646)
		(stroke
			(width 0.05715)
			(type default)
		)
		(layer "In4.Cu")
	)
	(gr_line
		(start 119.275098 -298.25442)
		(end 119.275098 -298.254166)
		(stroke
			(width 0.07112)
			(type default)
		)
		(layer "In4.Cu")
	)
	(gr_line
		(start 119.288814 -378.741178)
		(end 119.395748 -378.581158)
		(stroke
			(width 0.07112)
			(type default)
		)
		(layer "In4.Cu")
	)
	(gr_line
		(start 119.304308 -293.853108)
		(end 119.308118 -293.850822)
		(stroke
			(width 0.05715)
			(type default)
		)
		(layer "In4.Cu")
	)
	(gr_line
		(start 119.304308 -292.233096)
		(end 119.308118 -292.23081)
		(stroke
			(width 0.05715)
			(type default)
		)
		(layer "In4.Cu")
	)
	(gr_line
		(start 119.304308 -288.993072)
		(end 119.308118 -288.990786)
		(stroke
			(width 0.05715)
			(type default)
		)
		(layer "In4.Cu")
	)
	(gr_line
		(start 119.304562 -291.5793)
		(end 119.30253 -291.57803)
		(stroke
			(width 0.05715)
			(type default)
		)
		(layer "In4.Cu")
	)
	(gr_line
		(start 119.306086 -291.580316)
		(end 119.305578 -291.580062)
		(stroke
			(width 0.05715)
			(type default)
		)
		(layer "In4.Cu")
	)
	(gr_line
		(start 119.308118 -293.850822)
		(end 119.309134 -293.850314)
		(stroke
			(width 0.05715)
			(type default)
		)
		(layer "In4.Cu")
	)
	(gr_line
		(start 119.308118 -292.23081)
		(end 119.309134 -292.230302)
		(stroke
			(width 0.05715)
			(type default)
		)
		(layer "In4.Cu")
	)
	(gr_line
		(start 119.308118 -288.990786)
		(end 119.309134 -288.990278)
		(stroke
			(width 0.05715)
			(type default)
		)
		(layer "In4.Cu")
	)
	(gr_line
		(start 119.309134 -293.850314)
		(end 119.310658 -293.849298)
		(stroke
			(width 0.05715)
			(type default)
		)
		(layer "In4.Cu")
	)
	(gr_line
		(start 119.309134 -292.230302)
		(end 119.310658 -292.229286)
		(stroke
			(width 0.05715)
			(type default)
		)
		(layer "In4.Cu")
	)
	(gr_line
		(start 119.309134 -291.582094)
		(end 119.308118 -291.581586)
		(stroke
			(width 0.05715)
			(type default)
		)
		(layer "In4.Cu")
	)
	(gr_line
		(start 119.309134 -288.990278)
		(end 119.310658 -288.989262)
		(stroke
			(width 0.05715)
			(type default)
		)
		(layer "In4.Cu")
	)
	(gr_line
		(start 119.310658 -293.849298)
		(end 119.311674 -293.84879)
		(stroke
			(width 0.05715)
			(type default)
		)
		(layer "In4.Cu")
	)
	(gr_line
		(start 119.310658 -292.229286)
		(end 119.311674 -292.228778)
		(stroke
			(width 0.05715)
			(type default)
		)
		(layer "In4.Cu")
	)
	(gr_line
		(start 119.310658 -291.58311)
		(end 119.309134 -291.582094)
		(stroke
			(width 0.05715)
			(type default)
		)
		(layer "In4.Cu")
	)
	(gr_line
		(start 119.310658 -288.989262)
		(end 119.311674 -288.988754)
		(stroke
			(width 0.05715)
			(type default)
		)
		(layer "In4.Cu")
	)
	(gr_line
		(start 119.311674 -293.84879)
		(end 119.312436 -293.848282)
		(stroke
			(width 0.05715)
			(type default)
		)
		(layer "In4.Cu")
	)
	(gr_line
		(start 119.311674 -292.228778)
		(end 119.312436 -292.22827)
		(stroke
			(width 0.05715)
			(type default)
		)
		(layer "In4.Cu")
	)
	(gr_line
		(start 119.311674 -291.583618)
		(end 119.310658 -291.58311)
		(stroke
			(width 0.05715)
			(type default)
		)
		(layer "In4.Cu")
	)
	(gr_line
		(start 119.311674 -288.988754)
		(end 119.312436 -288.988246)
		(stroke
			(width 0.05715)
			(type default)
		)
		(layer "In4.Cu")
	)
	(gr_line
		(start 119.312436 -291.584126)
		(end 119.311674 -291.583618)
		(stroke
			(width 0.05715)
			(type default)
		)
		(layer "In4.Cu")
	)
	(gr_line
		(start 119.313706 -294.824912)
		(end 119.312436 -294.82415)
		(stroke
			(width 0.05715)
			(type default)
		)
		(layer "In4.Cu")
	)
	(gr_line
		(start 119.313706 -293.2049)
		(end 119.312436 -293.204138)
		(stroke
			(width 0.05715)
			(type default)
		)
		(layer "In4.Cu")
	)
	(gr_line
		(start 119.315484 -293.846504)
		(end 119.315992 -293.84625)
		(stroke
			(width 0.05715)
			(type default)
		)
		(layer "In4.Cu")
	)
	(gr_line
		(start 119.315484 -292.226492)
		(end 119.315992 -292.226238)
		(stroke
			(width 0.05715)
			(type default)
		)
		(layer "In4.Cu")
	)
	(gr_line
		(start 119.315484 -288.986468)
		(end 119.315992 -288.986214)
		(stroke
			(width 0.05715)
			(type default)
		)
		(layer "In4.Cu")
	)
	(gr_line
		(start 119.318786 -291.587682)
		(end 119.31777 -291.587174)
		(stroke
			(width 0.05715)
			(type default)
		)
		(layer "In4.Cu")
	)
	(gr_line
		(start 119.319294 -291.587936)
		(end 119.318786 -291.587682)
		(stroke
			(width 0.05715)
			(type default)
		)
		(layer "In4.Cu")
	)
	(gr_line
		(start 119.371872 -379.160024)
		(end 119.288814 -378.741178)
		(stroke
			(width 0.07112)
			(type default)
		)
		(layer "In4.Cu")
	)
	(gr_line
		(start 119.397526 -294.019478)
		(end 119.398288 -294.01897)
		(stroke
			(width 0.05715)
			(type default)
		)
		(layer "In4.Cu")
	)
	(gr_line
		(start 119.397526 -292.399466)
		(end 119.398288 -292.398958)
		(stroke
			(width 0.05715)
			(type default)
		)
		(layer "In4.Cu")
	)
	(gr_line
		(start 119.397526 -289.159442)
		(end 119.398288 -289.158934)
		(stroke
			(width 0.05715)
			(type default)
		)
		(layer "In4.Cu")
	)
	(gr_line
		(start 119.403368 -291.416232)
		(end 119.401844 -291.41547)
		(stroke
			(width 0.05715)
			(type default)
		)
		(layer "In4.Cu")
	)
	(gr_line
		(start 119.4054 -294.014906)
		(end 119.406924 -294.014144)
		(stroke
			(width 0.05715)
			(type default)
		)
		(layer "In4.Cu")
	)
	(gr_line
		(start 119.4054 -292.394894)
		(end 119.406924 -292.394132)
		(stroke
			(width 0.05715)
			(type default)
		)
		(layer "In4.Cu")
	)
	(gr_line
		(start 119.4054 -289.15487)
		(end 119.406924 -289.154108)
		(stroke
			(width 0.05715)
			(type default)
		)
		(layer "In4.Cu")
	)
	(gr_line
		(start 119.406924 -294.014144)
		(end 119.407686 -294.013636)
		(stroke
			(width 0.05715)
			(type default)
		)
		(layer "In4.Cu")
	)
	(gr_line
		(start 119.406924 -292.394132)
		(end 119.407686 -292.393624)
		(stroke
			(width 0.05715)
			(type default)
		)
		(layer "In4.Cu")
	)
	(gr_line
		(start 119.406924 -291.418264)
		(end 119.406416 -291.41801)
		(stroke
			(width 0.05715)
			(type default)
		)
		(layer "In4.Cu")
	)
	(gr_line
		(start 119.406924 -289.154108)
		(end 119.407686 -289.1536)
		(stroke
			(width 0.05715)
			(type default)
		)
		(layer "In4.Cu")
	)
	(gr_line
		(start 119.407686 -294.658796)
		(end 119.407178 -294.658542)
		(stroke
			(width 0.05715)
			(type default)
		)
		(layer "In4.Cu")
	)
	(gr_line
		(start 119.407686 -294.013636)
		(end 119.408702 -294.013128)
		(stroke
			(width 0.05715)
			(type default)
		)
		(layer "In4.Cu")
	)
	(gr_line
		(start 119.407686 -293.038784)
		(end 119.407178 -293.03853)
		(stroke
			(width 0.05715)
			(type default)
		)
		(layer "In4.Cu")
	)
	(gr_line
		(start 119.407686 -292.393624)
		(end 119.408702 -292.393116)
		(stroke
			(width 0.05715)
			(type default)
		)
		(layer "In4.Cu")
	)
	(gr_line
		(start 119.407686 -291.418772)
		(end 119.406924 -291.418264)
		(stroke
			(width 0.05715)
			(type default)
		)
		(layer "In4.Cu")
	)
	(gr_line
		(start 119.407686 -289.1536)
		(end 119.408702 -289.153092)
		(stroke
			(width 0.05715)
			(type default)
		)
		(layer "In4.Cu")
	)
	(gr_line
		(start 119.408702 -294.659304)
		(end 119.407686 -294.658796)
		(stroke
			(width 0.05715)
			(type default)
		)
		(layer "In4.Cu")
	)
	(gr_line
		(start 119.408702 -294.013128)
		(end 119.410226 -294.012112)
		(stroke
			(width 0.05715)
			(type default)
		)
		(layer "In4.Cu")
	)
	(gr_line
		(start 119.408702 -293.039292)
		(end 119.407686 -293.038784)
		(stroke
			(width 0.05715)
			(type default)
		)
		(layer "In4.Cu")
	)
	(gr_line
		(start 119.408702 -292.393116)
		(end 119.410226 -292.3921)
		(stroke
			(width 0.05715)
			(type default)
		)
		(layer "In4.Cu")
	)
	(gr_line
		(start 119.408702 -291.41928)
		(end 119.407686 -291.418772)
		(stroke
			(width 0.05715)
			(type default)
		)
		(layer "In4.Cu")
	)
	(gr_line
		(start 119.408702 -289.153092)
		(end 119.410226 -289.152076)
		(stroke
			(width 0.05715)
			(type default)
		)
		(layer "In4.Cu")
	)
	(gr_line
		(start 119.41048 -291.420296)
		(end 119.408702 -291.41928)
		(stroke
			(width 0.05715)
			(type default)
		)
		(layer "In4.Cu")
	)
	(gr_line
		(start 119.412004 -294.011096)
		(end 119.414036 -294.009826)
		(stroke
			(width 0.05715)
			(type default)
		)
		(layer "In4.Cu")
	)
	(gr_line
		(start 119.412004 -292.391084)
		(end 119.414036 -292.389814)
		(stroke
			(width 0.05715)
			(type default)
		)
		(layer "In4.Cu")
	)
	(gr_line
		(start 119.412004 -289.15106)
		(end 119.414036 -289.14979)
		(stroke
			(width 0.05715)
			(type default)
		)
		(layer "In4.Cu")
	)
	(gr_line
		(start 119.41302 -291.42182)
		(end 119.412004 -291.421312)
		(stroke
			(width 0.05715)
			(type default)
		)
		(layer "In4.Cu")
	)
	(gr_line
		(start 119.414036 -291.422582)
		(end 119.41302 -291.42182)
		(stroke
			(width 0.05715)
			(type default)
		)
		(layer "In4.Cu")
	)
	(gr_line
		(start 119.439182 -291.43706)
		(end 119.438674 -291.436806)
		(stroke
			(width 0.05715)
			(type default)
		)
		(layer "In4.Cu")
	)
	(gr_line
		(start 119.439944 -291.437568)
		(end 119.439182 -291.43706)
		(stroke
			(width 0.05715)
			(type default)
		)
		(layer "In4.Cu")
	)
	(gr_line
		(start 119.446802 -291.441632)
		(end 119.439944 -291.437568)
		(stroke
			(width 0.05715)
			(type default)
		)
		(layer "In4.Cu")
	)
	(gr_arc
		(start 119.454676 -291.44722)
		(mid 119.450751 -291.444409)
		(end 119.446802 -291.441632)
		(stroke
			(width 0.05715)
			(type default)
		)
		(layer "In4.Cu")
	)
	(gr_line
		(start 119.499634 -295.146476)
		(end 119.499634 -295.146222)
		(stroke
			(width 0.05715)
			(type default)
		)
		(layer "In4.Cu")
	)
	(gr_line
		(start 119.508778 -379.847602)
		(end 119.615712 -379.687582)
		(stroke
			(width 0.07112)
			(type default)
		)
		(layer "In4.Cu")
	)
	(gr_line
		(start 119.532146 -379.267212)
		(end 119.371872 -379.160024)
		(stroke
			(width 0.07112)
			(type default)
		)
		(layer "In4.Cu")
	)
	(gr_line
		(start 119.591836 -380.266194)
		(end 119.508778 -379.847602)
		(stroke
			(width 0.07112)
			(type default)
		)
		(layer "In4.Cu")
	)
	(gr_line
		(start 119.647462 -335.109312)
		(end 119.657876 -335.139284)
		(stroke
			(width 0.07112)
			(type default)
		)
		(layer "In4.Cu")
	)
	(gr_line
		(start 119.657876 -335.139284)
		(end 119.663718 -335.171288)
		(stroke
			(width 0.07112)
			(type default)
		)
		(layer "In4.Cu")
	)
	(gr_line
		(start 119.690134 -295.14673)
		(end 119.690134 -295.146222)
		(stroke
			(width 0.05715)
			(type default)
		)
		(layer "In4.Cu")
	)
	(gr_line
		(start 119.69115 -385.31038)
		(end 120.044464 -385.405376)
		(stroke
			(width 0.07112)
			(type default)
		)
		(layer "In4.Cu")
	)
	(gr_line
		(start 119.728742 -380.953772)
		(end 119.835676 -380.793752)
		(stroke
			(width 0.07112)
			(type default)
		)
		(layer "In4.Cu")
	)
	(gr_line
		(start 119.75211 -380.373128)
		(end 119.591836 -380.266194)
		(stroke
			(width 0.07112)
			(type default)
		)
		(layer "In4.Cu")
	)
	(gr_line
		(start 119.810022 -379.21311)
		(end 119.67337 -378.525278)
		(stroke
			(width 0.07112)
			(type default)
		)
		(layer "In4.Cu")
	)
	(gr_line
		(start 119.812054 -381.372364)
		(end 119.728742 -380.953772)
		(stroke
			(width 0.07112)
			(type default)
		)
		(layer "In4.Cu")
	)
	(gr_line
		(start 119.892572 -291.096192)
		(end 119.59463 -291.096192)
		(stroke
			(width 0.05715)
			(type default)
		)
		(layer "In4.Cu")
	)
	(gr_line
		(start 119.892572 -289.47618)
		(end 119.59463 -289.47618)
		(stroke
			(width 0.05715)
			(type default)
		)
		(layer "In4.Cu")
	)
	(gr_line
		(start 119.892572 -287.856422)
		(end 119.59463 -287.856422)
		(stroke
			(width 0.05715)
			(type default)
		)
		(layer "In4.Cu")
	)
	(gr_arc
		(start 119.923814 -335.048352)
		(mid 119.919619 -335.034217)
		(end 119.915178 -335.020158)
		(stroke
			(width 0.07112)
			(type default)
		)
		(layer "In4.Cu")
	)
	(gr_line
		(start 119.923814 -296.462704)
		(end 119.923814 -296.434256)
		(stroke
			(width 0.05715)
			(type default)
		)
		(layer "In4.Cu")
	)
	(gr_line
		(start 119.923814 -296.434256)
		(end 119.969534 -296.388536)
		(stroke
			(width 0.05715)
			(type default)
		)
		(layer "In4.Cu")
	)
	(gr_arc
		(start 119.934482 -335.0895)
		(mid 119.92941 -335.068858)
		(end 119.923814 -335.048352)
		(stroke
			(width 0.07112)
			(type default)
		)
		(layer "In4.Cu")
	)
	(gr_arc
		(start 119.940832 -335.119218)
		(mid 119.937793 -335.10433)
		(end 119.934482 -335.0895)
		(stroke
			(width 0.07112)
			(type default)
		)
		(layer "In4.Cu")
	)
	(gr_line
		(start 119.961914 -287.925764)
		(end 119.892572 -287.856422)
		(stroke
			(width 0.05715)
			(type default)
		)
		(layer "In4.Cu")
	)
	(gr_line
		(start 119.972074 -381.479298)
		(end 119.812054 -381.372364)
		(stroke
			(width 0.07112)
			(type default)
		)
		(layer "In4.Cu")
	)
	(gr_line
		(start 119.975376 -291.178996)
		(end 119.892572 -291.096192)
		(stroke
			(width 0.05715)
			(type default)
		)
		(layer "In4.Cu")
	)
	(gr_line
		(start 119.975376 -289.558984)
		(end 119.892572 -289.47618)
		(stroke
			(width 0.05715)
			(type default)
		)
		(layer "In4.Cu")
	)
	(gr_arc
		(start 119.975376 -289.558984)
		(mid 119.977168 -289.570306)
		(end 119.979186 -289.58159)
		(stroke
			(width 0.05715)
			(type default)
		)
		(layer "In4.Cu")
	)
	(gr_line
		(start 119.97563 -291.178996)
		(end 119.975376 -291.178996)
		(stroke
			(width 0.05715)
			(type default)
		)
		(layer "In4.Cu")
	)
	(gr_arc
		(start 119.97563 -291.178996)
		(mid 119.977422 -291.190318)
		(end 119.97944 -291.201602)
		(stroke
			(width 0.05715)
			(type default)
		)
		(layer "In4.Cu")
	)
	(gr_line
		(start 120.029986 -380.31928)
		(end 119.893334 -379.631448)
		(stroke
			(width 0.07112)
			(type default)
		)
		(layer "In4.Cu")
	)
	(gr_line
		(start 120.044464 -385.405376)
		(end 120.044972 -385.404868)
		(stroke
			(width 0.07112)
			(type default)
		)
		(layer "In4.Cu")
	)
	(gr_line
		(start 120.0912 -386.003292)
		(end 120.185942 -385.649724)
		(stroke
			(width 0.07112)
			(type default)
		)
		(layer "In4.Cu")
	)
	(gr_arc
		(start 120.150128 -287.962086)
		(mid 120.152151 -287.950676)
		(end 120.153938 -287.939226)
		(stroke
			(width 0.05715)
			(type default)
		)
		(layer "In4.Cu")
	)
	(gr_line
		(start 120.153938 -287.939226)
		(end 120.236742 -287.856422)
		(stroke
			(width 0.05715)
			(type default)
		)
		(layer "In4.Cu")
	)
	(gr_line
		(start 120.1674 -289.545522)
		(end 120.236742 -289.47618)
		(stroke
			(width 0.05715)
			(type default)
		)
		(layer "In4.Cu")
	)
	(gr_line
		(start 120.167654 -291.16528)
		(end 120.236742 -291.096192)
		(stroke
			(width 0.05715)
			(type default)
		)
		(layer "In4.Cu")
	)
	(gr_line
		(start 120.186958 -402.422868)
		(end 120.187212 -402.423122)
		(stroke
			(width 0.07112)
			(type default)
		)
		(layer "In4.Cu")
	)
	(gr_arc
		(start 120.204484 -289.935158)
		(mid 120.208535 -289.93797)
		(end 120.212612 -289.940746)
		(stroke
			(width 0.05715)
			(type default)
		)
		(layer "In4.Cu")
	)
	(gr_line
		(start 120.205754 -296.462704)
		(end 120.205754 -296.434256)
		(stroke
			(width 0.05715)
			(type default)
		)
		(layer "In4.Cu")
	)
	(gr_line
		(start 120.205754 -296.434256)
		(end 120.160034 -296.388536)
		(stroke
			(width 0.05715)
			(type default)
		)
		(layer "In4.Cu")
	)
	(gr_arc
		(start 120.213374 -289.941254)
		(mid 120.212993 -289.941)
		(end 120.212612 -289.940746)
		(stroke
			(width 0.05715)
			(type default)
		)
		(layer "In4.Cu")
	)
	(gr_line
		(start 120.220486 -289.945318)
		(end 120.213374 -289.941254)
		(stroke
			(width 0.05715)
			(type default)
		)
		(layer "In4.Cu")
	)
	(gr_line
		(start 120.236742 -291.096192)
		(end 120.534684 -291.096192)
		(stroke
			(width 0.05715)
			(type default)
		)
		(layer "In4.Cu")
	)
	(gr_line
		(start 120.236742 -289.47618)
		(end 120.534684 -289.47618)
		(stroke
			(width 0.05715)
			(type default)
		)
		(layer "In4.Cu")
	)
	(gr_line
		(start 120.236742 -287.856422)
		(end 120.534684 -287.856422)
		(stroke
			(width 0.05715)
			(type default)
		)
		(layer "In4.Cu")
	)
	(gr_line
		(start 120.245632 -293.852092)
		(end 120.248172 -293.850314)
		(stroke
			(width 0.05715)
			(type default)
		)
		(layer "In4.Cu")
	)
	(gr_line
		(start 120.248172 -293.850314)
		(end 120.249188 -293.849806)
		(stroke
			(width 0.05715)
			(type default)
		)
		(layer "In4.Cu")
	)
	(gr_line
		(start 120.249188 -293.849806)
		(end 120.24995 -293.849298)
		(stroke
			(width 0.05715)
			(type default)
		)
		(layer "In4.Cu")
	)
	(gr_line
		(start 120.24995 -381.425196)
		(end 120.113298 -380.737618)
		(stroke
			(width 0.07112)
			(type default)
		)
		(layer "In4.Cu")
	)
	(gr_line
		(start 120.24995 -293.849298)
		(end 120.250966 -293.84879)
		(stroke
			(width 0.05715)
			(type default)
		)
		(layer "In4.Cu")
	)
	(gr_line
		(start 120.250966 -293.84879)
		(end 120.251982 -293.848028)
		(stroke
			(width 0.05715)
			(type default)
		)
		(layer "In4.Cu")
	)
	(gr_line
		(start 120.252236 -289.96386)
		(end 120.251474 -289.963352)
		(stroke
			(width 0.05715)
			(type default)
		)
		(layer "In4.Cu")
	)
	(gr_line
		(start 120.25503 -289.965384)
		(end 120.252236 -289.96386)
		(stroke
			(width 0.05715)
			(type default)
		)
		(layer "In4.Cu")
	)
	(gr_line
		(start 120.257062 -293.844726)
		(end 120.282716 -293.827708)
		(stroke
			(width 0.05715)
			(type default)
		)
		(layer "In4.Cu")
	)
	(gr_line
		(start 120.258586 -295.463976)
		(end 120.282462 -295.447974)
		(stroke
			(width 0.05715)
			(type default)
		)
		(layer "In4.Cu")
	)
	(gr_line
		(start 120.307608 -385.579112)
		(end 120.36044 -385.548632)
		(stroke
			(width 0.07112)
			(type default)
		)
		(layer "In4.Cu")
	)
	(gr_line
		(start 120.33504 -294.020748)
		(end 120.335548 -294.020494)
		(stroke
			(width 0.05715)
			(type default)
		)
		(layer "In4.Cu")
	)
	(gr_line
		(start 120.336564 -294.019986)
		(end 120.34139 -294.017192)
		(stroke
			(width 0.05715)
			(type default)
		)
		(layer "In4.Cu")
	)
	(gr_line
		(start 120.338596 -295.638982)
		(end 120.346978 -295.634156)
		(stroke
			(width 0.05715)
			(type default)
		)
		(layer "In4.Cu")
	)
	(gr_line
		(start 120.34139 -294.017192)
		(end 120.343422 -294.016176)
		(stroke
			(width 0.05715)
			(type default)
		)
		(layer "In4.Cu")
	)
	(gr_line
		(start 120.343422 -294.016176)
		(end 120.344184 -294.015668)
		(stroke
			(width 0.05715)
			(type default)
		)
		(layer "In4.Cu")
	)
	(gr_line
		(start 120.344184 -294.015668)
		(end 120.3452 -294.01516)
		(stroke
			(width 0.05715)
			(type default)
		)
		(layer "In4.Cu")
	)
	(gr_line
		(start 120.3452 -294.01516)
		(end 120.345962 -294.014652)
		(stroke
			(width 0.05715)
			(type default)
		)
		(layer "In4.Cu")
	)
	(gr_line
		(start 120.345962 -294.014652)
		(end 120.346978 -294.014144)
		(stroke
			(width 0.05715)
			(type default)
		)
		(layer "In4.Cu")
	)
	(gr_line
		(start 120.346978 -295.634156)
		(end 120.34774 -295.633648)
		(stroke
			(width 0.05715)
			(type default)
		)
		(layer "In4.Cu")
	)
	(gr_line
		(start 120.347232 -292.393878)
		(end 120.34774 -292.393624)
		(stroke
			(width 0.05715)
			(type default)
		)
		(layer "In4.Cu")
	)
	(gr_line
		(start 120.347486 -294.658542)
		(end 120.342152 -294.655494)
		(stroke
			(width 0.05715)
			(type default)
		)
		(layer "In4.Cu")
	)
	(gr_line
		(start 120.347486 -293.03853)
		(end 120.342152 -293.035482)
		(stroke
			(width 0.05715)
			(type default)
		)
		(layer "In4.Cu")
	)
	(gr_line
		(start 120.34774 -295.633648)
		(end 120.348248 -295.633648)
		(stroke
			(width 0.05715)
			(type default)
		)
		(layer "In4.Cu")
	)
	(gr_line
		(start 120.34774 -291.418772)
		(end 120.347232 -291.418518)
		(stroke
			(width 0.05715)
			(type default)
		)
		(layer "In4.Cu")
	)
	(gr_line
		(start 120.34774 -289.79876)
		(end 120.346724 -289.798252)
		(stroke
			(width 0.05715)
			(type default)
		)
		(layer "In4.Cu")
	)
	(gr_arc
		(start 120.348248 -295.633648)
		(mid 120.349519 -295.632888)
		(end 120.350788 -295.632124)
		(stroke
			(width 0.05715)
			(type default)
		)
		(layer "In4.Cu")
	)
	(gr_arc
		(start 120.35028 -294.012366)
		(mid 120.351424 -294.011732)
		(end 120.352566 -294.011096)
		(stroke
			(width 0.05715)
			(type default)
		)
		(layer "In4.Cu")
	)
	(gr_line
		(start 120.350534 -289.800538)
		(end 120.34774 -289.79876)
		(stroke
			(width 0.05715)
			(type default)
		)
		(layer "In4.Cu")
	)
	(gr_arc
		(start 120.355614 -294.009318)
		(mid 120.354979 -294.009699)
		(end 120.354344 -294.01008)
		(stroke
			(width 0.05715)
			(type default)
		)
		(layer "In4.Cu")
	)
	(gr_arc
		(start 120.359678 -294.006778)
		(mid 120.375727 -293.99663)
		(end 120.391428 -293.98595)
		(stroke
			(width 0.05715)
			(type default)
		)
		(layer "In4.Cu")
	)
	(gr_line
		(start 120.36044 -385.548632)
		(end 120.448578 -385.460494)
		(stroke
			(width 0.07112)
			(type default)
		)
		(layer "In4.Cu")
	)
	(gr_arc
		(start 120.36171 -295.62552)
		(mid 120.376598 -295.615976)
		(end 120.391174 -295.605962)
		(stroke
			(width 0.05715)
			(type default)
		)
		(layer "In4.Cu")
	)
	(gr_arc
		(start 120.367806 -294.670734)
		(mid 120.364638 -294.668692)
		(end 120.361456 -294.66667)
		(stroke
			(width 0.05715)
			(type default)
		)
		(layer "In4.Cu")
	)
	(gr_arc
		(start 120.367806 -293.050722)
		(mid 120.364638 -293.04868)
		(end 120.361456 -293.046658)
		(stroke
			(width 0.05715)
			(type default)
		)
		(layer "In4.Cu")
	)
	(gr_arc
		(start 120.395492 -293.982902)
		(mid 120.40085 -293.978997)
		(end 120.40616 -293.975028)
		(stroke
			(width 0.05715)
			(type default)
		)
		(layer "In4.Cu")
	)
	(gr_arc
		(start 120.395746 -295.602914)
		(mid 120.400976 -295.599007)
		(end 120.40616 -295.59504)
		(stroke
			(width 0.05715)
			(type default)
		)
		(layer "In4.Cu")
	)
	(gr_line
		(start 120.448578 -385.460494)
		(end 120.448578 -385.334764)
		(stroke
			(width 0.07112)
			(type default)
		)
		(layer "In4.Cu")
	)
	(gr_line
		(start 120.474232 -402.757894)
		(end 120.296178 -402.684234)
		(stroke
			(width 0.07112)
			(type default)
		)
		(layer "In4.Cu")
	)
	(gr_line
		(start 120.521984 -378.893324)
		(end 120.629172 -378.73305)
		(stroke
			(width 0.07112)
			(type default)
		)
		(layer "In4.Cu")
	)
	(gr_line
		(start 120.603518 -307.992272)
		(end 120.603772 -307.992272)
		(stroke
			(width 0.07112)
			(type default)
		)
		(layer "In4.Cu")
	)
	(gr_line
		(start 120.605296 -379.311916)
		(end 120.521984 -378.893324)
		(stroke
			(width 0.07112)
			(type default)
		)
		(layer "In4.Cu")
	)
	(gr_line
		(start 120.606312 -347.203522)
		(end 120.606312 -347.203776)
		(stroke
			(width 0.07112)
			(type default)
		)
		(layer "In4.Cu")
	)
	(gr_line
		(start 120.72239 -290.77412)
		(end 120.721628 -290.773612)
		(stroke
			(width 0.05715)
			(type default)
		)
		(layer "In4.Cu")
	)
	(gr_line
		(start 120.72366 -290.774882)
		(end 120.72239 -290.77412)
		(stroke
			(width 0.05715)
			(type default)
		)
		(layer "In4.Cu")
	)
	(gr_line
		(start 120.727724 -290.777168)
		(end 120.7262 -290.776152)
		(stroke
			(width 0.05715)
			(type default)
		)
		(layer "In4.Cu")
	)
	(gr_line
		(start 120.72874 -290.777676)
		(end 120.727724 -290.777168)
		(stroke
			(width 0.05715)
			(type default)
		)
		(layer "In4.Cu")
	)
	(gr_line
		(start 120.729248 -290.77793)
		(end 120.72874 -290.777676)
		(stroke
			(width 0.05715)
			(type default)
		)
		(layer "In4.Cu")
	)
	(gr_line
		(start 120.742202 -379.999494)
		(end 120.84939 -379.83922)
		(stroke
			(width 0.07112)
			(type default)
		)
		(layer "In4.Cu")
	)
	(gr_line
		(start 120.765824 -379.419104)
		(end 120.605296 -379.311916)
		(stroke
			(width 0.07112)
			(type default)
		)
		(layer "In4.Cu")
	)
	(gr_line
		(start 120.822974 -290.611814)
		(end 120.821958 -290.611306)
		(stroke
			(width 0.05715)
			(type default)
		)
		(layer "In4.Cu")
	)
	(gr_line
		(start 120.82399 -290.612576)
		(end 120.822974 -290.611814)
		(stroke
			(width 0.05715)
			(type default)
		)
		(layer "In4.Cu")
	)
	(gr_line
		(start 120.825514 -380.41834)
		(end 120.742202 -379.999494)
		(stroke
			(width 0.07112)
			(type default)
		)
		(layer "In4.Cu")
	)
	(gr_line
		(start 120.835166 -402.15439)
		(end 120.186958 -402.422868)
		(stroke
			(width 0.07112)
			(type default)
		)
		(layer "In4.Cu")
	)
	(gr_line
		(start 120.849136 -290.627054)
		(end 120.848628 -290.6268)
		(stroke
			(width 0.05715)
			(type default)
		)
		(layer "In4.Cu")
	)
	(gr_line
		(start 120.849898 -290.627562)
		(end 120.849136 -290.627054)
		(stroke
			(width 0.05715)
			(type default)
		)
		(layer "In4.Cu")
	)
	(gr_line
		(start 120.856756 -290.631626)
		(end 120.849898 -290.627562)
		(stroke
			(width 0.05715)
			(type default)
		)
		(layer "In4.Cu")
	)
	(gr_line
		(start 120.863868 -296.463212)
		(end 120.863868 -296.434764)
		(stroke
			(width 0.05715)
			(type default)
		)
		(layer "In4.Cu")
	)
	(gr_line
		(start 120.863868 -296.434764)
		(end 120.909588 -296.389044)
		(stroke
			(width 0.05715)
			(type default)
		)
		(layer "In4.Cu")
	)
	(gr_arc
		(start 120.86463 -290.637214)
		(mid 120.860705 -290.634403)
		(end 120.856756 -290.631626)
		(stroke
			(width 0.05715)
			(type default)
		)
		(layer "In4.Cu")
	)
	(gr_line
		(start 120.868694 -402.594572)
		(end 120.474232 -402.757894)
		(stroke
			(width 0.07112)
			(type default)
		)
		(layer "In4.Cu")
	)
	(gr_line
		(start 120.8913 -385.31038)
		(end 121.244614 -385.405376)
		(stroke
			(width 0.07112)
			(type default)
		)
		(layer "In4.Cu")
	)
	(gr_line
		(start 120.9421 -402.416518)
		(end 120.868694 -402.594572)
		(stroke
			(width 0.07112)
			(type default)
		)
		(layer "In4.Cu")
	)
	(gr_line
		(start 120.94718 -374.47982)
		(end 120.946672 -374.478804)
		(stroke
			(width 0.07112)
			(type default)
		)
		(layer "In4.Cu")
	)
	(gr_line
		(start 120.96242 -381.105664)
		(end 121.069354 -380.94539)
		(stroke
			(width 0.07112)
			(type default)
		)
		(layer "In4.Cu")
	)
	(gr_line
		(start 120.985788 -380.525274)
		(end 120.825514 -380.41834)
		(stroke
			(width 0.07112)
			(type default)
		)
		(layer "In4.Cu")
	)
	(gr_line
		(start 121.0437 -379.365002)
		(end 120.906794 -378.676916)
		(stroke
			(width 0.07112)
			(type default)
		)
		(layer "In4.Cu")
	)
	(gr_line
		(start 121.045732 -381.52451)
		(end 120.96242 -381.105664)
		(stroke
			(width 0.07112)
			(type default)
		)
		(layer "In4.Cu")
	)
	(gr_line
		(start 121.145808 -296.463212)
		(end 121.145808 -296.434764)
		(stroke
			(width 0.05715)
			(type default)
		)
		(layer "In4.Cu")
	)
	(gr_line
		(start 121.145808 -296.434764)
		(end 121.100088 -296.389044)
		(stroke
			(width 0.05715)
			(type default)
		)
		(layer "In4.Cu")
	)
	(gr_line
		(start 121.205752 -381.63119)
		(end 121.045732 -381.52451)
		(stroke
			(width 0.07112)
			(type default)
		)
		(layer "In4.Cu")
	)
	(gr_line
		(start 121.219722 -381.69469)
		(end 121.207276 -381.632206)
		(stroke
			(width 0.07112)
			(type default)
		)
		(layer "In4.Cu")
	)
	(gr_line
		(start 121.244614 -385.405376)
		(end 121.245122 -385.404868)
		(stroke
			(width 0.07112)
			(type default)
		)
		(layer "In4.Cu")
	)
	(gr_line
		(start 121.263664 -380.471172)
		(end 121.127012 -379.783086)
		(stroke
			(width 0.07112)
			(type default)
		)
		(layer "In4.Cu")
	)
	(gr_line
		(start 121.29135 -386.003292)
		(end 121.386092 -385.649724)
		(stroke
			(width 0.07112)
			(type default)
		)
		(layer "In4.Cu")
	)
	(gr_line
		(start 121.311416 -404.17369)
		(end 121.020586 -404.46452)
		(stroke
			(width 0.07112)
			(type default)
		)
		(layer "In4.Cu")
	)
	(gr_line
		(start 121.483882 -381.577342)
		(end 121.346976 -380.88951)
		(stroke
			(width 0.07112)
			(type default)
		)
		(layer "In4.Cu")
	)
	(gr_line
		(start 121.507758 -385.579112)
		(end 121.56059 -385.548632)
		(stroke
			(width 0.07112)
			(type default)
		)
		(layer "In4.Cu")
	)
	(gr_line
		(start 121.51614 -402.326094)
		(end 121.33834 -402.252434)
		(stroke
			(width 0.07112)
			(type default)
		)
		(layer "In4.Cu")
	)
	(gr_line
		(start 121.56059 -385.548632)
		(end 121.648728 -385.460494)
		(stroke
			(width 0.07112)
			(type default)
		)
		(layer "In4.Cu")
	)
	(gr_line
		(start 121.593356 -404.17369)
		(end 121.884186 -404.46452)
		(stroke
			(width 0.07112)
			(type default)
		)
		(layer "In4.Cu")
	)
	(gr_line
		(start 121.648728 -385.460494)
		(end 121.648728 -385.334764)
		(stroke
			(width 0.07112)
			(type default)
		)
		(layer "In4.Cu")
	)
	(gr_arc
		(start 121.716038 -403.15388)
		(mid 121.716165 -403.153753)
		(end 121.716292 -403.153626)
		(stroke
			(width 0.07112)
			(type default)
		)
		(layer "In4.Cu")
	)
	(gr_line
		(start 121.725944 -378.961904)
		(end 121.833132 -378.801884)
		(stroke
			(width 0.07112)
			(type default)
		)
		(layer "In4.Cu")
	)
	(gr_line
		(start 121.803668 -296.456608)
		(end 121.803668 -296.42816)
		(stroke
			(width 0.05715)
			(type default)
		)
		(layer "In4.Cu")
	)
	(gr_line
		(start 121.803668 -296.42816)
		(end 121.849388 -296.38244)
		(stroke
			(width 0.05715)
			(type default)
		)
		(layer "In4.Cu")
	)
	(gr_line
		(start 121.809256 -379.380496)
		(end 121.725944 -378.961904)
		(stroke
			(width 0.07112)
			(type default)
		)
		(layer "In4.Cu")
	)
	(gr_arc
		(start 121.849388 -295.948354)
		(mid 121.849375 -295.952291)
		(end 121.849388 -295.956228)
		(stroke
			(width 0.05715)
			(type default)
		)
		(layer "In4.Cu")
	)
	(gr_line
		(start 121.877074 -401.722844)
		(end 121.22912 -401.991068)
		(stroke
			(width 0.07112)
			(type default)
		)
		(layer "In4.Cu")
	)
	(gr_line
		(start 121.910602 -402.162772)
		(end 121.51614 -402.326094)
		(stroke
			(width 0.07112)
			(type default)
		)
		(layer "In4.Cu")
	)
	(gr_line
		(start 121.945908 -380.068074)
		(end 122.053096 -379.908054)
		(stroke
			(width 0.07112)
			(type default)
		)
		(layer "In4.Cu")
	)
	(gr_line
		(start 121.96953 -379.487684)
		(end 121.809256 -379.380496)
		(stroke
			(width 0.07112)
			(type default)
		)
		(layer "In4.Cu")
	)
	(gr_line
		(start 121.984516 -401.984718)
		(end 121.910602 -402.162772)
		(stroke
			(width 0.07112)
			(type default)
		)
		(layer "In4.Cu")
	)
	(gr_line
		(start 122.02922 -380.486666)
		(end 121.945908 -380.068074)
		(stroke
			(width 0.07112)
			(type default)
		)
		(layer "In4.Cu")
	)
	(gr_line
		(start 122.085608 -296.456608)
		(end 122.085608 -296.42816)
		(stroke
			(width 0.05715)
			(type default)
		)
		(layer "In4.Cu")
	)
	(gr_line
		(start 122.085608 -296.42816)
		(end 122.039888 -296.38244)
		(stroke
			(width 0.05715)
			(type default)
		)
		(layer "In4.Cu")
	)
	(gr_line
		(start 122.091196 -385.31038)
		(end 122.44451 -385.405376)
		(stroke
			(width 0.07112)
			(type default)
		)
		(layer "In4.Cu")
	)
	(gr_arc
		(start 122.093228 -295.491154)
		(mid 122.085562 -295.496551)
		(end 122.077988 -295.502076)
		(stroke
			(width 0.05715)
			(type default)
		)
		(layer "In4.Cu")
	)
	(gr_arc
		(start 122.093228 -295.491154)
		(mid 122.093609 -295.4909)
		(end 122.09399 -295.490646)
		(stroke
			(width 0.05715)
			(type default)
		)
		(layer "In4.Cu")
	)
	(gr_line
		(start 122.09399 -295.490646)
		(end 122.100594 -295.486836)
		(stroke
			(width 0.05715)
			(type default)
		)
		(layer "In4.Cu")
	)
	(gr_line
		(start 122.09526 -292.250114)
		(end 122.098054 -292.24859)
		(stroke
			(width 0.05715)
			(type default)
		)
		(layer "In4.Cu")
	)
	(gr_line
		(start 122.098816 -292.248082)
		(end 122.10161 -292.246558)
		(stroke
			(width 0.05715)
			(type default)
		)
		(layer "In4.Cu")
	)
	(gr_arc
		(start 122.102118 -9.272016)
		(mid 123.157118 -8.83502)
		(end 123.594114 -7.78002)
		(stroke
			(width 0.2)
			(type default)
		)
		(layer "In4.Cu")
	)
	(gr_line
		(start 122.109992 -289.001454)
		(end 122.111262 -289.000692)
		(stroke
			(width 0.05715)
			(type default)
		)
		(layer "In4.Cu")
	)
	(gr_line
		(start 122.112532 -288.99993)
		(end 122.113548 -288.999422)
		(stroke
			(width 0.05715)
			(type default)
		)
		(layer "In4.Cu")
	)
	(gr_line
		(start 122.113548 -288.999422)
		(end 122.11431 -288.998914)
		(stroke
			(width 0.05715)
			(type default)
		)
		(layer "In4.Cu")
	)
	(gr_line
		(start 122.117612 -291.574982)
		(end 122.116342 -291.573966)
		(stroke
			(width 0.05715)
			(type default)
		)
		(layer "In4.Cu")
	)
	(gr_line
		(start 122.119898 -292.234874)
		(end 122.122184 -292.23335)
		(stroke
			(width 0.05715)
			(type default)
		)
		(layer "In4.Cu")
	)
	(gr_line
		(start 122.121168 -291.577014)
		(end 122.118374 -291.57549)
		(stroke
			(width 0.05715)
			(type default)
		)
		(layer "In4.Cu")
	)
	(gr_line
		(start 122.122184 -292.23335)
		(end 122.127772 -292.230048)
		(stroke
			(width 0.05715)
			(type default)
		)
		(layer "In4.Cu")
	)
	(gr_line
		(start 122.123454 -291.578538)
		(end 122.12193 -291.577522)
		(stroke
			(width 0.05715)
			(type default)
		)
		(layer "In4.Cu")
	)
	(gr_line
		(start 122.124724 -291.5793)
		(end 122.123454 -291.578538)
		(stroke
			(width 0.05715)
			(type default)
		)
		(layer "In4.Cu")
	)
	(gr_line
		(start 122.127772 -292.230048)
		(end 122.140726 -292.223952)
		(stroke
			(width 0.05715)
			(type default)
		)
		(layer "In4.Cu")
	)
	(gr_line
		(start 122.12828 -288.990786)
		(end 122.129296 -288.990278)
		(stroke
			(width 0.05715)
			(type default)
		)
		(layer "In4.Cu")
	)
	(gr_line
		(start 122.129042 -293.850568)
		(end 122.13082 -293.849298)
		(stroke
			(width 0.05715)
			(type default)
		)
		(layer "In4.Cu")
	)
	(gr_line
		(start 122.129296 -288.990278)
		(end 122.133106 -288.987738)
		(stroke
			(width 0.05715)
			(type default)
		)
		(layer "In4.Cu")
	)
	(gr_line
		(start 122.13082 -294.823134)
		(end 122.128788 -294.821864)
		(stroke
			(width 0.05715)
			(type default)
		)
		(layer "In4.Cu")
	)
	(gr_line
		(start 122.13082 -293.849298)
		(end 122.131836 -293.84879)
		(stroke
			(width 0.05715)
			(type default)
		)
		(layer "In4.Cu")
	)
	(gr_line
		(start 122.13082 -293.203122)
		(end 122.129804 -293.202614)
		(stroke
			(width 0.05715)
			(type default)
		)
		(layer "In4.Cu")
	)
	(gr_line
		(start 122.131328 -294.823388)
		(end 122.13082 -294.823134)
		(stroke
			(width 0.05715)
			(type default)
		)
		(layer "In4.Cu")
	)
	(gr_line
		(start 122.131836 -293.84879)
		(end 122.132598 -293.848282)
		(stroke
			(width 0.05715)
			(type default)
		)
		(layer "In4.Cu")
	)
	(gr_line
		(start 122.131836 -293.20363)
		(end 122.13082 -293.203122)
		(stroke
			(width 0.05715)
			(type default)
		)
		(layer "In4.Cu")
	)
	(gr_line
		(start 122.133868 -294.824912)
		(end 122.133106 -294.824404)
		(stroke
			(width 0.05715)
			(type default)
		)
		(layer "In4.Cu")
	)
	(gr_line
		(start 122.135646 -288.986214)
		(end 122.136408 -288.985706)
		(stroke
			(width 0.05715)
			(type default)
		)
		(layer "In4.Cu")
	)
	(gr_line
		(start 122.139456 -293.20871)
		(end 122.131836 -293.20363)
		(stroke
			(width 0.05715)
			(type default)
		)
		(layer "In4.Cu")
	)
	(gr_line
		(start 122.141996 -293.210234)
		(end 122.140726 -293.209472)
		(stroke
			(width 0.05715)
			(type default)
		)
		(layer "In4.Cu")
	)
	(gr_line
		(start 122.144028 -293.21125)
		(end 122.143012 -293.210742)
		(stroke
			(width 0.05715)
			(type default)
		)
		(layer "In4.Cu")
	)
	(gr_line
		(start 122.145552 -293.8399)
		(end 122.147838 -293.838376)
		(stroke
			(width 0.05715)
			(type default)
		)
		(layer "In4.Cu")
	)
	(gr_line
		(start 122.147838 -293.838376)
		(end 122.154442 -293.834566)
		(stroke
			(width 0.05715)
			(type default)
		)
		(layer "In4.Cu")
	)
	(gr_line
		(start 122.166126 -381.174244)
		(end 122.27306 -381.014224)
		(stroke
			(width 0.07112)
			(type default)
		)
		(layer "In4.Cu")
	)
	(gr_line
		(start 122.189494 -380.593854)
		(end 122.02922 -380.486666)
		(stroke
			(width 0.07112)
			(type default)
		)
		(layer "In4.Cu")
	)
	(gr_line
		(start 122.205496 -292.406578)
		(end 122.20829 -292.4048)
		(stroke
			(width 0.05715)
			(type default)
		)
		(layer "In4.Cu")
	)
	(gr_line
		(start 122.20829 -292.4048)
		(end 122.212862 -292.402006)
		(stroke
			(width 0.05715)
			(type default)
		)
		(layer "In4.Cu")
	)
	(gr_line
		(start 122.211592 -289.162744)
		(end 122.214132 -289.161474)
		(stroke
			(width 0.05715)
			(type default)
		)
		(layer "In4.Cu")
	)
	(gr_line
		(start 122.214132 -289.161474)
		(end 122.214386 -289.161474)
		(stroke
			(width 0.05715)
			(type default)
		)
		(layer "In4.Cu")
	)
	(gr_line
		(start 122.214386 -289.161474)
		(end 122.21464 -289.16122)
		(stroke
			(width 0.05715)
			(type default)
		)
		(layer "In4.Cu")
	)
	(gr_line
		(start 122.21464 -289.16122)
		(end 122.216418 -289.160204)
		(stroke
			(width 0.05715)
			(type default)
		)
		(layer "In4.Cu")
	)
	(gr_line
		(start 122.214894 -294.022018)
		(end 122.220736 -294.018716)
		(stroke
			(width 0.05715)
			(type default)
		)
		(layer "In4.Cu")
	)
	(gr_line
		(start 122.216418 -289.160204)
		(end 122.217688 -289.159442)
		(stroke
			(width 0.05715)
			(type default)
		)
		(layer "In4.Cu")
	)
	(gr_line
		(start 122.217688 -289.159442)
		(end 122.21845 -289.158934)
		(stroke
			(width 0.05715)
			(type default)
		)
		(layer "In4.Cu")
	)
	(gr_line
		(start 122.21845 -289.158934)
		(end 122.219974 -289.158172)
		(stroke
			(width 0.05715)
			(type default)
		)
		(layer "In4.Cu")
	)
	(gr_line
		(start 122.220736 -294.018716)
		(end 122.226832 -294.014652)
		(stroke
			(width 0.05715)
			(type default)
		)
		(layer "In4.Cu")
	)
	(gr_line
		(start 122.225308 -294.657272)
		(end 122.225308 -294.657526)
		(stroke
			(width 0.05715)
			(type default)
		)
		(layer "In4.Cu")
	)
	(gr_line
		(start 122.225562 -289.15487)
		(end 122.227086 -289.154108)
		(stroke
			(width 0.05715)
			(type default)
		)
		(layer "In4.Cu")
	)
	(gr_line
		(start 122.22607 -294.65778)
		(end 122.225308 -294.657272)
		(stroke
			(width 0.05715)
			(type default)
		)
		(layer "In4.Cu")
	)
	(gr_line
		(start 122.226578 -293.038022)
		(end 122.225562 -293.037514)
		(stroke
			(width 0.05715)
			(type default)
		)
		(layer "In4.Cu")
	)
	(gr_line
		(start 122.226832 -294.014652)
		(end 122.228356 -294.013636)
		(stroke
			(width 0.05715)
			(type default)
		)
		(layer "In4.Cu")
	)
	(gr_line
		(start 122.226832 -292.394132)
		(end 122.229372 -292.392862)
		(stroke
			(width 0.05715)
			(type default)
		)
		(layer "In4.Cu")
	)
	(gr_line
		(start 122.227086 -291.418264)
		(end 122.226578 -291.41801)
		(stroke
			(width 0.05715)
			(type default)
		)
		(layer "In4.Cu")
	)
	(gr_line
		(start 122.227848 -294.658796)
		(end 122.22607 -294.65778)
		(stroke
			(width 0.05715)
			(type default)
		)
		(layer "In4.Cu")
	)
	(gr_line
		(start 122.227848 -293.038784)
		(end 122.226578 -293.038022)
		(stroke
			(width 0.05715)
			(type default)
		)
		(layer "In4.Cu")
	)
	(gr_line
		(start 122.227848 -291.418772)
		(end 122.227086 -291.418264)
		(stroke
			(width 0.05715)
			(type default)
		)
		(layer "In4.Cu")
	)
	(gr_line
		(start 122.228864 -294.659304)
		(end 122.227848 -294.658796)
		(stroke
			(width 0.05715)
			(type default)
		)
		(layer "In4.Cu")
	)
	(gr_line
		(start 122.228864 -294.013382)
		(end 122.228864 -294.013128)
		(stroke
			(width 0.05715)
			(type default)
		)
		(layer "In4.Cu")
	)
	(gr_line
		(start 122.228864 -293.039292)
		(end 122.227848 -293.038784)
		(stroke
			(width 0.05715)
			(type default)
		)
		(layer "In4.Cu")
	)
	(gr_line
		(start 122.228864 -291.41928)
		(end 122.227848 -291.418772)
		(stroke
			(width 0.05715)
			(type default)
		)
		(layer "In4.Cu")
	)
	(gr_line
		(start 122.228864 -289.153092)
		(end 122.232674 -289.150552)
		(stroke
			(width 0.05715)
			(type default)
		)
		(layer "In4.Cu")
	)
	(gr_line
		(start 122.230388 -293.040308)
		(end 122.228864 -293.039292)
		(stroke
			(width 0.05715)
			(type default)
		)
		(layer "In4.Cu")
	)
	(gr_line
		(start 122.230642 -293.040054)
		(end 122.230388 -293.040308)
		(stroke
			(width 0.05715)
			(type default)
		)
		(layer "In4.Cu")
	)
	(gr_line
		(start 122.230642 -291.420296)
		(end 122.228864 -291.41928)
		(stroke
			(width 0.05715)
			(type default)
		)
		(layer "In4.Cu")
	)
	(gr_line
		(start 122.233182 -291.42182)
		(end 122.232166 -291.421312)
		(stroke
			(width 0.05715)
			(type default)
		)
		(layer "In4.Cu")
	)
	(gr_line
		(start 122.234452 -293.042848)
		(end 122.230642 -293.040054)
		(stroke
			(width 0.05715)
			(type default)
		)
		(layer "In4.Cu")
	)
	(gr_line
		(start 122.235214 -291.42309)
		(end 122.233182 -291.42182)
		(stroke
			(width 0.05715)
			(type default)
		)
		(layer "In4.Cu")
	)
	(gr_line
		(start 122.235214 -291.422836)
		(end 122.235214 -291.42309)
		(stroke
			(width 0.05715)
			(type default)
		)
		(layer "In4.Cu")
	)
	(gr_line
		(start 122.237754 -291.424614)
		(end 122.236992 -291.424106)
		(stroke
			(width 0.05715)
			(type default)
		)
		(layer "In4.Cu")
	)
	(gr_line
		(start 122.238516 -294.007032)
		(end 122.241818 -294.004746)
		(stroke
			(width 0.05715)
			(type default)
		)
		(layer "In4.Cu")
	)
	(gr_line
		(start 122.239786 -291.425884)
		(end 122.238516 -291.425122)
		(stroke
			(width 0.05715)
			(type default)
		)
		(layer "In4.Cu")
	)
	(gr_line
		(start 122.247406 -379.433582)
		(end 122.110754 -378.745496)
		(stroke
			(width 0.07112)
			(type default)
		)
		(layer "In4.Cu")
	)
	(gr_line
		(start 122.249438 -381.59309)
		(end 122.166126 -381.174244)
		(stroke
			(width 0.07112)
			(type default)
		)
		(layer "In4.Cu")
	)
	(gr_line
		(start 122.319796 -295.146476)
		(end 122.319796 -295.146222)
		(stroke
			(width 0.05715)
			(type default)
		)
		(layer "In4.Cu")
	)
	(gr_line
		(start 122.372628 -328.17054)
		(end 122.372882 -328.17054)
		(stroke
			(width 0.07112)
			(type default)
		)
		(layer "In4.Cu")
	)
	(gr_line
		(start 122.409458 -381.69977)
		(end 122.249438 -381.59309)
		(stroke
			(width 0.07112)
			(type default)
		)
		(layer "In4.Cu")
	)
	(gr_line
		(start 122.410728 -381.700786)
		(end 122.410982 -381.700786)
		(stroke
			(width 0.07112)
			(type default)
		)
		(layer "In4.Cu")
	)
	(gr_line
		(start 122.428254 -370.827554)
		(end 122.432572 -370.816886)
		(stroke
			(width 0.07112)
			(type default)
		)
		(layer "In4.Cu")
	)
	(gr_line
		(start 122.44451 -385.405376)
		(end 122.445018 -385.404868)
		(stroke
			(width 0.07112)
			(type default)
		)
		(layer "In4.Cu")
	)
	(gr_line
		(start 122.46737 -380.539752)
		(end 122.330718 -379.85192)
		(stroke
			(width 0.07112)
			(type default)
		)
		(layer "In4.Cu")
	)
	(gr_line
		(start 122.491246 -386.003292)
		(end 122.585988 -385.649724)
		(stroke
			(width 0.07112)
			(type default)
		)
		(layer "In4.Cu")
	)
	(gr_arc
		(start 122.510042 -288.68243)
		(mid 122.510187 -288.677859)
		(end 122.510296 -288.673286)
		(stroke
			(width 0.05715)
			(type default)
		)
		(layer "In4.Cu")
	)
	(gr_line
		(start 122.510296 -295.14673)
		(end 122.510296 -295.146222)
		(stroke
			(width 0.05715)
			(type default)
		)
		(layer "In4.Cu")
	)
	(gr_line
		(start 122.510296 -288.666174)
		(end 122.510042 -288.666174)
		(stroke
			(width 0.05715)
			(type default)
		)
		(layer "In4.Cu")
	)
	(gr_line
		(start 122.529854 -403.236938)
		(end 122.352054 -403.163278)
		(stroke
			(width 0.07112)
			(type default)
		)
		(layer "In4.Cu")
	)
	(gr_line
		(start 122.558302 -401.894548)
		(end 122.380502 -401.820634)
		(stroke
			(width 0.07112)
			(type default)
		)
		(layer "In4.Cu")
	)
	(gr_line
		(start 122.687334 -381.645668)
		(end 122.550682 -380.95809)
		(stroke
			(width 0.07112)
			(type default)
		)
		(layer "In4.Cu")
	)
	(gr_line
		(start 122.707654 -385.579112)
		(end 122.760486 -385.548632)
		(stroke
			(width 0.07112)
			(type default)
		)
		(layer "In4.Cu")
	)
	(gr_line
		(start 122.712734 -291.096192)
		(end 122.414792 -291.096192)
		(stroke
			(width 0.05715)
			(type default)
		)
		(layer "In4.Cu")
	)
	(gr_line
		(start 122.712734 -289.47618)
		(end 122.414792 -289.47618)
		(stroke
			(width 0.05715)
			(type default)
		)
		(layer "In4.Cu")
	)
	(gr_line
		(start 122.712734 -287.856422)
		(end 122.414792 -287.856422)
		(stroke
			(width 0.05715)
			(type default)
		)
		(layer "In4.Cu")
	)
	(gr_line
		(start 122.7328 -310.586628)
		(end 122.733054 -310.586628)
		(stroke
			(width 0.07112)
			(type default)
		)
		(layer "In4.Cu")
	)
	(gr_line
		(start 122.743468 -299.961554)
		(end 122.7328 -299.9359)
		(stroke
			(width 0.07112)
			(type default)
		)
		(layer "In4.Cu")
	)
	(gr_line
		(start 122.743976 -296.489628)
		(end 122.743976 -296.46118)
		(stroke
			(width 0.05715)
			(type default)
		)
		(layer "In4.Cu")
	)
	(gr_line
		(start 122.743976 -296.46118)
		(end 122.789696 -296.41546)
		(stroke
			(width 0.05715)
			(type default)
		)
		(layer "In4.Cu")
	)
	(gr_line
		(start 122.758708 -299.984668)
		(end 122.743468 -299.961554)
		(stroke
			(width 0.07112)
			(type default)
		)
		(layer "In4.Cu")
	)
	(gr_line
		(start 122.758962 -299.984668)
		(end 122.758708 -299.984668)
		(stroke
			(width 0.07112)
			(type default)
		)
		(layer "In4.Cu")
	)
	(gr_line
		(start 122.760486 -385.548632)
		(end 122.848624 -385.460494)
		(stroke
			(width 0.07112)
			(type default)
		)
		(layer "In4.Cu")
	)
	(gr_line
		(start 122.782076 -287.925764)
		(end 122.712734 -287.856422)
		(stroke
			(width 0.05715)
			(type default)
		)
		(layer "In4.Cu")
	)
	(gr_line
		(start 122.795538 -291.178996)
		(end 122.712734 -291.096192)
		(stroke
			(width 0.05715)
			(type default)
		)
		(layer "In4.Cu")
	)
	(gr_line
		(start 122.795538 -289.558984)
		(end 122.712734 -289.47618)
		(stroke
			(width 0.05715)
			(type default)
		)
		(layer "In4.Cu")
	)
	(gr_arc
		(start 122.795538 -289.558984)
		(mid 122.79733 -289.570306)
		(end 122.799348 -289.58159)
		(stroke
			(width 0.05715)
			(type default)
		)
		(layer "In4.Cu")
	)
	(gr_line
		(start 122.795792 -291.178996)
		(end 122.795538 -291.178996)
		(stroke
			(width 0.05715)
			(type default)
		)
		(layer "In4.Cu")
	)
	(gr_arc
		(start 122.795792 -291.178996)
		(mid 122.797584 -291.190191)
		(end 122.799602 -291.201348)
		(stroke
			(width 0.05715)
			(type default)
		)
		(layer "In4.Cu")
	)
	(gr_line
		(start 122.848624 -385.460494)
		(end 122.848624 -385.334764)
		(stroke
			(width 0.07112)
			(type default)
		)
		(layer "In4.Cu")
	)
	(gr_line
		(start 122.890788 -402.633688)
		(end 122.242834 -402.901912)
		(stroke
			(width 0.07112)
			(type default)
		)
		(layer "In4.Cu")
	)
	(gr_line
		(start 122.918982 -401.291044)
		(end 122.271282 -401.559522)
		(stroke
			(width 0.07112)
			(type default)
		)
		(layer "In4.Cu")
	)
	(gr_line
		(start 122.924316 -403.073616)
		(end 122.529854 -403.236938)
		(stroke
			(width 0.07112)
			(type default)
		)
		(layer "In4.Cu")
	)
	(gr_line
		(start 122.952764 -401.731226)
		(end 122.558302 -401.894548)
		(stroke
			(width 0.07112)
			(type default)
		)
		(layer "In4.Cu")
	)
	(gr_arc
		(start 122.97029 -287.962086)
		(mid 122.972313 -287.950676)
		(end 122.9741 -287.939226)
		(stroke
			(width 0.05715)
			(type default)
		)
		(layer "In4.Cu")
	)
	(gr_line
		(start 122.9741 -287.939226)
		(end 123.056904 -287.856422)
		(stroke
			(width 0.05715)
			(type default)
		)
		(layer "In4.Cu")
	)
	(gr_line
		(start 122.987562 -289.545522)
		(end 123.056904 -289.47618)
		(stroke
			(width 0.05715)
			(type default)
		)
		(layer "In4.Cu")
	)
	(gr_line
		(start 122.987816 -291.16528)
		(end 123.056904 -291.096192)
		(stroke
			(width 0.05715)
			(type default)
		)
		(layer "In4.Cu")
	)
	(gr_line
		(start 122.99823 -402.895816)
		(end 122.924316 -403.073616)
		(stroke
			(width 0.07112)
			(type default)
		)
		(layer "In4.Cu")
	)
	(gr_line
		(start 123.006866 -372.411752)
		(end 123.006612 -372.411752)
		(stroke
			(width 0.07112)
			(type default)
		)
		(layer "In4.Cu")
	)
	(gr_arc
		(start 123.024646 -289.935158)
		(mid 123.028698 -289.93797)
		(end 123.032774 -289.940746)
		(stroke
			(width 0.05715)
			(type default)
		)
		(layer "In4.Cu")
	)
	(gr_line
		(start 123.025916 -296.489628)
		(end 123.025916 -296.46118)
		(stroke
			(width 0.05715)
			(type default)
		)
		(layer "In4.Cu")
	)
	(gr_line
		(start 123.025916 -296.46118)
		(end 122.980196 -296.41546)
		(stroke
			(width 0.05715)
			(type default)
		)
		(layer "In4.Cu")
	)
	(gr_line
		(start 123.026424 -401.553172)
		(end 122.952764 -401.731226)
		(stroke
			(width 0.07112)
			(type default)
		)
		(layer "In4.Cu")
	)
	(gr_arc
		(start 123.033536 -289.941254)
		(mid 123.033155 -289.941)
		(end 123.032774 -289.940746)
		(stroke
			(width 0.05715)
			(type default)
		)
		(layer "In4.Cu")
	)
	(gr_line
		(start 123.040648 -289.945318)
		(end 123.033536 -289.941254)
		(stroke
			(width 0.05715)
			(type default)
		)
		(layer "In4.Cu")
	)
	(gr_line
		(start 123.056904 -291.096192)
		(end 123.354846 -291.096192)
		(stroke
			(width 0.05715)
			(type default)
		)
		(layer "In4.Cu")
	)
	(gr_line
		(start 123.056904 -289.47618)
		(end 123.354846 -289.47618)
		(stroke
			(width 0.05715)
			(type default)
		)
		(layer "In4.Cu")
	)
	(gr_line
		(start 123.056904 -287.856422)
		(end 123.354846 -287.856422)
		(stroke
			(width 0.05715)
			(type default)
		)
		(layer "In4.Cu")
	)
	(gr_line
		(start 123.066048 -293.852346)
		(end 123.072652 -293.848536)
		(stroke
			(width 0.05715)
			(type default)
		)
		(layer "In4.Cu")
	)
	(gr_line
		(start 123.07189 -295.468802)
		(end 123.072398 -295.468548)
		(stroke
			(width 0.05715)
			(type default)
		)
		(layer "In4.Cu")
	)
	(gr_line
		(start 123.072398 -289.96386)
		(end 123.071636 -289.963352)
		(stroke
			(width 0.05715)
			(type default)
		)
		(layer "In4.Cu")
	)
	(gr_line
		(start 123.075192 -289.965384)
		(end 123.072398 -289.96386)
		(stroke
			(width 0.05715)
			(type default)
		)
		(layer "In4.Cu")
	)
	(gr_arc
		(start 123.118626 -338.431886)
		(mid 123.118626 -338.432267)
		(end 123.118626 -338.432648)
		(stroke
			(width 0.07112)
			(type default)
		)
		(layer "In4.Cu")
	)
	(gr_line
		(start 123.165616 -295.634918)
		(end 123.16714 -295.634156)
		(stroke
			(width 0.05715)
			(type default)
		)
		(layer "In4.Cu")
	)
	(gr_line
		(start 123.167902 -294.658796)
		(end 123.167394 -294.658542)
		(stroke
			(width 0.05715)
			(type default)
		)
		(layer "In4.Cu")
	)
	(gr_line
		(start 123.167902 -293.038784)
		(end 123.167394 -293.03853)
		(stroke
			(width 0.05715)
			(type default)
		)
		(layer "In4.Cu")
	)
	(gr_line
		(start 123.167902 -291.418772)
		(end 123.167394 -291.418518)
		(stroke
			(width 0.05715)
			(type default)
		)
		(layer "In4.Cu")
	)
	(gr_line
		(start 123.167902 -289.79876)
		(end 123.166886 -289.798252)
		(stroke
			(width 0.05715)
			(type default)
		)
		(layer "In4.Cu")
	)
	(gr_line
		(start 123.16841 -294.658796)
		(end 123.167902 -294.658796)
		(stroke
			(width 0.05715)
			(type default)
		)
		(layer "In4.Cu")
	)
	(gr_line
		(start 123.16841 -293.038784)
		(end 123.167902 -293.038784)
		(stroke
			(width 0.05715)
			(type default)
		)
		(layer "In4.Cu")
	)
	(gr_line
		(start 123.170696 -289.800538)
		(end 123.167902 -289.79876)
		(stroke
			(width 0.05715)
			(type default)
		)
		(layer "In4.Cu")
	)
	(gr_arc
		(start 123.178824 -295.627552)
		(mid 123.18175 -295.625782)
		(end 123.184666 -295.623996)
		(stroke
			(width 0.05715)
			(type default)
		)
		(layer "In4.Cu")
	)
	(gr_arc
		(start 123.179332 -294.007032)
		(mid 123.182003 -294.005515)
		(end 123.184666 -294.003984)
		(stroke
			(width 0.05715)
			(type default)
		)
		(layer "In4.Cu")
	)
	(gr_arc
		(start 123.185682 -294.66921)
		(mid 123.18264 -294.667295)
		(end 123.179586 -294.6654)
		(stroke
			(width 0.05715)
			(type default)
		)
		(layer "In4.Cu")
	)
	(gr_arc
		(start 123.185682 -293.049198)
		(mid 123.18264 -293.047283)
		(end 123.179586 -293.045388)
		(stroke
			(width 0.05715)
			(type default)
		)
		(layer "In4.Cu")
	)
	(gr_line
		(start 123.222766 -321.837812)
		(end 123.238514 -321.868292)
		(stroke
			(width 0.07112)
			(type default)
		)
		(layer "In4.Cu")
	)
	(gr_line
		(start 123.238514 -321.868292)
		(end 123.250198 -321.902836)
		(stroke
			(width 0.07112)
			(type default)
		)
		(layer "In4.Cu")
	)
	(gr_line
		(start 123.291346 -385.31038)
		(end 123.644406 -385.405376)
		(stroke
			(width 0.07112)
			(type default)
		)
		(layer "In4.Cu")
	)
	(gr_line
		(start 123.400566 -338.431886)
		(end 123.400566 -338.432648)
		(stroke
			(width 0.07112)
			(type default)
		)
		(layer "In4.Cu")
	)
	(gr_arc
		(start 123.488196 -321.739768)
		(mid 123.481477 -321.725098)
		(end 123.47448 -321.710558)
		(stroke
			(width 0.07112)
			(type default)
		)
		(layer "In4.Cu")
	)
	(gr_arc
		(start 123.504706 -321.778122)
		(mid 123.496683 -321.758845)
		(end 123.488196 -321.739768)
		(stroke
			(width 0.07112)
			(type default)
		)
		(layer "In4.Cu")
	)
	(gr_arc
		(start 123.516898 -321.811396)
		(mid 123.510976 -321.794695)
		(end 123.504706 -321.778122)
		(stroke
			(width 0.07112)
			(type default)
		)
		(layer "In4.Cu")
	)
	(gr_line
		(start 123.542552 -290.77412)
		(end 123.54179 -290.773612)
		(stroke
			(width 0.05715)
			(type default)
		)
		(layer "In4.Cu")
	)
	(gr_line
		(start 123.543822 -290.774882)
		(end 123.542552 -290.77412)
		(stroke
			(width 0.05715)
			(type default)
		)
		(layer "In4.Cu")
	)
	(gr_line
		(start 123.547886 -290.777168)
		(end 123.546362 -290.776152)
		(stroke
			(width 0.05715)
			(type default)
		)
		(layer "In4.Cu")
	)
	(gr_line
		(start 123.548902 -290.777676)
		(end 123.547886 -290.777168)
		(stroke
			(width 0.05715)
			(type default)
		)
		(layer "In4.Cu")
	)
	(gr_line
		(start 123.54941 -290.77793)
		(end 123.548902 -290.777676)
		(stroke
			(width 0.05715)
			(type default)
		)
		(layer "In4.Cu")
	)
	(gr_line
		(start 123.572016 -402.805392)
		(end 123.394216 -402.731732)
		(stroke
			(width 0.07112)
			(type default)
		)
		(layer "In4.Cu")
	)
	(gr_line
		(start 123.594114 -7.78002)
		(end 123.594114 -4.879848)
		(stroke
			(width 0.2)
			(type default)
		)
		(layer "In4.Cu")
	)
	(gr_line
		(start 123.611132 -299.579538)
		(end 123.600464 -299.553884)
		(stroke
			(width 0.07112)
			(type default)
		)
		(layer "In4.Cu")
	)
	(gr_line
		(start 123.626372 -299.602652)
		(end 123.611132 -299.579538)
		(stroke
			(width 0.07112)
			(type default)
		)
		(layer "In4.Cu")
	)
	(gr_line
		(start 123.626626 -299.602652)
		(end 123.626372 -299.602652)
		(stroke
			(width 0.07112)
			(type default)
		)
		(layer "In4.Cu")
	)
	(gr_line
		(start 123.643136 -290.611814)
		(end 123.64212 -290.611306)
		(stroke
			(width 0.05715)
			(type default)
		)
		(layer "In4.Cu")
	)
	(gr_line
		(start 123.644152 -290.612576)
		(end 123.643136 -290.611814)
		(stroke
			(width 0.05715)
			(type default)
		)
		(layer "In4.Cu")
	)
	(gr_line
		(start 123.644406 -385.405376)
		(end 123.644914 -385.404868)
		(stroke
			(width 0.07112)
			(type default)
		)
		(layer "In4.Cu")
	)
	(gr_line
		(start 123.669298 -290.627054)
		(end 123.66879 -290.6268)
		(stroke
			(width 0.05715)
			(type default)
		)
		(layer "In4.Cu")
	)
	(gr_line
		(start 123.67006 -290.627562)
		(end 123.669298 -290.627054)
		(stroke
			(width 0.05715)
			(type default)
		)
		(layer "In4.Cu")
	)
	(gr_line
		(start 123.676918 -290.631626)
		(end 123.67006 -290.627562)
		(stroke
			(width 0.05715)
			(type default)
		)
		(layer "In4.Cu")
	)
	(gr_line
		(start 123.682252 -381.397002)
		(end 123.71197 -380.971298)
		(stroke
			(width 0.07112)
			(type default)
		)
		(layer "In4.Cu")
	)
	(gr_line
		(start 123.68403 -296.42308)
		(end 123.68403 -296.394632)
		(stroke
			(width 0.05715)
			(type default)
		)
		(layer "In4.Cu")
	)
	(gr_line
		(start 123.68403 -296.394632)
		(end 123.72975 -296.348912)
		(stroke
			(width 0.05715)
			(type default)
		)
		(layer "In4.Cu")
	)
	(gr_arc
		(start 123.684792 -290.637214)
		(mid 123.680867 -290.634403)
		(end 123.676918 -290.631626)
		(stroke
			(width 0.05715)
			(type default)
		)
		(layer "In4.Cu")
	)
	(gr_line
		(start 123.691142 -386.003292)
		(end 123.785884 -385.649724)
		(stroke
			(width 0.07112)
			(type default)
		)
		(layer "In4.Cu")
	)
	(gr_line
		(start 123.71197 -380.971298)
		(end 123.857258 -380.845314)
		(stroke
			(width 0.07112)
			(type default)
		)
		(layer "In4.Cu")
	)
	(gr_line
		(start 123.760992 -380.272036)
		(end 123.79071 -379.846078)
		(stroke
			(width 0.07112)
			(type default)
		)
		(layer "In4.Cu")
	)
	(gr_line
		(start 123.79071 -379.846078)
		(end 123.935998 -379.720094)
		(stroke
			(width 0.07112)
			(type default)
		)
		(layer "In4.Cu")
	)
	(gr_line
		(start 123.808236 -381.542544)
		(end 123.682252 -381.397002)
		(stroke
			(width 0.07112)
			(type default)
		)
		(layer "In4.Cu")
	)
	(gr_line
		(start 123.839986 -379.146816)
		(end 123.869704 -378.720858)
		(stroke
			(width 0.07112)
			(type default)
		)
		(layer "In4.Cu")
	)
	(gr_line
		(start 123.869704 -378.720858)
		(end 124.014738 -378.594874)
		(stroke
			(width 0.07112)
			(type default)
		)
		(layer "In4.Cu")
	)
	(gr_line
		(start 123.88723 -380.417324)
		(end 123.760992 -380.272036)
		(stroke
			(width 0.07112)
			(type default)
		)
		(layer "In4.Cu")
	)
	(gr_line
		(start 123.90755 -385.579112)
		(end 123.960382 -385.548632)
		(stroke
			(width 0.07112)
			(type default)
		)
		(layer "In4.Cu")
	)
	(gr_line
		(start 123.93295 -402.201888)
		(end 123.284996 -402.470366)
		(stroke
			(width 0.07112)
			(type default)
		)
		(layer "In4.Cu")
	)
	(gr_line
		(start 123.937522 -379.718824)
		(end 123.937014 -379.71857)
		(stroke
			(width 0.07112)
			(type default)
		)
		(layer "In4.Cu")
	)
	(gr_line
		(start 123.960382 -385.548632)
		(end 124.04852 -385.460494)
		(stroke
			(width 0.07112)
			(type default)
		)
		(layer "In4.Cu")
	)
	(gr_line
		(start 123.96597 -379.29185)
		(end 123.839986 -379.146816)
		(stroke
			(width 0.07112)
			(type default)
		)
		(layer "In4.Cu")
	)
	(gr_line
		(start 123.96597 -296.42308)
		(end 123.96597 -296.394632)
		(stroke
			(width 0.05715)
			(type default)
		)
		(layer "In4.Cu")
	)
	(gr_line
		(start 123.96597 -296.394632)
		(end 123.92025 -296.348912)
		(stroke
			(width 0.05715)
			(type default)
		)
		(layer "In4.Cu")
	)
	(gr_line
		(start 123.966478 -402.64207)
		(end 123.572016 -402.805392)
		(stroke
			(width 0.07112)
			(type default)
		)
		(layer "In4.Cu")
	)
	(gr_line
		(start 123.966732 -379.293628)
		(end 123.96724 -379.293374)
		(stroke
			(width 0.07112)
			(type default)
		)
		(layer "In4.Cu")
	)
	(gr_line
		(start 123.994672 -321.208654)
		(end 124.005086 -321.22872)
		(stroke
			(width 0.07112)
			(type default)
		)
		(layer "In4.Cu")
	)
	(gr_line
		(start 124.005086 -321.22872)
		(end 124.012706 -321.250564)
		(stroke
			(width 0.07112)
			(type default)
		)
		(layer "In4.Cu")
	)
	(gr_line
		(start 124.040392 -402.464016)
		(end 123.966478 -402.64207)
		(stroke
			(width 0.07112)
			(type default)
		)
		(layer "In4.Cu")
	)
	(gr_line
		(start 124.04852 -385.460494)
		(end 124.04852 -385.334764)
		(stroke
			(width 0.07112)
			(type default)
		)
		(layer "In4.Cu")
	)
	(gr_line
		(start 124.084334 -348.504256)
		(end 124.084334 -348.50451)
		(stroke
			(width 0.07112)
			(type default)
		)
		(layer "In4.Cu")
	)
	(gr_line
		(start 124.090684 -381.563118)
		(end 124.139706 -380.863602)
		(stroke
			(width 0.07112)
			(type default)
		)
		(layer "In4.Cu")
	)
	(gr_line
		(start 124.102114 -12.288012)
		(end 83.70189 -12.288012)
		(stroke
			(width 0.2)
			(type default)
		)
		(layer "In4.Cu")
	)
	(gr_arc
		(start 124.102114 -12.288012)
		(mid 125.875532 -11.553433)
		(end 126.61011 -9.780016)
		(stroke
			(width 0.2)
			(type default)
		)
		(layer "In4.Cu")
	)
	(gr_line
		(start 124.169678 -380.438152)
		(end 124.2187 -379.738382)
		(stroke
			(width 0.07112)
			(type default)
		)
		(layer "In4.Cu")
	)
	(gr_line
		(start 124.241052 -317.646812)
		(end 124.241052 -317.647066)
		(stroke
			(width 0.07112)
			(type default)
		)
		(layer "In4.Cu")
	)
	(gr_line
		(start 124.248418 -379.31344)
		(end 124.29744 -378.613162)
		(stroke
			(width 0.07112)
			(type default)
		)
		(layer "In4.Cu")
	)
	(gr_arc
		(start 124.25426 -321.098418)
		(mid 124.250494 -321.090269)
		(end 124.24664 -321.082162)
		(stroke
			(width 0.07112)
			(type default)
		)
		(layer "In4.Cu")
	)
	(gr_arc
		(start 124.271024 -321.137788)
		(mid 124.262897 -321.117995)
		(end 124.25426 -321.098418)
		(stroke
			(width 0.07112)
			(type default)
		)
		(layer "In4.Cu")
	)
	(gr_arc
		(start 124.277882 -321.155314)
		(mid 124.274501 -321.146532)
		(end 124.271024 -321.137788)
		(stroke
			(width 0.07112)
			(type default)
		)
		(layer "In4.Cu")
	)
	(gr_line
		(start 124.350526 -359.086912)
		(end 124.350526 -359.086658)
		(stroke
			(width 0.07112)
			(type default)
		)
		(layer "In4.Cu")
	)
	(gr_line
		(start 124.374656 -404.17369)
		(end 124.083826 -404.46452)
		(stroke
			(width 0.07112)
			(type default)
		)
		(layer "In4.Cu")
	)
	(gr_line
		(start 124.491242 -385.31038)
		(end 124.844556 -385.405376)
		(stroke
			(width 0.07112)
			(type default)
		)
		(layer "In4.Cu")
	)
	(gr_line
		(start 124.496322 -289.777678)
		(end 124.497084 -289.77717)
		(stroke
			(width 0.05715)
			(type default)
		)
		(layer "In4.Cu")
	)
	(gr_arc
		(start 124.505466 -317.537846)
		(mid 124.505086 -317.537084)
		(end 124.504704 -317.536322)
		(stroke
			(width 0.07112)
			(type default)
		)
		(layer "In4.Cu")
	)
	(gr_line
		(start 124.614178 -402.373846)
		(end 124.436124 -402.300186)
		(stroke
			(width 0.07112)
			(type default)
		)
		(layer "In4.Cu")
	)
	(gr_line
		(start 124.623576 -296.439844)
		(end 124.623576 -296.411396)
		(stroke
			(width 0.05715)
			(type default)
		)
		(layer "In4.Cu")
	)
	(gr_line
		(start 124.623576 -296.411396)
		(end 124.669296 -296.365676)
		(stroke
			(width 0.05715)
			(type default)
		)
		(layer "In4.Cu")
	)
	(gr_line
		(start 124.656596 -404.17369)
		(end 124.947426 -404.46452)
		(stroke
			(width 0.07112)
			(type default)
		)
		(layer "In4.Cu")
	)
	(gr_arc
		(start 124.669296 -295.948354)
		(mid 124.669283 -295.952291)
		(end 124.669296 -295.956228)
		(stroke
			(width 0.05715)
			(type default)
		)
		(layer "In4.Cu")
	)
	(gr_line
		(start 124.844556 -385.405376)
		(end 124.845064 -385.404868)
		(stroke
			(width 0.07112)
			(type default)
		)
		(layer "In4.Cu")
	)
	(gr_line
		(start 124.861066 -381.59436)
		(end 124.890784 -381.168402)
		(stroke
			(width 0.07112)
			(type default)
		)
		(layer "In4.Cu")
	)
	(gr_line
		(start 124.867162 -401.8153)
		(end 124.867162 -401.815046)
		(stroke
			(width 0.07112)
			(type default)
		)
		(layer "In4.Cu")
	)
	(gr_line
		(start 124.867162 -401.815046)
		(end 124.327158 -402.03882)
		(stroke
			(width 0.07112)
			(type default)
		)
		(layer "In4.Cu")
	)
	(gr_line
		(start 124.887228 -293.86911)
		(end 124.952506 -293.84752)
		(stroke
			(width 0.05715)
			(type default)
		)
		(layer "In4.Cu")
	)
	(gr_line
		(start 124.887482 -293.882826)
		(end 124.887228 -293.86911)
		(stroke
			(width 0.05715)
			(type default)
		)
		(layer "In4.Cu")
	)
	(gr_line
		(start 124.890784 -381.168402)
		(end 125.036072 -381.042418)
		(stroke
			(width 0.07112)
			(type default)
		)
		(layer "In4.Cu")
	)
	(gr_line
		(start 124.891292 -386.003292)
		(end 124.986034 -385.649724)
		(stroke
			(width 0.07112)
			(type default)
		)
		(layer "In4.Cu")
	)
	(gr_line
		(start 124.905516 -296.439844)
		(end 124.905516 -296.411396)
		(stroke
			(width 0.05715)
			(type default)
		)
		(layer "In4.Cu")
	)
	(gr_line
		(start 124.905516 -296.411396)
		(end 124.859796 -296.365676)
		(stroke
			(width 0.05715)
			(type default)
		)
		(layer "In4.Cu")
	)
	(gr_arc
		(start 124.913136 -295.491154)
		(mid 124.90547 -295.496551)
		(end 124.897896 -295.502076)
		(stroke
			(width 0.05715)
			(type default)
		)
		(layer "In4.Cu")
	)
	(gr_arc
		(start 124.913136 -295.491154)
		(mid 124.913517 -295.4909)
		(end 124.913898 -295.490646)
		(stroke
			(width 0.05715)
			(type default)
		)
		(layer "In4.Cu")
	)
	(gr_line
		(start 124.913898 -295.490646)
		(end 124.91974 -295.48709)
		(stroke
			(width 0.05715)
			(type default)
		)
		(layer "In4.Cu")
	)
	(gr_line
		(start 124.923042 -292.245288)
		(end 124.925328 -292.244018)
		(stroke
			(width 0.05715)
			(type default)
		)
		(layer "In4.Cu")
	)
	(gr_line
		(start 124.925328 -292.244018)
		(end 124.92736 -292.242748)
		(stroke
			(width 0.05715)
			(type default)
		)
		(layer "In4.Cu")
	)
	(gr_line
		(start 124.94006 -380.46914)
		(end 124.969778 -380.043182)
		(stroke
			(width 0.07112)
			(type default)
		)
		(layer "In4.Cu")
	)
	(gr_line
		(start 124.943108 -288.993834)
		(end 124.947172 -288.991294)
		(stroke
			(width 0.05715)
			(type default)
		)
		(layer "In4.Cu")
	)
	(gr_line
		(start 124.943362 -291.578538)
		(end 124.937012 -291.574474)
		(stroke
			(width 0.05715)
			(type default)
		)
		(layer "In4.Cu")
	)
	(gr_line
		(start 124.944632 -291.5793)
		(end 124.943362 -291.578538)
		(stroke
			(width 0.05715)
			(type default)
		)
		(layer "In4.Cu")
	)
	(gr_line
		(start 124.945648 -291.580062)
		(end 124.944632 -291.5793)
		(stroke
			(width 0.05715)
			(type default)
		)
		(layer "In4.Cu")
	)
	(gr_line
		(start 124.949204 -288.990278)
		(end 124.949458 -288.990024)
		(stroke
			(width 0.05715)
			(type default)
		)
		(layer "In4.Cu")
	)
	(gr_line
		(start 124.949458 -294.822372)
		(end 124.944378 -294.818816)
		(stroke
			(width 0.05715)
			(type default)
		)
		(layer "In4.Cu")
	)
	(gr_line
		(start 124.949458 -288.990024)
		(end 124.950728 -288.989262)
		(stroke
			(width 0.05715)
			(type default)
		)
		(layer "In4.Cu")
	)
	(gr_line
		(start 124.950728 -288.989262)
		(end 124.951744 -288.988754)
		(stroke
			(width 0.05715)
			(type default)
		)
		(layer "In4.Cu")
	)
	(gr_line
		(start 124.951744 -288.988754)
		(end 124.952506 -288.988246)
		(stroke
			(width 0.05715)
			(type default)
		)
		(layer "In4.Cu")
	)
	(gr_line
		(start 124.952506 -292.228016)
		(end 124.952506 -292.22827)
		(stroke
			(width 0.05715)
			(type default)
		)
		(layer "In4.Cu")
	)
	(gr_line
		(start 124.954538 -292.227254)
		(end 124.956062 -292.226238)
		(stroke
			(width 0.05715)
			(type default)
		)
		(layer "In4.Cu")
	)
	(gr_line
		(start 124.954792 -294.82542)
		(end 124.949458 -294.822372)
		(stroke
			(width 0.05715)
			(type default)
		)
		(layer "In4.Cu")
	)
	(gr_line
		(start 124.956062 -292.226238)
		(end 124.957078 -292.22573)
		(stroke
			(width 0.05715)
			(type default)
		)
		(layer "In4.Cu")
	)
	(gr_line
		(start 124.956316 -291.586158)
		(end 124.955046 -291.58565)
		(stroke
			(width 0.05715)
			(type default)
		)
		(layer "In4.Cu")
	)
	(gr_line
		(start 124.957078 -292.22573)
		(end 124.958348 -292.224968)
		(stroke
			(width 0.05715)
			(type default)
		)
		(layer "In4.Cu")
	)
	(gr_line
		(start 124.957332 -291.586666)
		(end 124.956316 -291.586158)
		(stroke
			(width 0.05715)
			(type default)
		)
		(layer "In4.Cu")
	)
	(gr_line
		(start 124.958094 -288.985198)
		(end 124.958856 -288.98469)
		(stroke
			(width 0.05715)
			(type default)
		)
		(layer "In4.Cu")
	)
	(gr_line
		(start 124.958856 -291.587682)
		(end 124.958348 -291.587428)
		(stroke
			(width 0.05715)
			(type default)
		)
		(layer "In4.Cu")
	)
	(gr_line
		(start 124.958856 -288.98469)
		(end 124.96165 -288.983166)
		(stroke
			(width 0.05715)
			(type default)
		)
		(layer "In4.Cu")
	)
	(gr_line
		(start 124.96165 -288.983166)
		(end 124.96165 -288.982912)
		(stroke
			(width 0.05715)
			(type default)
		)
		(layer "In4.Cu")
	)
	(gr_line
		(start 124.96165 -288.982912)
		(end 124.962158 -288.982404)
		(stroke
			(width 0.05715)
			(type default)
		)
		(layer "In4.Cu")
	)
	(gr_line
		(start 124.969778 -380.043182)
		(end 125.114812 -379.917198)
		(stroke
			(width 0.07112)
			(type default)
		)
		(layer "In4.Cu")
	)
	(gr_line
		(start 124.975112 -401.770596)
		(end 124.867162 -401.8153)
		(stroke
			(width 0.07112)
			(type default)
		)
		(layer "In4.Cu")
	)
	(gr_line
		(start 124.987304 -381.739648)
		(end 124.861066 -381.59436)
		(stroke
			(width 0.07112)
			(type default)
		)
		(layer "In4.Cu")
	)
	(gr_line
		(start 125.00864 -402.210524)
		(end 124.614178 -402.373846)
		(stroke
			(width 0.07112)
			(type default)
		)
		(layer "In4.Cu")
	)
	(gr_arc
		(start 125.010164 -294.030654)
		(mid 125.00685 -294.03305)
		(end 125.00356 -294.03548)
		(stroke
			(width 0.05715)
			(type default)
		)
		(layer "In4.Cu")
	)
	(gr_line
		(start 125.02261 -294.02532)
		(end 125.034548 -294.021256)
		(stroke
			(width 0.05715)
			(type default)
		)
		(layer "In4.Cu")
	)
	(gr_line
		(start 125.02388 -292.40734)
		(end 125.02642 -292.405816)
		(stroke
			(width 0.05715)
			(type default)
		)
		(layer "In4.Cu")
	)
	(gr_line
		(start 125.028452 -292.404546)
		(end 125.032262 -292.402514)
		(stroke
			(width 0.05715)
			(type default)
		)
		(layer "In4.Cu")
	)
	(gr_line
		(start 125.034548 -294.021256)
		(end 125.036326 -294.02024)
		(stroke
			(width 0.05715)
			(type default)
		)
		(layer "In4.Cu")
	)
	(gr_line
		(start 125.035056 -375.35358)
		(end 125.167644 -375.21388)
		(stroke
			(width 0.07112)
			(type default)
		)
		(layer "In4.Cu")
	)
	(gr_line
		(start 125.036326 -294.02024)
		(end 125.037596 -294.019478)
		(stroke
			(width 0.05715)
			(type default)
		)
		(layer "In4.Cu")
	)
	(gr_line
		(start 125.037596 -381.041148)
		(end 125.037088 -381.040894)
		(stroke
			(width 0.07112)
			(type default)
		)
		(layer "In4.Cu")
	)
	(gr_line
		(start 125.037596 -294.019478)
		(end 125.038358 -294.01897)
		(stroke
			(width 0.05715)
			(type default)
		)
		(layer "In4.Cu")
	)
	(gr_line
		(start 125.037596 -289.159442)
		(end 125.038358 -289.158934)
		(stroke
			(width 0.05715)
			(type default)
		)
		(layer "In4.Cu")
	)
	(gr_line
		(start 125.038104 -292.399466)
		(end 125.040136 -292.39845)
		(stroke
			(width 0.05715)
			(type default)
		)
		(layer "In4.Cu")
	)
	(gr_line
		(start 125.038358 -294.01897)
		(end 125.039882 -294.018208)
		(stroke
			(width 0.05715)
			(type default)
		)
		(layer "In4.Cu")
	)
	(gr_line
		(start 125.038358 -289.158934)
		(end 125.039374 -289.158426)
		(stroke
			(width 0.05715)
			(type default)
		)
		(layer "In4.Cu")
	)
	(gr_line
		(start 125.039882 -294.018208)
		(end 125.041152 -294.017446)
		(stroke
			(width 0.05715)
			(type default)
		)
		(layer "In4.Cu")
	)
	(gr_line
		(start 125.040136 -292.39845)
		(end 125.04166 -292.397434)
		(stroke
			(width 0.05715)
			(type default)
		)
		(layer "In4.Cu")
	)
	(gr_line
		(start 125.042422 -294.016684)
		(end 125.043438 -294.016176)
		(stroke
			(width 0.05715)
			(type default)
		)
		(layer "In4.Cu")
	)
	(gr_line
		(start 125.042676 -292.396926)
		(end 125.050804 -292.391846)
		(stroke
			(width 0.05715)
			(type default)
		)
		(layer "In4.Cu")
	)
	(gr_line
		(start 125.043438 -294.016176)
		(end 125.0442 -294.015668)
		(stroke
			(width 0.05715)
			(type default)
		)
		(layer "In4.Cu")
	)
	(gr_line
		(start 125.0442 -294.015668)
		(end 125.046994 -294.014144)
		(stroke
			(width 0.05715)
			(type default)
		)
		(layer "In4.Cu")
	)
	(gr_line
		(start 125.045216 -289.155124)
		(end 125.046994 -289.154108)
		(stroke
			(width 0.05715)
			(type default)
		)
		(layer "In4.Cu")
	)
	(gr_line
		(start 125.046232 -375.7803)
		(end 125.035056 -375.35358)
		(stroke
			(width 0.07112)
			(type default)
		)
		(layer "In4.Cu")
	)
	(gr_line
		(start 125.046994 -294.014144)
		(end 125.047756 -294.013636)
		(stroke
			(width 0.05715)
			(type default)
		)
		(layer "In4.Cu")
	)
	(gr_line
		(start 125.047756 -294.013636)
		(end 125.048772 -294.013128)
		(stroke
			(width 0.05715)
			(type default)
		)
		(layer "In4.Cu")
	)
	(gr_line
		(start 125.048772 -294.013128)
		(end 125.050296 -294.012112)
		(stroke
			(width 0.05715)
			(type default)
		)
		(layer "In4.Cu")
	)
	(gr_line
		(start 125.048772 -291.419534)
		(end 125.046232 -291.41801)
		(stroke
			(width 0.05715)
			(type default)
		)
		(layer "In4.Cu")
	)
	(gr_line
		(start 125.049026 -289.153092)
		(end 125.050296 -289.15233)
		(stroke
			(width 0.05715)
			(type default)
		)
		(layer "In4.Cu")
	)
	(gr_line
		(start 125.050042 -291.420042)
		(end 125.048772 -291.419534)
		(stroke
			(width 0.05715)
			(type default)
		)
		(layer "In4.Cu")
	)
	(gr_line
		(start 125.050296 -294.012112)
		(end 125.052074 -294.011096)
		(stroke
			(width 0.05715)
			(type default)
		)
		(layer "In4.Cu")
	)
	(gr_line
		(start 125.050804 -291.42055)
		(end 125.050042 -291.420042)
		(stroke
			(width 0.05715)
			(type default)
		)
		(layer "In4.Cu")
	)
	(gr_line
		(start 125.051312 -294.660828)
		(end 125.050296 -294.66032)
		(stroke
			(width 0.05715)
			(type default)
		)
		(layer "In4.Cu")
	)
	(gr_line
		(start 125.053344 -289.150552)
		(end 125.054868 -289.149536)
		(stroke
			(width 0.05715)
			(type default)
		)
		(layer "In4.Cu")
	)
	(gr_line
		(start 125.053598 -294.662098)
		(end 125.051312 -294.660828)
		(stroke
			(width 0.05715)
			(type default)
		)
		(layer "In4.Cu")
	)
	(gr_line
		(start 125.054106 -291.422582)
		(end 125.052074 -291.421312)
		(stroke
			(width 0.05715)
			(type default)
		)
		(layer "In4.Cu")
	)
	(gr_line
		(start 125.059948 -289.146742)
		(end 125.061726 -289.145726)
		(stroke
			(width 0.05715)
			(type default)
		)
		(layer "In4.Cu")
	)
	(gr_line
		(start 125.062234 -289.145472)
		(end 125.064266 -289.144202)
		(stroke
			(width 0.05715)
			(type default)
		)
		(layer "In4.Cu")
	)
	(gr_line
		(start 125.065028 -289.143948)
		(end 125.067314 -289.142424)
		(stroke
			(width 0.05715)
			(type default)
		)
		(layer "In4.Cu")
	)
	(gr_line
		(start 125.066044 -380.614174)
		(end 124.94006 -380.46914)
		(stroke
			(width 0.07112)
			(type default)
		)
		(layer "In4.Cu")
	)
	(gr_line
		(start 125.06706 -380.615698)
		(end 125.067314 -380.615698)
		(stroke
			(width 0.07112)
			(type default)
		)
		(layer "In4.Cu")
	)
	(gr_line
		(start 125.082554 -402.032724)
		(end 125.00864 -402.210524)
		(stroke
			(width 0.07112)
			(type default)
		)
		(layer "In4.Cu")
	)
	(gr_line
		(start 125.1077 -385.579112)
		(end 125.160532 -385.548632)
		(stroke
			(width 0.07112)
			(type default)
		)
		(layer "In4.Cu")
	)
	(gr_line
		(start 125.116336 -379.915928)
		(end 125.116082 -379.915928)
		(stroke
			(width 0.07112)
			(type default)
		)
		(layer "In4.Cu")
	)
	(gr_line
		(start 125.139704 -295.146476)
		(end 125.139704 -295.146222)
		(stroke
			(width 0.05715)
			(type default)
		)
		(layer "In4.Cu")
	)
	(gr_line
		(start 125.160532 -385.548632)
		(end 125.24867 -385.460494)
		(stroke
			(width 0.07112)
			(type default)
		)
		(layer "In4.Cu")
	)
	(gr_line
		(start 125.185932 -375.912634)
		(end 125.046232 -375.7803)
		(stroke
			(width 0.07112)
			(type default)
		)
		(layer "In4.Cu")
	)
	(gr_line
		(start 125.24867 -385.460494)
		(end 125.24867 -385.334764)
		(stroke
			(width 0.07112)
			(type default)
		)
		(layer "In4.Cu")
	)
	(gr_line
		(start 125.269752 -381.760476)
		(end 125.318774 -381.060706)
		(stroke
			(width 0.07112)
			(type default)
		)
		(layer "In4.Cu")
	)
	(gr_line
		(start 125.330204 -295.14673)
		(end 125.330204 -295.146222)
		(stroke
			(width 0.05715)
			(type default)
		)
		(layer "In4.Cu")
	)
	(gr_line
		(start 125.348492 -380.63551)
		(end 125.397514 -379.93574)
		(stroke
			(width 0.07112)
			(type default)
		)
		(layer "In4.Cu")
	)
	(gr_line
		(start 125.469142 -375.906538)
		(end 125.450854 -375.205498)
		(stroke
			(width 0.07112)
			(type default)
		)
		(layer "In4.Cu")
	)
	(gr_line
		(start 125.532642 -291.096192)
		(end 125.2347 -291.096192)
		(stroke
			(width 0.05715)
			(type default)
		)
		(layer "In4.Cu")
	)
	(gr_line
		(start 125.532642 -289.47618)
		(end 125.2347 -289.47618)
		(stroke
			(width 0.05715)
			(type default)
		)
		(layer "In4.Cu")
	)
	(gr_line
		(start 125.532642 -287.856422)
		(end 125.2347 -287.856422)
		(stroke
			(width 0.05715)
			(type default)
		)
		(layer "In4.Cu")
	)
	(gr_line
		(start 125.532642 -286.23641)
		(end 125.2347 -286.23641)
		(stroke
			(width 0.05715)
			(type default)
		)
		(layer "In4.Cu")
	)
	(gr_line
		(start 125.553216 -350.043242)
		(end 125.553216 -350.043496)
		(stroke
			(width 0.07112)
			(type default)
		)
		(layer "In4.Cu")
	)
	(gr_arc
		(start 125.559312 -288.31921)
		(mid 125.562112 -288.317186)
		(end 125.5649 -288.315146)
		(stroke
			(width 0.05715)
			(type default)
		)
		(layer "In4.Cu")
	)
	(gr_line
		(start 125.563884 -296.351198)
		(end 125.563884 -296.32275)
		(stroke
			(width 0.05715)
			(type default)
		)
		(layer "In4.Cu")
	)
	(gr_line
		(start 125.563884 -296.32275)
		(end 125.609604 -296.27703)
		(stroke
			(width 0.05715)
			(type default)
		)
		(layer "In4.Cu")
	)
	(gr_line
		(start 125.601984 -287.925764)
		(end 125.532642 -287.856422)
		(stroke
			(width 0.05715)
			(type default)
		)
		(layer "In4.Cu")
	)
	(gr_line
		(start 125.615446 -291.178996)
		(end 125.532642 -291.096192)
		(stroke
			(width 0.05715)
			(type default)
		)
		(layer "In4.Cu")
	)
	(gr_line
		(start 125.615446 -289.558984)
		(end 125.532642 -289.47618)
		(stroke
			(width 0.05715)
			(type default)
		)
		(layer "In4.Cu")
	)
	(gr_arc
		(start 125.615446 -289.558984)
		(mid 125.617238 -289.570306)
		(end 125.619256 -289.58159)
		(stroke
			(width 0.05715)
			(type default)
		)
		(layer "In4.Cu")
	)
	(gr_line
		(start 125.615446 -286.319214)
		(end 125.532642 -286.23641)
		(stroke
			(width 0.05715)
			(type default)
		)
		(layer "In4.Cu")
	)
	(gr_arc
		(start 125.615446 -286.319214)
		(mid 125.617234 -286.330664)
		(end 125.619256 -286.342074)
		(stroke
			(width 0.05715)
			(type default)
		)
		(layer "In4.Cu")
	)
	(gr_line
		(start 125.6157 -291.178996)
		(end 125.615446 -291.178996)
		(stroke
			(width 0.05715)
			(type default)
		)
		(layer "In4.Cu")
	)
	(gr_arc
		(start 125.6157 -291.178996)
		(mid 125.617492 -291.190191)
		(end 125.61951 -291.201348)
		(stroke
			(width 0.05715)
			(type default)
		)
		(layer "In4.Cu")
	)
	(gr_line
		(start 125.691138 -385.31038)
		(end 126.044452 -385.405376)
		(stroke
			(width 0.07112)
			(type default)
		)
		(layer "In4.Cu")
	)
	(gr_line
		(start 125.70714 -320.446146)
		(end 125.707394 -320.4464)
		(stroke
			(width 0.07112)
			(type default)
		)
		(layer "In4.Cu")
	)
	(gr_arc
		(start 125.790198 -287.962086)
		(mid 125.792221 -287.950676)
		(end 125.794008 -287.939226)
		(stroke
			(width 0.05715)
			(type default)
		)
		(layer "In4.Cu")
	)
	(gr_line
		(start 125.794008 -287.939226)
		(end 125.876812 -287.856422)
		(stroke
			(width 0.05715)
			(type default)
		)
		(layer "In4.Cu")
	)
	(gr_line
		(start 125.80747 -289.545522)
		(end 125.876812 -289.47618)
		(stroke
			(width 0.05715)
			(type default)
		)
		(layer "In4.Cu")
	)
	(gr_line
		(start 125.80747 -286.305752)
		(end 125.876812 -286.23641)
		(stroke
			(width 0.05715)
			(type default)
		)
		(layer "In4.Cu")
	)
	(gr_line
		(start 125.807724 -291.16528)
		(end 125.876812 -291.096192)
		(stroke
			(width 0.05715)
			(type default)
		)
		(layer "In4.Cu")
	)
	(gr_line
		(start 125.810264 -403.075394)
		(end 125.632464 -403.00148)
		(stroke
			(width 0.07112)
			(type default)
		)
		(layer "In4.Cu")
	)
	(gr_arc
		(start 125.844554 -289.935158)
		(mid 125.848606 -289.93797)
		(end 125.852682 -289.940746)
		(stroke
			(width 0.05715)
			(type default)
		)
		(layer "In4.Cu")
	)
	(gr_line
		(start 125.845824 -296.351198)
		(end 125.845824 -296.32275)
		(stroke
			(width 0.05715)
			(type default)
		)
		(layer "In4.Cu")
	)
	(gr_line
		(start 125.845824 -296.32275)
		(end 125.800104 -296.27703)
		(stroke
			(width 0.05715)
			(type default)
		)
		(layer "In4.Cu")
	)
	(gr_arc
		(start 125.853444 -289.941254)
		(mid 125.853063 -289.941)
		(end 125.852682 -289.940746)
		(stroke
			(width 0.05715)
			(type default)
		)
		(layer "In4.Cu")
	)
	(gr_line
		(start 125.860556 -289.945318)
		(end 125.853444 -289.941254)
		(stroke
			(width 0.05715)
			(type default)
		)
		(layer "In4.Cu")
	)
	(gr_line
		(start 125.876812 -291.096192)
		(end 126.174754 -291.096192)
		(stroke
			(width 0.05715)
			(type default)
		)
		(layer "In4.Cu")
	)
	(gr_line
		(start 125.876812 -289.47618)
		(end 126.174754 -289.47618)
		(stroke
			(width 0.05715)
			(type default)
		)
		(layer "In4.Cu")
	)
	(gr_line
		(start 125.876812 -287.856422)
		(end 126.174754 -287.856422)
		(stroke
			(width 0.05715)
			(type default)
		)
		(layer "In4.Cu")
	)
	(gr_line
		(start 125.876812 -286.23641)
		(end 126.174754 -286.23641)
		(stroke
			(width 0.05715)
			(type default)
		)
		(layer "In4.Cu")
	)
	(gr_line
		(start 125.890782 -293.849298)
		(end 125.891798 -293.84879)
		(stroke
			(width 0.05715)
			(type default)
		)
		(layer "In4.Cu")
	)
	(gr_line
		(start 125.891798 -293.84879)
		(end 125.892306 -293.848536)
		(stroke
			(width 0.05715)
			(type default)
		)
		(layer "In4.Cu")
	)
	(gr_line
		(start 125.892306 -289.96386)
		(end 125.891544 -289.963352)
		(stroke
			(width 0.05715)
			(type default)
		)
		(layer "In4.Cu")
	)
	(gr_line
		(start 125.8951 -289.965384)
		(end 125.892306 -289.96386)
		(stroke
			(width 0.05715)
			(type default)
		)
		(layer "In4.Cu")
	)
	(gr_arc
		(start 125.959108 -320.319146)
		(mid 125.958097 -320.317238)
		(end 125.957076 -320.315336)
		(stroke
			(width 0.07112)
			(type default)
		)
		(layer "In4.Cu")
	)
	(gr_line
		(start 125.985778 -294.014906)
		(end 125.987048 -294.014144)
		(stroke
			(width 0.05715)
			(type default)
		)
		(layer "In4.Cu")
	)
	(gr_line
		(start 125.987302 -295.633902)
		(end 125.98781 -295.633648)
		(stroke
			(width 0.05715)
			(type default)
		)
		(layer "In4.Cu")
	)
	(gr_line
		(start 125.98781 -294.658796)
		(end 125.98654 -294.658034)
		(stroke
			(width 0.05715)
			(type default)
		)
		(layer "In4.Cu")
	)
	(gr_line
		(start 125.98781 -293.038784)
		(end 125.987302 -293.03853)
		(stroke
			(width 0.05715)
			(type default)
		)
		(layer "In4.Cu")
	)
	(gr_line
		(start 125.98781 -291.418772)
		(end 125.987302 -291.418518)
		(stroke
			(width 0.05715)
			(type default)
		)
		(layer "In4.Cu")
	)
	(gr_line
		(start 125.98781 -289.79876)
		(end 125.986794 -289.798252)
		(stroke
			(width 0.05715)
			(type default)
		)
		(layer "In4.Cu")
	)
	(gr_line
		(start 125.988318 -293.038784)
		(end 125.98781 -293.038784)
		(stroke
			(width 0.05715)
			(type default)
		)
		(layer "In4.Cu")
	)
	(gr_line
		(start 125.990604 -289.800538)
		(end 125.98781 -289.79876)
		(stroke
			(width 0.05715)
			(type default)
		)
		(layer "In4.Cu")
	)
	(gr_arc
		(start 125.998732 -294.00754)
		(mid 126.001658 -294.00577)
		(end 126.004574 -294.003984)
		(stroke
			(width 0.05715)
			(type default)
		)
		(layer "In4.Cu")
	)
	(gr_arc
		(start 126.00559 -293.049198)
		(mid 126.002548 -293.047283)
		(end 125.999494 -293.045388)
		(stroke
			(width 0.05715)
			(type default)
		)
		(layer "In4.Cu")
	)
	(gr_line
		(start 126.026672 -381.826516)
		(end 126.05639 -381.400558)
		(stroke
			(width 0.07112)
			(type default)
		)
		(layer "In4.Cu")
	)
	(gr_line
		(start 126.044452 -385.405376)
		(end 126.04496 -385.404868)
		(stroke
			(width 0.07112)
			(type default)
		)
		(layer "In4.Cu")
	)
	(gr_line
		(start 126.05639 -381.400558)
		(end 126.201678 -381.274574)
		(stroke
			(width 0.07112)
			(type default)
		)
		(layer "In4.Cu")
	)
	(gr_line
		(start 126.081536 -333.16799)
		(end 126.081536 -333.167736)
		(stroke
			(width 0.07112)
			(type default)
		)
		(layer "In4.Cu")
	)
	(gr_line
		(start 126.091188 -386.003292)
		(end 126.18593 -385.649724)
		(stroke
			(width 0.07112)
			(type default)
		)
		(layer "In4.Cu")
	)
	(gr_arc
		(start 126.10211 -2.371852)
		(mid 124.3287 -3.106426)
		(end 123.594114 -4.879848)
		(stroke
			(width 0.2)
			(type default)
		)
		(layer "In4.Cu")
	)
	(gr_line
		(start 126.10211 -2.371852)
		(end 194.701922 -2.371852)
		(stroke
			(width 0.2)
			(type default)
		)
		(layer "In4.Cu")
	)
	(gr_line
		(start 126.105666 -380.701296)
		(end 126.135384 -380.275338)
		(stroke
			(width 0.07112)
			(type default)
		)
		(layer "In4.Cu")
	)
	(gr_line
		(start 126.135384 -380.275338)
		(end 126.280672 -380.149354)
		(stroke
			(width 0.07112)
			(type default)
		)
		(layer "In4.Cu")
	)
	(gr_line
		(start 126.15291 -381.97155)
		(end 126.026672 -381.826516)
		(stroke
			(width 0.07112)
			(type default)
		)
		(layer "In4.Cu")
	)
	(gr_line
		(start 126.163324 -375.697242)
		(end 126.295912 -375.557542)
		(stroke
			(width 0.07112)
			(type default)
		)
		(layer "In4.Cu")
	)
	(gr_line
		(start 126.171198 -402.47189)
		(end 125.52299 -402.740368)
		(stroke
			(width 0.07112)
			(type default)
		)
		(layer "In4.Cu")
	)
	(gr_line
		(start 126.1745 -376.124216)
		(end 126.163324 -375.697242)
		(stroke
			(width 0.07112)
			(type default)
		)
		(layer "In4.Cu")
	)
	(gr_line
		(start 126.203202 -381.273304)
		(end 126.202948 -381.273304)
		(stroke
			(width 0.07112)
			(type default)
		)
		(layer "In4.Cu")
	)
	(gr_line
		(start 126.204726 -402.912072)
		(end 125.810264 -403.075394)
		(stroke
			(width 0.07112)
			(type default)
		)
		(layer "In4.Cu")
	)
	(gr_line
		(start 126.23165 -380.846584)
		(end 126.105666 -380.701296)
		(stroke
			(width 0.07112)
			(type default)
		)
		(layer "In4.Cu")
	)
	(gr_line
		(start 126.278386 -402.734018)
		(end 126.204726 -402.912072)
		(stroke
			(width 0.07112)
			(type default)
		)
		(layer "In4.Cu")
	)
	(gr_line
		(start 126.282196 -380.148084)
		(end 126.281688 -380.14783)
		(stroke
			(width 0.07112)
			(type default)
		)
		(layer "In4.Cu")
	)
	(gr_line
		(start 126.307596 -385.579112)
		(end 126.360428 -385.548632)
		(stroke
			(width 0.07112)
			(type default)
		)
		(layer "In4.Cu")
	)
	(gr_line
		(start 126.3142 -376.256296)
		(end 126.1745 -376.124216)
		(stroke
			(width 0.07112)
			(type default)
		)
		(layer "In4.Cu")
	)
	(gr_arc
		(start 126.351284 -287.527746)
		(mid 126.35344 -287.529021)
		(end 126.355602 -287.530286)
		(stroke
			(width 0.05715)
			(type default)
		)
		(layer "In4.Cu")
	)
	(gr_line
		(start 126.360428 -385.548632)
		(end 126.448566 -385.460494)
		(stroke
			(width 0.07112)
			(type default)
		)
		(layer "In4.Cu")
	)
	(gr_line
		(start 126.361698 -287.533842)
		(end 126.361444 -287.533842)
		(stroke
			(width 0.05715)
			(type default)
		)
		(layer "In4.Cu")
	)
	(gr_line
		(start 126.362968 -290.774374)
		(end 126.361952 -290.773866)
		(stroke
			(width 0.05715)
			(type default)
		)
		(layer "In4.Cu")
	)
	(gr_line
		(start 126.370334 -290.778692)
		(end 126.369064 -290.77793)
		(stroke
			(width 0.05715)
			(type default)
		)
		(layer "In4.Cu")
	)
	(gr_line
		(start 126.435358 -381.992378)
		(end 126.48438 -381.293116)
		(stroke
			(width 0.07112)
			(type default)
		)
		(layer "In4.Cu")
	)
	(gr_line
		(start 126.448566 -385.460494)
		(end 126.448566 -385.334764)
		(stroke
			(width 0.07112)
			(type default)
		)
		(layer "In4.Cu")
	)
	(gr_line
		(start 126.465076 -290.613084)
		(end 126.46406 -290.612322)
		(stroke
			(width 0.05715)
			(type default)
		)
		(layer "In4.Cu")
	)
	(gr_line
		(start 126.489206 -290.627054)
		(end 126.487682 -290.626038)
		(stroke
			(width 0.05715)
			(type default)
		)
		(layer "In4.Cu")
	)
	(gr_line
		(start 126.489968 -290.627562)
		(end 126.489206 -290.627054)
		(stroke
			(width 0.05715)
			(type default)
		)
		(layer "In4.Cu")
	)
	(gr_line
		(start 126.496826 -290.631626)
		(end 126.489968 -290.627562)
		(stroke
			(width 0.05715)
			(type default)
		)
		(layer "In4.Cu")
	)
	(gr_line
		(start 126.503938 -296.400982)
		(end 126.503938 -296.372534)
		(stroke
			(width 0.05715)
			(type default)
		)
		(layer "In4.Cu")
	)
	(gr_line
		(start 126.503938 -296.372534)
		(end 126.549658 -296.326814)
		(stroke
			(width 0.05715)
			(type default)
		)
		(layer "In4.Cu")
	)
	(gr_arc
		(start 126.5047 -290.637214)
		(mid 126.500775 -290.634403)
		(end 126.496826 -290.631626)
		(stroke
			(width 0.05715)
			(type default)
		)
		(layer "In4.Cu")
	)
	(gr_line
		(start 126.514098 -380.868936)
		(end 126.563374 -380.167642)
		(stroke
			(width 0.07112)
			(type default)
		)
		(layer "In4.Cu")
	)
	(gr_line
		(start 126.59741 -376.2502)
		(end 126.578868 -375.54916)
		(stroke
			(width 0.07112)
			(type default)
		)
		(layer "In4.Cu")
	)
	(gr_line
		(start 126.61011 -5.787898)
		(end 126.61011 -9.780016)
		(stroke
			(width 0.2)
			(type default)
		)
		(layer "In4.Cu")
	)
	(gr_line
		(start 126.785878 -296.400982)
		(end 126.785878 -296.372534)
		(stroke
			(width 0.05715)
			(type default)
		)
		(layer "In4.Cu")
	)
	(gr_line
		(start 126.785878 -296.372534)
		(end 126.740158 -296.326814)
		(stroke
			(width 0.05715)
			(type default)
		)
		(layer "In4.Cu")
	)
	(gr_line
		(start 126.852426 -402.643594)
		(end 126.674372 -402.569934)
		(stroke
			(width 0.07112)
			(type default)
		)
		(layer "In4.Cu")
	)
	(gr_line
		(start 126.891288 -385.31038)
		(end 127.244602 -385.405376)
		(stroke
			(width 0.07112)
			(type default)
		)
		(layer "In4.Cu")
	)
	(gr_line
		(start 127.21336 -402.04009)
		(end 126.565152 -402.308568)
		(stroke
			(width 0.07112)
			(type default)
		)
		(layer "In4.Cu")
	)
	(gr_line
		(start 127.244602 -385.405376)
		(end 127.24511 -385.404868)
		(stroke
			(width 0.07112)
			(type default)
		)
		(layer "In4.Cu")
	)
	(gr_line
		(start 127.246888 -402.480272)
		(end 126.852426 -402.643594)
		(stroke
			(width 0.07112)
			(type default)
		)
		(layer "In4.Cu")
	)
	(gr_line
		(start 127.25781 -381.72263)
		(end 127.287528 -381.296672)
		(stroke
			(width 0.07112)
			(type default)
		)
		(layer "In4.Cu")
	)
	(gr_line
		(start 127.287528 -381.296672)
		(end 127.432816 -381.170688)
		(stroke
			(width 0.07112)
			(type default)
		)
		(layer "In4.Cu")
	)
	(gr_line
		(start 127.291338 -386.003292)
		(end 127.38608 -385.649724)
		(stroke
			(width 0.07112)
			(type default)
		)
		(layer "In4.Cu")
	)
	(gr_line
		(start 127.295148 -290.769802)
		(end 127.293624 -290.768786)
		(stroke
			(width 0.05715)
			(type default)
		)
		(layer "In4.Cu")
	)
	(gr_line
		(start 127.297434 -290.771072)
		(end 127.295148 -290.769802)
		(stroke
			(width 0.05715)
			(type default)
		)
		(layer "In4.Cu")
	)
	(gr_line
		(start 127.300736 -290.773104)
		(end 127.299212 -290.772088)
		(stroke
			(width 0.05715)
			(type default)
		)
		(layer "In4.Cu")
	)
	(gr_line
		(start 127.301752 -290.773612)
		(end 127.300736 -290.773104)
		(stroke
			(width 0.05715)
			(type default)
		)
		(layer "In4.Cu")
	)
	(gr_line
		(start 127.302514 -290.77412)
		(end 127.301752 -290.773612)
		(stroke
			(width 0.05715)
			(type default)
		)
		(layer "In4.Cu")
	)
	(gr_line
		(start 127.320294 -402.302218)
		(end 127.246888 -402.480272)
		(stroke
			(width 0.07112)
			(type default)
		)
		(layer "In4.Cu")
	)
	(gr_line
		(start 127.33909 -376.002042)
		(end 127.471424 -375.862342)
		(stroke
			(width 0.07112)
			(type default)
		)
		(layer "In4.Cu")
	)
	(gr_line
		(start 127.350266 -376.428762)
		(end 127.33909 -376.002042)
		(stroke
			(width 0.07112)
			(type default)
		)
		(layer "In4.Cu")
	)
	(gr_line
		(start 127.368808 -377.129548)
		(end 127.501142 -376.990102)
		(stroke
			(width 0.07112)
			(type default)
		)
		(layer "In4.Cu")
	)
	(gr_line
		(start 127.379984 -377.556268)
		(end 127.368808 -377.129548)
		(stroke
			(width 0.07112)
			(type default)
		)
		(layer "In4.Cu")
	)
	(gr_line
		(start 127.384048 -381.867918)
		(end 127.25781 -381.72263)
		(stroke
			(width 0.07112)
			(type default)
		)
		(layer "In4.Cu")
	)
	(gr_line
		(start 127.393446 -290.606226)
		(end 127.39243 -290.605718)
		(stroke
			(width 0.05715)
			(type default)
		)
		(layer "In4.Cu")
	)
	(gr_line
		(start 127.394208 -290.606734)
		(end 127.393446 -290.606226)
		(stroke
			(width 0.05715)
			(type default)
		)
		(layer "In4.Cu")
	)
	(gr_line
		(start 127.395732 -290.607496)
		(end 127.394208 -290.606734)
		(stroke
			(width 0.05715)
			(type default)
		)
		(layer "In4.Cu")
	)
	(gr_line
		(start 127.397002 -290.608258)
		(end 127.395732 -290.607496)
		(stroke
			(width 0.05715)
			(type default)
		)
		(layer "In4.Cu")
	)
	(gr_line
		(start 127.397764 -290.608766)
		(end 127.397002 -290.608258)
		(stroke
			(width 0.05715)
			(type default)
		)
		(layer "In4.Cu")
	)
	(gr_line
		(start 127.39878 -290.609274)
		(end 127.397764 -290.608766)
		(stroke
			(width 0.05715)
			(type default)
		)
		(layer "In4.Cu")
	)
	(gr_line
		(start 127.399542 -290.609782)
		(end 127.39878 -290.609274)
		(stroke
			(width 0.05715)
			(type default)
		)
		(layer "In4.Cu")
	)
	(gr_line
		(start 127.403352 -290.611814)
		(end 127.402082 -290.611052)
		(stroke
			(width 0.05715)
			(type default)
		)
		(layer "In4.Cu")
	)
	(gr_line
		(start 127.42926 -290.627054)
		(end 127.42799 -290.626292)
		(stroke
			(width 0.05715)
			(type default)
		)
		(layer "In4.Cu")
	)
	(gr_line
		(start 127.430022 -290.627562)
		(end 127.42926 -290.627054)
		(stroke
			(width 0.05715)
			(type default)
		)
		(layer "In4.Cu")
	)
	(gr_line
		(start 127.43688 -290.631626)
		(end 127.430022 -290.627562)
		(stroke
			(width 0.05715)
			(type default)
		)
		(layer "In4.Cu")
	)
	(gr_line
		(start 127.437896 -404.17369)
		(end 127.147066 -404.46452)
		(stroke
			(width 0.07112)
			(type default)
		)
		(layer "In4.Cu")
	)
	(gr_arc
		(start 127.444754 -290.637214)
		(mid 127.440829 -290.634403)
		(end 127.43688 -290.631626)
		(stroke
			(width 0.05715)
			(type default)
		)
		(layer "In4.Cu")
	)
	(gr_line
		(start 127.489966 -376.561096)
		(end 127.350266 -376.428762)
		(stroke
			(width 0.07112)
			(type default)
		)
		(layer "In4.Cu")
	)
	(gr_line
		(start 127.507746 -385.579112)
		(end 127.560578 -385.548632)
		(stroke
			(width 0.07112)
			(type default)
		)
		(layer "In4.Cu")
	)
	(gr_line
		(start 127.519684 -377.688602)
		(end 127.379984 -377.556268)
		(stroke
			(width 0.07112)
			(type default)
		)
		(layer "In4.Cu")
	)
	(gr_line
		(start 127.560578 -385.548632)
		(end 127.648716 -385.460494)
		(stroke
			(width 0.07112)
			(type default)
		)
		(layer "In4.Cu")
	)
	(gr_arc
		(start 127.626618 -295.588182)
		(mid 127.621757 -295.593101)
		(end 127.616966 -295.598088)
		(stroke
			(width 0.05715)
			(type default)
		)
		(layer "In4.Cu")
	)
	(gr_line
		(start 127.626618 -295.588182)
		(end 127.627888 -295.586912)
		(stroke
			(width 0.05715)
			(type default)
		)
		(layer "In4.Cu")
	)
	(gr_line
		(start 127.627126 -296.612564)
		(end 127.627126 -296.584116)
		(stroke
			(width 0.05715)
			(type default)
		)
		(layer "In4.Cu")
	)
	(gr_line
		(start 127.627126 -296.584116)
		(end 127.672846 -296.538396)
		(stroke
			(width 0.05715)
			(type default)
		)
		(layer "In4.Cu")
	)
	(gr_line
		(start 127.627888 -295.586912)
		(end 127.639318 -295.578022)
		(stroke
			(width 0.05715)
			(type default)
		)
		(layer "In4.Cu")
	)
	(gr_line
		(start 127.648716 -385.460494)
		(end 127.648716 -385.334764)
		(stroke
			(width 0.07112)
			(type default)
		)
		(layer "In4.Cu")
	)
	(gr_line
		(start 127.666496 -381.888746)
		(end 127.715264 -381.188976)
		(stroke
			(width 0.07112)
			(type default)
		)
		(layer "In4.Cu")
	)
	(gr_line
		(start 127.715772 -296.176954)
		(end 127.715772 -296.177208)
		(stroke
			(width 0.05715)
			(type default)
		)
		(layer "In4.Cu")
	)
	(gr_line
		(start 127.719836 -404.17369)
		(end 128.010666 -404.46452)
		(stroke
			(width 0.07112)
			(type default)
		)
		(layer "In4.Cu")
	)
	(gr_line
		(start 127.773176 -376.559572)
		(end 127.754634 -375.85396)
		(stroke
			(width 0.07112)
			(type default)
		)
		(layer "In4.Cu")
	)
	(gr_line
		(start 127.794766 -295.45661)
		(end 127.796798 -295.455086)
		(stroke
			(width 0.05715)
			(type default)
		)
		(layer "In4.Cu")
	)
	(gr_arc
		(start 127.79756 -295.454324)
		(mid 127.797179 -295.454705)
		(end 127.796798 -295.455086)
		(stroke
			(width 0.05715)
			(type default)
		)
		(layer "In4.Cu")
	)
	(gr_line
		(start 127.80264 -377.682506)
		(end 127.784352 -376.981466)
		(stroke
			(width 0.07112)
			(type default)
		)
		(layer "In4.Cu")
	)
	(gr_line
		(start 127.894588 -402.212048)
		(end 127.716534 -402.138134)
		(stroke
			(width 0.07112)
			(type default)
		)
		(layer "In4.Cu")
	)
	(gr_line
		(start 127.909066 -296.612564)
		(end 127.909066 -296.584116)
		(stroke
			(width 0.05715)
			(type default)
		)
		(layer "In4.Cu")
	)
	(gr_line
		(start 127.909066 -296.584116)
		(end 127.863346 -296.538396)
		(stroke
			(width 0.05715)
			(type default)
		)
		(layer "In4.Cu")
	)
	(gr_line
		(start 128.091184 -385.31038)
		(end 128.444498 -385.405376)
		(stroke
			(width 0.07112)
			(type default)
		)
		(layer "In4.Cu")
	)
	(gr_line
		(start 128.138428 -306.80279)
		(end 128.138682 -306.80279)
		(stroke
			(width 0.07112)
			(type default)
		)
		(layer "In4.Cu")
	)
	(gr_line
		(start 128.148334 -337.854036)
		(end 128.148334 -337.854544)
		(stroke
			(width 0.07112)
			(type default)
		)
		(layer "In4.Cu")
	)
	(gr_line
		(start 128.255268 -401.608544)
		(end 127.607314 -401.876768)
		(stroke
			(width 0.07112)
			(type default)
		)
		(layer "In4.Cu")
	)
	(gr_line
		(start 128.28905 -402.048726)
		(end 127.894588 -402.212048)
		(stroke
			(width 0.07112)
			(type default)
		)
		(layer "In4.Cu")
	)
	(gr_line
		(start 128.36271 -401.870418)
		(end 128.28905 -402.048726)
		(stroke
			(width 0.07112)
			(type default)
		)
		(layer "In4.Cu")
	)
	(gr_line
		(start 128.444498 -385.405376)
		(end 128.445006 -385.404868)
		(stroke
			(width 0.07112)
			(type default)
		)
		(layer "In4.Cu")
	)
	(gr_line
		(start 128.491234 -386.003292)
		(end 128.585976 -385.649724)
		(stroke
			(width 0.07112)
			(type default)
		)
		(layer "In4.Cu")
	)
	(gr_line
		(start 128.560322 -403.283674)
		(end 128.382522 -403.210014)
		(stroke
			(width 0.07112)
			(type default)
		)
		(layer "In4.Cu")
	)
	(gr_line
		(start 128.707642 -385.579112)
		(end 128.760474 -385.548632)
		(stroke
			(width 0.07112)
			(type default)
		)
		(layer "In4.Cu")
	)
	(gr_line
		(start 128.760474 -385.548632)
		(end 128.848612 -385.460494)
		(stroke
			(width 0.07112)
			(type default)
		)
		(layer "In4.Cu")
	)
	(gr_line
		(start 128.848612 -385.460494)
		(end 128.848612 -385.334764)
		(stroke
			(width 0.07112)
			(type default)
		)
		(layer "In4.Cu")
	)
	(gr_line
		(start 128.92151 -402.680424)
		(end 128.273302 -402.948902)
		(stroke
			(width 0.07112)
			(type default)
		)
		(layer "In4.Cu")
	)
	(gr_line
		(start 128.954784 -403.120352)
		(end 128.560322 -403.283674)
		(stroke
			(width 0.07112)
			(type default)
		)
		(layer "In4.Cu")
	)
	(gr_line
		(start 128.993646 -325.513192)
		(end 128.993392 -325.513192)
		(stroke
			(width 0.07112)
			(type default)
		)
		(layer "In4.Cu")
	)
	(gr_line
		(start 128.994916 -380.779782)
		(end 129.158238 -380.38532)
		(stroke
			(width 0.07112)
			(type default)
		)
		(layer "In4.Cu")
	)
	(gr_line
		(start 129.028698 -402.942552)
		(end 128.954784 -403.120352)
		(stroke
			(width 0.07112)
			(type default)
		)
		(layer "In4.Cu")
	)
	(gr_line
		(start 129.06883 -380.957582)
		(end 128.994916 -380.779782)
		(stroke
			(width 0.07112)
			(type default)
		)
		(layer "In4.Cu")
	)
	(gr_line
		(start 129.113788 -337.950302)
		(end 129.113788 -337.95081)
		(stroke
			(width 0.07112)
			(type default)
		)
		(layer "In4.Cu")
	)
	(gr_line
		(start 129.158238 -380.38532)
		(end 129.336292 -380.311914)
		(stroke
			(width 0.07112)
			(type default)
		)
		(layer "In4.Cu")
	)
	(gr_line
		(start 129.291334 -385.31038)
		(end 129.644394 -385.405376)
		(stroke
			(width 0.07112)
			(type default)
		)
		(layer "In4.Cu")
	)
	(gr_line
		(start 129.292096 -299.346366)
		(end 129.29235 -299.346366)
		(stroke
			(width 0.07112)
			(type default)
		)
		(layer "In4.Cu")
	)
	(gr_line
		(start 129.29997 -299.357796)
		(end 129.292096 -299.346366)
		(stroke
			(width 0.07112)
			(type default)
		)
		(layer "In4.Cu")
	)
	(gr_line
		(start 129.30886 -299.368464)
		(end 129.29997 -299.357796)
		(stroke
			(width 0.07112)
			(type default)
		)
		(layer "In4.Cu")
	)
	(gr_line
		(start 129.329942 -381.067056)
		(end 129.59842 -380.418848)
		(stroke
			(width 0.07112)
			(type default)
		)
		(layer "In4.Cu")
	)
	(gr_line
		(start 129.426716 -379.737874)
		(end 129.590038 -379.343412)
		(stroke
			(width 0.07112)
			(type default)
		)
		(layer "In4.Cu")
	)
	(gr_line
		(start 129.500376 -379.915674)
		(end 129.426716 -379.737874)
		(stroke
			(width 0.07112)
			(type default)
		)
		(layer "In4.Cu")
	)
	(gr_line
		(start 129.590038 -379.343412)
		(end 129.767838 -379.269498)
		(stroke
			(width 0.07112)
			(type default)
		)
		(layer "In4.Cu")
	)
	(gr_line
		(start 129.602484 -402.852128)
		(end 129.424684 -402.778468)
		(stroke
			(width 0.07112)
			(type default)
		)
		(layer "In4.Cu")
	)
	(gr_line
		(start 129.644394 -385.405376)
		(end 129.644902 -385.404868)
		(stroke
			(width 0.07112)
			(type default)
		)
		(layer "In4.Cu")
	)
	(gr_line
		(start 129.69113 -386.003292)
		(end 129.785872 -385.649724)
		(stroke
			(width 0.07112)
			(type default)
		)
		(layer "In4.Cu")
	)
	(gr_line
		(start 129.761488 -380.024894)
		(end 130.029966 -379.376686)
		(stroke
			(width 0.07112)
			(type default)
		)
		(layer "In4.Cu")
	)
	(gr_line
		(start 129.858262 -378.695712)
		(end 130.021584 -378.30125)
		(stroke
			(width 0.07112)
			(type default)
		)
		(layer "In4.Cu")
	)
	(gr_line
		(start 129.884678 -325.234808)
		(end 129.884678 -325.2343)
		(stroke
			(width 0.07112)
			(type default)
		)
		(layer "In4.Cu")
	)
	(gr_line
		(start 129.907538 -385.579112)
		(end 129.96037 -385.548632)
		(stroke
			(width 0.07112)
			(type default)
		)
		(layer "In4.Cu")
	)
	(gr_line
		(start 129.931922 -378.873512)
		(end 129.858262 -378.695712)
		(stroke
			(width 0.07112)
			(type default)
		)
		(layer "In4.Cu")
	)
	(gr_line
		(start 129.94132 -331.945234)
		(end 129.94132 -331.945488)
		(stroke
			(width 0.07112)
			(type default)
		)
		(layer "In4.Cu")
	)
	(gr_line
		(start 129.96037 -385.548632)
		(end 130.048508 -385.460494)
		(stroke
			(width 0.07112)
			(type default)
		)
		(layer "In4.Cu")
	)
	(gr_line
		(start 129.963418 -402.248878)
		(end 129.315464 -402.517102)
		(stroke
			(width 0.07112)
			(type default)
		)
		(layer "In4.Cu")
	)
	(gr_line
		(start 129.996946 -402.688806)
		(end 129.602484 -402.852128)
		(stroke
			(width 0.07112)
			(type default)
		)
		(layer "In4.Cu")
	)
	(gr_line
		(start 130.021584 -378.30125)
		(end 130.199384 -378.227336)
		(stroke
			(width 0.07112)
			(type default)
		)
		(layer "In4.Cu")
	)
	(gr_line
		(start 130.04038 -382.597914)
		(end 130.040634 -382.598168)
		(stroke
			(width 0.07112)
			(type default)
		)
		(layer "In4.Cu")
	)
	(gr_line
		(start 130.048508 -385.460494)
		(end 130.048508 -385.334764)
		(stroke
			(width 0.07112)
			(type default)
		)
		(layer "In4.Cu")
	)
	(gr_line
		(start 130.07086 -402.511006)
		(end 129.996946 -402.688806)
		(stroke
			(width 0.07112)
			(type default)
		)
		(layer "In4.Cu")
	)
	(gr_line
		(start 130.105404 -380.92634)
		(end 130.268726 -380.531878)
		(stroke
			(width 0.07112)
			(type default)
		)
		(layer "In4.Cu")
	)
	(gr_line
		(start 130.15722 -325.159624)
		(end 130.15722 -325.159116)
		(stroke
			(width 0.07112)
			(type default)
		)
		(layer "In4.Cu")
	)
	(gr_line
		(start 130.179064 -381.10414)
		(end 130.105404 -380.92634)
		(stroke
			(width 0.07112)
			(type default)
		)
		(layer "In4.Cu")
	)
	(gr_line
		(start 130.193288 -378.982732)
		(end 130.461512 -378.334778)
		(stroke
			(width 0.07112)
			(type default)
		)
		(layer "In4.Cu")
	)
	(gr_line
		(start 130.268726 -380.531878)
		(end 130.446526 -380.458218)
		(stroke
			(width 0.07112)
			(type default)
		)
		(layer "In4.Cu")
	)
	(gr_line
		(start 130.44043 -381.21336)
		(end 130.708654 -380.565406)
		(stroke
			(width 0.07112)
			(type default)
		)
		(layer "In4.Cu")
	)
	(gr_line
		(start 130.49123 -385.31038)
		(end 130.844544 -385.405376)
		(stroke
			(width 0.07112)
			(type default)
		)
		(layer "In4.Cu")
	)
	(gr_line
		(start 130.501136 -404.17369)
		(end 130.210306 -404.46452)
		(stroke
			(width 0.07112)
			(type default)
		)
		(layer "In4.Cu")
	)
	(gr_line
		(start 130.53695 -379.884432)
		(end 130.700272 -379.48997)
		(stroke
			(width 0.07112)
			(type default)
		)
		(layer "In4.Cu")
	)
	(gr_line
		(start 130.61061 -380.062232)
		(end 130.53695 -379.884432)
		(stroke
			(width 0.07112)
			(type default)
		)
		(layer "In4.Cu")
	)
	(gr_line
		(start 130.644646 -402.420582)
		(end 130.466846 -402.346922)
		(stroke
			(width 0.07112)
			(type default)
		)
		(layer "In4.Cu")
	)
	(gr_line
		(start 130.700272 -379.48997)
		(end 130.878326 -379.41631)
		(stroke
			(width 0.07112)
			(type default)
		)
		(layer "In4.Cu")
	)
	(gr_line
		(start 130.769614 -324.936866)
		(end 130.76936 -324.936866)
		(stroke
			(width 0.07112)
			(type default)
		)
		(layer "In4.Cu")
	)
	(gr_line
		(start 130.783076 -404.17369)
		(end 131.073906 -404.46452)
		(stroke
			(width 0.07112)
			(type default)
		)
		(layer "In4.Cu")
	)
	(gr_line
		(start 130.821176 -369.379246)
		(end 130.820922 -369.376198)
		(stroke
			(width 0.07112)
			(type default)
		)
		(layer "In4.Cu")
	)
	(gr_line
		(start 130.844544 -385.405376)
		(end 130.845052 -385.404868)
		(stroke
			(width 0.07112)
			(type default)
		)
		(layer "In4.Cu")
	)
	(gr_line
		(start 130.871976 -380.171452)
		(end 131.140454 -379.523244)
		(stroke
			(width 0.07112)
			(type default)
		)
		(layer "In4.Cu")
	)
	(gr_line
		(start 130.89128 -386.003292)
		(end 130.986022 -385.649724)
		(stroke
			(width 0.07112)
			(type default)
		)
		(layer "In4.Cu")
	)
	(gr_line
		(start 130.96875 -378.84227)
		(end 131.132072 -378.447808)
		(stroke
			(width 0.07112)
			(type default)
		)
		(layer "In4.Cu")
	)
	(gr_line
		(start 131.00558 -401.817332)
		(end 130.357626 -402.085556)
		(stroke
			(width 0.07112)
			(type default)
		)
		(layer "In4.Cu")
	)
	(gr_line
		(start 131.039108 -402.25726)
		(end 130.644646 -402.420582)
		(stroke
			(width 0.07112)
			(type default)
		)
		(layer "In4.Cu")
	)
	(gr_line
		(start 131.04241 -379.02007)
		(end 130.96875 -378.84227)
		(stroke
			(width 0.07112)
			(type default)
		)
		(layer "In4.Cu")
	)
	(gr_line
		(start 131.107688 -385.579112)
		(end 131.16052 -385.548632)
		(stroke
			(width 0.07112)
			(type default)
		)
		(layer "In4.Cu")
	)
	(gr_line
		(start 131.113022 -402.079206)
		(end 131.039108 -402.25726)
		(stroke
			(width 0.07112)
			(type default)
		)
		(layer "In4.Cu")
	)
	(gr_line
		(start 131.132072 -378.447808)
		(end 131.309872 -378.374148)
		(stroke
			(width 0.07112)
			(type default)
		)
		(layer "In4.Cu")
	)
	(gr_line
		(start 131.16052 -385.548632)
		(end 131.248658 -385.460494)
		(stroke
			(width 0.07112)
			(type default)
		)
		(layer "In4.Cu")
	)
	(gr_line
		(start 131.248658 -385.460494)
		(end 131.248658 -385.334764)
		(stroke
			(width 0.07112)
			(type default)
		)
		(layer "In4.Cu")
	)
	(gr_line
		(start 131.303522 -379.12929)
		(end 131.572 -378.481082)
		(stroke
			(width 0.07112)
			(type default)
		)
		(layer "In4.Cu")
	)
	(gr_line
		(start 131.31165 -378.373386)
		(end 131.311396 -378.373132)
		(stroke
			(width 0.07112)
			(type default)
		)
		(layer "In4.Cu")
	)
	(gr_line
		(start 131.336796 -380.78918)
		(end 131.500118 -380.394718)
		(stroke
			(width 0.07112)
			(type default)
		)
		(layer "In4.Cu")
	)
	(gr_line
		(start 131.410456 -380.967234)
		(end 131.336796 -380.78918)
		(stroke
			(width 0.07112)
			(type default)
		)
		(layer "In4.Cu")
	)
	(gr_line
		(start 131.500118 -380.394718)
		(end 131.677918 -380.321058)
		(stroke
			(width 0.07112)
			(type default)
		)
		(layer "In4.Cu")
	)
	(gr_line
		(start 131.57835 -403.344126)
		(end 131.40055 -403.270466)
		(stroke
			(width 0.07112)
			(type default)
		)
		(layer "In4.Cu")
	)
	(gr_line
		(start 131.59359 -305.103784)
		(end 131.593844 -305.103784)
		(stroke
			(width 0.07112)
			(type default)
		)
		(layer "In4.Cu")
	)
	(gr_line
		(start 131.661154 -354.175822)
		(end 131.661154 -354.176076)
		(stroke
			(width 0.07112)
			(type default)
		)
		(layer "In4.Cu")
	)
	(gr_line
		(start 131.671568 -381.076454)
		(end 131.940046 -380.428246)
		(stroke
			(width 0.07112)
			(type default)
		)
		(layer "In4.Cu")
	)
	(gr_line
		(start 131.69138 -385.31038)
		(end 132.04444 -385.405376)
		(stroke
			(width 0.07112)
			(type default)
		)
		(layer "In4.Cu")
	)
	(gr_line
		(start 131.768342 -379.747272)
		(end 131.931664 -379.35281)
		(stroke
			(width 0.07112)
			(type default)
		)
		(layer "In4.Cu")
	)
	(gr_line
		(start 131.842002 -379.925072)
		(end 131.768342 -379.747272)
		(stroke
			(width 0.07112)
			(type default)
		)
		(layer "In4.Cu")
	)
	(gr_line
		(start 131.868164 -370.453158)
		(end 131.86791 -370.453158)
		(stroke
			(width 0.07112)
			(type default)
		)
		(layer "In4.Cu")
	)
	(gr_line
		(start 131.916932 -324.538086)
		(end 131.916678 -324.53707)
		(stroke
			(width 0.07112)
			(type default)
		)
		(layer "In4.Cu")
	)
	(gr_line
		(start 131.931664 -379.35281)
		(end 132.109464 -379.27915)
		(stroke
			(width 0.07112)
			(type default)
		)
		(layer "In4.Cu")
	)
	(gr_line
		(start 131.932172 -324.582028)
		(end 131.932172 -324.581774)
		(stroke
			(width 0.07112)
			(type default)
		)
		(layer "In4.Cu")
	)
	(gr_line
		(start 131.939284 -402.740876)
		(end 131.29133 -403.009354)
		(stroke
			(width 0.07112)
			(type default)
		)
		(layer "In4.Cu")
	)
	(gr_line
		(start 131.9403 -324.605396)
		(end 131.939792 -324.603618)
		(stroke
			(width 0.07112)
			(type default)
		)
		(layer "In4.Cu")
	)
	(gr_line
		(start 131.972812 -403.180804)
		(end 131.57835 -403.344126)
		(stroke
			(width 0.07112)
			(type default)
		)
		(layer "In4.Cu")
	)
	(gr_line
		(start 131.97586 -370.192554)
		(end 131.975606 -370.192554)
		(stroke
			(width 0.07112)
			(type default)
		)
		(layer "In4.Cu")
	)
	(gr_line
		(start 132.04444 -385.405376)
		(end 132.044948 -385.404868)
		(stroke
			(width 0.07112)
			(type default)
		)
		(layer "In4.Cu")
	)
	(gr_line
		(start 132.046726 -403.003004)
		(end 131.972812 -403.180804)
		(stroke
			(width 0.07112)
			(type default)
		)
		(layer "In4.Cu")
	)
	(gr_line
		(start 132.091176 -386.003292)
		(end 132.185918 -385.649724)
		(stroke
			(width 0.07112)
			(type default)
		)
		(layer "In4.Cu")
	)
	(gr_line
		(start 132.103368 -380.034292)
		(end 132.371846 -379.386084)
		(stroke
			(width 0.07112)
			(type default)
		)
		(layer "In4.Cu")
	)
	(gr_line
		(start 132.111242 -379.278388)
		(end 132.11556 -379.26772)
		(stroke
			(width 0.07112)
			(type default)
		)
		(layer "In4.Cu")
	)
	(gr_line
		(start 132.158486 -382.057656)
		(end 132.158486 -382.001014)
		(stroke
			(width 0.07112)
			(type default)
		)
		(layer "In4.Cu")
	)
	(gr_line
		(start 132.158486 -382.001014)
		(end 132.15874 -382.00076)
		(stroke
			(width 0.07112)
			(type default)
		)
		(layer "In4.Cu")
	)
	(gr_line
		(start 132.15874 -382.00076)
		(end 132.179822 -381.949706)
		(stroke
			(width 0.07112)
			(type default)
		)
		(layer "In4.Cu")
	)
	(gr_line
		(start 132.200142 -378.70511)
		(end 132.363464 -378.310648)
		(stroke
			(width 0.07112)
			(type default)
		)
		(layer "In4.Cu")
	)
	(gr_line
		(start 132.273802 -378.882656)
		(end 132.200142 -378.70511)
		(stroke
			(width 0.07112)
			(type default)
		)
		(layer "In4.Cu")
	)
	(gr_line
		(start 132.307584 -385.579112)
		(end 132.360416 -385.548632)
		(stroke
			(width 0.07112)
			(type default)
		)
		(layer "In4.Cu")
	)
	(gr_line
		(start 132.360416 -385.548632)
		(end 132.448554 -385.460494)
		(stroke
			(width 0.07112)
			(type default)
		)
		(layer "In4.Cu")
	)
	(gr_line
		(start 132.363464 -378.310648)
		(end 132.541264 -378.236988)
		(stroke
			(width 0.07112)
			(type default)
		)
		(layer "In4.Cu")
	)
	(gr_line
		(start 132.430774 -380.985268)
		(end 132.594096 -380.590806)
		(stroke
			(width 0.07112)
			(type default)
		)
		(layer "In4.Cu")
	)
	(gr_line
		(start 132.448554 -385.460494)
		(end 132.448554 -385.334764)
		(stroke
			(width 0.07112)
			(type default)
		)
		(layer "In4.Cu")
	)
	(gr_line
		(start 132.504434 -381.163322)
		(end 132.430774 -380.985268)
		(stroke
			(width 0.07112)
			(type default)
		)
		(layer "In4.Cu")
	)
	(gr_line
		(start 132.534914 -378.99213)
		(end 132.803392 -378.344176)
		(stroke
			(width 0.07112)
			(type default)
		)
		(layer "In4.Cu")
	)
	(gr_line
		(start 132.543042 -378.236226)
		(end 132.542534 -378.236226)
		(stroke
			(width 0.07112)
			(type default)
		)
		(layer "In4.Cu")
	)
	(gr_line
		(start 132.594096 -380.590806)
		(end 132.771896 -380.5174)
		(stroke
			(width 0.07112)
			(type default)
		)
		(layer "In4.Cu")
	)
	(gr_line
		(start 132.620512 -402.912326)
		(end 132.442966 -402.83892)
		(stroke
			(width 0.07112)
			(type default)
		)
		(layer "In4.Cu")
	)
	(gr_line
		(start 132.765546 -381.272542)
		(end 133.034024 -380.624334)
		(stroke
			(width 0.07112)
			(type default)
		)
		(layer "In4.Cu")
	)
	(gr_line
		(start 132.773674 -380.516638)
		(end 132.839714 -380.35738)
		(stroke
			(width 0.07112)
			(type default)
		)
		(layer "In4.Cu")
	)
	(gr_line
		(start 132.86232 -379.943106)
		(end 133.025642 -379.548644)
		(stroke
			(width 0.07112)
			(type default)
		)
		(layer "In4.Cu")
	)
	(gr_line
		(start 132.891276 -385.31038)
		(end 133.24459 -385.405376)
		(stroke
			(width 0.07112)
			(type default)
		)
		(layer "In4.Cu")
	)
	(gr_line
		(start 132.936234 -380.120906)
		(end 132.86232 -379.943106)
		(stroke
			(width 0.07112)
			(type default)
		)
		(layer "In4.Cu")
	)
	(gr_line
		(start 132.9817 -402.309076)
		(end 132.333492 -402.577554)
		(stroke
			(width 0.07112)
			(type default)
		)
		(layer "In4.Cu")
	)
	(gr_line
		(start 133.014974 -402.749004)
		(end 132.620512 -402.912326)
		(stroke
			(width 0.07112)
			(type default)
		)
		(layer "In4.Cu")
	)
	(gr_line
		(start 133.025642 -379.548644)
		(end 133.203696 -379.475238)
		(stroke
			(width 0.07112)
			(type default)
		)
		(layer "In4.Cu")
	)
	(gr_line
		(start 133.034024 -380.624334)
		(end 133.100064 -380.465076)
		(stroke
			(width 0.07112)
			(type default)
		)
		(layer "In4.Cu")
	)
	(gr_line
		(start 133.088634 -402.571204)
		(end 133.014974 -402.749004)
		(stroke
			(width 0.07112)
			(type default)
		)
		(layer "In4.Cu")
	)
	(gr_arc
		(start 133.100318 -349.603314)
		(mid 133.100318 -349.603568)
		(end 133.100318 -349.603822)
		(stroke
			(width 0.07112)
			(type default)
		)
		(layer "In4.Cu")
	)
	(gr_line
		(start 133.197346 -380.230126)
		(end 133.465824 -379.582172)
		(stroke
			(width 0.07112)
			(type default)
		)
		(layer "In4.Cu")
	)
	(gr_line
		(start 133.24459 -385.405376)
		(end 133.245098 -385.404868)
		(stroke
			(width 0.07112)
			(type default)
		)
		(layer "In4.Cu")
	)
	(gr_line
		(start 133.291326 -386.003292)
		(end 133.386322 -385.649216)
		(stroke
			(width 0.07112)
			(type default)
		)
		(layer "In4.Cu")
	)
	(gr_line
		(start 133.29412 -378.901198)
		(end 133.457442 -378.506736)
		(stroke
			(width 0.07112)
			(type default)
		)
		(layer "In4.Cu")
	)
	(gr_line
		(start 133.36778 -379.078998)
		(end 133.29412 -378.901198)
		(stroke
			(width 0.07112)
			(type default)
		)
		(layer "In4.Cu")
	)
	(gr_line
		(start 133.439408 -334.202786)
		(end 133.439154 -334.202786)
		(stroke
			(width 0.07112)
			(type default)
		)
		(layer "In4.Cu")
	)
	(gr_line
		(start 133.457442 -378.506736)
		(end 133.635242 -378.432822)
		(stroke
			(width 0.07112)
			(type default)
		)
		(layer "In4.Cu")
	)
	(gr_line
		(start 133.564376 -404.17369)
		(end 133.273546 -404.46452)
		(stroke
			(width 0.07112)
			(type default)
		)
		(layer "In4.Cu")
	)
	(gr_line
		(start 133.629146 -379.188218)
		(end 133.89737 -378.540264)
		(stroke
			(width 0.07112)
			(type default)
		)
		(layer "In4.Cu")
	)
	(gr_line
		(start 133.662674 -402.48078)
		(end 133.484874 -402.40712)
		(stroke
			(width 0.07112)
			(type default)
		)
		(layer "In4.Cu")
	)
	(gr_line
		(start 133.721348 -334.17764)
		(end 133.721348 -334.177386)
		(stroke
			(width 0.07112)
			(type default)
		)
		(layer "In4.Cu")
	)
	(gr_line
		(start 133.846316 -404.17369)
		(end 134.137146 -404.46452)
		(stroke
			(width 0.07112)
			(type default)
		)
		(layer "In4.Cu")
	)
	(gr_line
		(start 134.023608 -401.87753)
		(end 133.375654 -402.146008)
		(stroke
			(width 0.07112)
			(type default)
		)
		(layer "In4.Cu")
	)
	(gr_line
		(start 134.057136 -402.317458)
		(end 133.662674 -402.48078)
		(stroke
			(width 0.07112)
			(type default)
		)
		(layer "In4.Cu")
	)
	(gr_line
		(start 134.13105 -402.139658)
		(end 134.057136 -402.317458)
		(stroke
			(width 0.07112)
			(type default)
		)
		(layer "In4.Cu")
	)
	(gr_line
		(start 134.513066 -368.313208)
		(end 134.51332 -368.313462)
		(stroke
			(width 0.07112)
			(type default)
		)
		(layer "In4.Cu")
	)
	(gr_line
		(start 134.67207 -373.095012)
		(end 134.672324 -373.094758)
		(stroke
			(width 0.07112)
			(type default)
		)
		(layer "In4.Cu")
	)
	(gr_line
		(start 134.705598 -403.210268)
		(end 134.528052 -403.136608)
		(stroke
			(width 0.07112)
			(type default)
		)
		(layer "In4.Cu")
	)
	(gr_line
		(start 135.066532 -402.607018)
		(end 134.418578 -402.875496)
		(stroke
			(width 0.07112)
			(type default)
		)
		(layer "In4.Cu")
	)
	(gr_line
		(start 135.100314 -403.0472)
		(end 134.705598 -403.210268)
		(stroke
			(width 0.07112)
			(type default)
		)
		(layer "In4.Cu")
	)
	(gr_line
		(start 135.173974 -402.869146)
		(end 135.100314 -403.0472)
		(stroke
			(width 0.07112)
			(type default)
		)
		(layer "In4.Cu")
	)
	(gr_line
		(start 135.379714 -381.328168)
		(end 135.462772 -380.909322)
		(stroke
			(width 0.07112)
			(type default)
		)
		(layer "In4.Cu")
	)
	(gr_line
		(start 135.462772 -380.909322)
		(end 135.622792 -380.802642)
		(stroke
			(width 0.07112)
			(type default)
		)
		(layer "In4.Cu")
	)
	(gr_line
		(start 135.486394 -381.488188)
		(end 135.379714 -381.328168)
		(stroke
			(width 0.07112)
			(type default)
		)
		(layer "In4.Cu")
	)
	(gr_line
		(start 135.599678 -380.221998)
		(end 135.68299 -379.803152)
		(stroke
			(width 0.07112)
			(type default)
		)
		(layer "In4.Cu")
	)
	(gr_line
		(start 135.68299 -379.803152)
		(end 135.84301 -379.696472)
		(stroke
			(width 0.07112)
			(type default)
		)
		(layer "In4.Cu")
	)
	(gr_line
		(start 135.706612 -380.382018)
		(end 135.599678 -380.221998)
		(stroke
			(width 0.07112)
			(type default)
		)
		(layer "In4.Cu")
	)
	(gr_line
		(start 135.74776 -402.778722)
		(end 135.569706 -402.705062)
		(stroke
			(width 0.07112)
			(type default)
		)
		(layer "In4.Cu")
	)
	(gr_line
		(start 135.764016 -381.544576)
		(end 135.900922 -380.85649)
		(stroke
			(width 0.07112)
			(type default)
		)
		(layer "In4.Cu")
	)
	(gr_line
		(start 135.819896 -379.115828)
		(end 135.903208 -378.696982)
		(stroke
			(width 0.07112)
			(type default)
		)
		(layer "In4.Cu")
	)
	(gr_line
		(start 135.844534 -379.695456)
		(end 135.87984 -379.517656)
		(stroke
			(width 0.07112)
			(type default)
		)
		(layer "In4.Cu")
	)
	(gr_line
		(start 135.903208 -378.696982)
		(end 136.062974 -378.590556)
		(stroke
			(width 0.07112)
			(type default)
		)
		(layer "In4.Cu")
	)
	(gr_line
		(start 135.926576 -379.275848)
		(end 135.819896 -379.115828)
		(stroke
			(width 0.07112)
			(type default)
		)
		(layer "In4.Cu")
	)
	(gr_line
		(start 135.984234 -380.438152)
		(end 136.120886 -379.75032)
		(stroke
			(width 0.07112)
			(type default)
		)
		(layer "In4.Cu")
	)
	(gr_line
		(start 136.064752 -378.589286)
		(end 136.411462 -376.845322)
		(stroke
			(width 0.07112)
			(type default)
		)
		(layer "In4.Cu")
	)
	(gr_line
		(start 136.071356 -323.08927)
		(end 136.071356 -323.089524)
		(stroke
			(width 0.07112)
			(type default)
		)
		(layer "In4.Cu")
	)
	(gr_line
		(start 136.108948 -402.175218)
		(end 135.46074 -402.443696)
		(stroke
			(width 0.07112)
			(type default)
		)
		(layer "In4.Cu")
	)
	(gr_line
		(start 136.120886 -379.75032)
		(end 136.156446 -379.57252)
		(stroke
			(width 0.07112)
			(type default)
		)
		(layer "In4.Cu")
	)
	(gr_line
		(start 136.142222 -402.6154)
		(end 135.74776 -402.778722)
		(stroke
			(width 0.07112)
			(type default)
		)
		(layer "In4.Cu")
	)
	(gr_line
		(start 136.204198 -379.331982)
		(end 136.341104 -378.64415)
		(stroke
			(width 0.07112)
			(type default)
		)
		(layer "In4.Cu")
	)
	(gr_line
		(start 136.216136 -402.437092)
		(end 136.142222 -402.6154)
		(stroke
			(width 0.07112)
			(type default)
		)
		(layer "In4.Cu")
	)
	(gr_line
		(start 136.216898 -402.435822)
		(end 136.216644 -402.436076)
		(stroke
			(width 0.07112)
			(type default)
		)
		(layer "In4.Cu")
	)
	(gr_line
		(start 136.341104 -378.64415)
		(end 136.688068 -376.90044)
		(stroke
			(width 0.07112)
			(type default)
		)
		(layer "In4.Cu")
	)
	(gr_line
		(start 136.440672 -397.151098)
		(end 136.440672 -397.151352)
		(stroke
			(width 0.07112)
			(type default)
		)
		(layer "In4.Cu")
	)
	(gr_line
		(start 136.627616 -404.17369)
		(end 136.336786 -404.46452)
		(stroke
			(width 0.07112)
			(type default)
		)
		(layer "In4.Cu")
	)
	(gr_line
		(start 136.722612 -397.360394)
		(end 136.722612 -397.360648)
		(stroke
			(width 0.07112)
			(type default)
		)
		(layer "In4.Cu")
	)
	(gr_line
		(start 136.909556 -404.17369)
		(end 137.200386 -404.46452)
		(stroke
			(width 0.07112)
			(type default)
		)
		(layer "In4.Cu")
	)
	(gr_line
		(start 137.12063 -333.592932)
		(end 137.120376 -333.591916)
		(stroke
			(width 0.07112)
			(type default)
		)
		(layer "In4.Cu")
	)
	(gr_line
		(start 137.233152 -402.222462)
		(end 137.063226 -402.131784)
		(stroke
			(width 0.07112)
			(type default)
		)
		(layer "In4.Cu")
	)
	(gr_line
		(start 137.397998 -333.542386)
		(end 137.397998 -333.542132)
		(stroke
			(width 0.07112)
			(type default)
		)
		(layer "In4.Cu")
	)
	(gr_line
		(start 137.397998 -333.542132)
		(end 137.398252 -333.542132)
		(stroke
			(width 0.07112)
			(type default)
		)
		(layer "In4.Cu")
	)
	(gr_line
		(start 137.398252 -333.54264)
		(end 137.397998 -333.542386)
		(stroke
			(width 0.07112)
			(type default)
		)
		(layer "In4.Cu")
	)
	(gr_line
		(start 137.641584 -402.09851)
		(end 137.233152 -402.222462)
		(stroke
			(width 0.07112)
			(type default)
		)
		(layer "In4.Cu")
	)
	(gr_line
		(start 137.651236 -401.657312)
		(end 136.980168 -401.86102)
		(stroke
			(width 0.07112)
			(type default)
		)
		(layer "In4.Cu")
	)
	(gr_line
		(start 137.702798 -403.289008)
		(end 137.524998 -403.215348)
		(stroke
			(width 0.07112)
			(type default)
		)
		(layer "In4.Cu")
	)
	(gr_line
		(start 137.722356 -335.347818)
		(end 137.722356 -335.347564)
		(stroke
			(width 0.07112)
			(type default)
		)
		(layer "In4.Cu")
	)
	(gr_line
		(start 137.732262 -401.928584)
		(end 137.641584 -402.09851)
		(stroke
			(width 0.07112)
			(type default)
		)
		(layer "In4.Cu")
	)
	(gr_line
		(start 137.915142 -368.921792)
		(end 137.915142 -368.917982)
		(stroke
			(width 0.07112)
			(type default)
		)
		(layer "In4.Cu")
	)
	(gr_line
		(start 138.063986 -402.685758)
		(end 137.415778 -402.954236)
		(stroke
			(width 0.07112)
			(type default)
		)
		(layer "In4.Cu")
	)
	(gr_line
		(start 138.09726 -403.125686)
		(end 137.702798 -403.289008)
		(stroke
			(width 0.07112)
			(type default)
		)
		(layer "In4.Cu")
	)
	(gr_line
		(start 138.171174 -402.947886)
		(end 138.09726 -403.125686)
		(stroke
			(width 0.07112)
			(type default)
		)
		(layer "In4.Cu")
	)
	(gr_line
		(start 138.218926 -364.086394)
		(end 138.218672 -364.086394)
		(stroke
			(width 0.07112)
			(type default)
		)
		(layer "In4.Cu")
	)
	(gr_line
		(start 138.74496 -402.857462)
		(end 138.56716 -402.783802)
		(stroke
			(width 0.07112)
			(type default)
		)
		(layer "In4.Cu")
	)
	(gr_line
		(start 139.105894 -402.254212)
		(end 138.45794 -402.522436)
		(stroke
			(width 0.07112)
			(type default)
		)
		(layer "In4.Cu")
	)
	(gr_line
		(start 139.139422 -402.69414)
		(end 138.74496 -402.857462)
		(stroke
			(width 0.07112)
			(type default)
		)
		(layer "In4.Cu")
	)
	(gr_line
		(start 139.213336 -402.51634)
		(end 139.139422 -402.69414)
		(stroke
			(width 0.07112)
			(type default)
		)
		(layer "In4.Cu")
	)
	(gr_line
		(start 139.690856 -404.17369)
		(end 139.400026 -404.46452)
		(stroke
			(width 0.07112)
			(type default)
		)
		(layer "In4.Cu")
	)
	(gr_line
		(start 139.972796 -404.17369)
		(end 140.263626 -404.46452)
		(stroke
			(width 0.07112)
			(type default)
		)
		(layer "In4.Cu")
	)
	(gr_line
		(start 140.349478 -402.25218)
		(end 140.179552 -402.161248)
		(stroke
			(width 0.07112)
			(type default)
		)
		(layer "In4.Cu")
	)
	(gr_line
		(start 140.621512 -403.384766)
		(end 140.467588 -403.316694)
		(stroke
			(width 0.07112)
			(type default)
		)
		(layer "In4.Cu")
	)
	(gr_line
		(start 140.75791 -402.128228)
		(end 140.349478 -402.25218)
		(stroke
			(width 0.07112)
			(type default)
		)
		(layer "In4.Cu")
	)
	(gr_line
		(start 140.767562 -401.68703)
		(end 140.096494 -401.890738)
		(stroke
			(width 0.07112)
			(type default)
		)
		(layer "In4.Cu")
	)
	(gr_line
		(start 140.848588 -401.958302)
		(end 140.75791 -402.128228)
		(stroke
			(width 0.07112)
			(type default)
		)
		(layer "In4.Cu")
	)
	(gr_line
		(start 140.951966 -359.513124)
		(end 140.951458 -359.513632)
		(stroke
			(width 0.07112)
			(type default)
		)
		(layer "In4.Cu")
	)
	(gr_line
		(start 140.984986 -402.811234)
		(end 140.363956 -403.053042)
		(stroke
			(width 0.07112)
			(type default)
		)
		(layer "In4.Cu")
	)
	(gr_line
		(start 141.01953 -403.229826)
		(end 140.621512 -403.384766)
		(stroke
			(width 0.07112)
			(type default)
		)
		(layer "In4.Cu")
	)
	(gr_line
		(start 141.086586 -403.075648)
		(end 141.01953 -403.229826)
		(stroke
			(width 0.07112)
			(type default)
		)
		(layer "In4.Cu")
	)
	(gr_line
		(start 141.661134 -402.998178)
		(end 141.485112 -402.920708)
		(stroke
			(width 0.07112)
			(type default)
		)
		(layer "In4.Cu")
	)
	(gr_line
		(start 142.034768 -402.402802)
		(end 141.381226 -402.657056)
		(stroke
			(width 0.07112)
			(type default)
		)
		(layer "In4.Cu")
	)
	(gr_line
		(start 142.058898 -402.843492)
		(end 141.661134 -402.998178)
		(stroke
			(width 0.07112)
			(type default)
		)
		(layer "In4.Cu")
	)
	(gr_line
		(start 142.136368 -402.667216)
		(end 142.058898 -402.843492)
		(stroke
			(width 0.07112)
			(type default)
		)
		(layer "In4.Cu")
	)
	(gr_line
		(start 142.17396 -365.249206)
		(end 142.17396 -365.248952)
		(stroke
			(width 0.07112)
			(type default)
		)
		(layer "In4.Cu")
	)
	(gr_line
		(start 142.18666 -359.510584)
		(end 142.185898 -359.511854)
		(stroke
			(width 0.07112)
			(type default)
		)
		(layer "In4.Cu")
	)
	(gr_line
		(start 142.444724 -359.62463)
		(end 142.44447 -359.625138)
		(stroke
			(width 0.07112)
			(type default)
		)
		(layer "In4.Cu")
	)
	(gr_line
		(start 142.712186 -402.589238)
		(end 142.536164 -402.511768)
		(stroke
			(width 0.07112)
			(type default)
		)
		(layer "In4.Cu")
	)
	(gr_line
		(start 142.754096 -404.17369)
		(end 142.463266 -404.46452)
		(stroke
			(width 0.07112)
			(type default)
		)
		(layer "In4.Cu")
	)
	(gr_line
		(start 143.036036 -404.17369)
		(end 143.326866 -404.46452)
		(stroke
			(width 0.07112)
			(type default)
		)
		(layer "In4.Cu")
	)
	(gr_line
		(start 143.08582 -401.993862)
		(end 142.432278 -402.248116)
		(stroke
			(width 0.07112)
			(type default)
		)
		(layer "In4.Cu")
	)
	(gr_line
		(start 143.10995 -402.434552)
		(end 142.712186 -402.589238)
		(stroke
			(width 0.07112)
			(type default)
		)
		(layer "In4.Cu")
	)
	(gr_line
		(start 143.187674 -402.258276)
		(end 143.10995 -402.434552)
		(stroke
			(width 0.07112)
			(type default)
		)
		(layer "In4.Cu")
	)
	(gr_line
		(start 143.900398 -403.348952)
		(end 143.726408 -403.266402)
		(stroke
			(width 0.07112)
			(type default)
		)
		(layer "In4.Cu")
	)
	(gr_line
		(start 144.290288 -402.76399)
		(end 143.630142 -403.00021)
		(stroke
			(width 0.07112)
			(type default)
		)
		(layer "In4.Cu")
	)
	(gr_line
		(start 144.30248 -403.205188)
		(end 143.900398 -403.348952)
		(stroke
			(width 0.07112)
			(type default)
		)
		(layer "In4.Cu")
	)
	(gr_line
		(start 144.384522 -403.030944)
		(end 144.30248 -403.205188)
		(stroke
			(width 0.07112)
			(type default)
		)
		(layer "In4.Cu")
	)
	(gr_line
		(start 144.962372 -402.968968)
		(end 144.788128 -402.886672)
		(stroke
			(width 0.07112)
			(type default)
		)
		(layer "In4.Cu")
	)
	(gr_line
		(start 145.352262 -402.384006)
		(end 144.691862 -402.620226)
		(stroke
			(width 0.07112)
			(type default)
		)
		(layer "In4.Cu")
	)
	(gr_line
		(start 145.3642 -402.825204)
		(end 144.962372 -402.968968)
		(stroke
			(width 0.07112)
			(type default)
		)
		(layer "In4.Cu")
	)
	(gr_line
		(start 145.446496 -402.651214)
		(end 145.3642 -402.825204)
		(stroke
			(width 0.07112)
			(type default)
		)
		(layer "In4.Cu")
	)
	(gr_line
		(start 145.817336 -404.17369)
		(end 145.526506 -404.46452)
		(stroke
			(width 0.07112)
			(type default)
		)
		(layer "In4.Cu")
	)
	(gr_line
		(start 146.099276 -404.17369)
		(end 146.390106 -404.46452)
		(stroke
			(width 0.07112)
			(type default)
		)
		(layer "In4.Cu")
	)
	(gr_line
		(start 146.52117 -335.532476)
		(end 146.520916 -335.531206)
		(stroke
			(width 0.07112)
			(type default)
		)
		(layer "In4.Cu")
	)
	(gr_line
		(start 147.001992 -403.318726)
		(end 146.832066 -403.228048)
		(stroke
			(width 0.07112)
			(type default)
		)
		(layer "In4.Cu")
	)
	(gr_line
		(start 147.410424 -403.194774)
		(end 147.001992 -403.318726)
		(stroke
			(width 0.07112)
			(type default)
		)
		(layer "In4.Cu")
	)
	(gr_line
		(start 147.41906 -388.774432)
		(end 147.464526 -388.819898)
		(stroke
			(width 0.07112)
			(type default)
		)
		(layer "In4.Cu")
	)
	(gr_line
		(start 147.420076 -402.75383)
		(end 146.749008 -402.957284)
		(stroke
			(width 0.07112)
			(type default)
		)
		(layer "In4.Cu")
	)
	(gr_line
		(start 147.464526 -388.999984)
		(end 147.319238 -389.145272)
		(stroke
			(width 0.07112)
			(type default)
		)
		(layer "In4.Cu")
	)
	(gr_line
		(start 147.464526 -388.819898)
		(end 147.464526 -388.999984)
		(stroke
			(width 0.07112)
			(type default)
		)
		(layer "In4.Cu")
	)
	(gr_line
		(start 147.501102 -403.025102)
		(end 147.410424 -403.194774)
		(stroke
			(width 0.07112)
			(type default)
		)
		(layer "In4.Cu")
	)
	(gr_line
		(start 147.696428 -389.344662)
		(end 147.520406 -389.344662)
		(stroke
			(width 0.07112)
			(type default)
		)
		(layer "In4.Cu")
	)
	(gr_line
		(start 147.81911 -389.467344)
		(end 147.696428 -389.344662)
		(stroke
			(width 0.07112)
			(type default)
		)
		(layer "In4.Cu")
	)
	(gr_line
		(start 148.081238 -402.99132)
		(end 147.911566 -402.900642)
		(stroke
			(width 0.07112)
			(type default)
		)
		(layer "In4.Cu")
	)
	(gr_line
		(start 148.48967 -402.867622)
		(end 148.081238 -402.99132)
		(stroke
			(width 0.07112)
			(type default)
		)
		(layer "In4.Cu")
	)
	(gr_line
		(start 148.499322 -402.426424)
		(end 147.828254 -402.629878)
		(stroke
			(width 0.07112)
			(type default)
		)
		(layer "In4.Cu")
	)
	(gr_line
		(start 148.580348 -402.697696)
		(end 148.48967 -402.867622)
		(stroke
			(width 0.07112)
			(type default)
		)
		(layer "In4.Cu")
	)
	(gr_line
		(start 148.618956 -388.774432)
		(end 148.67128 -388.826756)
		(stroke
			(width 0.07112)
			(type default)
		)
		(layer "In4.Cu")
	)
	(gr_line
		(start 148.655278 -402.37918)
		(end 148.499322 -402.426424)
		(stroke
			(width 0.07112)
			(type default)
		)
		(layer "In4.Cu")
	)
	(gr_line
		(start 148.67128 -389.006588)
		(end 148.524722 -389.153146)
		(stroke
			(width 0.07112)
			(type default)
		)
		(layer "In4.Cu")
	)
	(gr_line
		(start 148.67128 -388.826756)
		(end 148.67128 -389.006588)
		(stroke
			(width 0.07112)
			(type default)
		)
		(layer "In4.Cu")
	)
	(gr_line
		(start 148.880576 -404.17369)
		(end 148.589746 -404.46452)
		(stroke
			(width 0.07112)
			(type default)
		)
		(layer "In4.Cu")
	)
	(gr_line
		(start 148.904198 -389.352536)
		(end 148.72589 -389.352536)
		(stroke
			(width 0.07112)
			(type default)
		)
		(layer "In4.Cu")
	)
	(gr_line
		(start 149.019006 -389.467344)
		(end 148.904198 -389.352536)
		(stroke
			(width 0.07112)
			(type default)
		)
		(layer "In4.Cu")
	)
	(gr_line
		(start 149.162516 -404.17369)
		(end 149.453346 -404.46452)
		(stroke
			(width 0.07112)
			(type default)
		)
		(layer "In4.Cu")
	)
	(gr_line
		(start 149.819106 -388.774432)
		(end 149.870414 -388.82574)
		(stroke
			(width 0.07112)
			(type default)
		)
		(layer "In4.Cu")
	)
	(gr_line
		(start 149.870414 -389.035544)
		(end 149.753828 -389.15213)
		(stroke
			(width 0.07112)
			(type default)
		)
		(layer "In4.Cu")
	)
	(gr_line
		(start 149.870414 -388.82574)
		(end 149.870414 -389.035544)
		(stroke
			(width 0.07112)
			(type default)
		)
		(layer "In4.Cu")
	)
	(gr_line
		(start 149.98192 -403.35708)
		(end 149.804374 -403.28342)
		(stroke
			(width 0.07112)
			(type default)
		)
		(layer "In4.Cu")
	)
	(gr_line
		(start 150.103078 -389.35152)
		(end 149.954996 -389.35152)
		(stroke
			(width 0.07112)
			(type default)
		)
		(layer "In4.Cu")
	)
	(gr_line
		(start 150.218902 -389.467344)
		(end 150.103078 -389.35152)
		(stroke
			(width 0.07112)
			(type default)
		)
		(layer "In4.Cu")
	)
	(gr_line
		(start 150.343108 -402.75383)
		(end 149.6949 -403.022054)
		(stroke
			(width 0.07112)
			(type default)
		)
		(layer "In4.Cu")
	)
	(gr_line
		(start 150.376382 -403.193758)
		(end 149.98192 -403.35708)
		(stroke
			(width 0.07112)
			(type default)
		)
		(layer "In4.Cu")
	)
	(gr_line
		(start 150.450042 -403.015958)
		(end 150.376382 -403.193758)
		(stroke
			(width 0.07112)
			(type default)
		)
		(layer "In4.Cu")
	)
	(gr_line
		(start 150.55723 -364.68939)
		(end 150.364952 -364.68939)
		(stroke
			(width 0.07112)
			(type default)
		)
		(layer "In4.Cu")
	)
	(gr_line
		(start 150.619968 -402.944076)
		(end 150.450804 -403.01418)
		(stroke
			(width 0.07112)
			(type default)
		)
		(layer "In4.Cu")
	)
	(gr_line
		(start 150.659846 -363.993938)
		(end 150.163784 -364.49)
		(stroke
			(width 0.07112)
			(type default)
		)
		(layer "In4.Cu")
	)
	(gr_line
		(start 150.859236 -364.387384)
		(end 150.55723 -364.68939)
		(stroke
			(width 0.07112)
			(type default)
		)
		(layer "In4.Cu")
	)
	(gr_line
		(start 150.859236 -364.195106)
		(end 150.859236 -364.387384)
		(stroke
			(width 0.07112)
			(type default)
		)
		(layer "In4.Cu")
	)
	(gr_line
		(start 151.019002 -388.774432)
		(end 151.071326 -388.826756)
		(stroke
			(width 0.07112)
			(type default)
		)
		(layer "In4.Cu")
	)
	(gr_line
		(start 151.024082 -402.92528)
		(end 150.846536 -402.85162)
		(stroke
			(width 0.07112)
			(type default)
		)
		(layer "In4.Cu")
	)
	(gr_line
		(start 151.071326 -389.006588)
		(end 150.924768 -389.153146)
		(stroke
			(width 0.07112)
			(type default)
		)
		(layer "In4.Cu")
	)
	(gr_line
		(start 151.071326 -388.826756)
		(end 151.071326 -389.006588)
		(stroke
			(width 0.07112)
			(type default)
		)
		(layer "In4.Cu")
	)
	(gr_line
		(start 151.304244 -389.352536)
		(end 151.125936 -389.352536)
		(stroke
			(width 0.07112)
			(type default)
		)
		(layer "In4.Cu")
	)
	(gr_line
		(start 151.35479 -363.89183)
		(end 151.162512 -363.89183)
		(stroke
			(width 0.07112)
			(type default)
		)
		(layer "In4.Cu")
	)
	(gr_line
		(start 151.385016 -402.32203)
		(end 150.737316 -402.590508)
		(stroke
			(width 0.07112)
			(type default)
		)
		(layer "In4.Cu")
	)
	(gr_line
		(start 151.414988 -402.309838)
		(end 151.385016 -402.32203)
		(stroke
			(width 0.07112)
			(type default)
		)
		(layer "In4.Cu")
	)
	(gr_line
		(start 151.418544 -402.761958)
		(end 151.024082 -402.92528)
		(stroke
			(width 0.07112)
			(type default)
		)
		(layer "In4.Cu")
	)
	(gr_line
		(start 151.419052 -389.467344)
		(end 151.304244 -389.352536)
		(stroke
			(width 0.07112)
			(type default)
		)
		(layer "In4.Cu")
	)
	(gr_line
		(start 151.454104 -379.941836)
		(end 151.318214 -380.077726)
		(stroke
			(width 0.07112)
			(type default)
		)
		(layer "In4.Cu")
	)
	(gr_line
		(start 151.457406 -363.196378)
		(end 150.961344 -363.69244)
		(stroke
			(width 0.07112)
			(type default)
		)
		(layer "In4.Cu")
	)
	(gr_line
		(start 151.492204 -402.584412)
		(end 151.418544 -402.761958)
		(stroke
			(width 0.07112)
			(type default)
		)
		(layer "In4.Cu")
	)
	(gr_line
		(start 151.656796 -363.589824)
		(end 151.35479 -363.89183)
		(stroke
			(width 0.07112)
			(type default)
		)
		(layer "In4.Cu")
	)
	(gr_line
		(start 151.656796 -363.397546)
		(end 151.656796 -363.589824)
		(stroke
			(width 0.07112)
			(type default)
		)
		(layer "In4.Cu")
	)
	(gr_line
		(start 151.880824 -379.941836)
		(end 151.454104 -379.941836)
		(stroke
			(width 0.07112)
			(type default)
		)
		(layer "In4.Cu")
	)
	(gr_line
		(start 151.943816 -404.17369)
		(end 151.652986 -404.46452)
		(stroke
			(width 0.07112)
			(type default)
		)
		(layer "In4.Cu")
	)
	(gr_line
		(start 152.016714 -380.077726)
		(end 151.880824 -379.941836)
		(stroke
			(width 0.07112)
			(type default)
		)
		(layer "In4.Cu")
	)
	(gr_line
		(start 152.017984 -380.360936)
		(end 151.316944 -380.360936)
		(stroke
			(width 0.07112)
			(type default)
		)
		(layer "In4.Cu")
	)
	(gr_line
		(start 152.15235 -363.09427)
		(end 151.960072 -363.09427)
		(stroke
			(width 0.07112)
			(type default)
		)
		(layer "In4.Cu")
	)
	(gr_line
		(start 152.218898 -388.774432)
		(end 152.271222 -388.826756)
		(stroke
			(width 0.07112)
			(type default)
		)
		(layer "In4.Cu")
	)
	(gr_line
		(start 152.225756 -404.17369)
		(end 152.516586 -404.46452)
		(stroke
			(width 0.07112)
			(type default)
		)
		(layer "In4.Cu")
	)
	(gr_line
		(start 152.254966 -362.398818)
		(end 151.758904 -362.89488)
		(stroke
			(width 0.07112)
			(type default)
		)
		(layer "In4.Cu")
	)
	(gr_line
		(start 152.271222 -389.006588)
		(end 152.124664 -389.153146)
		(stroke
			(width 0.07112)
			(type default)
		)
		(layer "In4.Cu")
	)
	(gr_line
		(start 152.271222 -388.826756)
		(end 152.271222 -389.006588)
		(stroke
			(width 0.07112)
			(type default)
		)
		(layer "In4.Cu")
	)
	(gr_line
		(start 152.30348 -402.395436)
		(end 152.125934 -402.321776)
		(stroke
			(width 0.07112)
			(type default)
		)
		(layer "In4.Cu")
	)
	(gr_line
		(start 152.454356 -362.792264)
		(end 152.15235 -363.09427)
		(stroke
			(width 0.07112)
			(type default)
		)
		(layer "In4.Cu")
	)
	(gr_line
		(start 152.454356 -362.599986)
		(end 152.454356 -362.792264)
		(stroke
			(width 0.07112)
			(type default)
		)
		(layer "In4.Cu")
	)
	(gr_line
		(start 152.50414 -389.352536)
		(end 152.325832 -389.352536)
		(stroke
			(width 0.07112)
			(type default)
		)
		(layer "In4.Cu")
	)
	(gr_line
		(start 152.581864 -379.941836)
		(end 152.445974 -380.077726)
		(stroke
			(width 0.07112)
			(type default)
		)
		(layer "In4.Cu")
	)
	(gr_line
		(start 152.618948 -389.467344)
		(end 152.50414 -389.352536)
		(stroke
			(width 0.07112)
			(type default)
		)
		(layer "In4.Cu")
	)
	(gr_line
		(start 152.664414 -401.792186)
		(end 152.01646 -402.060664)
		(stroke
			(width 0.07112)
			(type default)
		)
		(layer "In4.Cu")
	)
	(gr_line
		(start 152.698196 -402.232114)
		(end 152.30348 -402.395436)
		(stroke
			(width 0.07112)
			(type default)
		)
		(layer "In4.Cu")
	)
	(gr_line
		(start 152.771602 -402.054314)
		(end 152.698196 -402.232114)
		(stroke
			(width 0.07112)
			(type default)
		)
		(layer "In4.Cu")
	)
	(gr_line
		(start 152.94991 -362.29671)
		(end 152.757632 -362.29671)
		(stroke
			(width 0.07112)
			(type default)
		)
		(layer "In4.Cu")
	)
	(gr_line
		(start 153.008584 -379.941836)
		(end 152.581864 -379.941836)
		(stroke
			(width 0.07112)
			(type default)
		)
		(layer "In4.Cu")
	)
	(gr_line
		(start 153.052526 -361.601258)
		(end 152.556464 -362.09732)
		(stroke
			(width 0.07112)
			(type default)
		)
		(layer "In4.Cu")
	)
	(gr_line
		(start 153.091134 -403.263862)
		(end 152.912572 -403.192488)
		(stroke
			(width 0.07112)
			(type default)
		)
		(layer "In4.Cu")
	)
	(gr_line
		(start 153.144474 -380.077726)
		(end 153.008584 -379.941836)
		(stroke
			(width 0.07112)
			(type default)
		)
		(layer "In4.Cu")
	)
	(gr_line
		(start 153.145744 -380.360936)
		(end 152.444704 -380.360936)
		(stroke
			(width 0.07112)
			(type default)
		)
		(layer "In4.Cu")
	)
	(gr_line
		(start 153.251916 -361.994704)
		(end 152.94991 -362.29671)
		(stroke
			(width 0.07112)
			(type default)
		)
		(layer "In4.Cu")
	)
	(gr_line
		(start 153.251916 -361.802426)
		(end 153.251916 -361.994704)
		(stroke
			(width 0.07112)
			(type default)
		)
		(layer "In4.Cu")
	)
	(gr_line
		(start 153.419048 -388.774432)
		(end 153.469594 -388.824978)
		(stroke
			(width 0.07112)
			(type default)
		)
		(layer "In4.Cu")
	)
	(gr_line
		(start 153.444194 -402.65604)
		(end 152.799796 -402.932646)
		(stroke
			(width 0.07112)
			(type default)
		)
		(layer "In4.Cu")
	)
	(gr_line
		(start 153.469594 -389.02513)
		(end 153.341578 -389.153146)
		(stroke
			(width 0.07112)
			(type default)
		)
		(layer "In4.Cu")
	)
	(gr_line
		(start 153.469594 -388.824978)
		(end 153.469594 -389.02513)
		(stroke
			(width 0.07112)
			(type default)
		)
		(layer "In4.Cu")
	)
	(gr_line
		(start 153.483564 -403.09546)
		(end 153.091134 -403.263862)
		(stroke
			(width 0.07112)
			(type default)
		)
		(layer "In4.Cu")
	)
	(gr_line
		(start 153.554684 -402.916644)
		(end 153.483564 -403.09546)
		(stroke
			(width 0.07112)
			(type default)
		)
		(layer "In4.Cu")
	)
	(gr_line
		(start 153.70429 -389.352536)
		(end 153.542746 -389.352536)
		(stroke
			(width 0.07112)
			(type default)
		)
		(layer "In4.Cu")
	)
	(gr_line
		(start 153.709624 -379.941836)
		(end 153.573734 -380.077726)
		(stroke
			(width 0.07112)
			(type default)
		)
		(layer "In4.Cu")
	)
	(gr_line
		(start 153.819098 -389.467344)
		(end 153.70429 -389.352536)
		(stroke
			(width 0.07112)
			(type default)
		)
		(layer "In4.Cu")
	)
	(gr_line
		(start 154.127454 -402.818854)
		(end 153.948892 -402.74748)
		(stroke
			(width 0.07112)
			(type default)
		)
		(layer "In4.Cu")
	)
	(gr_line
		(start 154.136344 -379.941836)
		(end 153.709624 -379.941836)
		(stroke
			(width 0.07112)
			(type default)
		)
		(layer "In4.Cu")
	)
	(gr_line
		(start 154.272234 -380.077726)
		(end 154.136344 -379.941836)
		(stroke
			(width 0.07112)
			(type default)
		)
		(layer "In4.Cu")
	)
	(gr_line
		(start 154.273504 -380.360936)
		(end 153.572464 -380.360936)
		(stroke
			(width 0.07112)
			(type default)
		)
		(layer "In4.Cu")
	)
	(gr_line
		(start 154.372818 -402.25726)
		(end 153.836116 -402.487638)
		(stroke
			(width 0.07112)
			(type default)
		)
		(layer "In4.Cu")
	)
	(gr_line
		(start 154.372818 -402.25726)
		(end 154.373072 -402.257006)
		(stroke
			(width 0.07112)
			(type default)
		)
		(layer "In4.Cu")
	)
	(gr_line
		(start 154.480514 -402.211032)
		(end 154.373072 -402.257006)
		(stroke
			(width 0.07112)
			(type default)
		)
		(layer "In4.Cu")
	)
	(gr_line
		(start 154.519884 -402.650452)
		(end 154.127454 -402.818854)
		(stroke
			(width 0.07112)
			(type default)
		)
		(layer "In4.Cu")
	)
	(gr_line
		(start 154.591258 -402.471636)
		(end 154.519884 -402.650452)
		(stroke
			(width 0.07112)
			(type default)
		)
		(layer "In4.Cu")
	)
	(gr_line
		(start 154.618944 -388.774432)
		(end 154.671268 -388.826756)
		(stroke
			(width 0.07112)
			(type default)
		)
		(layer "In4.Cu")
	)
	(gr_line
		(start 154.671268 -389.006588)
		(end 154.52471 -389.153146)
		(stroke
			(width 0.07112)
			(type default)
		)
		(layer "In4.Cu")
	)
	(gr_line
		(start 154.671268 -388.826756)
		(end 154.671268 -389.006588)
		(stroke
			(width 0.07112)
			(type default)
		)
		(layer "In4.Cu")
	)
	(gr_line
		(start 154.837384 -379.941836)
		(end 154.701494 -380.077726)
		(stroke
			(width 0.07112)
			(type default)
		)
		(layer "In4.Cu")
	)
	(gr_line
		(start 154.904186 -389.352536)
		(end 154.725878 -389.352536)
		(stroke
			(width 0.07112)
			(type default)
		)
		(layer "In4.Cu")
	)
	(gr_line
		(start 155.007056 -404.17369)
		(end 154.716226 -404.46452)
		(stroke
			(width 0.07112)
			(type default)
		)
		(layer "In4.Cu")
	)
	(gr_line
		(start 155.018994 -389.467344)
		(end 154.904186 -389.352536)
		(stroke
			(width 0.07112)
			(type default)
		)
		(layer "In4.Cu")
	)
	(gr_line
		(start 155.264104 -379.941836)
		(end 154.837384 -379.941836)
		(stroke
			(width 0.07112)
			(type default)
		)
		(layer "In4.Cu")
	)
	(gr_line
		(start 155.288996 -404.17369)
		(end 155.579826 -404.46452)
		(stroke
			(width 0.07112)
			(type default)
		)
		(layer "In4.Cu")
	)
	(gr_line
		(start 155.399994 -380.077726)
		(end 155.264104 -379.941836)
		(stroke
			(width 0.07112)
			(type default)
		)
		(layer "In4.Cu")
	)
	(gr_line
		(start 155.401264 -380.360936)
		(end 154.700224 -380.360936)
		(stroke
			(width 0.07112)
			(type default)
		)
		(layer "In4.Cu")
	)
	(gr_line
		(start 155.819094 -388.774432)
		(end 155.871418 -388.826756)
		(stroke
			(width 0.07112)
			(type default)
		)
		(layer "In4.Cu")
	)
	(gr_line
		(start 155.871418 -389.006588)
		(end 155.72486 -389.153146)
		(stroke
			(width 0.07112)
			(type default)
		)
		(layer "In4.Cu")
	)
	(gr_line
		(start 155.871418 -388.826756)
		(end 155.871418 -389.006588)
		(stroke
			(width 0.07112)
			(type default)
		)
		(layer "In4.Cu")
	)
	(gr_line
		(start 156.104082 -389.352536)
		(end 155.926028 -389.352536)
		(stroke
			(width 0.07112)
			(type default)
		)
		(layer "In4.Cu")
	)
	(gr_arc
		(start 156.195522 -390.175496)
		(mid 156.195522 -390.175877)
		(end 156.195522 -390.176258)
		(stroke
			(width 0.07112)
			(type default)
		)
		(layer "In4.Cu")
	)
	(gr_line
		(start 156.21889 -389.467344)
		(end 156.104082 -389.352536)
		(stroke
			(width 0.07112)
			(type default)
		)
		(layer "In4.Cu")
	)
	(gr_line
		(start 156.527754 -402.408136)
		(end 156.33573 -402.408136)
		(stroke
			(width 0.07112)
			(type default)
		)
		(layer "In4.Cu")
	)
	(gr_line
		(start 156.63037 -401.712938)
		(end 156.134562 -402.208746)
		(stroke
			(width 0.07112)
			(type default)
		)
		(layer "In4.Cu")
	)
	(gr_line
		(start 156.82976 -402.10613)
		(end 156.527754 -402.408136)
		(stroke
			(width 0.07112)
			(type default)
		)
		(layer "In4.Cu")
	)
	(gr_line
		(start 156.82976 -401.914106)
		(end 156.82976 -402.10613)
		(stroke
			(width 0.07112)
			(type default)
		)
		(layer "In4.Cu")
	)
	(gr_line
		(start 157.01899 -388.774432)
		(end 157.071314 -388.826756)
		(stroke
			(width 0.07112)
			(type default)
		)
		(layer "In4.Cu")
	)
	(gr_line
		(start 157.071314 -389.006588)
		(end 156.924756 -389.153146)
		(stroke
			(width 0.07112)
			(type default)
		)
		(layer "In4.Cu")
	)
	(gr_line
		(start 157.071314 -388.826756)
		(end 157.071314 -389.006588)
		(stroke
			(width 0.07112)
			(type default)
		)
		(layer "In4.Cu")
	)
	(gr_line
		(start 157.304232 -389.352536)
		(end 157.125924 -389.352536)
		(stroke
			(width 0.07112)
			(type default)
		)
		(layer "In4.Cu")
	)
	(gr_line
		(start 157.41904 -389.467344)
		(end 157.304232 -389.352536)
		(stroke
			(width 0.07112)
			(type default)
		)
		(layer "In4.Cu")
	)
	(gr_line
		(start 157.541722 -394.314426)
		(end 157.541722 -395.015466)
		(stroke
			(width 0.07112)
			(type default)
		)
		(layer "In4.Cu")
	)
	(gr_line
		(start 157.824932 -394.315696)
		(end 157.960822 -394.451586)
		(stroke
			(width 0.07112)
			(type default)
		)
		(layer "In4.Cu")
	)
	(gr_line
		(start 157.838902 -401.097242)
		(end 157.646624 -401.097242)
		(stroke
			(width 0.07112)
			(type default)
		)
		(layer "In4.Cu")
	)
	(gr_line
		(start 157.941518 -400.40179)
		(end 157.445456 -400.897852)
		(stroke
			(width 0.07112)
			(type default)
		)
		(layer "In4.Cu")
	)
	(gr_line
		(start 157.960822 -394.878306)
		(end 157.824932 -395.014196)
		(stroke
			(width 0.07112)
			(type default)
		)
		(layer "In4.Cu")
	)
	(gr_line
		(start 157.960822 -394.451586)
		(end 157.960822 -394.878306)
		(stroke
			(width 0.07112)
			(type default)
		)
		(layer "In4.Cu")
	)
	(gr_line
		(start 158.070296 -404.17369)
		(end 157.779466 -404.46452)
		(stroke
			(width 0.07112)
			(type default)
		)
		(layer "In4.Cu")
	)
	(gr_line
		(start 158.140908 -400.795236)
		(end 157.838902 -401.097242)
		(stroke
			(width 0.07112)
			(type default)
		)
		(layer "In4.Cu")
	)
	(gr_line
		(start 158.140908 -400.602958)
		(end 158.140908 -400.795236)
		(stroke
			(width 0.07112)
			(type default)
		)
		(layer "In4.Cu")
	)
	(gr_line
		(start 158.218886 -388.774432)
		(end 158.27121 -388.826756)
		(stroke
			(width 0.07112)
			(type default)
		)
		(layer "In4.Cu")
	)
	(gr_line
		(start 158.27121 -389.006588)
		(end 158.124652 -389.153146)
		(stroke
			(width 0.07112)
			(type default)
		)
		(layer "In4.Cu")
	)
	(gr_line
		(start 158.27121 -388.826756)
		(end 158.27121 -389.006588)
		(stroke
			(width 0.07112)
			(type default)
		)
		(layer "In4.Cu")
	)
	(gr_line
		(start 158.352236 -404.17369)
		(end 158.643066 -404.46452)
		(stroke
			(width 0.07112)
			(type default)
		)
		(layer "In4.Cu")
	)
	(gr_line
		(start 158.504128 -389.352536)
		(end 158.32582 -389.352536)
		(stroke
			(width 0.07112)
			(type default)
		)
		(layer "In4.Cu")
	)
	(gr_line
		(start 158.618936 -389.467344)
		(end 158.504128 -389.352536)
		(stroke
			(width 0.07112)
			(type default)
		)
		(layer "In4.Cu")
	)
	(gr_line
		(start 158.682436 -394.335)
		(end 158.682436 -395.03604)
		(stroke
			(width 0.07112)
			(type default)
		)
		(layer "In4.Cu")
	)
	(gr_line
		(start 158.951168 -399.984722)
		(end 158.759144 -399.984722)
		(stroke
			(width 0.07112)
			(type default)
		)
		(layer "In4.Cu")
	)
	(gr_line
		(start 158.965646 -394.33627)
		(end 159.101536 -394.47216)
		(stroke
			(width 0.07112)
			(type default)
		)
		(layer "In4.Cu")
	)
	(gr_line
		(start 159.053784 -399.289524)
		(end 158.557976 -399.785332)
		(stroke
			(width 0.07112)
			(type default)
		)
		(layer "In4.Cu")
	)
	(gr_line
		(start 159.101536 -394.89888)
		(end 158.965646 -395.03477)
		(stroke
			(width 0.07112)
			(type default)
		)
		(layer "In4.Cu")
	)
	(gr_line
		(start 159.101536 -394.47216)
		(end 159.101536 -394.89888)
		(stroke
			(width 0.07112)
			(type default)
		)
		(layer "In4.Cu")
	)
	(gr_line
		(start 159.253174 -399.682716)
		(end 158.951168 -399.984722)
		(stroke
			(width 0.07112)
			(type default)
		)
		(layer "In4.Cu")
	)
	(gr_line
		(start 159.253174 -399.490692)
		(end 159.253174 -399.682716)
		(stroke
			(width 0.07112)
			(type default)
		)
		(layer "In4.Cu")
	)
	(gr_line
		(start 159.419036 -388.774432)
		(end 159.47136 -388.826756)
		(stroke
			(width 0.07112)
			(type default)
		)
		(layer "In4.Cu")
	)
	(gr_line
		(start 159.47136 -389.006588)
		(end 159.324802 -389.153146)
		(stroke
			(width 0.07112)
			(type default)
		)
		(layer "In4.Cu")
	)
	(gr_line
		(start 159.47136 -388.826756)
		(end 159.47136 -389.006588)
		(stroke
			(width 0.07112)
			(type default)
		)
		(layer "In4.Cu")
	)
	(gr_line
		(start 159.704278 -389.352536)
		(end 159.52597 -389.352536)
		(stroke
			(width 0.07112)
			(type default)
		)
		(layer "In4.Cu")
	)
	(gr_line
		(start 159.819086 -389.467344)
		(end 159.704278 -389.352536)
		(stroke
			(width 0.07112)
			(type default)
		)
		(layer "In4.Cu")
	)
	(gr_line
		(start 160.21177 -400.91487)
		(end 160.020254 -400.933666)
		(stroke
			(width 0.07112)
			(type default)
		)
		(layer "In4.Cu")
	)
	(gr_line
		(start 160.245552 -400.212814)
		(end 159.800798 -400.75485)
		(stroke
			(width 0.07112)
			(type default)
		)
		(layer "In4.Cu")
	)
	(gr_line
		(start 160.463992 -400.393154)
		(end 160.482534 -400.584924)
		(stroke
			(width 0.07112)
			(type default)
		)
		(layer "In4.Cu")
	)
	(gr_line
		(start 160.482534 -400.584924)
		(end 160.21177 -400.91487)
		(stroke
			(width 0.07112)
			(type default)
		)
		(layer "In4.Cu")
	)
	(gr_line
		(start 160.618932 -388.774432)
		(end 160.671256 -388.826756)
		(stroke
			(width 0.07112)
			(type default)
		)
		(layer "In4.Cu")
	)
	(gr_line
		(start 160.671256 -389.006588)
		(end 160.524698 -389.153146)
		(stroke
			(width 0.07112)
			(type default)
		)
		(layer "In4.Cu")
	)
	(gr_line
		(start 160.671256 -388.826756)
		(end 160.671256 -389.006588)
		(stroke
			(width 0.07112)
			(type default)
		)
		(layer "In4.Cu")
	)
	(gr_line
		(start 160.904174 -389.352536)
		(end 160.725866 -389.352536)
		(stroke
			(width 0.07112)
			(type default)
		)
		(layer "In4.Cu")
	)
	(gr_line
		(start 161.018982 -389.467344)
		(end 160.904174 -389.352536)
		(stroke
			(width 0.07112)
			(type default)
		)
		(layer "In4.Cu")
	)
	(gr_line
		(start 161.133536 -404.17369)
		(end 160.842706 -404.46452)
		(stroke
			(width 0.07112)
			(type default)
		)
		(layer "In4.Cu")
	)
	(gr_line
		(start 161.148268 -394.535406)
		(end 161.148268 -395.236446)
		(stroke
			(width 0.07112)
			(type default)
		)
		(layer "In4.Cu")
	)
	(gr_line
		(start 161.318194 -399.566892)
		(end 161.126424 -399.585688)
		(stroke
			(width 0.07112)
			(type default)
		)
		(layer "In4.Cu")
	)
	(gr_line
		(start 161.351976 -398.864582)
		(end 160.906968 -399.406872)
		(stroke
			(width 0.07112)
			(type default)
		)
		(layer "In4.Cu")
	)
	(gr_line
		(start 161.415476 -404.17369)
		(end 161.706306 -404.46452)
		(stroke
			(width 0.07112)
			(type default)
		)
		(layer "In4.Cu")
	)
	(gr_line
		(start 161.431478 -394.536676)
		(end 161.567368 -394.672566)
		(stroke
			(width 0.07112)
			(type default)
		)
		(layer "In4.Cu")
	)
	(gr_line
		(start 161.567368 -395.099286)
		(end 161.431478 -395.235176)
		(stroke
			(width 0.07112)
			(type default)
		)
		(layer "In4.Cu")
	)
	(gr_line
		(start 161.567368 -394.672566)
		(end 161.567368 -395.099286)
		(stroke
			(width 0.07112)
			(type default)
		)
		(layer "In4.Cu")
	)
	(gr_line
		(start 161.570416 -399.044922)
		(end 161.589212 -399.236692)
		(stroke
			(width 0.07112)
			(type default)
		)
		(layer "In4.Cu")
	)
	(gr_line
		(start 161.589212 -399.236692)
		(end 161.318194 -399.566892)
		(stroke
			(width 0.07112)
			(type default)
		)
		(layer "In4.Cu")
	)
	(gr_line
		(start 161.819082 -388.774432)
		(end 161.871406 -388.826756)
		(stroke
			(width 0.07112)
			(type default)
		)
		(layer "In4.Cu")
	)
	(gr_line
		(start 161.871406 -389.006588)
		(end 161.724848 -389.153146)
		(stroke
			(width 0.07112)
			(type default)
		)
		(layer "In4.Cu")
	)
	(gr_line
		(start 161.871406 -388.826756)
		(end 161.871406 -389.006588)
		(stroke
			(width 0.07112)
			(type default)
		)
		(layer "In4.Cu")
	)
	(gr_line
		(start 162.10407 -389.352536)
		(end 161.926016 -389.352536)
		(stroke
			(width 0.07112)
			(type default)
		)
		(layer "In4.Cu")
	)
	(gr_line
		(start 162.19424 -401.506436)
		(end 161.863786 -402.124926)
		(stroke
			(width 0.07112)
			(type default)
		)
		(layer "In4.Cu")
	)
	(gr_line
		(start 162.218878 -389.467344)
		(end 162.10407 -389.352536)
		(stroke
			(width 0.07112)
			(type default)
		)
		(layer "In4.Cu")
	)
	(gr_line
		(start 162.29838 -402.201634)
		(end 162.113976 -402.25726)
		(stroke
			(width 0.07112)
			(type default)
		)
		(layer "In4.Cu")
	)
	(gr_line
		(start 162.417506 -398.227296)
		(end 162.225736 -398.246092)
		(stroke
			(width 0.07112)
			(type default)
		)
		(layer "In4.Cu")
	)
	(gr_line
		(start 162.443668 -401.640802)
		(end 162.499548 -401.824952)
		(stroke
			(width 0.07112)
			(type default)
		)
		(layer "In4.Cu")
	)
	(gr_line
		(start 162.451034 -397.52524)
		(end 162.00628 -398.067276)
		(stroke
			(width 0.07112)
			(type default)
		)
		(layer "In4.Cu")
	)
	(gr_line
		(start 162.499548 -401.824952)
		(end 162.29838 -402.201634)
		(stroke
			(width 0.07112)
			(type default)
		)
		(layer "In4.Cu")
	)
	(gr_line
		(start 162.644074 -401.263104)
		(end 162.6235 -401.301712)
		(stroke
			(width 0.07112)
			(type default)
		)
		(layer "In4.Cu")
	)
	(gr_line
		(start 162.669474 -397.705326)
		(end 162.68827 -397.89735)
		(stroke
			(width 0.07112)
			(type default)
		)
		(layer "In4.Cu")
	)
	(gr_line
		(start 162.68827 -397.89735)
		(end 162.417506 -398.227296)
		(stroke
			(width 0.07112)
			(type default)
		)
		(layer "In4.Cu")
	)
	(gr_line
		(start 162.726116 -400.511518)
		(end 162.395408 -401.130262)
		(stroke
			(width 0.07112)
			(type default)
		)
		(layer "In4.Cu")
	)
	(gr_line
		(start 162.830002 -401.206716)
		(end 162.645852 -401.262596)
		(stroke
			(width 0.07112)
			(type default)
		)
		(layer "In4.Cu")
	)
	(gr_line
		(start 162.975544 -400.645884)
		(end 163.03117 -400.830288)
		(stroke
			(width 0.07112)
			(type default)
		)
		(layer "In4.Cu")
	)
	(gr_line
		(start 163.018978 -388.774432)
		(end 163.071302 -388.826756)
		(stroke
			(width 0.07112)
			(type default)
		)
		(layer "In4.Cu")
	)
	(gr_line
		(start 163.03117 -400.830288)
		(end 162.830002 -401.206716)
		(stroke
			(width 0.07112)
			(type default)
		)
		(layer "In4.Cu")
	)
	(gr_line
		(start 163.071302 -389.006588)
		(end 162.924744 -389.153146)
		(stroke
			(width 0.07112)
			(type default)
		)
		(layer "In4.Cu")
	)
	(gr_line
		(start 163.071302 -388.826756)
		(end 163.071302 -389.006588)
		(stroke
			(width 0.07112)
			(type default)
		)
		(layer "In4.Cu")
	)
	(gr_line
		(start 163.30422 -389.352536)
		(end 163.125912 -389.352536)
		(stroke
			(width 0.07112)
			(type default)
		)
		(layer "In4.Cu")
	)
	(gr_line
		(start 163.306252 -399.42643)
		(end 162.975544 -400.04492)
		(stroke
			(width 0.07112)
			(type default)
		)
		(layer "In4.Cu")
	)
	(gr_line
		(start 163.410392 -400.121628)
		(end 163.225988 -400.177254)
		(stroke
			(width 0.07112)
			(type default)
		)
		(layer "In4.Cu")
	)
	(gr_line
		(start 163.419028 -389.467344)
		(end 163.30422 -389.352536)
		(stroke
			(width 0.07112)
			(type default)
		)
		(layer "In4.Cu")
	)
	(gr_line
		(start 163.555426 -399.560796)
		(end 163.61156 -399.744946)
		(stroke
			(width 0.07112)
			(type default)
		)
		(layer "In4.Cu")
	)
	(gr_line
		(start 163.61156 -399.744946)
		(end 163.410392 -400.121628)
		(stroke
			(width 0.07112)
			(type default)
		)
		(layer "In4.Cu")
	)
	(gr_line
		(start 164.219128 -388.774432)
		(end 164.271452 -388.826756)
		(stroke
			(width 0.07112)
			(type default)
		)
		(layer "In4.Cu")
	)
	(gr_line
		(start 164.271452 -389.006588)
		(end 164.124894 -389.153146)
		(stroke
			(width 0.07112)
			(type default)
		)
		(layer "In4.Cu")
	)
	(gr_line
		(start 164.271452 -388.826756)
		(end 164.271452 -389.006588)
		(stroke
			(width 0.07112)
			(type default)
		)
		(layer "In4.Cu")
	)
	(gr_line
		(start 164.504116 -389.352536)
		(end 164.326062 -389.352536)
		(stroke
			(width 0.07112)
			(type default)
		)
		(layer "In4.Cu")
	)
	(gr_line
		(start 164.618924 -389.467344)
		(end 164.504116 -389.352536)
		(stroke
			(width 0.07112)
			(type default)
		)
		(layer "In4.Cu")
	)
	(gr_line
		(start 165.419024 -388.774432)
		(end 165.471348 -388.826756)
		(stroke
			(width 0.07112)
			(type default)
		)
		(layer "In4.Cu")
	)
	(gr_line
		(start 165.471348 -389.006588)
		(end 165.32479 -389.153146)
		(stroke
			(width 0.07112)
			(type default)
		)
		(layer "In4.Cu")
	)
	(gr_line
		(start 165.471348 -388.826756)
		(end 165.471348 -389.006588)
		(stroke
			(width 0.07112)
			(type default)
		)
		(layer "In4.Cu")
	)
	(gr_line
		(start 165.704266 -389.352536)
		(end 165.525958 -389.352536)
		(stroke
			(width 0.07112)
			(type default)
		)
		(layer "In4.Cu")
	)
	(gr_line
		(start 165.819074 -389.467344)
		(end 165.704266 -389.352536)
		(stroke
			(width 0.07112)
			(type default)
		)
		(layer "In4.Cu")
	)
	(gr_line
		(start 166.115746 -362.396278)
		(end 165.824916 -362.105448)
		(stroke
			(width 0.07112)
			(type default)
		)
		(layer "In4.Cu")
	)
	(gr_line
		(start 166.115746 -361.532678)
		(end 165.824916 -361.823508)
		(stroke
			(width 0.07112)
			(type default)
		)
		(layer "In4.Cu")
	)
	(gr_line
		(start 175.584104 -369.598448)
		(end 175.874934 -369.889278)
		(stroke
			(width 0.07112)
			(type default)
		)
		(layer "In4.Cu")
	)
	(gr_line
		(start 176.447704 -369.598448)
		(end 176.156874 -369.889278)
		(stroke
			(width 0.07112)
			(type default)
		)
		(layer "In4.Cu")
	)
	(gr_line
		(start 194.193922 -9.780016)
		(end 194.193922 -5.787898)
		(stroke
			(width 0.2)
			(type default)
		)
		(layer "In4.Cu")
	)
	(gr_arc
		(start 194.193922 -9.780016)
		(mid 194.928504 -11.55342)
		(end 196.701918 -12.288012)
		(stroke
			(width 0.2)
			(type default)
		)
		(layer "In4.Cu")
	)
	(gr_line
		(start 194.193922 -5.787898)
		(end 126.61011 -5.787898)
		(stroke
			(width 0.2)
			(type default)
		)
		(layer "In4.Cu")
	)
	(gr_line
		(start 194.496944 -441.481972)
		(end 194.496944 -441.17006)
		(stroke
			(width 0.2)
			(type default)
		)
		(layer "In4.Cu")
	)
	(gr_arc
		(start 195.50507 -440.161934)
		(mid 194.792223 -440.457215)
		(end 194.496944 -441.17006)
		(stroke
			(width 0.2)
			(type default)
		)
		(layer "In4.Cu")
	)
	(gr_line
		(start 195.50507 -440.161934)
		(end 276.314916 -440.161934)
		(stroke
			(width 0.2)
			(type default)
		)
		(layer "In4.Cu")
	)
	(gr_arc
		(start 197.209918 -7.78002)
		(mid 197.646914 -8.83502)
		(end 198.701914 -9.272016)
		(stroke
			(width 0.2)
			(type default)
		)
		(layer "In4.Cu")
	)
	(gr_arc
		(start 197.209918 -4.879848)
		(mid 196.475361 -3.106388)
		(end 194.701922 -2.371852)
		(stroke
			(width 0.2)
			(type default)
		)
		(layer "In4.Cu")
	)
	(gr_line
		(start 197.209918 -4.879848)
		(end 197.209918 -7.78002)
		(stroke
			(width 0.2)
			(type default)
		)
		(layer "In4.Cu")
	)
	(gr_line
		(start 198.701914 -9.272016)
		(end 223.300036 -9.272016)
		(stroke
			(width 0.2)
			(type default)
		)
		(layer "In4.Cu")
	)
	(gr_line
		(start 204.62367 -353.525836)
		(end 204.431392 -353.525836)
		(stroke
			(width 0.07112)
			(type default)
		)
		(layer "In4.Cu")
	)
	(gr_line
		(start 204.726286 -352.830384)
		(end 204.230224 -353.326446)
		(stroke
			(width 0.07112)
			(type default)
		)
		(layer "In4.Cu")
	)
	(gr_line
		(start 204.925676 -353.22383)
		(end 204.62367 -353.525836)
		(stroke
			(width 0.07112)
			(type default)
		)
		(layer "In4.Cu")
	)
	(gr_line
		(start 204.925676 -353.031552)
		(end 204.925676 -353.22383)
		(stroke
			(width 0.07112)
			(type default)
		)
		(layer "In4.Cu")
	)
	(gr_line
		(start 206.551784 -352.13163)
		(end 206.528924 -352.13163)
		(stroke
			(width 0.07112)
			(type default)
		)
		(layer "In4.Cu")
	)
	(gr_line
		(start 206.831184 -352.41103)
		(end 206.551784 -352.13163)
		(stroke
			(width 0.07112)
			(type default)
		)
		(layer "In4.Cu")
	)
	(gr_line
		(start 206.831184 -351.54743)
		(end 206.530194 -351.84842)
		(stroke
			(width 0.07112)
			(type default)
		)
		(layer "In4.Cu")
	)
	(gr_line
		(start 214.24011 -5.218176)
		(end 213.94928 -5.509006)
		(stroke
			(width 0.07112)
			(type default)
		)
		(layer "In4.Cu")
	)
	(gr_line
		(start 214.24011 -4.936236)
		(end 213.94928 -4.645406)
		(stroke
			(width 0.07112)
			(type default)
		)
		(layer "In4.Cu")
	)
	(gr_line
		(start 221.30004 -12.288012)
		(end 196.701918 -12.288012)
		(stroke
			(width 0.2)
			(type default)
		)
		(layer "In4.Cu")
	)
	(gr_line
		(start 222.792036 -34.120074)
		(end 222.792036 -13.780008)
		(stroke
			(width 0.2)
			(type default)
		)
		(layer "In4.Cu")
	)
	(gr_arc
		(start 222.792036 -34.120074)
		(mid 223.526604 -35.8935)
		(end 225.300032 -36.62807)
		(stroke
			(width 0.2)
			(type default)
		)
		(layer "In4.Cu")
	)
	(gr_arc
		(start 222.792036 -13.780008)
		(mid 222.35504 -12.725008)
		(end 221.30004 -12.288012)
		(stroke
			(width 0.2)
			(type default)
		)
		(layer "In4.Cu")
	)
	(gr_arc
		(start 225.808032 -33.120076)
		(mid 225.952135 -33.467971)
		(end 226.30003 -33.612074)
		(stroke
			(width 0.2)
			(type default)
		)
		(layer "In4.Cu")
	)
	(gr_arc
		(start 225.808032 -11.780012)
		(mid 225.073463 -10.006571)
		(end 223.300036 -9.272016)
		(stroke
			(width 0.2)
			(type default)
		)
		(layer "In4.Cu")
	)
	(gr_line
		(start 225.808032 -11.780012)
		(end 225.808032 -33.120076)
		(stroke
			(width 0.2)
			(type default)
		)
		(layer "In4.Cu")
	)
	(gr_line
		(start 226.30003 -33.612074)
		(end 255.800098 -33.612074)
		(stroke
			(width 0.2)
			(type default)
		)
		(layer "In4.Cu")
	)
	(gr_arc
		(start 255.800098 -33.612074)
		(mid 256.147993 -33.467971)
		(end 256.292096 -33.120076)
		(stroke
			(width 0.2)
			(type default)
		)
		(layer "In4.Cu")
	)
	(gr_line
		(start 256.292096 -33.120076)
		(end 256.292096 -11.780012)
		(stroke
			(width 0.2)
			(type default)
		)
		(layer "In4.Cu")
	)
	(gr_line
		(start 256.800096 -36.62807)
		(end 225.300032 -36.62807)
		(stroke
			(width 0.2)
			(type default)
		)
		(layer "In4.Cu")
	)
	(gr_arc
		(start 256.800096 -36.62807)
		(mid 258.57351 -35.893495)
		(end 259.308092 -34.120074)
		(stroke
			(width 0.2)
			(type default)
		)
		(layer "In4.Cu")
	)
	(gr_arc
		(start 258.800092 -9.272016)
		(mid 257.02668 -10.006595)
		(end 256.292096 -11.780012)
		(stroke
			(width 0.2)
			(type default)
		)
		(layer "In4.Cu")
	)
	(gr_line
		(start 258.800092 -9.272016)
		(end 383.601976 -9.272016)
		(stroke
			(width 0.2)
			(type default)
		)
		(layer "In4.Cu")
	)
	(gr_line
		(start 259.308092 -13.780008)
		(end 259.308092 -34.120074)
		(stroke
			(width 0.2)
			(type default)
		)
		(layer "In4.Cu")
	)
	(gr_arc
		(start 260.800088 -12.288012)
		(mid 259.745088 -12.725008)
		(end 259.308092 -13.780008)
		(stroke
			(width 0.2)
			(type default)
		)
		(layer "In4.Cu")
	)
	(gr_line
		(start 277.323042 -441.481972)
		(end 463.300064 -441.481972)
		(stroke
			(width 0.2)
			(type default)
		)
		(layer "In4.Cu")
	)
	(gr_arc
		(start 277.323042 -441.17006)
		(mid 277.027756 -440.457227)
		(end 276.314916 -440.161934)
		(stroke
			(width 0.2)
			(type default)
		)
		(layer "In4.Cu")
	)
	(gr_line
		(start 277.323042 -441.17006)
		(end 277.323042 -441.481972)
		(stroke
			(width 0.2)
			(type default)
		)
		(layer "In4.Cu")
	)
	(gr_line
		(start 277.394162 -418.790882)
		(end 277.103332 -419.081712)
		(stroke
			(width 0.07112)
			(type default)
		)
		(layer "In4.Cu")
	)
	(gr_line
		(start 277.394162 -418.508942)
		(end 277.103332 -418.218112)
		(stroke
			(width 0.07112)
			(type default)
		)
		(layer "In4.Cu")
	)
	(gr_line
		(start 283.234892 -373.956834)
		(end 282.944062 -373.666004)
		(stroke
			(width 0.07112)
			(type default)
		)
		(layer "In4.Cu")
	)
	(gr_line
		(start 283.234892 -373.093234)
		(end 282.944062 -373.384064)
		(stroke
			(width 0.07112)
			(type default)
		)
		(layer "In4.Cu")
	)
	(gr_line
		(start 299.060616 -5.509006)
		(end 298.769786 -5.218176)
		(stroke
			(width 0.07112)
			(type default)
		)
		(layer "In4.Cu")
	)
	(gr_line
		(start 299.060616 -4.645406)
		(end 298.769786 -4.936236)
		(stroke
			(width 0.07112)
			(type default)
		)
		(layer "In4.Cu")
	)
	(gr_line
		(start 303.791112 -397.156432)
		(end 303.843436 -397.208756)
		(stroke
			(width 0.07112)
			(type default)
		)
		(layer "In4.Cu")
	)
	(gr_line
		(start 303.843436 -397.388588)
		(end 303.696878 -397.535146)
		(stroke
			(width 0.07112)
			(type default)
		)
		(layer "In4.Cu")
	)
	(gr_line
		(start 303.843436 -397.208756)
		(end 303.843436 -397.388588)
		(stroke
			(width 0.07112)
			(type default)
		)
		(layer "In4.Cu")
	)
	(gr_arc
		(start 304.003456 -399.497042)
		(mid 304.005605 -399.50403)
		(end 304.007774 -399.511012)
		(stroke
			(width 0.07112)
			(type default)
		)
		(layer "In4.Cu")
	)
	(gr_line
		(start 304.007774 -399.511012)
		(end 304.012854 -399.523204)
		(stroke
			(width 0.07112)
			(type default)
		)
		(layer "In4.Cu")
	)
	(gr_line
		(start 304.012854 -399.523204)
		(end 304.012854 -399.523458)
		(stroke
			(width 0.07112)
			(type default)
		)
		(layer "In4.Cu")
	)
	(gr_line
		(start 304.076354 -397.734536)
		(end 303.898046 -397.734536)
		(stroke
			(width 0.07112)
			(type default)
		)
		(layer "In4.Cu")
	)
	(gr_line
		(start 304.084736 -412.55569)
		(end 303.793906 -412.84652)
		(stroke
			(width 0.07112)
			(type default)
		)
		(layer "In4.Cu")
	)
	(gr_line
		(start 304.191162 -397.849344)
		(end 304.076354 -397.734536)
		(stroke
			(width 0.07112)
			(type default)
		)
		(layer "In4.Cu")
	)
	(gr_line
		(start 304.27168 -407.383488)
		(end 304.27168 -408.084528)
		(stroke
			(width 0.07112)
			(type default)
		)
		(layer "In4.Cu")
	)
	(gr_line
		(start 304.27168 -406.07361)
		(end 304.27168 -406.77465)
		(stroke
			(width 0.07112)
			(type default)
		)
		(layer "In4.Cu")
	)
	(gr_line
		(start 304.27168 -402.74621)
		(end 304.27168 -403.44725)
		(stroke
			(width 0.07112)
			(type default)
		)
		(layer "In4.Cu")
	)
	(gr_line
		(start 304.366676 -412.55569)
		(end 304.657506 -412.84652)
		(stroke
			(width 0.07112)
			(type default)
		)
		(layer "In4.Cu")
	)
	(gr_line
		(start 304.55489 -407.384758)
		(end 304.69078 -407.520648)
		(stroke
			(width 0.07112)
			(type default)
		)
		(layer "In4.Cu")
	)
	(gr_line
		(start 304.55489 -406.07488)
		(end 304.69078 -406.21077)
		(stroke
			(width 0.07112)
			(type default)
		)
		(layer "In4.Cu")
	)
	(gr_line
		(start 304.55489 -402.74748)
		(end 304.69078 -402.88337)
		(stroke
			(width 0.07112)
			(type default)
		)
		(layer "In4.Cu")
	)
	(gr_line
		(start 304.69078 -407.947368)
		(end 304.55489 -408.083258)
		(stroke
			(width 0.07112)
			(type default)
		)
		(layer "In4.Cu")
	)
	(gr_line
		(start 304.69078 -407.520648)
		(end 304.69078 -407.947368)
		(stroke
			(width 0.07112)
			(type default)
		)
		(layer "In4.Cu")
	)
	(gr_line
		(start 304.69078 -406.63749)
		(end 304.55489 -406.77338)
		(stroke
			(width 0.07112)
			(type default)
		)
		(layer "In4.Cu")
	)
	(gr_line
		(start 304.69078 -406.21077)
		(end 304.69078 -406.63749)
		(stroke
			(width 0.07112)
			(type default)
		)
		(layer "In4.Cu")
	)
	(gr_line
		(start 304.69078 -403.31009)
		(end 304.55489 -403.44598)
		(stroke
			(width 0.07112)
			(type default)
		)
		(layer "In4.Cu")
	)
	(gr_line
		(start 304.69078 -402.88337)
		(end 304.69078 -403.31009)
		(stroke
			(width 0.07112)
			(type default)
		)
		(layer "In4.Cu")
	)
	(gr_line
		(start 304.991008 -397.156432)
		(end 305.043332 -397.208756)
		(stroke
			(width 0.07112)
			(type default)
		)
		(layer "In4.Cu")
	)
	(gr_line
		(start 305.043332 -397.388588)
		(end 304.896774 -397.535146)
		(stroke
			(width 0.07112)
			(type default)
		)
		(layer "In4.Cu")
	)
	(gr_line
		(start 305.043332 -397.208756)
		(end 305.043332 -397.388588)
		(stroke
			(width 0.07112)
			(type default)
		)
		(layer "In4.Cu")
	)
	(gr_line
		(start 305.27625 -397.734536)
		(end 305.097942 -397.734536)
		(stroke
			(width 0.07112)
			(type default)
		)
		(layer "In4.Cu")
	)
	(gr_line
		(start 305.391058 -397.849344)
		(end 305.27625 -397.734536)
		(stroke
			(width 0.07112)
			(type default)
		)
		(layer "In4.Cu")
	)
	(gr_arc
		(start 305.753516 -404.430484)
		(mid 305.753516 -404.43023)
		(end 305.753516 -404.429976)
		(stroke
			(width 0.07112)
			(type default)
		)
		(layer "In4.Cu")
	)
	(gr_line
		(start 306.191158 -397.156432)
		(end 306.243482 -397.208756)
		(stroke
			(width 0.07112)
			(type default)
		)
		(layer "In4.Cu")
	)
	(gr_line
		(start 306.21605 -406.830784)
		(end 306.516024 -407.464768)
		(stroke
			(width 0.07112)
			(type default)
		)
		(layer "In4.Cu")
	)
	(gr_line
		(start 306.243482 -397.412972)
		(end 306.121308 -397.535146)
		(stroke
			(width 0.07112)
			(type default)
		)
		(layer "In4.Cu")
	)
	(gr_line
		(start 306.243482 -397.208756)
		(end 306.243482 -397.412972)
		(stroke
			(width 0.07112)
			(type default)
		)
		(layer "In4.Cu")
	)
	(gr_line
		(start 306.47259 -406.710642)
		(end 306.653946 -406.775412)
		(stroke
			(width 0.07112)
			(type default)
		)
		(layer "In4.Cu")
	)
	(gr_line
		(start 306.476146 -397.734536)
		(end 306.322476 -397.734536)
		(stroke
			(width 0.07112)
			(type default)
		)
		(layer "In4.Cu")
	)
	(gr_line
		(start 306.590954 -397.849344)
		(end 306.476146 -397.734536)
		(stroke
			(width 0.07112)
			(type default)
		)
		(layer "In4.Cu")
	)
	(gr_line
		(start 306.653946 -406.775412)
		(end 306.836318 -407.161238)
		(stroke
			(width 0.07112)
			(type default)
		)
		(layer "In4.Cu")
	)
	(gr_line
		(start 306.671726 -403.837648)
		(end 306.671726 -404.538688)
		(stroke
			(width 0.07112)
			(type default)
		)
		(layer "In4.Cu")
	)
	(gr_line
		(start 306.671726 -402.709888)
		(end 306.671726 -403.410928)
		(stroke
			(width 0.07112)
			(type default)
		)
		(layer "In4.Cu")
	)
	(gr_line
		(start 306.698396 -407.85034)
		(end 306.99837 -408.484324)
		(stroke
			(width 0.07112)
			(type default)
		)
		(layer "In4.Cu")
	)
	(gr_line
		(start 306.836318 -407.161238)
		(end 306.771548 -407.342594)
		(stroke
			(width 0.07112)
			(type default)
		)
		(layer "In4.Cu")
	)
	(gr_line
		(start 306.954936 -407.730198)
		(end 307.136292 -407.794968)
		(stroke
			(width 0.07112)
			(type default)
		)
		(layer "In4.Cu")
	)
	(gr_line
		(start 306.954936 -403.838918)
		(end 307.090826 -403.974808)
		(stroke
			(width 0.07112)
			(type default)
		)
		(layer "In4.Cu")
	)
	(gr_line
		(start 306.954936 -402.711158)
		(end 307.090826 -402.847048)
		(stroke
			(width 0.07112)
			(type default)
		)
		(layer "In4.Cu")
	)
	(gr_line
		(start 307.090826 -404.401528)
		(end 306.954936 -404.537418)
		(stroke
			(width 0.07112)
			(type default)
		)
		(layer "In4.Cu")
	)
	(gr_line
		(start 307.090826 -403.974808)
		(end 307.090826 -404.401528)
		(stroke
			(width 0.07112)
			(type default)
		)
		(layer "In4.Cu")
	)
	(gr_line
		(start 307.090826 -403.273768)
		(end 306.954936 -403.409658)
		(stroke
			(width 0.07112)
			(type default)
		)
		(layer "In4.Cu")
	)
	(gr_line
		(start 307.090826 -402.847048)
		(end 307.090826 -403.273768)
		(stroke
			(width 0.07112)
			(type default)
		)
		(layer "In4.Cu")
	)
	(gr_line
		(start 307.135784 -408.7749)
		(end 307.135784 -408.774646)
		(stroke
			(width 0.07112)
			(type default)
		)
		(layer "In4.Cu")
	)
	(gr_line
		(start 307.136292 -407.794968)
		(end 307.318664 -408.181048)
		(stroke
			(width 0.07112)
			(type default)
		)
		(layer "In4.Cu")
	)
	(gr_line
		(start 307.147976 -412.55569)
		(end 306.857146 -412.84652)
		(stroke
			(width 0.07112)
			(type default)
		)
		(layer "In4.Cu")
	)
	(gr_line
		(start 307.147976 -410.526992)
		(end 307.147976 -411.228032)
		(stroke
			(width 0.07112)
			(type default)
		)
		(layer "In4.Cu")
	)
	(gr_line
		(start 307.318664 -408.181048)
		(end 307.253894 -408.36215)
		(stroke
			(width 0.07112)
			(type default)
		)
		(layer "In4.Cu")
	)
	(gr_line
		(start 307.391054 -397.156432)
		(end 307.443378 -397.208756)
		(stroke
			(width 0.07112)
			(type default)
		)
		(layer "In4.Cu")
	)
	(gr_line
		(start 307.429916 -412.55569)
		(end 307.720746 -412.84652)
		(stroke
			(width 0.07112)
			(type default)
		)
		(layer "In4.Cu")
	)
	(gr_line
		(start 307.431186 -410.528262)
		(end 307.567076 -410.664152)
		(stroke
			(width 0.07112)
			(type default)
		)
		(layer "In4.Cu")
	)
	(gr_line
		(start 307.443378 -397.388588)
		(end 307.29682 -397.535146)
		(stroke
			(width 0.07112)
			(type default)
		)
		(layer "In4.Cu")
	)
	(gr_line
		(start 307.443378 -397.208756)
		(end 307.443378 -397.388588)
		(stroke
			(width 0.07112)
			(type default)
		)
		(layer "In4.Cu")
	)
	(gr_line
		(start 307.567076 -411.090872)
		(end 307.431186 -411.226762)
		(stroke
			(width 0.07112)
			(type default)
		)
		(layer "In4.Cu")
	)
	(gr_line
		(start 307.567076 -410.664152)
		(end 307.567076 -411.090872)
		(stroke
			(width 0.07112)
			(type default)
		)
		(layer "In4.Cu")
	)
	(gr_line
		(start 307.676296 -397.734536)
		(end 307.497988 -397.734536)
		(stroke
			(width 0.07112)
			(type default)
		)
		(layer "In4.Cu")
	)
	(gr_line
		(start 307.791104 -397.849344)
		(end 307.676296 -397.734536)
		(stroke
			(width 0.07112)
			(type default)
		)
		(layer "In4.Cu")
	)
	(gr_line
		(start 307.871622 -403.811232)
		(end 307.871622 -404.512272)
		(stroke
			(width 0.07112)
			(type default)
		)
		(layer "In4.Cu")
	)
	(gr_line
		(start 307.871622 -402.683472)
		(end 307.871622 -403.384512)
		(stroke
			(width 0.07112)
			(type default)
		)
		(layer "In4.Cu")
	)
	(gr_arc
		(start 308.153562 -400.202654)
		(mid 308.153562 -400.202908)
		(end 308.153562 -400.203162)
		(stroke
			(width 0.07112)
			(type default)
		)
		(layer "In4.Cu")
	)
	(gr_line
		(start 308.154832 -403.812502)
		(end 308.290722 -403.948392)
		(stroke
			(width 0.07112)
			(type default)
		)
		(layer "In4.Cu")
	)
	(gr_line
		(start 308.154832 -402.684742)
		(end 308.290722 -402.820632)
		(stroke
			(width 0.07112)
			(type default)
		)
		(layer "In4.Cu")
	)
	(gr_line
		(start 308.290722 -404.375112)
		(end 308.154832 -404.511002)
		(stroke
			(width 0.07112)
			(type default)
		)
		(layer "In4.Cu")
	)
	(gr_line
		(start 308.290722 -403.948392)
		(end 308.290722 -404.375112)
		(stroke
			(width 0.07112)
			(type default)
		)
		(layer "In4.Cu")
	)
	(gr_line
		(start 308.290722 -403.247352)
		(end 308.154832 -403.383242)
		(stroke
			(width 0.07112)
			(type default)
		)
		(layer "In4.Cu")
	)
	(gr_line
		(start 308.290722 -402.820632)
		(end 308.290722 -403.247352)
		(stroke
			(width 0.07112)
			(type default)
		)
		(layer "In4.Cu")
	)
	(gr_line
		(start 308.59095 -397.156432)
		(end 308.643274 -397.208756)
		(stroke
			(width 0.07112)
			(type default)
		)
		(layer "In4.Cu")
	)
	(gr_line
		(start 308.643274 -397.388588)
		(end 308.496716 -397.535146)
		(stroke
			(width 0.07112)
			(type default)
		)
		(layer "In4.Cu")
	)
	(gr_line
		(start 308.643274 -397.208756)
		(end 308.643274 -397.388588)
		(stroke
			(width 0.07112)
			(type default)
		)
		(layer "In4.Cu")
	)
	(gr_line
		(start 308.876192 -397.734536)
		(end 308.697884 -397.734536)
		(stroke
			(width 0.07112)
			(type default)
		)
		(layer "In4.Cu")
	)
	(gr_line
		(start 308.991 -397.849344)
		(end 308.876192 -397.734536)
		(stroke
			(width 0.07112)
			(type default)
		)
		(layer "In4.Cu")
	)
	(gr_line
		(start 309.071518 -402.921978)
		(end 309.071518 -403.623018)
		(stroke
			(width 0.07112)
			(type default)
		)
		(layer "In4.Cu")
	)
	(gr_line
		(start 309.354728 -402.923248)
		(end 309.490618 -403.059138)
		(stroke
			(width 0.07112)
			(type default)
		)
		(layer "In4.Cu")
	)
	(gr_line
		(start 309.490618 -403.485858)
		(end 309.354728 -403.621748)
		(stroke
			(width 0.07112)
			(type default)
		)
		(layer "In4.Cu")
	)
	(gr_line
		(start 309.490618 -403.059138)
		(end 309.490618 -403.485858)
		(stroke
			(width 0.07112)
			(type default)
		)
		(layer "In4.Cu")
	)
	(gr_line
		(start 309.7911 -397.156432)
		(end 309.843424 -397.208756)
		(stroke
			(width 0.07112)
			(type default)
		)
		(layer "In4.Cu")
	)
	(gr_line
		(start 309.843424 -397.388588)
		(end 309.696866 -397.535146)
		(stroke
			(width 0.07112)
			(type default)
		)
		(layer "In4.Cu")
	)
	(gr_line
		(start 309.843424 -397.208756)
		(end 309.843424 -397.388588)
		(stroke
			(width 0.07112)
			(type default)
		)
		(layer "In4.Cu")
	)
	(gr_line
		(start 309.996586 -406.336246)
		(end 310.463946 -406.803606)
		(stroke
			(width 0.07112)
			(type default)
		)
		(layer "In4.Cu")
	)
	(gr_line
		(start 310.076342 -397.734536)
		(end 309.898034 -397.734536)
		(stroke
			(width 0.07112)
			(type default)
		)
		(layer "In4.Cu")
	)
	(gr_line
		(start 310.19115 -397.849344)
		(end 310.076342 -397.734536)
		(stroke
			(width 0.07112)
			(type default)
		)
		(layer "In4.Cu")
	)
	(gr_line
		(start 310.197754 -406.136856)
		(end 310.390032 -406.136856)
		(stroke
			(width 0.07112)
			(type default)
		)
		(layer "In4.Cu")
	)
	(gr_line
		(start 310.211216 -412.55569)
		(end 309.920386 -412.84652)
		(stroke
			(width 0.07112)
			(type default)
		)
		(layer "In4.Cu")
	)
	(gr_line
		(start 310.211216 -411.131258)
		(end 310.211216 -411.791658)
		(stroke
			(width 0.07112)
			(type default)
		)
		(layer "In4.Cu")
	)
	(gr_line
		(start 310.271668 -403.187154)
		(end 310.271668 -403.888194)
		(stroke
			(width 0.07112)
			(type default)
		)
		(layer "In4.Cu")
	)
	(gr_line
		(start 310.390032 -406.136856)
		(end 310.663336 -406.41016)
		(stroke
			(width 0.07112)
			(type default)
		)
		(layer "In4.Cu")
	)
	(gr_line
		(start 310.493156 -412.55569)
		(end 310.783986 -412.84652)
		(stroke
			(width 0.07112)
			(type default)
		)
		(layer "In4.Cu")
	)
	(gr_line
		(start 310.494426 -411.132528)
		(end 310.630316 -411.268418)
		(stroke
			(width 0.07112)
			(type default)
		)
		(layer "In4.Cu")
	)
	(gr_line
		(start 310.554878 -403.188424)
		(end 310.690768 -403.324314)
		(stroke
			(width 0.07112)
			(type default)
		)
		(layer "In4.Cu")
	)
	(gr_line
		(start 310.630316 -411.654498)
		(end 310.494426 -411.790388)
		(stroke
			(width 0.07112)
			(type default)
		)
		(layer "In4.Cu")
	)
	(gr_line
		(start 310.630316 -411.268418)
		(end 310.630316 -411.654498)
		(stroke
			(width 0.07112)
			(type default)
		)
		(layer "In4.Cu")
	)
	(gr_line
		(start 310.663336 -406.41016)
		(end 310.663336 -406.602438)
		(stroke
			(width 0.07112)
			(type default)
		)
		(layer "In4.Cu")
	)
	(gr_line
		(start 310.690768 -403.751034)
		(end 310.554878 -403.886924)
		(stroke
			(width 0.07112)
			(type default)
		)
		(layer "In4.Cu")
	)
	(gr_line
		(start 310.690768 -403.324314)
		(end 310.690768 -403.751034)
		(stroke
			(width 0.07112)
			(type default)
		)
		(layer "In4.Cu")
	)
	(gr_line
		(start 310.736742 -407.076402)
		(end 311.204102 -407.543762)
		(stroke
			(width 0.07112)
			(type default)
		)
		(layer "In4.Cu")
	)
	(gr_line
		(start 310.93791 -406.877012)
		(end 311.130188 -406.877012)
		(stroke
			(width 0.07112)
			(type default)
		)
		(layer "In4.Cu")
	)
	(gr_line
		(start 310.990996 -397.156432)
		(end 311.04332 -397.208756)
		(stroke
			(width 0.07112)
			(type default)
		)
		(layer "In4.Cu")
	)
	(gr_line
		(start 311.04332 -397.388588)
		(end 310.896762 -397.535146)
		(stroke
			(width 0.07112)
			(type default)
		)
		(layer "In4.Cu")
	)
	(gr_line
		(start 311.04332 -397.208756)
		(end 311.04332 -397.388588)
		(stroke
			(width 0.07112)
			(type default)
		)
		(layer "In4.Cu")
	)
	(gr_line
		(start 311.130188 -406.877012)
		(end 311.403492 -407.150316)
		(stroke
			(width 0.07112)
			(type default)
		)
		(layer "In4.Cu")
	)
	(gr_line
		(start 311.224422 -406.048464)
		(end 311.691528 -406.51557)
		(stroke
			(width 0.07112)
			(type default)
		)
		(layer "In4.Cu")
	)
	(gr_line
		(start 311.276238 -397.734536)
		(end 311.09793 -397.734536)
		(stroke
			(width 0.07112)
			(type default)
		)
		(layer "In4.Cu")
	)
	(gr_line
		(start 311.391046 -397.849344)
		(end 311.276238 -397.734536)
		(stroke
			(width 0.07112)
			(type default)
		)
		(layer "In4.Cu")
	)
	(gr_line
		(start 311.403492 -407.150316)
		(end 311.403492 -407.342594)
		(stroke
			(width 0.07112)
			(type default)
		)
		(layer "In4.Cu")
	)
	(gr_line
		(start 311.42559 -405.849074)
		(end 311.617614 -405.849074)
		(stroke
			(width 0.07112)
			(type default)
		)
		(layer "In4.Cu")
	)
	(gr_line
		(start 311.471564 -402.912834)
		(end 311.471564 -403.613874)
		(stroke
			(width 0.07112)
			(type default)
		)
		(layer "In4.Cu")
	)
	(gr_line
		(start 311.617614 -405.849074)
		(end 311.890918 -406.122378)
		(stroke
			(width 0.07112)
			(type default)
		)
		(layer "In4.Cu")
	)
	(gr_line
		(start 311.754774 -402.914104)
		(end 311.890664 -403.049994)
		(stroke
			(width 0.07112)
			(type default)
		)
		(layer "In4.Cu")
	)
	(gr_line
		(start 311.890664 -403.476714)
		(end 311.754774 -403.612604)
		(stroke
			(width 0.07112)
			(type default)
		)
		(layer "In4.Cu")
	)
	(gr_line
		(start 311.890664 -403.049994)
		(end 311.890664 -403.476714)
		(stroke
			(width 0.07112)
			(type default)
		)
		(layer "In4.Cu")
	)
	(gr_line
		(start 311.890918 -406.122378)
		(end 311.890918 -406.314402)
		(stroke
			(width 0.07112)
			(type default)
		)
		(layer "In4.Cu")
	)
	(gr_line
		(start 312.191146 -397.156432)
		(end 312.24347 -397.208756)
		(stroke
			(width 0.07112)
			(type default)
		)
		(layer "In4.Cu")
	)
	(gr_line
		(start 312.24347 -397.401796)
		(end 312.11012 -397.535146)
		(stroke
			(width 0.07112)
			(type default)
		)
		(layer "In4.Cu")
	)
	(gr_line
		(start 312.24347 -397.208756)
		(end 312.24347 -397.401796)
		(stroke
			(width 0.07112)
			(type default)
		)
		(layer "In4.Cu")
	)
	(gr_line
		(start 312.407554 -407.231596)
		(end 312.903362 -407.727404)
		(stroke
			(width 0.07112)
			(type default)
		)
		(layer "In4.Cu")
	)
	(gr_line
		(start 312.476134 -397.734536)
		(end 312.311288 -397.734536)
		(stroke
			(width 0.07112)
			(type default)
		)
		(layer "In4.Cu")
	)
	(gr_line
		(start 312.590942 -397.849344)
		(end 312.476134 -397.734536)
		(stroke
			(width 0.07112)
			(type default)
		)
		(layer "In4.Cu")
	)
	(gr_line
		(start 312.608722 -407.032206)
		(end 312.800746 -407.032206)
		(stroke
			(width 0.07112)
			(type default)
		)
		(layer "In4.Cu")
	)
	(gr_line
		(start 312.671714 -402.886418)
		(end 312.671714 -403.587458)
		(stroke
			(width 0.07112)
			(type default)
		)
		(layer "In4.Cu")
	)
	(gr_line
		(start 312.800746 -407.032206)
		(end 313.102752 -407.334212)
		(stroke
			(width 0.07112)
			(type default)
		)
		(layer "In4.Cu")
	)
	(gr_line
		(start 312.954924 -402.887688)
		(end 313.090814 -403.023578)
		(stroke
			(width 0.07112)
			(type default)
		)
		(layer "In4.Cu")
	)
	(gr_line
		(start 313.090814 -403.450298)
		(end 312.954924 -403.586188)
		(stroke
			(width 0.07112)
			(type default)
		)
		(layer "In4.Cu")
	)
	(gr_line
		(start 313.090814 -403.023578)
		(end 313.090814 -403.450298)
		(stroke
			(width 0.07112)
			(type default)
		)
		(layer "In4.Cu")
	)
	(gr_line
		(start 313.102752 -407.334212)
		(end 313.102752 -407.526236)
		(stroke
			(width 0.07112)
			(type default)
		)
		(layer "In4.Cu")
	)
	(gr_line
		(start 313.274456 -412.55569)
		(end 312.983626 -412.84652)
		(stroke
			(width 0.07112)
			(type default)
		)
		(layer "In4.Cu")
	)
	(gr_line
		(start 313.274456 -411.242256)
		(end 313.274456 -411.902656)
		(stroke
			(width 0.07112)
			(type default)
		)
		(layer "In4.Cu")
	)
	(gr_line
		(start 313.391042 -397.156432)
		(end 313.443366 -397.208756)
		(stroke
			(width 0.07112)
			(type default)
		)
		(layer "In4.Cu")
	)
	(gr_line
		(start 313.443366 -397.388588)
		(end 313.296808 -397.535146)
		(stroke
			(width 0.07112)
			(type default)
		)
		(layer "In4.Cu")
	)
	(gr_line
		(start 313.443366 -397.208756)
		(end 313.443366 -397.388588)
		(stroke
			(width 0.07112)
			(type default)
		)
		(layer "In4.Cu")
	)
	(gr_line
		(start 313.556396 -412.55569)
		(end 313.847226 -412.84652)
		(stroke
			(width 0.07112)
			(type default)
		)
		(layer "In4.Cu")
	)
	(gr_line
		(start 313.557666 -411.243526)
		(end 313.693556 -411.379416)
		(stroke
			(width 0.07112)
			(type default)
		)
		(layer "In4.Cu")
	)
	(gr_line
		(start 313.676284 -397.734536)
		(end 313.497976 -397.734536)
		(stroke
			(width 0.07112)
			(type default)
		)
		(layer "In4.Cu")
	)
	(gr_line
		(start 313.693556 -411.765496)
		(end 313.557666 -411.901386)
		(stroke
			(width 0.07112)
			(type default)
		)
		(layer "In4.Cu")
	)
	(gr_line
		(start 313.693556 -411.379416)
		(end 313.693556 -411.765496)
		(stroke
			(width 0.07112)
			(type default)
		)
		(layer "In4.Cu")
	)
	(gr_line
		(start 313.791092 -397.849344)
		(end 313.676284 -397.734536)
		(stroke
			(width 0.07112)
			(type default)
		)
		(layer "In4.Cu")
	)
	(gr_line
		(start 313.84748 -402.90496)
		(end 313.84748 -403.606)
		(stroke
			(width 0.07112)
			(type default)
		)
		(layer "In4.Cu")
	)
	(gr_line
		(start 314.095638 -174.572422)
		(end 314.070746 -174.54753)
		(stroke
			(width 0.07112)
			(type default)
		)
		(layer "In4.Cu")
	)
	(gr_line
		(start 314.125356 -174.590202)
		(end 314.095638 -174.572422)
		(stroke
			(width 0.07112)
			(type default)
		)
		(layer "In4.Cu")
	)
	(gr_line
		(start 314.13069 -402.90623)
		(end 314.26658 -403.04212)
		(stroke
			(width 0.07112)
			(type default)
		)
		(layer "In4.Cu")
	)
	(gr_line
		(start 314.26658 -403.46884)
		(end 314.13069 -403.60473)
		(stroke
			(width 0.07112)
			(type default)
		)
		(layer "In4.Cu")
	)
	(gr_line
		(start 314.26658 -403.04212)
		(end 314.26658 -403.46884)
		(stroke
			(width 0.07112)
			(type default)
		)
		(layer "In4.Cu")
	)
	(gr_line
		(start 314.27039 -174.34814)
		(end 314.27039 -174.348394)
		(stroke
			(width 0.07112)
			(type default)
		)
		(layer "In4.Cu")
	)
	(gr_line
		(start 314.590938 -397.156432)
		(end 314.643262 -397.208756)
		(stroke
			(width 0.07112)
			(type default)
		)
		(layer "In4.Cu")
	)
	(gr_line
		(start 314.643262 -397.388588)
		(end 314.496704 -397.535146)
		(stroke
			(width 0.07112)
			(type default)
		)
		(layer "In4.Cu")
	)
	(gr_line
		(start 314.643262 -397.208756)
		(end 314.643262 -397.388588)
		(stroke
			(width 0.07112)
			(type default)
		)
		(layer "In4.Cu")
	)
	(gr_line
		(start 314.87618 -397.734536)
		(end 314.697872 -397.734536)
		(stroke
			(width 0.07112)
			(type default)
		)
		(layer "In4.Cu")
	)
	(gr_line
		(start 314.990988 -397.849344)
		(end 314.87618 -397.734536)
		(stroke
			(width 0.07112)
			(type default)
		)
		(layer "In4.Cu")
	)
	(gr_line
		(start 315.791088 -397.156432)
		(end 315.843412 -397.208756)
		(stroke
			(width 0.07112)
			(type default)
		)
		(layer "In4.Cu")
	)
	(gr_line
		(start 315.843412 -397.388588)
		(end 315.696854 -397.535146)
		(stroke
			(width 0.07112)
			(type default)
		)
		(layer "In4.Cu")
	)
	(gr_line
		(start 315.843412 -397.208756)
		(end 315.843412 -397.388588)
		(stroke
			(width 0.07112)
			(type default)
		)
		(layer "In4.Cu")
	)
	(gr_line
		(start 316.07633 -397.734536)
		(end 315.898022 -397.734536)
		(stroke
			(width 0.07112)
			(type default)
		)
		(layer "In4.Cu")
	)
	(gr_line
		(start 316.117224 -161.440876)
		(end 316.117224 -161.385504)
		(stroke
			(width 0.07112)
			(type default)
		)
		(layer "In4.Cu")
	)
	(gr_line
		(start 316.117224 -161.374582)
		(end 316.117224 -161.374074)
		(stroke
			(width 0.07112)
			(type default)
		)
		(layer "In4.Cu")
	)
	(gr_line
		(start 316.117478 -161.442146)
		(end 316.117478 -161.441384)
		(stroke
			(width 0.07112)
			(type default)
		)
		(layer "In4.Cu")
	)
	(gr_line
		(start 316.117478 -161.441384)
		(end 316.117224 -161.440876)
		(stroke
			(width 0.07112)
			(type default)
		)
		(layer "In4.Cu")
	)
	(gr_line
		(start 316.139322 -161.49447)
		(end 316.117478 -161.442146)
		(stroke
			(width 0.07112)
			(type default)
		)
		(layer "In4.Cu")
	)
	(gr_line
		(start 316.191138 -397.849344)
		(end 316.07633 -397.734536)
		(stroke
			(width 0.07112)
			(type default)
		)
		(layer "In4.Cu")
	)
	(gr_line
		(start 316.337696 -412.55569)
		(end 316.046866 -412.84652)
		(stroke
			(width 0.07112)
			(type default)
		)
		(layer "In4.Cu")
	)
	(gr_line
		(start 316.619636 -412.55569)
		(end 316.910466 -412.84652)
		(stroke
			(width 0.07112)
			(type default)
		)
		(layer "In4.Cu")
	)
	(gr_line
		(start 316.990984 -397.156432)
		(end 317.043308 -397.208756)
		(stroke
			(width 0.07112)
			(type default)
		)
		(layer "In4.Cu")
	)
	(gr_line
		(start 317.043308 -397.388588)
		(end 316.89675 -397.535146)
		(stroke
			(width 0.07112)
			(type default)
		)
		(layer "In4.Cu")
	)
	(gr_line
		(start 317.043308 -397.208756)
		(end 317.043308 -397.388588)
		(stroke
			(width 0.07112)
			(type default)
		)
		(layer "In4.Cu")
	)
	(gr_line
		(start 317.276226 -397.734536)
		(end 317.097918 -397.734536)
		(stroke
			(width 0.07112)
			(type default)
		)
		(layer "In4.Cu")
	)
	(gr_line
		(start 317.281052 -166.990522)
		(end 317.281306 -166.990522)
		(stroke
			(width 0.07112)
			(type default)
		)
		(layer "In4.Cu")
	)
	(gr_line
		(start 317.391034 -397.849344)
		(end 317.276226 -397.734536)
		(stroke
			(width 0.07112)
			(type default)
		)
		(layer "In4.Cu")
	)
	(gr_line
		(start 317.883286 -404.337012)
		(end 318.379348 -404.833074)
		(stroke
			(width 0.07112)
			(type default)
		)
		(layer "In4.Cu")
	)
	(gr_line
		(start 318.084454 -404.137622)
		(end 318.276732 -404.137622)
		(stroke
			(width 0.07112)
			(type default)
		)
		(layer "In4.Cu")
	)
	(gr_line
		(start 318.191134 -397.156432)
		(end 318.243458 -397.208756)
		(stroke
			(width 0.07112)
			(type default)
		)
		(layer "In4.Cu")
	)
	(gr_line
		(start 318.243458 -397.405352)
		(end 318.113664 -397.535146)
		(stroke
			(width 0.07112)
			(type default)
		)
		(layer "In4.Cu")
	)
	(gr_line
		(start 318.243458 -397.208756)
		(end 318.243458 -397.405352)
		(stroke
			(width 0.07112)
			(type default)
		)
		(layer "In4.Cu")
	)
	(gr_line
		(start 318.276732 -404.137622)
		(end 318.578738 -404.439628)
		(stroke
			(width 0.07112)
			(type default)
		)
		(layer "In4.Cu")
	)
	(gr_line
		(start 318.476122 -397.734536)
		(end 318.314832 -397.734536)
		(stroke
			(width 0.07112)
			(type default)
		)
		(layer "In4.Cu")
	)
	(gr_line
		(start 318.578738 -404.439628)
		(end 318.578738 -404.631906)
		(stroke
			(width 0.07112)
			(type default)
		)
		(layer "In4.Cu")
	)
	(gr_line
		(start 318.59093 -397.849344)
		(end 318.476122 -397.734536)
		(stroke
			(width 0.07112)
			(type default)
		)
		(layer "In4.Cu")
	)
	(gr_line
		(start 318.825118 -167.14597)
		(end 318.815466 -167.136318)
		(stroke
			(width 0.07112)
			(type default)
		)
		(layer "In4.Cu")
	)
	(gr_line
		(start 318.830198 -167.150542)
		(end 318.825118 -167.14597)
		(stroke
			(width 0.07112)
			(type default)
		)
		(layer "In4.Cu")
	)
	(gr_line
		(start 319.055496 -403.732492)
		(end 319.551558 -404.228554)
		(stroke
			(width 0.07112)
			(type default)
		)
		(layer "In4.Cu")
	)
	(gr_line
		(start 319.256664 -403.533102)
		(end 319.448942 -403.533102)
		(stroke
			(width 0.07112)
			(type default)
		)
		(layer "In4.Cu")
	)
	(gr_line
		(start 319.39103 -397.156432)
		(end 319.443354 -397.208756)
		(stroke
			(width 0.07112)
			(type default)
		)
		(layer "In4.Cu")
	)
	(gr_line
		(start 319.400936 -412.55569)
		(end 319.110106 -412.84652)
		(stroke
			(width 0.07112)
			(type default)
		)
		(layer "In4.Cu")
	)
	(gr_line
		(start 319.443354 -397.388588)
		(end 319.296796 -397.535146)
		(stroke
			(width 0.07112)
			(type default)
		)
		(layer "In4.Cu")
	)
	(gr_line
		(start 319.443354 -397.208756)
		(end 319.443354 -397.388588)
		(stroke
			(width 0.07112)
			(type default)
		)
		(layer "In4.Cu")
	)
	(gr_line
		(start 319.448942 -403.533102)
		(end 319.750948 -403.835108)
		(stroke
			(width 0.07112)
			(type default)
		)
		(layer "In4.Cu")
	)
	(gr_line
		(start 319.676272 -397.734536)
		(end 319.497964 -397.734536)
		(stroke
			(width 0.07112)
			(type default)
		)
		(layer "In4.Cu")
	)
	(gr_line
		(start 319.682876 -412.55569)
		(end 319.973706 -412.84652)
		(stroke
			(width 0.07112)
			(type default)
		)
		(layer "In4.Cu")
	)
	(gr_line
		(start 319.750948 -403.835108)
		(end 319.750948 -404.027386)
		(stroke
			(width 0.07112)
			(type default)
		)
		(layer "In4.Cu")
	)
	(gr_line
		(start 319.786762 -410.655516)
		(end 320.400426 -410.90088)
		(stroke
			(width 0.07112)
			(type default)
		)
		(layer "In4.Cu")
	)
	(gr_line
		(start 319.79108 -397.849344)
		(end 319.676272 -397.734536)
		(stroke
			(width 0.07112)
			(type default)
		)
		(layer "In4.Cu")
	)
	(gr_line
		(start 319.892934 -410.39288)
		(end 320.069972 -410.317188)
		(stroke
			(width 0.07112)
			(type default)
		)
		(layer "In4.Cu")
	)
	(gr_line
		(start 320.069972 -410.317188)
		(end 320.42862 -410.460444)
		(stroke
			(width 0.07112)
			(type default)
		)
		(layer "In4.Cu")
	)
	(gr_line
		(start 320.155824 -168.221406)
		(end 320.156078 -168.221406)
		(stroke
			(width 0.07112)
			(type default)
		)
		(layer "In4.Cu")
	)
	(gr_line
		(start 320.18478 -179.038758)
		(end 320.185542 -179.039266)
		(stroke
			(width 0.07112)
			(type default)
		)
		(layer "In4.Cu")
	)
	(gr_line
		(start 320.185542 -179.039266)
		(end 320.185542 -179.039012)
		(stroke
			(width 0.07112)
			(type default)
		)
		(layer "In4.Cu")
	)
	(gr_line
		(start 320.185542 -179.039012)
		(end 320.196972 -179.046886)
		(stroke
			(width 0.07112)
			(type default)
		)
		(layer "In4.Cu")
	)
	(gr_line
		(start 320.196972 -179.046886)
		(end 320.206878 -179.055014)
		(stroke
			(width 0.07112)
			(type default)
		)
		(layer "In4.Cu")
	)
	(gr_line
		(start 320.42862 -410.460444)
		(end 320.504312 -410.637482)
		(stroke
			(width 0.07112)
			(type default)
		)
		(layer "In4.Cu")
	)
	(gr_line
		(start 320.59118 -397.156432)
		(end 320.636392 -397.201644)
		(stroke
			(width 0.07112)
			(type default)
		)
		(layer "In4.Cu")
	)
	(gr_line
		(start 320.636392 -397.381476)
		(end 320.482722 -397.535146)
		(stroke
			(width 0.07112)
			(type default)
		)
		(layer "In4.Cu")
	)
	(gr_line
		(start 320.636392 -397.201644)
		(end 320.636392 -397.381476)
		(stroke
			(width 0.07112)
			(type default)
		)
		(layer "In4.Cu")
	)
	(gr_line
		(start 320.75882 -411.04439)
		(end 321.37223 -411.289754)
		(stroke
			(width 0.07112)
			(type default)
		)
		(layer "In4.Cu")
	)
	(gr_line
		(start 320.864738 -410.781754)
		(end 321.041776 -410.705808)
		(stroke
			(width 0.07112)
			(type default)
		)
		(layer "In4.Cu")
	)
	(gr_line
		(start 320.876168 -397.734536)
		(end 320.68389 -397.734536)
		(stroke
			(width 0.07112)
			(type default)
		)
		(layer "In4.Cu")
	)
	(gr_line
		(start 320.990976 -397.849344)
		(end 320.876168 -397.734536)
		(stroke
			(width 0.07112)
			(type default)
		)
		(layer "In4.Cu")
	)
	(gr_line
		(start 321.041776 -410.705808)
		(end 321.400424 -410.849318)
		(stroke
			(width 0.07112)
			(type default)
		)
		(layer "In4.Cu")
	)
	(gr_line
		(start 321.400424 -410.849318)
		(end 321.476116 -411.026356)
		(stroke
			(width 0.07112)
			(type default)
		)
		(layer "In4.Cu")
	)
	(gr_line
		(start 321.791076 -397.156432)
		(end 321.8434 -397.208756)
		(stroke
			(width 0.07112)
			(type default)
		)
		(layer "In4.Cu")
	)
	(gr_line
		(start 321.8434 -397.388588)
		(end 321.696842 -397.535146)
		(stroke
			(width 0.07112)
			(type default)
		)
		(layer "In4.Cu")
	)
	(gr_line
		(start 321.8434 -397.208756)
		(end 321.8434 -397.388588)
		(stroke
			(width 0.07112)
			(type default)
		)
		(layer "In4.Cu")
	)
	(gr_line
		(start 322.076318 -397.734536)
		(end 321.89801 -397.734536)
		(stroke
			(width 0.07112)
			(type default)
		)
		(layer "In4.Cu")
	)
	(gr_line
		(start 322.191126 -397.849344)
		(end 322.076318 -397.734536)
		(stroke
			(width 0.07112)
			(type default)
		)
		(layer "In4.Cu")
	)
	(gr_line
		(start 322.223638 -410.272738)
		(end 322.853558 -410.473144)
		(stroke
			(width 0.07112)
			(type default)
		)
		(layer "In4.Cu")
	)
	(gr_line
		(start 322.310506 -410.00299)
		(end 322.481702 -409.914598)
		(stroke
			(width 0.07112)
			(type default)
		)
		(layer "In4.Cu")
	)
	(gr_line
		(start 322.464176 -412.55569)
		(end 322.173346 -412.84652)
		(stroke
			(width 0.07112)
			(type default)
		)
		(layer "In4.Cu")
	)
	(gr_line
		(start 322.481702 -409.914598)
		(end 322.849748 -410.031692)
		(stroke
			(width 0.07112)
			(type default)
		)
		(layer "In4.Cu")
	)
	(gr_line
		(start 322.737734 -403.361398)
		(end 323.378576 -403.521926)
		(stroke
			(width 0.07112)
			(type default)
		)
		(layer "In4.Cu")
	)
	(gr_line
		(start 322.746116 -412.55569)
		(end 323.036946 -412.84652)
		(stroke
			(width 0.07112)
			(type default)
		)
		(layer "In4.Cu")
	)
	(gr_line
		(start 322.807584 -403.086824)
		(end 322.972684 -402.988018)
		(stroke
			(width 0.07112)
			(type default)
		)
		(layer "In4.Cu")
	)
	(gr_line
		(start 322.849748 -410.031692)
		(end 322.93814 -410.202888)
		(stroke
			(width 0.07112)
			(type default)
		)
		(layer "In4.Cu")
	)
	(gr_line
		(start 322.972684 -402.988018)
		(end 323.347334 -403.081744)
		(stroke
			(width 0.07112)
			(type default)
		)
		(layer "In4.Cu")
	)
	(gr_line
		(start 323.22135 -410.590238)
		(end 323.332348 -410.625544)
		(stroke
			(width 0.07112)
			(type default)
		)
		(layer "In4.Cu")
	)
	(gr_line
		(start 323.26326 -170.08856)
		(end 323.263514 -170.08856)
		(stroke
			(width 0.07112)
			(type default)
		)
		(layer "In4.Cu")
	)
	(gr_line
		(start 323.307964 -410.32049)
		(end 323.47916 -410.232098)
		(stroke
			(width 0.07112)
			(type default)
		)
		(layer "In4.Cu")
	)
	(gr_line
		(start 323.332348 -410.625544)
		(end 323.332602 -410.625544)
		(stroke
			(width 0.07112)
			(type default)
		)
		(layer "In4.Cu")
	)
	(gr_line
		(start 323.332602 -410.625544)
		(end 323.850762 -410.79039)
		(stroke
			(width 0.07112)
			(type default)
		)
		(layer "In4.Cu")
	)
	(gr_line
		(start 323.347334 -403.081744)
		(end 323.446394 -403.246844)
		(stroke
			(width 0.07112)
			(type default)
		)
		(layer "In4.Cu")
	)
	(gr_line
		(start 323.39407 -168.68394)
		(end 323.66458 -168.86555)
		(stroke
			(width 0.07112)
			(type default)
		)
		(layer "In4.Cu")
	)
	(gr_line
		(start 323.408548 -169.846498)
		(end 323.41439 -169.850054)
		(stroke
			(width 0.07112)
			(type default)
		)
		(layer "In4.Cu")
	)
	(gr_line
		(start 323.41439 -169.850054)
		(end 323.414898 -169.850308)
		(stroke
			(width 0.07112)
			(type default)
		)
		(layer "In4.Cu")
	)
	(gr_line
		(start 323.414898 -169.850308)
		(end 323.420486 -169.854118)
		(stroke
			(width 0.07112)
			(type default)
		)
		(layer "In4.Cu")
	)
	(gr_line
		(start 323.47916 -410.232098)
		(end 323.847206 -410.349192)
		(stroke
			(width 0.07112)
			(type default)
		)
		(layer "In4.Cu")
	)
	(gr_line
		(start 323.503544 -169.10177)
		(end 323.23532 -168.918636)
		(stroke
			(width 0.07112)
			(type default)
		)
		(layer "In4.Cu")
	)
	(gr_line
		(start 323.506084 -169.1005)
		(end 323.503544 -169.10177)
		(stroke
			(width 0.07112)
			(type default)
		)
		(layer "In4.Cu")
	)
	(gr_line
		(start 323.847206 -410.349192)
		(end 323.935344 -410.520134)
		(stroke
			(width 0.07112)
			(type default)
		)
		(layer "In4.Cu")
	)
	(gr_line
		(start 323.850762 -410.79039)
		(end 323.851016 -410.790644)
		(stroke
			(width 0.07112)
			(type default)
		)
		(layer "In4.Cu")
	)
	(gr_line
		(start 324.130416 -174.074582)
		(end 324.130416 -174.074836)
		(stroke
			(width 0.07112)
			(type default)
		)
		(layer "In4.Cu")
	)
	(gr_line
		(start 325.37146 -404.02129)
		(end 326.012556 -404.181818)
		(stroke
			(width 0.07112)
			(type default)
		)
		(layer "In4.Cu")
	)
	(gr_line
		(start 325.44131 -403.746716)
		(end 325.60641 -403.64791)
		(stroke
			(width 0.07112)
			(type default)
		)
		(layer "In4.Cu")
	)
	(gr_line
		(start 325.480172 -412.602934)
		(end 325.236586 -412.84652)
		(stroke
			(width 0.07112)
			(type default)
		)
		(layer "In4.Cu")
	)
	(gr_arc
		(start 325.480172 -412.602934)
		(mid 325.515146 -412.550613)
		(end 325.527416 -412.488888)
		(stroke
			(width 0.07112)
			(type default)
		)
		(layer "In4.Cu")
	)
	(gr_line
		(start 325.541386 -412.488888)
		(end 325.527416 -412.488888)
		(stroke
			(width 0.07112)
			(type default)
		)
		(layer "In4.Cu")
	)
	(gr_line
		(start 325.60641 -403.64791)
		(end 325.981314 -403.741636)
		(stroke
			(width 0.07112)
			(type default)
		)
		(layer "In4.Cu")
	)
	(gr_arc
		(start 325.824596 -412.504128)
		(mid 325.836882 -412.565846)
		(end 325.87184 -412.618174)
		(stroke
			(width 0.07112)
			(type default)
		)
		(layer "In4.Cu")
	)
	(gr_line
		(start 325.824596 -412.488888)
		(end 325.824596 -412.504128)
		(stroke
			(width 0.07112)
			(type default)
		)
		(layer "In4.Cu")
	)
	(gr_line
		(start 325.87184 -412.618174)
		(end 326.100186 -412.84652)
		(stroke
			(width 0.07112)
			(type default)
		)
		(layer "In4.Cu")
	)
	(gr_line
		(start 325.981314 -403.741636)
		(end 326.080374 -403.906736)
		(stroke
			(width 0.07112)
			(type default)
		)
		(layer "In4.Cu")
	)
	(gr_line
		(start 326.561958 -410.653738)
		(end 327.17232 -410.906722)
		(stroke
			(width 0.07112)
			(type default)
		)
		(layer "In4.Cu")
	)
	(gr_line
		(start 326.671178 -410.392626)
		(end 326.849232 -410.318966)
		(stroke
			(width 0.07112)
			(type default)
		)
		(layer "In4.Cu")
	)
	(gr_line
		(start 326.72909 -172.069506)
		(end 326.746362 -172.080936)
		(stroke
			(width 0.07112)
			(type default)
		)
		(layer "In4.Cu")
	)
	(gr_line
		(start 326.746362 -172.080936)
		(end 326.761602 -172.094906)
		(stroke
			(width 0.07112)
			(type default)
		)
		(layer "In4.Cu")
	)
	(gr_line
		(start 326.761602 -172.094906)
		(end 326.761602 -172.09516)
		(stroke
			(width 0.07112)
			(type default)
		)
		(layer "In4.Cu")
	)
	(gr_line
		(start 326.778366 -409.598368)
		(end 327.400158 -409.821888)
		(stroke
			(width 0.07112)
			(type default)
		)
		(layer "In4.Cu")
	)
	(gr_line
		(start 326.849232 -410.318966)
		(end 327.206102 -410.46654)
		(stroke
			(width 0.07112)
			(type default)
		)
		(layer "In4.Cu")
	)
	(gr_line
		(start 326.87514 -409.332176)
		(end 327.049384 -409.250134)
		(stroke
			(width 0.07112)
			(type default)
		)
		(layer "In4.Cu")
	)
	(gr_line
		(start 327.049384 -409.250134)
		(end 327.412858 -409.38069)
		(stroke
			(width 0.07112)
			(type default)
		)
		(layer "In4.Cu")
	)
	(gr_line
		(start 327.206102 -410.46654)
		(end 327.279762 -410.644594)
		(stroke
			(width 0.07112)
			(type default)
		)
		(layer "In4.Cu")
	)
	(gr_line
		(start 327.412858 -409.38069)
		(end 327.495154 -409.555188)
		(stroke
			(width 0.07112)
			(type default)
		)
		(layer "In4.Cu")
	)
	(gr_line
		(start 327.528936 -411.05455)
		(end 328.139298 -411.30728)
		(stroke
			(width 0.07112)
			(type default)
		)
		(layer "In4.Cu")
	)
	(gr_line
		(start 327.638156 -410.793184)
		(end 327.81621 -410.719524)
		(stroke
			(width 0.07112)
			(type default)
		)
		(layer "In4.Cu")
	)
	(gr_line
		(start 327.81621 -410.719524)
		(end 328.17308 -410.867098)
		(stroke
			(width 0.07112)
			(type default)
		)
		(layer "In4.Cu")
	)
	(gr_line
		(start 328.17308 -410.867098)
		(end 328.24674 -411.045152)
		(stroke
			(width 0.07112)
			(type default)
		)
		(layer "In4.Cu")
	)
	(gr_line
		(start 328.45756 -386.342128)
		(end 328.45756 -387.043168)
		(stroke
			(width 0.07112)
			(type default)
		)
		(layer "In4.Cu")
	)
	(gr_line
		(start 328.45756 -383.266442)
		(end 328.45756 -383.967482)
		(stroke
			(width 0.07112)
			(type default)
		)
		(layer "In4.Cu")
	)
	(gr_line
		(start 328.45756 -382.138682)
		(end 328.45756 -382.839722)
		(stroke
			(width 0.07112)
			(type default)
		)
		(layer "In4.Cu")
	)
	(gr_line
		(start 328.45756 -380.07798)
		(end 328.45756 -380.77902)
		(stroke
			(width 0.07112)
			(type default)
		)
		(layer "In4.Cu")
	)
	(gr_line
		(start 328.590656 -412.55569)
		(end 328.299826 -412.84652)
		(stroke
			(width 0.07112)
			(type default)
		)
		(layer "In4.Cu")
	)
	(gr_line
		(start 328.720704 -410.297122)
		(end 329.342242 -410.520896)
		(stroke
			(width 0.07112)
			(type default)
		)
		(layer "In4.Cu")
	)
	(gr_line
		(start 328.74077 -386.343398)
		(end 328.87666 -386.479288)
		(stroke
			(width 0.07112)
			(type default)
		)
		(layer "In4.Cu")
	)
	(gr_line
		(start 328.74077 -383.267712)
		(end 328.87666 -383.403602)
		(stroke
			(width 0.07112)
			(type default)
		)
		(layer "In4.Cu")
	)
	(gr_line
		(start 328.74077 -382.139952)
		(end 328.87666 -382.275842)
		(stroke
			(width 0.07112)
			(type default)
		)
		(layer "In4.Cu")
	)
	(gr_line
		(start 328.74077 -380.07925)
		(end 328.87666 -380.21514)
		(stroke
			(width 0.07112)
			(type default)
		)
		(layer "In4.Cu")
	)
	(gr_line
		(start 328.817732 -410.03093)
		(end 328.991722 -409.948888)
		(stroke
			(width 0.07112)
			(type default)
		)
		(layer "In4.Cu")
	)
	(gr_line
		(start 328.872596 -412.55569)
		(end 329.163426 -412.84652)
		(stroke
			(width 0.07112)
			(type default)
		)
		(layer "In4.Cu")
	)
	(gr_line
		(start 328.87666 -386.906008)
		(end 328.74077 -387.041898)
		(stroke
			(width 0.07112)
			(type default)
		)
		(layer "In4.Cu")
	)
	(gr_line
		(start 328.87666 -386.479288)
		(end 328.87666 -386.906008)
		(stroke
			(width 0.07112)
			(type default)
		)
		(layer "In4.Cu")
	)
	(gr_line
		(start 328.87666 -383.830322)
		(end 328.74077 -383.966212)
		(stroke
			(width 0.07112)
			(type default)
		)
		(layer "In4.Cu")
	)
	(gr_line
		(start 328.87666 -383.403602)
		(end 328.87666 -383.830322)
		(stroke
			(width 0.07112)
			(type default)
		)
		(layer "In4.Cu")
	)
	(gr_line
		(start 328.87666 -382.702562)
		(end 328.74077 -382.838452)
		(stroke
			(width 0.07112)
			(type default)
		)
		(layer "In4.Cu")
	)
	(gr_line
		(start 328.87666 -382.275842)
		(end 328.87666 -382.702562)
		(stroke
			(width 0.07112)
			(type default)
		)
		(layer "In4.Cu")
	)
	(gr_line
		(start 328.87666 -380.64186)
		(end 328.74077 -380.77775)
		(stroke
			(width 0.07112)
			(type default)
		)
		(layer "In4.Cu")
	)
	(gr_line
		(start 328.87666 -380.21514)
		(end 328.87666 -380.64186)
		(stroke
			(width 0.07112)
			(type default)
		)
		(layer "In4.Cu")
	)
	(gr_line
		(start 328.991722 -409.948888)
		(end 329.355196 -410.079698)
		(stroke
			(width 0.07112)
			(type default)
		)
		(layer "In4.Cu")
	)
	(gr_line
		(start 329.355196 -410.079698)
		(end 329.436984 -410.253942)
		(stroke
			(width 0.07112)
			(type default)
		)
		(layer "In4.Cu")
	)
	(gr_line
		(start 329.667362 -390.46023)
		(end 329.958192 -390.75106)
		(stroke
			(width 0.07112)
			(type default)
		)
		(layer "In4.Cu")
	)
	(gr_line
		(start 329.667362 -390.17829)
		(end 329.958192 -389.88746)
		(stroke
			(width 0.07112)
			(type default)
		)
		(layer "In4.Cu")
	)
	(gr_line
		(start 329.904852 -380.734316)
		(end 330.040742 -380.870206)
		(stroke
			(width 0.07112)
			(type default)
		)
		(layer "In4.Cu")
	)
	(gr_line
		(start 329.904852 -380.307596)
		(end 329.904852 -380.734316)
		(stroke
			(width 0.07112)
			(type default)
		)
		(layer "In4.Cu")
	)
	(gr_line
		(start 329.904852 -379.606556)
		(end 330.040742 -379.742446)
		(stroke
			(width 0.07112)
			(type default)
		)
		(layer "In4.Cu")
	)
	(gr_line
		(start 329.904852 -379.179836)
		(end 329.904852 -379.606556)
		(stroke
			(width 0.07112)
			(type default)
		)
		(layer "In4.Cu")
	)
	(gr_line
		(start 329.904852 -378.478796)
		(end 330.040742 -378.614686)
		(stroke
			(width 0.07112)
			(type default)
		)
		(layer "In4.Cu")
	)
	(gr_line
		(start 329.904852 -378.052076)
		(end 329.904852 -378.478796)
		(stroke
			(width 0.07112)
			(type default)
		)
		(layer "In4.Cu")
	)
	(gr_line
		(start 330.040742 -380.171706)
		(end 329.904852 -380.307596)
		(stroke
			(width 0.07112)
			(type default)
		)
		(layer "In4.Cu")
	)
	(gr_line
		(start 330.040742 -379.043946)
		(end 329.904852 -379.179836)
		(stroke
			(width 0.07112)
			(type default)
		)
		(layer "In4.Cu")
	)
	(gr_line
		(start 330.040742 -377.916186)
		(end 329.904852 -378.052076)
		(stroke
			(width 0.07112)
			(type default)
		)
		(layer "In4.Cu")
	)
	(gr_line
		(start 330.249022 -384.92303)
		(end 329.958192 -385.21386)
		(stroke
			(width 0.07112)
			(type default)
		)
		(layer "In4.Cu")
	)
	(gr_line
		(start 330.249022 -384.64109)
		(end 329.958192 -384.35026)
		(stroke
			(width 0.07112)
			(type default)
		)
		(layer "In4.Cu")
	)
	(gr_line
		(start 330.323952 -380.170436)
		(end 330.323952 -380.871476)
		(stroke
			(width 0.07112)
			(type default)
		)
		(layer "In4.Cu")
	)
	(gr_line
		(start 330.323952 -379.042676)
		(end 330.323952 -379.743716)
		(stroke
			(width 0.07112)
			(type default)
		)
		(layer "In4.Cu")
	)
	(gr_line
		(start 330.323952 -377.914916)
		(end 330.323952 -378.615956)
		(stroke
			(width 0.07112)
			(type default)
		)
		(layer "In4.Cu")
	)
	(gr_line
		(start 330.36764 -411.008576)
		(end 330.92136 -411.367986)
		(stroke
			(width 0.07112)
			(type default)
		)
		(layer "In4.Cu")
	)
	(gr_line
		(start 330.522326 -410.77134)
		(end 330.71054 -410.731208)
		(stroke
			(width 0.07112)
			(type default)
		)
		(layer "In4.Cu")
	)
	(gr_line
		(start 330.71054 -410.731208)
		(end 331.034644 -410.94152)
		(stroke
			(width 0.07112)
			(type default)
		)
		(layer "In4.Cu")
	)
	(gr_line
		(start 330.92136 -411.367986)
		(end 330.921868 -411.36824)
		(stroke
			(width 0.07112)
			(type default)
		)
		(layer "In4.Cu")
	)
	(gr_line
		(start 331.034644 -410.94152)
		(end 331.074776 -411.129988)
		(stroke
			(width 0.07112)
			(type default)
		)
		(layer "In4.Cu")
	)
	(gr_line
		(start 331.043534 -383.759964)
		(end 331.153008 -383.869438)
		(stroke
			(width 0.07112)
			(type default)
		)
		(layer "In4.Cu")
	)
	(gr_line
		(start 331.043534 -383.333244)
		(end 331.043534 -383.759964)
		(stroke
			(width 0.07112)
			(type default)
		)
		(layer "In4.Cu")
	)
	(gr_line
		(start 331.07503 -411.131512)
		(end 331.075538 -411.131766)
		(stroke
			(width 0.07112)
			(type default)
		)
		(layer "In4.Cu")
	)
	(gr_line
		(start 331.153008 -383.22377)
		(end 331.043534 -383.333244)
		(stroke
			(width 0.07112)
			(type default)
		)
		(layer "In4.Cu")
	)
	(gr_line
		(start 331.436218 -383.2225)
		(end 331.436218 -383.870708)
		(stroke
			(width 0.07112)
			(type default)
		)
		(layer "In4.Cu")
	)
	(gr_line
		(start 331.653896 -412.55569)
		(end 331.363066 -412.84652)
		(stroke
			(width 0.07112)
			(type default)
		)
		(layer "In4.Cu")
	)
	(gr_line
		(start 331.831696 -404.578566)
		(end 332.50759 -404.765764)
		(stroke
			(width 0.07112)
			(type default)
		)
		(layer "In4.Cu")
	)
	(gr_line
		(start 331.833474 -379.5903)
		(end 331.542644 -379.88113)
		(stroke
			(width 0.07112)
			(type default)
		)
		(layer "In4.Cu")
	)
	(gr_line
		(start 331.869288 -410.214572)
		(end 332.479904 -410.467048)
		(stroke
			(width 0.07112)
			(type default)
		)
		(layer "In4.Cu")
	)
	(gr_line
		(start 331.90815 -404.306024)
		(end 332.075536 -404.211028)
		(stroke
			(width 0.07112)
			(type default)
		)
		(layer "In4.Cu")
	)
	(gr_line
		(start 331.935836 -412.55569)
		(end 332.226666 -412.84652)
		(stroke
			(width 0.07112)
			(type default)
		)
		(layer "In4.Cu")
	)
	(gr_line
		(start 331.978 -409.953206)
		(end 332.156054 -409.879292)
		(stroke
			(width 0.07112)
			(type default)
		)
		(layer "In4.Cu")
	)
	(gr_line
		(start 332.075536 -404.211028)
		(end 332.487016 -404.325074)
		(stroke
			(width 0.07112)
			(type default)
		)
		(layer "In4.Cu")
	)
	(gr_line
		(start 332.115414 -379.5903)
		(end 332.406244 -379.88113)
		(stroke
			(width 0.07112)
			(type default)
		)
		(layer "In4.Cu")
	)
	(gr_line
		(start 332.156054 -409.879292)
		(end 332.513178 -410.026866)
		(stroke
			(width 0.07112)
			(type default)
		)
		(layer "In4.Cu")
	)
	(gr_line
		(start 332.487016 -404.325074)
		(end 332.582012 -404.49246)
		(stroke
			(width 0.07112)
			(type default)
		)
		(layer "In4.Cu")
	)
	(gr_line
		(start 332.513178 -410.026866)
		(end 332.587092 -410.20492)
		(stroke
			(width 0.07112)
			(type default)
		)
		(layer "In4.Cu")
	)
	(gr_line
		(start 332.83652 -410.614368)
		(end 333.447136 -410.86659)
		(stroke
			(width 0.07112)
			(type default)
		)
		(layer "In4.Cu")
	)
	(gr_line
		(start 332.945486 -410.353002)
		(end 333.123286 -410.279088)
		(stroke
			(width 0.07112)
			(type default)
		)
		(layer "In4.Cu")
	)
	(gr_line
		(start 333.123286 -410.279088)
		(end 333.48041 -410.426662)
		(stroke
			(width 0.07112)
			(type default)
		)
		(layer "In4.Cu")
	)
	(gr_line
		(start 333.48041 -410.426662)
		(end 333.554324 -410.604462)
		(stroke
			(width 0.07112)
			(type default)
		)
		(layer "In4.Cu")
	)
	(gr_line
		(start 333.535274 -377.1265)
		(end 333.244444 -377.41733)
		(stroke
			(width 0.07112)
			(type default)
		)
		(layer "In4.Cu")
	)
	(gr_line
		(start 333.817214 -377.1265)
		(end 334.108044 -377.41733)
		(stroke
			(width 0.07112)
			(type default)
		)
		(layer "In4.Cu")
	)
	(gr_line
		(start 334.15986 -411.342586)
		(end 334.62722 -411.809946)
		(stroke
			(width 0.07112)
			(type default)
		)
		(layer "In4.Cu")
	)
	(gr_line
		(start 334.166972 -409.745942)
		(end 334.84693 -410.027628)
		(stroke
			(width 0.07112)
			(type default)
		)
		(layer "In4.Cu")
	)
	(gr_line
		(start 334.275684 -409.484576)
		(end 334.453738 -409.410916)
		(stroke
			(width 0.07112)
			(type default)
		)
		(layer "In4.Cu")
	)
	(gr_line
		(start 334.361028 -411.143196)
		(end 334.553306 -411.143196)
		(stroke
			(width 0.07112)
			(type default)
		)
		(layer "In4.Cu")
	)
	(gr_line
		(start 334.44434 -407.689812)
		(end 335.09458 -407.922222)
		(stroke
			(width 0.07112)
			(type default)
		)
		(layer "In4.Cu")
	)
	(gr_line
		(start 334.453738 -409.410916)
		(end 334.8482 -409.574238)
		(stroke
			(width 0.07112)
			(type default)
		)
		(layer "In4.Cu")
	)
	(gr_line
		(start 334.506824 -407.412698)
		(end 334.520032 -407.416762)
		(stroke
			(width 0.07112)
			(type default)
		)
		(layer "In4.Cu")
	)
	(gr_line
		(start 334.529684 -407.419556)
		(end 334.704944 -407.336752)
		(stroke
			(width 0.07112)
			(type default)
		)
		(layer "In4.Cu")
	)
	(gr_line
		(start 334.553306 -411.143196)
		(end 334.82661 -411.4165)
		(stroke
			(width 0.07112)
			(type default)
		)
		(layer "In4.Cu")
	)
	(gr_line
		(start 334.704944 -407.336752)
		(end 335.106772 -407.480516)
		(stroke
			(width 0.07112)
			(type default)
		)
		(layer "In4.Cu")
	)
	(gr_line
		(start 334.717136 -412.55569)
		(end 334.426306 -412.84652)
		(stroke
			(width 0.07112)
			(type default)
		)
		(layer "In4.Cu")
	)
	(gr_line
		(start 334.82661 -411.4165)
		(end 334.82661 -411.608778)
		(stroke
			(width 0.07112)
			(type default)
		)
		(layer "In4.Cu")
	)
	(gr_line
		(start 334.8482 -409.574238)
		(end 334.896968 -409.692094)
		(stroke
			(width 0.07112)
			(type default)
		)
		(layer "In4.Cu")
	)
	(gr_arc
		(start 334.896968 -409.692094)
		(mid 334.92528 -409.737326)
		(end 334.966818 -409.770834)
		(stroke
			(width 0.07112)
			(type default)
		)
		(layer "In4.Cu")
	)
	(gr_line
		(start 334.907636 -405.429974)
		(end 335.583784 -405.617172)
		(stroke
			(width 0.07112)
			(type default)
		)
		(layer "In4.Cu")
	)
	(gr_line
		(start 334.984344 -405.157432)
		(end 335.151476 -405.062436)
		(stroke
			(width 0.07112)
			(type default)
		)
		(layer "In4.Cu")
	)
	(gr_line
		(start 334.999076 -412.55569)
		(end 335.289906 -412.84652)
		(stroke
			(width 0.07112)
			(type default)
		)
		(layer "In4.Cu")
	)
	(gr_line
		(start 335.106772 -407.480516)
		(end 335.189576 -407.655522)
		(stroke
			(width 0.07112)
			(type default)
		)
		(layer "In4.Cu")
	)
	(gr_line
		(start 335.151476 -405.062436)
		(end 335.56321 -405.176228)
		(stroke
			(width 0.07112)
			(type default)
		)
		(layer "In4.Cu")
	)
	(gr_line
		(start 335.56321 -405.176228)
		(end 335.657698 -405.343868)
		(stroke
			(width 0.07112)
			(type default)
		)
		(layer "In4.Cu")
	)
	(gr_line
		(start 335.65846 -410.363924)
		(end 336.269076 -410.616654)
		(stroke
			(width 0.07112)
			(type default)
		)
		(layer "In4.Cu")
	)
	(gr_line
		(start 335.658714 -405.345392)
		(end 335.658968 -405.345392)
		(stroke
			(width 0.07112)
			(type default)
		)
		(layer "In4.Cu")
	)
	(gr_line
		(start 335.767934 -410.102558)
		(end 335.945734 -410.028898)
		(stroke
			(width 0.07112)
			(type default)
		)
		(layer "In4.Cu")
	)
	(gr_line
		(start 335.945734 -410.028898)
		(end 336.302604 -410.176726)
		(stroke
			(width 0.07112)
			(type default)
		)
		(layer "In4.Cu")
	)
	(gr_line
		(start 336.302604 -410.176726)
		(end 336.376518 -410.354526)
		(stroke
			(width 0.07112)
			(type default)
		)
		(layer "In4.Cu")
	)
	(gr_line
		(start 336.89163 -382.101344)
		(end 336.648044 -382.34493)
		(stroke
			(width 0.07112)
			(type default)
		)
		(layer "In4.Cu")
	)
	(gr_arc
		(start 336.89163 -382.101344)
		(mid 336.923072 -382.056934)
		(end 336.937858 -382.00457)
		(stroke
			(width 0.07112)
			(type default)
		)
		(layer "In4.Cu")
	)
	(gr_arc
		(start 337.22183 -382.00457)
		(mid 337.236687 -382.056901)
		(end 337.268058 -382.101344)
		(stroke
			(width 0.07112)
			(type default)
		)
		(layer "In4.Cu")
	)
	(gr_line
		(start 337.268058 -382.101344)
		(end 337.511644 -382.34493)
		(stroke
			(width 0.07112)
			(type default)
		)
		(layer "In4.Cu")
	)
	(gr_line
		(start 337.643216 -406.187148)
		(end 338.31911 -406.374092)
		(stroke
			(width 0.07112)
			(type default)
		)
		(layer "In4.Cu")
	)
	(gr_line
		(start 337.710018 -407.510488)
		(end 338.342224 -407.702258)
		(stroke
			(width 0.07112)
			(type default)
		)
		(layer "In4.Cu")
	)
	(gr_line
		(start 337.719924 -405.914606)
		(end 337.887056 -405.81961)
		(stroke
			(width 0.07112)
			(type default)
		)
		(layer "In4.Cu")
	)
	(gr_line
		(start 337.780376 -412.55569)
		(end 337.489546 -412.84652)
		(stroke
			(width 0.07112)
			(type default)
		)
		(layer "In4.Cu")
	)
	(gr_line
		(start 337.793076 -407.239724)
		(end 337.917282 -407.17343)
		(stroke
			(width 0.07112)
			(type default)
		)
		(layer "In4.Cu")
	)
	(gr_line
		(start 337.887056 -405.81961)
		(end 338.298536 -405.933402)
		(stroke
			(width 0.07112)
			(type default)
		)
		(layer "In4.Cu")
	)
	(gr_line
		(start 337.917282 -407.17343)
		(end 338.356956 -407.30678)
		(stroke
			(width 0.07112)
			(type default)
		)
		(layer "In4.Cu")
	)
	(gr_line
		(start 338.062316 -412.55569)
		(end 338.353146 -412.84652)
		(stroke
			(width 0.07112)
			(type default)
		)
		(layer "In4.Cu")
	)
	(gr_line
		(start 338.298536 -405.933402)
		(end 338.393278 -406.100788)
		(stroke
			(width 0.07112)
			(type default)
		)
		(layer "In4.Cu")
	)
	(gr_line
		(start 338.299806 -176.202848)
		(end 338.299806 -176.202594)
		(stroke
			(width 0.07112)
			(type default)
		)
		(layer "In4.Cu")
	)
	(gr_line
		(start 338.356956 -407.30678)
		(end 338.42325 -407.430986)
		(stroke
			(width 0.07112)
			(type default)
		)
		(layer "In4.Cu")
	)
	(gr_line
		(start 338.394294 -406.102566)
		(end 338.394294 -406.102312)
		(stroke
			(width 0.07112)
			(type default)
		)
		(layer "In4.Cu")
	)
	(gr_line
		(start 338.43087 -410.295598)
		(end 339.079078 -410.564076)
		(stroke
			(width 0.07112)
			(type default)
		)
		(layer "In4.Cu")
	)
	(gr_line
		(start 338.511896 -409.14447)
		(end 339.17255 -409.38069)
		(stroke
			(width 0.07112)
			(type default)
		)
		(layer "In4.Cu")
	)
	(gr_line
		(start 338.53882 -410.03474)
		(end 338.53882 -410.034994)
		(stroke
			(width 0.07112)
			(type default)
		)
		(layer "In4.Cu")
	)
	(gr_line
		(start 338.540344 -410.034232)
		(end 338.71789 -409.960572)
		(stroke
			(width 0.07112)
			(type default)
		)
		(layer "In4.Cu")
	)
	(gr_line
		(start 338.608162 -408.878024)
		(end 338.782406 -408.795728)
		(stroke
			(width 0.07112)
			(type default)
		)
		(layer "In4.Cu")
	)
	(gr_line
		(start 338.640674 -379.5903)
		(end 338.349844 -379.88113)
		(stroke
			(width 0.07112)
			(type default)
		)
		(layer "In4.Cu")
	)
	(gr_line
		(start 338.71789 -409.960572)
		(end 339.112352 -410.123894)
		(stroke
			(width 0.07112)
			(type default)
		)
		(layer "In4.Cu")
	)
	(gr_line
		(start 338.782406 -408.795728)
		(end 339.184488 -408.939492)
		(stroke
			(width 0.07112)
			(type default)
		)
		(layer "In4.Cu")
	)
	(gr_line
		(start 338.922614 -379.5903)
		(end 339.213444 -379.88113)
		(stroke
			(width 0.07112)
			(type default)
		)
		(layer "In4.Cu")
	)
	(gr_line
		(start 339.112352 -410.123894)
		(end 339.186012 -410.301948)
		(stroke
			(width 0.07112)
			(type default)
		)
		(layer "In4.Cu")
	)
	(gr_line
		(start 339.17255 -409.38069)
		(end 339.172804 -409.38069)
		(stroke
			(width 0.07112)
			(type default)
		)
		(layer "In4.Cu")
	)
	(gr_line
		(start 339.184488 -408.939492)
		(end 339.266784 -409.113736)
		(stroke
			(width 0.07112)
			(type default)
		)
		(layer "In4.Cu")
	)
	(gr_line
		(start 339.473032 -410.727398)
		(end 340.120732 -410.995368)
		(stroke
			(width 0.07112)
			(type default)
		)
		(layer "In4.Cu")
	)
	(gr_line
		(start 339.582252 -410.466032)
		(end 339.760052 -410.392372)
		(stroke
			(width 0.07112)
			(type default)
		)
		(layer "In4.Cu")
	)
	(gr_line
		(start 339.621114 -409.540964)
		(end 340.24316 -409.763468)
		(stroke
			(width 0.07112)
			(type default)
		)
		(layer "In4.Cu")
	)
	(gr_line
		(start 339.717634 -409.274772)
		(end 339.891624 -409.192476)
		(stroke
			(width 0.07112)
			(type default)
		)
		(layer "In4.Cu")
	)
	(gr_line
		(start 339.760052 -410.392372)
		(end 340.154514 -410.555694)
		(stroke
			(width 0.07112)
			(type default)
		)
		(layer "In4.Cu")
	)
	(gr_line
		(start 339.891624 -409.192476)
		(end 340.255352 -409.322524)
		(stroke
			(width 0.07112)
			(type default)
		)
		(layer "In4.Cu")
	)
	(gr_line
		(start 340.154514 -410.555694)
		(end 340.22792 -410.733494)
		(stroke
			(width 0.07112)
			(type default)
		)
		(layer "In4.Cu")
	)
	(gr_line
		(start 340.228682 -410.735272)
		(end 340.228682 -410.734764)
		(stroke
			(width 0.07112)
			(type default)
		)
		(layer "In4.Cu")
	)
	(gr_line
		(start 340.255352 -409.322524)
		(end 340.337394 -409.496514)
		(stroke
			(width 0.07112)
			(type default)
		)
		(layer "In4.Cu")
	)
	(gr_line
		(start 340.342474 -377.1265)
		(end 340.051644 -377.41733)
		(stroke
			(width 0.07112)
			(type default)
		)
		(layer "In4.Cu")
	)
	(gr_arc
		(start 340.342474 -376.586496)
		(mid 340.342474 -376.586242)
		(end 340.342474 -376.585988)
		(stroke
			(width 0.07112)
			(type default)
		)
		(layer "In4.Cu")
	)
	(gr_line
		(start 340.624414 -377.1265)
		(end 340.915244 -377.41733)
		(stroke
			(width 0.07112)
			(type default)
		)
		(layer "In4.Cu")
	)
	(gr_line
		(start 340.843616 -412.55569)
		(end 340.552786 -412.84652)
		(stroke
			(width 0.07112)
			(type default)
		)
		(layer "In4.Cu")
	)
	(gr_line
		(start 341.125556 -412.55569)
		(end 341.416386 -412.84652)
		(stroke
			(width 0.07112)
			(type default)
		)
		(layer "In4.Cu")
	)
	(gr_line
		(start 342.784684 -409.476448)
		(end 343.395046 -409.729178)
		(stroke
			(width 0.07112)
			(type default)
		)
		(layer "In4.Cu")
	)
	(gr_line
		(start 342.893904 -409.215082)
		(end 343.033858 -409.15717)
		(stroke
			(width 0.07112)
			(type default)
		)
		(layer "In4.Cu")
	)
	(gr_line
		(start 343.033858 -409.15717)
		(end 343.444322 -409.327096)
		(stroke
			(width 0.07112)
			(type default)
		)
		(layer "In4.Cu")
	)
	(gr_line
		(start 343.444322 -409.327096)
		(end 343.502488 -409.46705)
		(stroke
			(width 0.07112)
			(type default)
		)
		(layer "In4.Cu")
	)
	(gr_line
		(start 343.69883 -382.101344)
		(end 343.455244 -382.34493)
		(stroke
			(width 0.07112)
			(type default)
		)
		(layer "In4.Cu")
	)
	(gr_arc
		(start 343.69883 -382.101344)
		(mid 343.730272 -382.056934)
		(end 343.745058 -382.00457)
		(stroke
			(width 0.07112)
			(type default)
		)
		(layer "In4.Cu")
	)
	(gr_line
		(start 343.906856 -412.55569)
		(end 343.616026 -412.84652)
		(stroke
			(width 0.07112)
			(type default)
		)
		(layer "In4.Cu")
	)
	(gr_arc
		(start 344.02903 -382.00457)
		(mid 344.043887 -382.056901)
		(end 344.075258 -382.101344)
		(stroke
			(width 0.07112)
			(type default)
		)
		(layer "In4.Cu")
	)
	(gr_line
		(start 344.075258 -382.101344)
		(end 344.318844 -382.34493)
		(stroke
			(width 0.07112)
			(type default)
		)
		(layer "In4.Cu")
	)
	(gr_line
		(start 344.188796 -412.55569)
		(end 344.479626 -412.84652)
		(stroke
			(width 0.07112)
			(type default)
		)
		(layer "In4.Cu")
	)
	(gr_line
		(start 344.370152 -296.205656)
		(end 344.370152 -296.234104)
		(stroke
			(width 0.05715)
			(type default)
		)
		(layer "In4.Cu")
	)
	(gr_line
		(start 344.415872 -296.159936)
		(end 344.370152 -296.205656)
		(stroke
			(width 0.05715)
			(type default)
		)
		(layer "In4.Cu")
	)
	(gr_line
		(start 344.606372 -296.159936)
		(end 344.652092 -296.205656)
		(stroke
			(width 0.05715)
			(type default)
		)
		(layer "In4.Cu")
	)
	(gr_line
		(start 344.652092 -296.205656)
		(end 344.652092 -296.234104)
		(stroke
			(width 0.05715)
			(type default)
		)
		(layer "In4.Cu")
	)
	(gr_line
		(start 345.071954 -291.86632)
		(end 345.071954 -291.867082)
		(stroke
			(width 0.05715)
			(type default)
		)
		(layer "In4.Cu")
	)
	(gr_line
		(start 345.076526 -295.145968)
		(end 345.076272 -295.145714)
		(stroke
			(width 0.05715)
			(type default)
		)
		(layer "In4.Cu")
	)
	(gr_line
		(start 345.076526 -291.916612)
		(end 345.076526 -291.91712)
		(stroke
			(width 0.05715)
			(type default)
		)
		(layer "In4.Cu")
	)
	(gr_line
		(start 345.310206 -296.078656)
		(end 345.310206 -296.107104)
		(stroke
			(width 0.05715)
			(type default)
		)
		(layer "In4.Cu")
	)
	(gr_line
		(start 345.355926 -296.032936)
		(end 345.310206 -296.078656)
		(stroke
			(width 0.05715)
			(type default)
		)
		(layer "In4.Cu")
	)
	(gr_line
		(start 345.447874 -379.5903)
		(end 345.157044 -379.88113)
		(stroke
			(width 0.07112)
			(type default)
		)
		(layer "In4.Cu")
	)
	(gr_line
		(start 345.546426 -296.032936)
		(end 345.592146 -296.078656)
		(stroke
			(width 0.05715)
			(type default)
		)
		(layer "In4.Cu")
	)
	(gr_line
		(start 345.592146 -296.078656)
		(end 345.592146 -296.107104)
		(stroke
			(width 0.05715)
			(type default)
		)
		(layer "In4.Cu")
	)
	(gr_line
		(start 345.63812 -290.608512)
		(end 345.637104 -290.60902)
		(stroke
			(width 0.05715)
			(type default)
		)
		(layer "In4.Cu")
	)
	(gr_line
		(start 345.638882 -291.583872)
		(end 345.63939 -291.584126)
		(stroke
			(width 0.05715)
			(type default)
		)
		(layer "In4.Cu")
	)
	(gr_line
		(start 345.638882 -290.608004)
		(end 345.63812 -290.608512)
		(stroke
			(width 0.05715)
			(type default)
		)
		(layer "In4.Cu")
	)
	(gr_line
		(start 345.640152 -290.607242)
		(end 345.638882 -290.608004)
		(stroke
			(width 0.05715)
			(type default)
		)
		(layer "In4.Cu")
	)
	(gr_line
		(start 345.641676 -291.585396)
		(end 345.642438 -291.585904)
		(stroke
			(width 0.05715)
			(type default)
		)
		(layer "In4.Cu")
	)
	(gr_line
		(start 345.642438 -291.585904)
		(end 345.643962 -291.586666)
		(stroke
			(width 0.05715)
			(type default)
		)
		(layer "In4.Cu")
	)
	(gr_line
		(start 345.643962 -291.586666)
		(end 345.644724 -291.587174)
		(stroke
			(width 0.05715)
			(type default)
		)
		(layer "In4.Cu")
	)
	(gr_line
		(start 345.644724 -291.587174)
		(end 345.64574 -291.587682)
		(stroke
			(width 0.05715)
			(type default)
		)
		(layer "In4.Cu")
	)
	(gr_line
		(start 345.729814 -379.5903)
		(end 346.020644 -379.88113)
		(stroke
			(width 0.07112)
			(type default)
		)
		(layer "In4.Cu")
	)
	(gr_line
		(start 345.73337 -290.773866)
		(end 345.7321 -290.774628)
		(stroke
			(width 0.05715)
			(type default)
		)
		(layer "In4.Cu")
	)
	(gr_line
		(start 345.733624 -291.418264)
		(end 345.734132 -291.418518)
		(stroke
			(width 0.05715)
			(type default)
		)
		(layer "In4.Cu")
	)
	(gr_line
		(start 345.734132 -291.418518)
		(end 345.735148 -291.419026)
		(stroke
			(width 0.05715)
			(type default)
		)
		(layer "In4.Cu")
	)
	(gr_line
		(start 345.734132 -290.773358)
		(end 345.73337 -290.773866)
		(stroke
			(width 0.05715)
			(type default)
		)
		(layer "In4.Cu")
	)
	(gr_line
		(start 345.735148 -291.419026)
		(end 345.736672 -291.420042)
		(stroke
			(width 0.05715)
			(type default)
		)
		(layer "In4.Cu")
	)
	(gr_line
		(start 345.735148 -290.77285)
		(end 345.734132 -290.773358)
		(stroke
			(width 0.05715)
			(type default)
		)
		(layer "In4.Cu")
	)
	(gr_line
		(start 345.736672 -291.420042)
		(end 345.737688 -291.42055)
		(stroke
			(width 0.05715)
			(type default)
		)
		(layer "In4.Cu")
	)
	(gr_line
		(start 345.737688 -291.42055)
		(end 345.740228 -291.422074)
		(stroke
			(width 0.05715)
			(type default)
		)
		(layer "In4.Cu")
	)
	(gr_line
		(start 345.740228 -291.422074)
		(end 345.741244 -291.422836)
		(stroke
			(width 0.05715)
			(type default)
		)
		(layer "In4.Cu")
	)
	(gr_line
		(start 345.921076 -291.095938)
		(end 346.219018 -291.095938)
		(stroke
			(width 0.05715)
			(type default)
		)
		(layer "In4.Cu")
	)
	(gr_line
		(start 345.921076 -289.475926)
		(end 346.219018 -289.475926)
		(stroke
			(width 0.05715)
			(type default)
		)
		(layer "In4.Cu")
	)
	(gr_line
		(start 345.921076 -287.856168)
		(end 346.219018 -287.856168)
		(stroke
			(width 0.05715)
			(type default)
		)
		(layer "In4.Cu")
	)
	(gr_line
		(start 345.921076 -286.236156)
		(end 346.219018 -286.236156)
		(stroke
			(width 0.05715)
			(type default)
		)
		(layer "In4.Cu")
	)
	(gr_line
		(start 346.01658 -295.145968)
		(end 346.016326 -295.145714)
		(stroke
			(width 0.05715)
			(type default)
		)
		(layer "In4.Cu")
	)
	(gr_line
		(start 346.219018 -291.095938)
		(end 346.301822 -291.178742)
		(stroke
			(width 0.05715)
			(type default)
		)
		(layer "In4.Cu")
	)
	(gr_line
		(start 346.219018 -289.475926)
		(end 346.28836 -289.545268)
		(stroke
			(width 0.05715)
			(type default)
		)
		(layer "In4.Cu")
	)
	(gr_line
		(start 346.219018 -287.856168)
		(end 346.301822 -287.938972)
		(stroke
			(width 0.05715)
			(type default)
		)
		(layer "In4.Cu")
	)
	(gr_line
		(start 346.219018 -286.236156)
		(end 346.28836 -286.305498)
		(stroke
			(width 0.05715)
			(type default)
		)
		(layer "In4.Cu")
	)
	(gr_line
		(start 346.25026 -296.078656)
		(end 346.25026 -296.107104)
		(stroke
			(width 0.05715)
			(type default)
		)
		(layer "In4.Cu")
	)
	(gr_line
		(start 346.29598 -296.032936)
		(end 346.25026 -296.078656)
		(stroke
			(width 0.05715)
			(type default)
		)
		(layer "In4.Cu")
	)
	(gr_arc
		(start 346.301822 -291.178742)
		(mid 346.303614 -291.190064)
		(end 346.305632 -291.201348)
		(stroke
			(width 0.05715)
			(type default)
		)
		(layer "In4.Cu")
	)
	(gr_arc
		(start 346.301822 -287.938972)
		(mid 346.303609 -287.950422)
		(end 346.305632 -287.961832)
		(stroke
			(width 0.05715)
			(type default)
		)
		(layer "In4.Cu")
	)
	(gr_arc
		(start 346.476574 -289.58159)
		(mid 346.478595 -289.570179)
		(end 346.480384 -289.55873)
		(stroke
			(width 0.05715)
			(type default)
		)
		(layer "In4.Cu")
	)
	(gr_arc
		(start 346.476574 -286.34182)
		(mid 346.478595 -286.330409)
		(end 346.480384 -286.31896)
		(stroke
			(width 0.05715)
			(type default)
		)
		(layer "In4.Cu")
	)
	(gr_line
		(start 346.48648 -296.032936)
		(end 346.5322 -296.078656)
		(stroke
			(width 0.05715)
			(type default)
		)
		(layer "In4.Cu")
	)
	(gr_arc
		(start 346.53093 -291.554916)
		(mid 346.534982 -291.557728)
		(end 346.539058 -291.560504)
		(stroke
			(width 0.05715)
			(type default)
		)
		(layer "In4.Cu")
	)
	(gr_line
		(start 346.5322 -296.078656)
		(end 346.5322 -296.107104)
		(stroke
			(width 0.05715)
			(type default)
		)
		(layer "In4.Cu")
	)
	(gr_line
		(start 346.539058 -291.560504)
		(end 346.545916 -291.564568)
		(stroke
			(width 0.05715)
			(type default)
		)
		(layer "In4.Cu")
	)
	(gr_line
		(start 346.545916 -291.564568)
		(end 346.546678 -291.565076)
		(stroke
			(width 0.05715)
			(type default)
		)
		(layer "In4.Cu")
	)
	(gr_line
		(start 346.546678 -291.565076)
		(end 346.54744 -291.565584)
		(stroke
			(width 0.05715)
			(type default)
		)
		(layer "In4.Cu")
	)
	(gr_line
		(start 346.563188 -291.095938)
		(end 346.493846 -291.16528)
		(stroke
			(width 0.05715)
			(type default)
		)
		(layer "In4.Cu")
	)
	(gr_line
		(start 346.563188 -289.475926)
		(end 346.480384 -289.55873)
		(stroke
			(width 0.05715)
			(type default)
		)
		(layer "In4.Cu")
	)
	(gr_line
		(start 346.563188 -287.856168)
		(end 346.493846 -287.92551)
		(stroke
			(width 0.05715)
			(type default)
		)
		(layer "In4.Cu")
	)
	(gr_line
		(start 346.563188 -286.236156)
		(end 346.480384 -286.31896)
		(stroke
			(width 0.05715)
			(type default)
		)
		(layer "In4.Cu")
	)
	(gr_line
		(start 346.587318 -291.588698)
		(end 346.589096 -291.589714)
		(stroke
			(width 0.05715)
			(type default)
		)
		(layer "In4.Cu")
	)
	(gr_line
		(start 346.86113 -291.095938)
		(end 346.563188 -291.095938)
		(stroke
			(width 0.05715)
			(type default)
		)
		(layer "In4.Cu")
	)
	(gr_line
		(start 346.86113 -289.475926)
		(end 346.563188 -289.475926)
		(stroke
			(width 0.05715)
			(type default)
		)
		(layer "In4.Cu")
	)
	(gr_line
		(start 346.86113 -287.856168)
		(end 346.563188 -287.856168)
		(stroke
			(width 0.05715)
			(type default)
		)
		(layer "In4.Cu")
	)
	(gr_line
		(start 346.86113 -286.236156)
		(end 346.563188 -286.236156)
		(stroke
			(width 0.05715)
			(type default)
		)
		(layer "In4.Cu")
	)
	(gr_line
		(start 346.970096 -412.55569)
		(end 346.679266 -412.84652)
		(stroke
			(width 0.07112)
			(type default)
		)
		(layer "In4.Cu")
	)
	(gr_line
		(start 347.0275 -293.050468)
		(end 347.026738 -293.050976)
		(stroke
			(width 0.05715)
			(type default)
		)
		(layer "In4.Cu")
	)
	(gr_line
		(start 347.122242 -293.83609)
		(end 347.12275 -293.83609)
		(stroke
			(width 0.05715)
			(type default)
		)
		(layer "In4.Cu")
	)
	(gr_line
		(start 347.12275 -293.215822)
		(end 347.122496 -293.215822)
		(stroke
			(width 0.05715)
			(type default)
		)
		(layer "In4.Cu")
	)
	(gr_line
		(start 347.123258 -293.215568)
		(end 347.12275 -293.215822)
		(stroke
			(width 0.05715)
			(type default)
		)
		(layer "In4.Cu")
	)
	(gr_line
		(start 347.149674 -377.1265)
		(end 346.858844 -377.41733)
		(stroke
			(width 0.07112)
			(type default)
		)
		(layer "In4.Cu")
	)
	(gr_line
		(start 347.151706 -289.005264)
		(end 347.15196 -289.005518)
		(stroke
			(width 0.05715)
			(type default)
		)
		(layer "In4.Cu")
	)
	(gr_line
		(start 347.172788 -293.8653)
		(end 347.18244 -293.870888)
		(stroke
			(width 0.05715)
			(type default)
		)
		(layer "In4.Cu")
	)
	(gr_line
		(start 347.17482 -292.246558)
		(end 347.18244 -292.250876)
		(stroke
			(width 0.05715)
			(type default)
		)
		(layer "In4.Cu")
	)
	(gr_arc
		(start 347.18244 -293.870888)
		(mid 347.182821 -293.871142)
		(end 347.183202 -293.871396)
		(stroke
			(width 0.05715)
			(type default)
		)
		(layer "In4.Cu")
	)
	(gr_arc
		(start 347.18244 -292.250876)
		(mid 347.182821 -292.25113)
		(end 347.183202 -292.251384)
		(stroke
			(width 0.05715)
			(type default)
		)
		(layer "In4.Cu")
	)
	(gr_line
		(start 347.183202 -293.871396)
		(end 347.185234 -293.87292)
		(stroke
			(width 0.05715)
			(type default)
		)
		(layer "In4.Cu")
	)
	(gr_arc
		(start 347.185234 -293.87292)
		(mid 347.185615 -293.873174)
		(end 347.185996 -293.873428)
		(stroke
			(width 0.05715)
			(type default)
		)
		(layer "In4.Cu")
	)
	(gr_line
		(start 347.190568 -296.078656)
		(end 347.190568 -296.107104)
		(stroke
			(width 0.05715)
			(type default)
		)
		(layer "In4.Cu")
	)
	(gr_arc
		(start 347.191076 -292.256972)
		(mid 347.187151 -292.254161)
		(end 347.183202 -292.251384)
		(stroke
			(width 0.05715)
			(type default)
		)
		(layer "In4.Cu")
	)
	(gr_line
		(start 347.236288 -296.032936)
		(end 347.190568 -296.078656)
		(stroke
			(width 0.05715)
			(type default)
		)
		(layer "In4.Cu")
	)
	(gr_line
		(start 347.252036 -412.55569)
		(end 347.542866 -412.84652)
		(stroke
			(width 0.07112)
			(type default)
		)
		(layer "In4.Cu")
	)
	(gr_line
		(start 347.426788 -296.032936)
		(end 347.472508 -296.078656)
		(stroke
			(width 0.05715)
			(type default)
		)
		(layer "In4.Cu")
	)
	(gr_line
		(start 347.431614 -377.1265)
		(end 347.722444 -377.41733)
		(stroke
			(width 0.07112)
			(type default)
		)
		(layer "In4.Cu")
	)
	(gr_line
		(start 347.472508 -296.078656)
		(end 347.472508 -296.107104)
		(stroke
			(width 0.05715)
			(type default)
		)
		(layer "In4.Cu")
	)
	(gr_line
		(start 347.896434 -295.145968)
		(end 347.89618 -295.145714)
		(stroke
			(width 0.05715)
			(type default)
		)
		(layer "In4.Cu")
	)
	(gr_line
		(start 348.125288 -296.078656)
		(end 348.125288 -296.107104)
		(stroke
			(width 0.05715)
			(type default)
		)
		(layer "In4.Cu")
	)
	(gr_line
		(start 348.171008 -296.032936)
		(end 348.125288 -296.078656)
		(stroke
			(width 0.05715)
			(type default)
		)
		(layer "In4.Cu")
	)
	(gr_line
		(start 348.361508 -296.032936)
		(end 348.407228 -296.078656)
		(stroke
			(width 0.05715)
			(type default)
		)
		(layer "In4.Cu")
	)
	(gr_line
		(start 348.407228 -296.078656)
		(end 348.407228 -296.107104)
		(stroke
			(width 0.05715)
			(type default)
		)
		(layer "In4.Cu")
	)
	(gr_arc
		(start 348.411292 -291.554916)
		(mid 348.415217 -291.557727)
		(end 348.419166 -291.560504)
		(stroke
			(width 0.05715)
			(type default)
		)
		(layer "In4.Cu")
	)
	(gr_line
		(start 348.419166 -291.560504)
		(end 348.426024 -291.564568)
		(stroke
			(width 0.05715)
			(type default)
		)
		(layer "In4.Cu")
	)
	(gr_line
		(start 348.426024 -291.564568)
		(end 348.426786 -291.565076)
		(stroke
			(width 0.05715)
			(type default)
		)
		(layer "In4.Cu")
	)
	(gr_line
		(start 348.426786 -291.565076)
		(end 348.427548 -291.565584)
		(stroke
			(width 0.05715)
			(type default)
		)
		(layer "In4.Cu")
	)
	(gr_line
		(start 348.458282 -290.608512)
		(end 348.457266 -290.60902)
		(stroke
			(width 0.05715)
			(type default)
		)
		(layer "In4.Cu")
	)
	(gr_line
		(start 348.458536 -291.583618)
		(end 348.459044 -291.583872)
		(stroke
			(width 0.05715)
			(type default)
		)
		(layer "In4.Cu")
	)
	(gr_line
		(start 348.45879 -290.608258)
		(end 348.458282 -290.608512)
		(stroke
			(width 0.05715)
			(type default)
		)
		(layer "In4.Cu")
	)
	(gr_line
		(start 348.459044 -291.583872)
		(end 348.459552 -291.584126)
		(stroke
			(width 0.05715)
			(type default)
		)
		(layer "In4.Cu")
	)
	(gr_line
		(start 348.461838 -291.585396)
		(end 348.4626 -291.585904)
		(stroke
			(width 0.05715)
			(type default)
		)
		(layer "In4.Cu")
	)
	(gr_line
		(start 348.4626 -291.585904)
		(end 348.464124 -291.586666)
		(stroke
			(width 0.05715)
			(type default)
		)
		(layer "In4.Cu")
	)
	(gr_line
		(start 348.464124 -291.586666)
		(end 348.464886 -291.587174)
		(stroke
			(width 0.05715)
			(type default)
		)
		(layer "In4.Cu")
	)
	(gr_line
		(start 348.464886 -291.587174)
		(end 348.465902 -291.587682)
		(stroke
			(width 0.05715)
			(type default)
		)
		(layer "In4.Cu")
	)
	(gr_line
		(start 348.553532 -290.773866)
		(end 348.552262 -290.774628)
		(stroke
			(width 0.05715)
			(type default)
		)
		(layer "In4.Cu")
	)
	(gr_line
		(start 348.554294 -291.418518)
		(end 348.55531 -291.419026)
		(stroke
			(width 0.05715)
			(type default)
		)
		(layer "In4.Cu")
	)
	(gr_line
		(start 348.554294 -290.773358)
		(end 348.553532 -290.773866)
		(stroke
			(width 0.05715)
			(type default)
		)
		(layer "In4.Cu")
	)
	(gr_line
		(start 348.55531 -291.419026)
		(end 348.556834 -291.420042)
		(stroke
			(width 0.05715)
			(type default)
		)
		(layer "In4.Cu")
	)
	(gr_line
		(start 348.55531 -290.77285)
		(end 348.554294 -290.773358)
		(stroke
			(width 0.05715)
			(type default)
		)
		(layer "In4.Cu")
	)
	(gr_line
		(start 348.556834 -291.420042)
		(end 348.55785 -291.42055)
		(stroke
			(width 0.05715)
			(type default)
		)
		(layer "In4.Cu")
	)
	(gr_line
		(start 348.55785 -291.42055)
		(end 348.56039 -291.422074)
		(stroke
			(width 0.05715)
			(type default)
		)
		(layer "In4.Cu")
	)
	(gr_line
		(start 348.56039 -291.422074)
		(end 348.561406 -291.422836)
		(stroke
			(width 0.05715)
			(type default)
		)
		(layer "In4.Cu")
	)
	(gr_line
		(start 348.741238 -291.095938)
		(end 349.03918 -291.095938)
		(stroke
			(width 0.05715)
			(type default)
		)
		(layer "In4.Cu")
	)
	(gr_line
		(start 348.741238 -289.475926)
		(end 349.03918 -289.475926)
		(stroke
			(width 0.05715)
			(type default)
		)
		(layer "In4.Cu")
	)
	(gr_line
		(start 348.741238 -287.856168)
		(end 349.03918 -287.856168)
		(stroke
			(width 0.05715)
			(type default)
		)
		(layer "In4.Cu")
	)
	(gr_line
		(start 348.836996 -295.145968)
		(end 348.836742 -295.145714)
		(stroke
			(width 0.05715)
			(type default)
		)
		(layer "In4.Cu")
	)
	(gr_line
		(start 348.993714 -294.841168)
		(end 348.993714 -294.840914)
		(stroke
			(width 0.05715)
			(type default)
		)
		(layer "In4.Cu")
	)
	(gr_line
		(start 349.03918 -291.095938)
		(end 349.121984 -291.178742)
		(stroke
			(width 0.05715)
			(type default)
		)
		(layer "In4.Cu")
	)
	(gr_line
		(start 349.03918 -289.475926)
		(end 349.108522 -289.545268)
		(stroke
			(width 0.05715)
			(type default)
		)
		(layer "In4.Cu")
	)
	(gr_line
		(start 349.03918 -287.856168)
		(end 349.121984 -287.938972)
		(stroke
			(width 0.05715)
			(type default)
		)
		(layer "In4.Cu")
	)
	(gr_line
		(start 349.070422 -296.205656)
		(end 349.070422 -296.234104)
		(stroke
			(width 0.05715)
			(type default)
		)
		(layer "In4.Cu")
	)
	(gr_line
		(start 349.116142 -296.159936)
		(end 349.070422 -296.205656)
		(stroke
			(width 0.05715)
			(type default)
		)
		(layer "In4.Cu")
	)
	(gr_arc
		(start 349.121984 -291.178742)
		(mid 349.123775 -291.190064)
		(end 349.125794 -291.201348)
		(stroke
			(width 0.05715)
			(type default)
		)
		(layer "In4.Cu")
	)
	(gr_arc
		(start 349.121984 -287.938972)
		(mid 349.123776 -287.950294)
		(end 349.125794 -287.961578)
		(stroke
			(width 0.05715)
			(type default)
		)
		(layer "In4.Cu")
	)
	(gr_arc
		(start 349.296736 -289.58159)
		(mid 349.298757 -289.570179)
		(end 349.300546 -289.55873)
		(stroke
			(width 0.05715)
			(type default)
		)
		(layer "In4.Cu")
	)
	(gr_line
		(start 349.306642 -296.159936)
		(end 349.352362 -296.205656)
		(stroke
			(width 0.05715)
			(type default)
		)
		(layer "In4.Cu")
	)
	(gr_line
		(start 349.352362 -296.205656)
		(end 349.352362 -296.234104)
		(stroke
			(width 0.05715)
			(type default)
		)
		(layer "In4.Cu")
	)
	(gr_line
		(start 349.383096 -291.095938)
		(end 349.314008 -291.165026)
		(stroke
			(width 0.05715)
			(type default)
		)
		(layer "In4.Cu")
	)
	(gr_line
		(start 349.38335 -289.475926)
		(end 349.300546 -289.55873)
		(stroke
			(width 0.05715)
			(type default)
		)
		(layer "In4.Cu")
	)
	(gr_line
		(start 349.38335 -287.856168)
		(end 349.314008 -287.92551)
		(stroke
			(width 0.05715)
			(type default)
		)
		(layer "In4.Cu")
	)
	(gr_arc
		(start 349.4024 -291.585904)
		(mid 349.401512 -291.585395)
		(end 349.400622 -291.584888)
		(stroke
			(width 0.05715)
			(type default)
		)
		(layer "In4.Cu")
	)
	(gr_line
		(start 349.49384 -291.418518)
		(end 349.495364 -291.41928)
		(stroke
			(width 0.05715)
			(type default)
		)
		(layer "In4.Cu")
	)
	(gr_line
		(start 349.681038 -291.095938)
		(end 349.383096 -291.095938)
		(stroke
			(width 0.05715)
			(type default)
		)
		(layer "In4.Cu")
	)
	(gr_line
		(start 349.681038 -289.475926)
		(end 349.38335 -289.475926)
		(stroke
			(width 0.05715)
			(type default)
		)
		(layer "In4.Cu")
	)
	(gr_line
		(start 349.681038 -287.856168)
		(end 349.38335 -287.856168)
		(stroke
			(width 0.05715)
			(type default)
		)
		(layer "In4.Cu")
	)
	(gr_arc
		(start 349.821246 -289.124898)
		(mid 349.825171 -289.127709)
		(end 349.82912 -289.130486)
		(stroke
			(width 0.05715)
			(type default)
		)
		(layer "In4.Cu")
	)
	(gr_line
		(start 349.82912 -289.130486)
		(end 349.835978 -289.13455)
		(stroke
			(width 0.05715)
			(type default)
		)
		(layer "In4.Cu")
	)
	(gr_line
		(start 349.835978 -289.13455)
		(end 349.83674 -289.135058)
		(stroke
			(width 0.05715)
			(type default)
		)
		(layer "In4.Cu")
	)
	(gr_line
		(start 349.83674 -289.135058)
		(end 349.837502 -289.135566)
		(stroke
			(width 0.05715)
			(type default)
		)
		(layer "In4.Cu")
	)
	(gr_line
		(start 349.850456 -293.048944)
		(end 349.8469 -293.050976)
		(stroke
			(width 0.05715)
			(type default)
		)
		(layer "In4.Cu")
	)
	(gr_line
		(start 349.86341 -292.390576)
		(end 349.862394 -292.390068)
		(stroke
			(width 0.05715)
			(type default)
		)
		(layer "In4.Cu")
	)
	(gr_line
		(start 349.867728 -293.038784)
		(end 349.866204 -293.039546)
		(stroke
			(width 0.05715)
			(type default)
		)
		(layer "In4.Cu")
	)
	(gr_line
		(start 349.942404 -293.83609)
		(end 349.942912 -293.83609)
		(stroke
			(width 0.05715)
			(type default)
		)
		(layer "In4.Cu")
	)
	(gr_line
		(start 349.99295 -293.8653)
		(end 350.002602 -293.870888)
		(stroke
			(width 0.05715)
			(type default)
		)
		(layer "In4.Cu")
	)
	(gr_line
		(start 349.994474 -292.246304)
		(end 350.001586 -292.250368)
		(stroke
			(width 0.05715)
			(type default)
		)
		(layer "In4.Cu")
	)
	(gr_arc
		(start 350.002602 -293.870888)
		(mid 350.002983 -293.871142)
		(end 350.003364 -293.871396)
		(stroke
			(width 0.05715)
			(type default)
		)
		(layer "In4.Cu")
	)
	(gr_arc
		(start 350.00311 -292.251384)
		(mid 350.002348 -292.250875)
		(end 350.001586 -292.250368)
		(stroke
			(width 0.05715)
			(type default)
		)
		(layer "In4.Cu")
	)
	(gr_line
		(start 350.003364 -293.871396)
		(end 350.005396 -293.87292)
		(stroke
			(width 0.05715)
			(type default)
		)
		(layer "In4.Cu")
	)
	(gr_arc
		(start 350.005396 -293.87292)
		(mid 350.005777 -293.873174)
		(end 350.006158 -293.873428)
		(stroke
			(width 0.05715)
			(type default)
		)
		(layer "In4.Cu")
	)
	(gr_arc
		(start 350.00946 -292.255956)
		(mid 350.006293 -292.253659)
		(end 350.00311 -292.251384)
		(stroke
			(width 0.05715)
			(type default)
		)
		(layer "In4.Cu")
	)
	(gr_line
		(start 350.015302 -296.205656)
		(end 350.015302 -296.234104)
		(stroke
			(width 0.05715)
			(type default)
		)
		(layer "In4.Cu")
	)
	(gr_line
		(start 350.033336 -412.55569)
		(end 349.742506 -412.84652)
		(stroke
			(width 0.07112)
			(type default)
		)
		(layer "In4.Cu")
	)
	(gr_line
		(start 350.061022 -296.159936)
		(end 350.015302 -296.205656)
		(stroke
			(width 0.05715)
			(type default)
		)
		(layer "In4.Cu")
	)
	(gr_line
		(start 350.251522 -296.159936)
		(end 350.297242 -296.205656)
		(stroke
			(width 0.05715)
			(type default)
		)
		(layer "In4.Cu")
	)
	(gr_line
		(start 350.297242 -296.205656)
		(end 350.297242 -296.234104)
		(stroke
			(width 0.05715)
			(type default)
		)
		(layer "In4.Cu")
	)
	(gr_line
		(start 350.315276 -412.55569)
		(end 350.606106 -412.84652)
		(stroke
			(width 0.07112)
			(type default)
		)
		(layer "In4.Cu")
	)
	(gr_arc
		(start 350.326706 -291.57676)
		(mid 350.328862 -291.578035)
		(end 350.331024 -291.5793)
		(stroke
			(width 0.05715)
			(type default)
		)
		(layer "In4.Cu")
	)
	(gr_line
		(start 350.337882 -291.583364)
		(end 350.338136 -291.583364)
		(stroke
			(width 0.05715)
			(type default)
		)
		(layer "In4.Cu")
	)
	(gr_line
		(start 350.338136 -290.608512)
		(end 350.337882 -290.608766)
		(stroke
			(width 0.05715)
			(type default)
		)
		(layer "In4.Cu")
	)
	(gr_line
		(start 350.34601 -291.587936)
		(end 350.346772 -291.58819)
		(stroke
			(width 0.05715)
			(type default)
		)
		(layer "In4.Cu")
	)
	(gr_line
		(start 350.421448 -289.79114)
		(end 350.422718 -289.791902)
		(stroke
			(width 0.05715)
			(type default)
		)
		(layer "In4.Cu")
	)
	(gr_line
		(start 350.43364 -291.418264)
		(end 350.44126 -291.422582)
		(stroke
			(width 0.05715)
			(type default)
		)
		(layer "In4.Cu")
	)
	(gr_line
		(start 350.44126 -291.422582)
		(end 350.442784 -291.423598)
		(stroke
			(width 0.05715)
			(type default)
		)
		(layer "In4.Cu")
	)
	(gr_line
		(start 350.45523 -290.761166)
		(end 350.454976 -290.761166)
		(stroke
			(width 0.05715)
			(type default)
		)
		(layer "In4.Cu")
	)
	(gr_line
		(start 350.465136 -290.755324)
		(end 350.463612 -290.75634)
		(stroke
			(width 0.05715)
			(type default)
		)
		(layer "In4.Cu")
	)
	(gr_line
		(start 350.465898 -291.43706)
		(end 350.472502 -291.44087)
		(stroke
			(width 0.05715)
			(type default)
		)
		(layer "In4.Cu")
	)
	(gr_arc
		(start 350.472502 -291.44087)
		(mid 350.472883 -291.441124)
		(end 350.473264 -291.441378)
		(stroke
			(width 0.05715)
			(type default)
		)
		(layer "In4.Cu")
	)
	(gr_arc
		(start 350.481138 -291.446966)
		(mid 350.477213 -291.444155)
		(end 350.473264 -291.441378)
		(stroke
			(width 0.05715)
			(type default)
		)
		(layer "In4.Cu")
	)
	(gr_line
		(start 350.50603 -382.101344)
		(end 350.262444 -382.34493)
		(stroke
			(width 0.07112)
			(type default)
		)
		(layer "In4.Cu")
	)
	(gr_arc
		(start 350.50603 -382.101344)
		(mid 350.537472 -382.056934)
		(end 350.552258 -382.00457)
		(stroke
			(width 0.07112)
			(type default)
		)
		(layer "In4.Cu")
	)
	(gr_line
		(start 350.716596 -295.145968)
		(end 350.716342 -295.145714)
		(stroke
			(width 0.05715)
			(type default)
		)
		(layer "In4.Cu")
	)
	(gr_arc
		(start 350.83623 -382.00457)
		(mid 350.851087 -382.056901)
		(end 350.882458 -382.101344)
		(stroke
			(width 0.07112)
			(type default)
		)
		(layer "In4.Cu")
	)
	(gr_line
		(start 350.882458 -382.101344)
		(end 351.126044 -382.34493)
		(stroke
			(width 0.07112)
			(type default)
		)
		(layer "In4.Cu")
	)
	(gr_line
		(start 350.960182 -296.078656)
		(end 350.960182 -296.107104)
		(stroke
			(width 0.05715)
			(type default)
		)
		(layer "In4.Cu")
	)
	(gr_line
		(start 351.005902 -296.032936)
		(end 350.960182 -296.078656)
		(stroke
			(width 0.05715)
			(type default)
		)
		(layer "In4.Cu")
	)
	(gr_line
		(start 351.196402 -296.032936)
		(end 351.242122 -296.078656)
		(stroke
			(width 0.05715)
			(type default)
		)
		(layer "In4.Cu")
	)
	(gr_arc
		(start 351.2312 -291.554916)
		(mid 351.235125 -291.557727)
		(end 351.239074 -291.560504)
		(stroke
			(width 0.05715)
			(type default)
		)
		(layer "In4.Cu")
	)
	(gr_line
		(start 351.239074 -291.560504)
		(end 351.245932 -291.564568)
		(stroke
			(width 0.05715)
			(type default)
		)
		(layer "In4.Cu")
	)
	(gr_arc
		(start 351.239074 -290.631372)
		(mid 351.235125 -290.634149)
		(end 351.2312 -290.63696)
		(stroke
			(width 0.05715)
			(type default)
		)
		(layer "In4.Cu")
	)
	(gr_arc
		(start 351.239074 -290.631372)
		(mid 351.239455 -290.631118)
		(end 351.239836 -290.630864)
		(stroke
			(width 0.05715)
			(type default)
		)
		(layer "In4.Cu")
	)
	(gr_line
		(start 351.242122 -296.078656)
		(end 351.242122 -296.107104)
		(stroke
			(width 0.05715)
			(type default)
		)
		(layer "In4.Cu")
	)
	(gr_line
		(start 351.245932 -291.564568)
		(end 351.246694 -291.565076)
		(stroke
			(width 0.05715)
			(type default)
		)
		(layer "In4.Cu")
	)
	(gr_line
		(start 351.246694 -291.565076)
		(end 351.247456 -291.565584)
		(stroke
			(width 0.05715)
			(type default)
		)
		(layer "In4.Cu")
	)
	(gr_line
		(start 351.246948 -290.6268)
		(end 351.239836 -290.630864)
		(stroke
			(width 0.05715)
			(type default)
		)
		(layer "In4.Cu")
	)
	(gr_line
		(start 351.278444 -291.583618)
		(end 351.278952 -291.583872)
		(stroke
			(width 0.05715)
			(type default)
		)
		(layer "In4.Cu")
	)
	(gr_line
		(start 351.278698 -290.608258)
		(end 351.277936 -290.608766)
		(stroke
			(width 0.05715)
			(type default)
		)
		(layer "In4.Cu")
	)
	(gr_line
		(start 351.280222 -290.607496)
		(end 351.278698 -290.608258)
		(stroke
			(width 0.05715)
			(type default)
		)
		(layer "In4.Cu")
	)
	(gr_line
		(start 351.374202 -290.773358)
		(end 351.373186 -290.773866)
		(stroke
			(width 0.05715)
			(type default)
		)
		(layer "In4.Cu")
	)
	(gr_line
		(start 351.375726 -290.772342)
		(end 351.374202 -290.773358)
		(stroke
			(width 0.05715)
			(type default)
		)
		(layer "In4.Cu")
	)
	(gr_line
		(start 351.404936 -291.436044)
		(end 351.410524 -291.439346)
		(stroke
			(width 0.05715)
			(type default)
		)
		(layer "In4.Cu")
	)
	(gr_line
		(start 351.410524 -291.439346)
		(end 351.413318 -291.441378)
		(stroke
			(width 0.05715)
			(type default)
		)
		(layer "In4.Cu")
	)
	(gr_arc
		(start 351.421192 -291.446966)
		(mid 351.417267 -291.444155)
		(end 351.413318 -291.441378)
		(stroke
			(width 0.05715)
			(type default)
		)
		(layer "In4.Cu")
	)
	(gr_line
		(start 351.561146 -291.095938)
		(end 351.859088 -291.095938)
		(stroke
			(width 0.05715)
			(type default)
		)
		(layer "In4.Cu")
	)
	(gr_line
		(start 351.561146 -289.475926)
		(end 351.859088 -289.475926)
		(stroke
			(width 0.05715)
			(type default)
		)
		(layer "In4.Cu")
	)
	(gr_line
		(start 351.561146 -287.856168)
		(end 351.859088 -287.856168)
		(stroke
			(width 0.05715)
			(type default)
		)
		(layer "In4.Cu")
	)
	(gr_line
		(start 351.65665 -295.145968)
		(end 351.656396 -295.145714)
		(stroke
			(width 0.05715)
			(type default)
		)
		(layer "In4.Cu")
	)
	(gr_arc
		(start 351.748344 -289.798506)
		(mid 351.7472 -289.79914)
		(end 351.746058 -289.799776)
		(stroke
			(width 0.05715)
			(type default)
		)
		(layer "In4.Cu")
	)
	(gr_line
		(start 351.859088 -291.095938)
		(end 351.941892 -291.178742)
		(stroke
			(width 0.05715)
			(type default)
		)
		(layer "In4.Cu")
	)
	(gr_line
		(start 351.859088 -289.475926)
		(end 351.92843 -289.545268)
		(stroke
			(width 0.05715)
			(type default)
		)
		(layer "In4.Cu")
	)
	(gr_line
		(start 351.859088 -287.856168)
		(end 351.941892 -287.938972)
		(stroke
			(width 0.05715)
			(type default)
		)
		(layer "In4.Cu")
	)
	(gr_arc
		(start 351.941892 -291.178742)
		(mid 351.943683 -291.190064)
		(end 351.945702 -291.201348)
		(stroke
			(width 0.05715)
			(type default)
		)
		(layer "In4.Cu")
	)
	(gr_arc
		(start 351.941892 -287.938972)
		(mid 351.943684 -287.950294)
		(end 351.945702 -287.961578)
		(stroke
			(width 0.05715)
			(type default)
		)
		(layer "In4.Cu")
	)
	(gr_line
		(start 351.966784 -296.078656)
		(end 351.966784 -296.107104)
		(stroke
			(width 0.05715)
			(type default)
		)
		(layer "In4.Cu")
	)
	(gr_line
		(start 352.012504 -296.032936)
		(end 351.966784 -296.078656)
		(stroke
			(width 0.05715)
			(type default)
		)
		(layer "In4.Cu")
	)
	(gr_arc
		(start 352.116644 -289.58159)
		(mid 352.118665 -289.570179)
		(end 352.120454 -289.55873)
		(stroke
			(width 0.05715)
			(type default)
		)
		(layer "In4.Cu")
	)
	(gr_arc
		(start 352.169476 -288.313876)
		(mid 352.174284 -288.317331)
		(end 352.179128 -288.320734)
		(stroke
			(width 0.05715)
			(type default)
		)
		(layer "In4.Cu")
	)
	(gr_arc
		(start 352.171 -291.554916)
		(mid 352.175052 -291.557728)
		(end 352.179128 -291.560504)
		(stroke
			(width 0.05715)
			(type default)
		)
		(layer "In4.Cu")
	)
	(gr_line
		(start 352.179128 -291.560504)
		(end 352.185986 -291.564568)
		(stroke
			(width 0.05715)
			(type default)
		)
		(layer "In4.Cu")
	)
	(gr_line
		(start 352.179128 -288.320734)
		(end 352.18116 -288.322258)
		(stroke
			(width 0.05715)
			(type default)
		)
		(layer "In4.Cu")
	)
	(gr_line
		(start 352.18116 -288.322258)
		(end 352.185986 -288.325052)
		(stroke
			(width 0.05715)
			(type default)
		)
		(layer "In4.Cu")
	)
	(gr_line
		(start 352.185986 -291.564568)
		(end 352.186748 -291.565076)
		(stroke
			(width 0.05715)
			(type default)
		)
		(layer "In4.Cu")
	)
	(gr_line
		(start 352.186748 -291.565076)
		(end 352.18751 -291.565584)
		(stroke
			(width 0.05715)
			(type default)
		)
		(layer "In4.Cu")
	)
	(gr_line
		(start 352.203004 -296.032936)
		(end 352.248724 -296.078656)
		(stroke
			(width 0.05715)
			(type default)
		)
		(layer "In4.Cu")
	)
	(gr_line
		(start 352.203258 -291.095938)
		(end 352.133916 -291.16528)
		(stroke
			(width 0.05715)
			(type default)
		)
		(layer "In4.Cu")
	)
	(gr_line
		(start 352.203258 -289.475926)
		(end 352.120454 -289.55873)
		(stroke
			(width 0.05715)
			(type default)
		)
		(layer "In4.Cu")
	)
	(gr_line
		(start 352.203258 -287.856168)
		(end 352.133916 -287.92551)
		(stroke
			(width 0.05715)
			(type default)
		)
		(layer "In4.Cu")
	)
	(gr_line
		(start 352.248724 -296.078656)
		(end 352.248724 -296.107104)
		(stroke
			(width 0.05715)
			(type default)
		)
		(layer "In4.Cu")
	)
	(gr_line
		(start 352.255074 -379.5903)
		(end 351.964244 -379.88113)
		(stroke
			(width 0.07112)
			(type default)
		)
		(layer "In4.Cu")
	)
	(gr_line
		(start 352.313494 -288.17824)
		(end 352.314002 -288.178494)
		(stroke
			(width 0.05715)
			(type default)
		)
		(layer "In4.Cu")
	)
	(gr_line
		(start 352.5012 -291.095938)
		(end 352.203258 -291.095938)
		(stroke
			(width 0.05715)
			(type default)
		)
		(layer "In4.Cu")
	)
	(gr_line
		(start 352.5012 -289.475926)
		(end 352.203258 -289.475926)
		(stroke
			(width 0.05715)
			(type default)
		)
		(layer "In4.Cu")
	)
	(gr_line
		(start 352.5012 -287.856168)
		(end 352.203258 -287.856168)
		(stroke
			(width 0.05715)
			(type default)
		)
		(layer "In4.Cu")
	)
	(gr_line
		(start 352.537014 -379.5903)
		(end 352.827844 -379.88113)
		(stroke
			(width 0.07112)
			(type default)
		)
		(layer "In4.Cu")
	)
	(gr_line
		(start 352.59264 -291.869622)
		(end 352.592894 -291.871146)
		(stroke
			(width 0.05715)
			(type default)
		)
		(layer "In4.Cu")
	)
	(gr_line
		(start 352.59645 -291.914326)
		(end 352.59645 -291.915596)
		(stroke
			(width 0.05715)
			(type default)
		)
		(layer "In4.Cu")
	)
	(gr_arc
		(start 352.641154 -289.124898)
		(mid 352.645079 -289.127709)
		(end 352.649028 -289.130486)
		(stroke
			(width 0.05715)
			(type default)
		)
		(layer "In4.Cu")
	)
	(gr_line
		(start 352.649028 -289.130486)
		(end 352.655886 -289.13455)
		(stroke
			(width 0.05715)
			(type default)
		)
		(layer "In4.Cu")
	)
	(gr_line
		(start 352.655886 -289.13455)
		(end 352.656648 -289.135058)
		(stroke
			(width 0.05715)
			(type default)
		)
		(layer "In4.Cu")
	)
	(gr_line
		(start 352.656648 -289.135058)
		(end 352.65741 -289.135566)
		(stroke
			(width 0.05715)
			(type default)
		)
		(layer "In4.Cu")
	)
	(gr_line
		(start 352.66757 -293.050468)
		(end 352.666808 -293.050976)
		(stroke
			(width 0.05715)
			(type default)
		)
		(layer "In4.Cu")
	)
	(gr_line
		(start 352.762312 -293.83609)
		(end 352.76282 -293.83609)
		(stroke
			(width 0.05715)
			(type default)
		)
		(layer "In4.Cu")
	)
	(gr_line
		(start 352.76282 -293.215822)
		(end 352.762566 -293.215822)
		(stroke
			(width 0.05715)
			(type default)
		)
		(layer "In4.Cu")
	)
	(gr_line
		(start 352.763328 -293.215568)
		(end 352.76282 -293.215822)
		(stroke
			(width 0.05715)
			(type default)
		)
		(layer "In4.Cu")
	)
	(gr_line
		(start 352.812858 -293.8653)
		(end 352.82251 -293.870888)
		(stroke
			(width 0.05715)
			(type default)
		)
		(layer "In4.Cu")
	)
	(gr_arc
		(start 352.82251 -293.870888)
		(mid 352.822891 -293.871142)
		(end 352.823272 -293.871396)
		(stroke
			(width 0.05715)
			(type default)
		)
		(layer "In4.Cu")
	)
	(gr_line
		(start 352.823272 -293.871396)
		(end 352.825304 -293.87292)
		(stroke
			(width 0.05715)
			(type default)
		)
		(layer "In4.Cu")
	)
	(gr_arc
		(start 352.825304 -293.87292)
		(mid 352.825685 -293.873174)
		(end 352.826066 -293.873428)
		(stroke
			(width 0.05715)
			(type default)
		)
		(layer "In4.Cu")
	)
	(gr_line
		(start 352.911918 -296.078656)
		(end 352.911918 -296.107104)
		(stroke
			(width 0.05715)
			(type default)
		)
		(layer "In4.Cu")
	)
	(gr_line
		(start 352.957638 -296.032936)
		(end 352.911918 -296.078656)
		(stroke
			(width 0.05715)
			(type default)
		)
		(layer "In4.Cu")
	)
	(gr_arc
		(start 353.146614 -291.57676)
		(mid 353.14877 -291.578035)
		(end 353.150932 -291.5793)
		(stroke
			(width 0.05715)
			(type default)
		)
		(layer "In4.Cu")
	)
	(gr_line
		(start 353.148138 -296.032936)
		(end 353.193858 -296.078656)
		(stroke
			(width 0.05715)
			(type default)
		)
		(layer "In4.Cu")
	)
	(gr_line
		(start 353.15779 -291.583364)
		(end 353.158044 -291.583364)
		(stroke
			(width 0.05715)
			(type default)
		)
		(layer "In4.Cu")
	)
	(gr_line
		(start 353.158044 -290.608512)
		(end 353.15779 -290.608766)
		(stroke
			(width 0.05715)
			(type default)
		)
		(layer "In4.Cu")
	)
	(gr_line
		(start 353.165918 -291.587936)
		(end 353.16668 -291.58819)
		(stroke
			(width 0.05715)
			(type default)
		)
		(layer "In4.Cu")
	)
	(gr_line
		(start 353.193858 -296.078656)
		(end 353.193858 -296.107104)
		(stroke
			(width 0.05715)
			(type default)
		)
		(layer "In4.Cu")
	)
	(gr_line
		(start 353.241356 -289.79114)
		(end 353.242626 -289.791902)
		(stroke
			(width 0.05715)
			(type default)
		)
		(layer "In4.Cu")
	)
	(gr_line
		(start 353.253548 -291.418264)
		(end 353.261168 -291.422582)
		(stroke
			(width 0.05715)
			(type default)
		)
		(layer "In4.Cu")
	)
	(gr_line
		(start 353.261168 -291.422582)
		(end 353.262692 -291.423598)
		(stroke
			(width 0.05715)
			(type default)
		)
		(layer "In4.Cu")
	)
	(gr_line
		(start 353.275138 -290.761166)
		(end 353.274884 -290.761166)
		(stroke
			(width 0.05715)
			(type default)
		)
		(layer "In4.Cu")
	)
	(gr_line
		(start 353.285044 -290.755324)
		(end 353.28352 -290.75634)
		(stroke
			(width 0.05715)
			(type default)
		)
		(layer "In4.Cu")
	)
	(gr_line
		(start 353.285806 -291.43706)
		(end 353.29241 -291.44087)
		(stroke
			(width 0.05715)
			(type default)
		)
		(layer "In4.Cu")
	)
	(gr_arc
		(start 353.29241 -291.44087)
		(mid 353.292791 -291.441124)
		(end 353.293172 -291.441378)
		(stroke
			(width 0.05715)
			(type default)
		)
		(layer "In4.Cu")
	)
	(gr_arc
		(start 353.301046 -291.446966)
		(mid 353.297121 -291.444155)
		(end 353.293172 -291.441378)
		(stroke
			(width 0.05715)
			(type default)
		)
		(layer "In4.Cu")
	)
	(gr_line
		(start 353.536504 -295.145968)
		(end 353.53625 -295.145714)
		(stroke
			(width 0.05715)
			(type default)
		)
		(layer "In4.Cu")
	)
	(gr_line
		(start 353.857052 -296.078656)
		(end 353.857052 -296.107104)
		(stroke
			(width 0.05715)
			(type default)
		)
		(layer "In4.Cu")
	)
	(gr_line
		(start 353.902772 -296.032936)
		(end 353.857052 -296.078656)
		(stroke
			(width 0.05715)
			(type default)
		)
		(layer "In4.Cu")
	)
	(gr_line
		(start 353.956874 -377.1265)
		(end 353.666044 -377.41733)
		(stroke
			(width 0.07112)
			(type default)
		)
		(layer "In4.Cu")
	)
	(gr_line
		(start 353.956874 -376.592592)
		(end 353.956874 -376.59183)
		(stroke
			(width 0.07112)
			(type default)
		)
		(layer "In4.Cu")
	)
	(gr_arc
		(start 354.051108 -291.554916)
		(mid 354.055033 -291.557727)
		(end 354.058982 -291.560504)
		(stroke
			(width 0.05715)
			(type default)
		)
		(layer "In4.Cu")
	)
	(gr_line
		(start 354.058982 -291.560504)
		(end 354.06584 -291.564568)
		(stroke
			(width 0.05715)
			(type default)
		)
		(layer "In4.Cu")
	)
	(gr_line
		(start 354.06584 -291.564568)
		(end 354.066602 -291.565076)
		(stroke
			(width 0.05715)
			(type default)
		)
		(layer "In4.Cu")
	)
	(gr_line
		(start 354.066602 -291.565076)
		(end 354.067364 -291.565584)
		(stroke
			(width 0.05715)
			(type default)
		)
		(layer "In4.Cu")
	)
	(gr_line
		(start 354.093272 -296.032936)
		(end 354.138992 -296.078656)
		(stroke
			(width 0.05715)
			(type default)
		)
		(layer "In4.Cu")
	)
	(gr_line
		(start 354.098098 -290.608512)
		(end 354.097082 -290.60902)
		(stroke
			(width 0.05715)
			(type default)
		)
		(layer "In4.Cu")
	)
	(gr_line
		(start 354.098352 -291.583618)
		(end 354.09886 -291.583872)
		(stroke
			(width 0.05715)
			(type default)
		)
		(layer "In4.Cu")
	)
	(gr_line
		(start 354.09886 -291.583872)
		(end 354.099368 -291.584126)
		(stroke
			(width 0.05715)
			(type default)
		)
		(layer "In4.Cu")
	)
	(gr_line
		(start 354.09886 -290.608004)
		(end 354.098098 -290.608512)
		(stroke
			(width 0.05715)
			(type default)
		)
		(layer "In4.Cu")
	)
	(gr_line
		(start 354.10013 -290.607242)
		(end 354.09886 -290.608004)
		(stroke
			(width 0.05715)
			(type default)
		)
		(layer "In4.Cu")
	)
	(gr_line
		(start 354.101654 -291.585396)
		(end 354.102416 -291.585904)
		(stroke
			(width 0.05715)
			(type default)
		)
		(layer "In4.Cu")
	)
	(gr_line
		(start 354.102416 -291.585904)
		(end 354.10394 -291.586666)
		(stroke
			(width 0.05715)
			(type default)
		)
		(layer "In4.Cu")
	)
	(gr_line
		(start 354.10394 -291.586666)
		(end 354.104702 -291.587174)
		(stroke
			(width 0.05715)
			(type default)
		)
		(layer "In4.Cu")
	)
	(gr_line
		(start 354.104702 -291.587174)
		(end 354.105718 -291.587682)
		(stroke
			(width 0.05715)
			(type default)
		)
		(layer "In4.Cu")
	)
	(gr_line
		(start 354.138992 -296.078656)
		(end 354.138992 -296.107104)
		(stroke
			(width 0.05715)
			(type default)
		)
		(layer "In4.Cu")
	)
	(gr_line
		(start 354.193348 -290.773866)
		(end 354.192078 -290.774628)
		(stroke
			(width 0.05715)
			(type default)
		)
		(layer "In4.Cu")
	)
	(gr_line
		(start 354.19411 -291.418518)
		(end 354.195126 -291.419026)
		(stroke
			(width 0.05715)
			(type default)
		)
		(layer "In4.Cu")
	)
	(gr_line
		(start 354.19411 -290.773358)
		(end 354.193348 -290.773866)
		(stroke
			(width 0.05715)
			(type default)
		)
		(layer "In4.Cu")
	)
	(gr_line
		(start 354.195126 -291.419026)
		(end 354.19665 -291.420042)
		(stroke
			(width 0.05715)
			(type default)
		)
		(layer "In4.Cu")
	)
	(gr_line
		(start 354.195126 -290.77285)
		(end 354.19411 -290.773358)
		(stroke
			(width 0.05715)
			(type default)
		)
		(layer "In4.Cu")
	)
	(gr_line
		(start 354.19665 -291.420042)
		(end 354.197666 -291.42055)
		(stroke
			(width 0.05715)
			(type default)
		)
		(layer "In4.Cu")
	)
	(gr_line
		(start 354.197666 -291.42055)
		(end 354.200206 -291.422074)
		(stroke
			(width 0.05715)
			(type default)
		)
		(layer "In4.Cu")
	)
	(gr_line
		(start 354.200206 -291.422074)
		(end 354.201222 -291.422836)
		(stroke
			(width 0.05715)
			(type default)
		)
		(layer "In4.Cu")
	)
	(gr_line
		(start 354.238814 -377.1265)
		(end 354.529644 -377.41733)
		(stroke
			(width 0.07112)
			(type default)
		)
		(layer "In4.Cu")
	)
	(gr_line
		(start 354.381054 -291.095938)
		(end 354.678996 -291.095938)
		(stroke
			(width 0.05715)
			(type default)
		)
		(layer "In4.Cu")
	)
	(gr_line
		(start 354.381054 -289.475926)
		(end 354.678996 -289.475926)
		(stroke
			(width 0.05715)
			(type default)
		)
		(layer "In4.Cu")
	)
	(gr_line
		(start 354.381054 -287.856168)
		(end 354.678996 -287.856168)
		(stroke
			(width 0.05715)
			(type default)
		)
		(layer "In4.Cu")
	)
	(gr_line
		(start 354.476558 -295.145968)
		(end 354.476304 -295.145714)
		(stroke
			(width 0.05715)
			(type default)
		)
		(layer "In4.Cu")
	)
	(gr_line
		(start 354.678996 -291.095938)
		(end 354.7618 -291.178742)
		(stroke
			(width 0.05715)
			(type default)
		)
		(layer "In4.Cu")
	)
	(gr_line
		(start 354.678996 -289.475926)
		(end 354.748338 -289.545268)
		(stroke
			(width 0.05715)
			(type default)
		)
		(layer "In4.Cu")
	)
	(gr_line
		(start 354.678996 -287.856168)
		(end 354.7618 -287.938972)
		(stroke
			(width 0.05715)
			(type default)
		)
		(layer "In4.Cu")
	)
	(gr_arc
		(start 354.7618 -291.178742)
		(mid 354.763591 -291.190064)
		(end 354.76561 -291.201348)
		(stroke
			(width 0.05715)
			(type default)
		)
		(layer "In4.Cu")
	)
	(gr_arc
		(start 354.7618 -287.938972)
		(mid 354.763587 -287.950422)
		(end 354.76561 -287.961832)
		(stroke
			(width 0.05715)
			(type default)
		)
		(layer "In4.Cu")
	)
	(gr_line
		(start 354.90023 -295.58488)
		(end 354.900484 -295.584626)
		(stroke
			(width 0.05715)
			(type default)
		)
		(layer "In4.Cu")
	)
	(gr_arc
		(start 354.936552 -289.58159)
		(mid 354.938573 -289.570179)
		(end 354.940362 -289.55873)
		(stroke
			(width 0.05715)
			(type default)
		)
		(layer "In4.Cu")
	)
	(gr_line
		(start 354.954332 -296.583862)
		(end 354.954332 -296.61231)
		(stroke
			(width 0.05715)
			(type default)
		)
		(layer "In4.Cu")
	)
	(gr_arc
		(start 354.990908 -291.554916)
		(mid 354.99496 -291.557728)
		(end 354.999036 -291.560504)
		(stroke
			(width 0.05715)
			(type default)
		)
		(layer "In4.Cu")
	)
	(gr_line
		(start 354.999036 -291.560504)
		(end 355.005894 -291.564568)
		(stroke
			(width 0.05715)
			(type default)
		)
		(layer "In4.Cu")
	)
	(gr_line
		(start 355.000052 -296.538142)
		(end 354.954332 -296.583862)
		(stroke
			(width 0.05715)
			(type default)
		)
		(layer "In4.Cu")
	)
	(gr_line
		(start 355.005894 -291.564568)
		(end 355.006656 -291.565076)
		(stroke
			(width 0.05715)
			(type default)
		)
		(layer "In4.Cu")
	)
	(gr_line
		(start 355.006656 -291.565076)
		(end 355.007418 -291.565584)
		(stroke
			(width 0.05715)
			(type default)
		)
		(layer "In4.Cu")
	)
	(gr_line
		(start 355.023166 -291.095938)
		(end 354.953824 -291.16528)
		(stroke
			(width 0.05715)
			(type default)
		)
		(layer "In4.Cu")
	)
	(gr_line
		(start 355.023166 -289.475926)
		(end 354.940362 -289.55873)
		(stroke
			(width 0.05715)
			(type default)
		)
		(layer "In4.Cu")
	)
	(gr_line
		(start 355.023166 -287.856168)
		(end 354.953824 -287.92551)
		(stroke
			(width 0.05715)
			(type default)
		)
		(layer "In4.Cu")
	)
	(gr_line
		(start 355.038406 -291.583618)
		(end 355.038914 -291.583872)
		(stroke
			(width 0.05715)
			(type default)
		)
		(layer "In4.Cu")
	)
	(gr_line
		(start 355.038914 -291.583872)
		(end 355.041708 -291.585396)
		(stroke
			(width 0.05715)
			(type default)
		)
		(layer "In4.Cu")
	)
	(gr_arc
		(start 355.039168 -295.468802)
		(mid 355.028146 -295.474587)
		(end 355.017324 -295.48074)
		(stroke
			(width 0.05715)
			(type default)
		)
		(layer "In4.Cu")
	)
	(gr_line
		(start 355.061774 -295.454832)
		(end 355.056694 -295.458642)
		(stroke
			(width 0.05715)
			(type default)
		)
		(layer "In4.Cu")
	)
	(gr_line
		(start 355.062536 -295.454324)
		(end 355.061774 -295.454832)
		(stroke
			(width 0.05715)
			(type default)
		)
		(layer "In4.Cu")
	)
	(gr_arc
		(start 355.108256 -295.64838)
		(mid 355.107493 -295.648886)
		(end 355.106732 -295.649396)
		(stroke
			(width 0.05715)
			(type default)
		)
		(layer "In4.Cu")
	)
	(gr_line
		(start 355.117908 -295.646856)
		(end 355.114606 -295.646094)
		(stroke
			(width 0.05715)
			(type default)
		)
		(layer "In4.Cu")
	)
	(gr_line
		(start 355.119178 -295.646094)
		(end 355.117908 -295.646856)
		(stroke
			(width 0.05715)
			(type default)
		)
		(layer "In4.Cu")
	)
	(gr_line
		(start 355.151182 -295.624758)
		(end 355.119178 -295.646094)
		(stroke
			(width 0.05715)
			(type default)
		)
		(layer "In4.Cu")
	)
	(gr_line
		(start 355.162612 -295.617138)
		(end 355.161596 -295.6179)
		(stroke
			(width 0.05715)
			(type default)
		)
		(layer "In4.Cu")
	)
	(gr_line
		(start 355.168708 -295.613582)
		(end 355.162612 -295.617138)
		(stroke
			(width 0.05715)
			(type default)
		)
		(layer "In4.Cu")
	)
	(gr_line
		(start 355.168962 -295.613328)
		(end 355.168708 -295.613582)
		(stroke
			(width 0.05715)
			(type default)
		)
		(layer "In4.Cu")
	)
	(gr_line
		(start 355.170232 -295.612566)
		(end 355.168962 -295.613328)
		(stroke
			(width 0.05715)
			(type default)
		)
		(layer "In4.Cu")
	)
	(gr_line
		(start 355.190552 -296.538142)
		(end 355.236272 -296.583862)
		(stroke
			(width 0.05715)
			(type default)
		)
		(layer "In4.Cu")
	)
	(gr_line
		(start 355.225858 -291.912548)
		(end 355.225858 -291.90696)
		(stroke
			(width 0.05715)
			(type default)
		)
		(layer "In4.Cu")
	)
	(gr_arc
		(start 355.225858 -291.912548)
		(mid 355.225982 -291.914453)
		(end 355.226112 -291.916358)
		(stroke
			(width 0.05715)
			(type default)
		)
		(layer "In4.Cu")
	)
	(gr_line
		(start 355.236272 -296.583862)
		(end 355.236272 -296.61231)
		(stroke
			(width 0.05715)
			(type default)
		)
		(layer "In4.Cu")
	)
	(gr_line
		(start 355.321108 -291.095938)
		(end 355.023166 -291.095938)
		(stroke
			(width 0.05715)
			(type default)
		)
		(layer "In4.Cu")
	)
	(gr_line
		(start 355.321108 -289.475926)
		(end 355.023166 -289.475926)
		(stroke
			(width 0.05715)
			(type default)
		)
		(layer "In4.Cu")
	)
	(gr_line
		(start 355.321108 -287.856168)
		(end 355.023166 -287.856168)
		(stroke
			(width 0.05715)
			(type default)
		)
		(layer "In4.Cu")
	)
	(gr_line
		(start 355.487224 -293.050722)
		(end 355.486716 -293.050976)
		(stroke
			(width 0.05715)
			(type default)
		)
		(layer "In4.Cu")
	)
	(gr_arc
		(start 355.51237 -289.155886)
		(mid 355.511482 -289.155377)
		(end 355.510592 -289.15487)
		(stroke
			(width 0.05715)
			(type default)
		)
		(layer "In4.Cu")
	)
	(gr_line
		(start 355.544628 -294.035988)
		(end 355.54666 -294.037258)
		(stroke
			(width 0.05715)
			(type default)
		)
		(layer "In4.Cu")
	)
	(gr_line
		(start 355.58222 -293.83609)
		(end 355.582728 -293.83609)
		(stroke
			(width 0.05715)
			(type default)
		)
		(layer "In4.Cu")
	)
	(gr_line
		(start 355.60381 -288.9885)
		(end 355.605334 -288.989262)
		(stroke
			(width 0.05715)
			(type default)
		)
		(layer "In4.Cu")
	)
	(gr_line
		(start 355.632766 -293.8653)
		(end 355.642418 -293.870888)
		(stroke
			(width 0.05715)
			(type default)
		)
		(layer "In4.Cu")
	)
	(gr_arc
		(start 355.642418 -293.870888)
		(mid 355.642799 -293.871142)
		(end 355.64318 -293.871396)
		(stroke
			(width 0.05715)
			(type default)
		)
		(layer "In4.Cu")
	)
	(gr_line
		(start 355.64318 -293.871396)
		(end 355.648768 -293.87546)
		(stroke
			(width 0.05715)
			(type default)
		)
		(layer "In4.Cu")
	)
	(gr_line
		(start 355.651308 -293.877238)
		(end 355.65207 -293.878)
		(stroke
			(width 0.05715)
			(type default)
		)
		(layer "In4.Cu")
	)
	(gr_line
		(start 355.656642 -293.881048)
		(end 355.657404 -293.88181)
		(stroke
			(width 0.05715)
			(type default)
		)
		(layer "In4.Cu")
	)
	(gr_line
		(start 355.657404 -293.88181)
		(end 355.661214 -293.884858)
		(stroke
			(width 0.05715)
			(type default)
		)
		(layer "In4.Cu")
	)
	(gr_line
		(start 355.66096 -301.834296)
		(end 355.661214 -301.83455)
		(stroke
			(width 0.07112)
			(type default)
		)
		(layer "In4.Cu")
	)
	(gr_line
		(start 355.974396 -289.961066)
		(end 355.978968 -289.96386)
		(stroke
			(width 0.05715)
			(type default)
		)
		(layer "In4.Cu")
	)
	(gr_line
		(start 355.978968 -289.96386)
		(end 355.979476 -289.964114)
		(stroke
			(width 0.05715)
			(type default)
		)
		(layer "In4.Cu")
	)
	(gr_line
		(start 356.070662 -312.799222)
		(end 356.070662 -312.799476)
		(stroke
			(width 0.07112)
			(type default)
		)
		(layer "In4.Cu")
	)
	(gr_line
		(start 356.104444 -289.816286)
		(end 356.111556 -289.82035)
		(stroke
			(width 0.05715)
			(type default)
		)
		(layer "In4.Cu")
	)
	(gr_arc
		(start 356.11308 -289.821366)
		(mid 356.112319 -289.820857)
		(end 356.111556 -289.82035)
		(stroke
			(width 0.05715)
			(type default)
		)
		(layer "In4.Cu")
	)
	(gr_arc
		(start 356.11943 -289.825938)
		(mid 356.116263 -289.823641)
		(end 356.11308 -289.821366)
		(stroke
			(width 0.05715)
			(type default)
		)
		(layer "In4.Cu")
	)
	(gr_line
		(start 356.119938 -295.528746)
		(end 356.119938 -295.557194)
		(stroke
			(width 0.05715)
			(type default)
		)
		(layer "In4.Cu")
	)
	(gr_line
		(start 356.165404 -361.871768)
		(end 356.164896 -361.872022)
		(stroke
			(width 0.07112)
			(type default)
		)
		(layer "In4.Cu")
	)
	(gr_line
		(start 356.165658 -295.483026)
		(end 356.119938 -295.528746)
		(stroke
			(width 0.05715)
			(type default)
		)
		(layer "In4.Cu")
	)
	(gr_line
		(start 356.291388 -320.580004)
		(end 356.291388 -320.57975)
		(stroke
			(width 0.07112)
			(type default)
		)
		(layer "In4.Cu")
	)
	(gr_line
		(start 356.356158 -295.483026)
		(end 356.401878 -295.528746)
		(stroke
			(width 0.05715)
			(type default)
		)
		(layer "In4.Cu")
	)
	(gr_arc
		(start 356.401116 -293.984934)
		(mid 356.405041 -293.987745)
		(end 356.40899 -293.990522)
		(stroke
			(width 0.05715)
			(type default)
		)
		(layer "In4.Cu")
	)
	(gr_arc
		(start 356.401116 -292.364922)
		(mid 356.405041 -292.367733)
		(end 356.40899 -292.37051)
		(stroke
			(width 0.05715)
			(type default)
		)
		(layer "In4.Cu")
	)
	(gr_arc
		(start 356.401116 -290.74491)
		(mid 356.405041 -290.747721)
		(end 356.40899 -290.750498)
		(stroke
			(width 0.05715)
			(type default)
		)
		(layer "In4.Cu")
	)
	(gr_line
		(start 356.401878 -295.528746)
		(end 356.401878 -295.557194)
		(stroke
			(width 0.05715)
			(type default)
		)
		(layer "In4.Cu")
	)
	(gr_arc
		(start 356.40899 -294.681402)
		(mid 356.405041 -294.684179)
		(end 356.401116 -294.68699)
		(stroke
			(width 0.05715)
			(type default)
		)
		(layer "In4.Cu")
	)
	(gr_line
		(start 356.40899 -293.990522)
		(end 356.415848 -293.994586)
		(stroke
			(width 0.05715)
			(type default)
		)
		(layer "In4.Cu")
	)
	(gr_arc
		(start 356.40899 -293.06139)
		(mid 356.405041 -293.064167)
		(end 356.401116 -293.066978)
		(stroke
			(width 0.05715)
			(type default)
		)
		(layer "In4.Cu")
	)
	(gr_line
		(start 356.40899 -292.37051)
		(end 356.415848 -292.374574)
		(stroke
			(width 0.05715)
			(type default)
		)
		(layer "In4.Cu")
	)
	(gr_arc
		(start 356.40899 -291.441378)
		(mid 356.405041 -291.444155)
		(end 356.401116 -291.446966)
		(stroke
			(width 0.05715)
			(type default)
		)
		(layer "In4.Cu")
	)
	(gr_line
		(start 356.40899 -290.750498)
		(end 356.415848 -290.754562)
		(stroke
			(width 0.05715)
			(type default)
		)
		(layer "In4.Cu")
	)
	(gr_line
		(start 356.415848 -293.994586)
		(end 356.41661 -293.995094)
		(stroke
			(width 0.05715)
			(type default)
		)
		(layer "In4.Cu")
	)
	(gr_line
		(start 356.415848 -292.374574)
		(end 356.41661 -292.375082)
		(stroke
			(width 0.05715)
			(type default)
		)
		(layer "In4.Cu")
	)
	(gr_line
		(start 356.415848 -290.754562)
		(end 356.41661 -290.75507)
		(stroke
			(width 0.05715)
			(type default)
		)
		(layer "In4.Cu")
	)
	(gr_line
		(start 356.41661 -293.995094)
		(end 356.417372 -293.995602)
		(stroke
			(width 0.05715)
			(type default)
		)
		(layer "In4.Cu")
	)
	(gr_line
		(start 356.41661 -292.375082)
		(end 356.417372 -292.37559)
		(stroke
			(width 0.05715)
			(type default)
		)
		(layer "In4.Cu")
	)
	(gr_line
		(start 356.41661 -290.75507)
		(end 356.417372 -290.755578)
		(stroke
			(width 0.05715)
			(type default)
		)
		(layer "In4.Cu")
	)
	(gr_line
		(start 356.417626 -294.676322)
		(end 356.40899 -294.681402)
		(stroke
			(width 0.05715)
			(type default)
		)
		(layer "In4.Cu")
	)
	(gr_line
		(start 356.417626 -293.05631)
		(end 356.40899 -293.06139)
		(stroke
			(width 0.05715)
			(type default)
		)
		(layer "In4.Cu")
	)
	(gr_line
		(start 356.417626 -291.436298)
		(end 356.40899 -291.441378)
		(stroke
			(width 0.05715)
			(type default)
		)
		(layer "In4.Cu")
	)
	(gr_line
		(start 356.422198 -294.673528)
		(end 356.419404 -294.675306)
		(stroke
			(width 0.05715)
			(type default)
		)
		(layer "In4.Cu")
	)
	(gr_line
		(start 356.422198 -293.053516)
		(end 356.419404 -293.055294)
		(stroke
			(width 0.05715)
			(type default)
		)
		(layer "In4.Cu")
	)
	(gr_line
		(start 356.422198 -291.433504)
		(end 356.419404 -291.435282)
		(stroke
			(width 0.05715)
			(type default)
		)
		(layer "In4.Cu")
	)
	(gr_line
		(start 356.430072 -294.668956)
		(end 356.42931 -294.669464)
		(stroke
			(width 0.05715)
			(type default)
		)
		(layer "In4.Cu")
	)
	(gr_line
		(start 356.430072 -293.048944)
		(end 356.42931 -293.049452)
		(stroke
			(width 0.05715)
			(type default)
		)
		(layer "In4.Cu")
	)
	(gr_line
		(start 356.430072 -291.428932)
		(end 356.42931 -291.42944)
		(stroke
			(width 0.05715)
			(type default)
		)
		(layer "In4.Cu")
	)
	(gr_line
		(start 356.431596 -294.66794)
		(end 356.430072 -294.668956)
		(stroke
			(width 0.05715)
			(type default)
		)
		(layer "In4.Cu")
	)
	(gr_line
		(start 356.431596 -293.047928)
		(end 356.430072 -293.048944)
		(stroke
			(width 0.05715)
			(type default)
		)
		(layer "In4.Cu")
	)
	(gr_line
		(start 356.431596 -291.427916)
		(end 356.430072 -291.428932)
		(stroke
			(width 0.05715)
			(type default)
		)
		(layer "In4.Cu")
	)
	(gr_line
		(start 356.43439 -294.666416)
		(end 356.43312 -294.667178)
		(stroke
			(width 0.05715)
			(type default)
		)
		(layer "In4.Cu")
	)
	(gr_line
		(start 356.43439 -293.046404)
		(end 356.43312 -293.047166)
		(stroke
			(width 0.05715)
			(type default)
		)
		(layer "In4.Cu")
	)
	(gr_line
		(start 356.43439 -291.426392)
		(end 356.43312 -291.427154)
		(stroke
			(width 0.05715)
			(type default)
		)
		(layer "In4.Cu")
	)
	(gr_line
		(start 356.435152 -294.665908)
		(end 356.43439 -294.666416)
		(stroke
			(width 0.05715)
			(type default)
		)
		(layer "In4.Cu")
	)
	(gr_line
		(start 356.435152 -293.045896)
		(end 356.43439 -293.046404)
		(stroke
			(width 0.05715)
			(type default)
		)
		(layer "In4.Cu")
	)
	(gr_line
		(start 356.435152 -291.425884)
		(end 356.43439 -291.426392)
		(stroke
			(width 0.05715)
			(type default)
		)
		(layer "In4.Cu")
	)
	(gr_line
		(start 356.436422 -294.665146)
		(end 356.435152 -294.665908)
		(stroke
			(width 0.05715)
			(type default)
		)
		(layer "In4.Cu")
	)
	(gr_line
		(start 356.436422 -293.045134)
		(end 356.435152 -293.045896)
		(stroke
			(width 0.05715)
			(type default)
		)
		(layer "In4.Cu")
	)
	(gr_line
		(start 356.436422 -291.425122)
		(end 356.435152 -291.425884)
		(stroke
			(width 0.05715)
			(type default)
		)
		(layer "In4.Cu")
	)
	(gr_line
		(start 356.44328 -294.661336)
		(end 356.442264 -294.661844)
		(stroke
			(width 0.05715)
			(type default)
		)
		(layer "In4.Cu")
	)
	(gr_line
		(start 356.44328 -293.041324)
		(end 356.442264 -293.041832)
		(stroke
			(width 0.05715)
			(type default)
		)
		(layer "In4.Cu")
	)
	(gr_line
		(start 356.44328 -291.421312)
		(end 356.442264 -291.42182)
		(stroke
			(width 0.05715)
			(type default)
		)
		(layer "In4.Cu")
	)
	(gr_line
		(start 356.443788 -294.661082)
		(end 356.44328 -294.661336)
		(stroke
			(width 0.05715)
			(type default)
		)
		(layer "In4.Cu")
	)
	(gr_line
		(start 356.443788 -293.04107)
		(end 356.44328 -293.041324)
		(stroke
			(width 0.05715)
			(type default)
		)
		(layer "In4.Cu")
	)
	(gr_line
		(start 356.443788 -291.421058)
		(end 356.44328 -291.421312)
		(stroke
			(width 0.05715)
			(type default)
		)
		(layer "In4.Cu")
	)
	(gr_line
		(start 356.44709 -294.65905)
		(end 356.445566 -294.660066)
		(stroke
			(width 0.05715)
			(type default)
		)
		(layer "In4.Cu")
	)
	(gr_line
		(start 356.44709 -293.039038)
		(end 356.445566 -293.040054)
		(stroke
			(width 0.05715)
			(type default)
		)
		(layer "In4.Cu")
	)
	(gr_line
		(start 356.44709 -291.419026)
		(end 356.445566 -291.420042)
		(stroke
			(width 0.05715)
			(type default)
		)
		(layer "In4.Cu")
	)
	(gr_line
		(start 356.448106 -294.658542)
		(end 356.44709 -294.65905)
		(stroke
			(width 0.05715)
			(type default)
		)
		(layer "In4.Cu")
	)
	(gr_line
		(start 356.448106 -293.03853)
		(end 356.44709 -293.039038)
		(stroke
			(width 0.05715)
			(type default)
		)
		(layer "In4.Cu")
	)
	(gr_line
		(start 356.448106 -291.418518)
		(end 356.44709 -291.419026)
		(stroke
			(width 0.05715)
			(type default)
		)
		(layer "In4.Cu")
	)
	(gr_line
		(start 356.44836 -294.013636)
		(end 356.448868 -294.01389)
		(stroke
			(width 0.05715)
			(type default)
		)
		(layer "In4.Cu")
	)
	(gr_line
		(start 356.44836 -292.393624)
		(end 356.448868 -292.393878)
		(stroke
			(width 0.05715)
			(type default)
		)
		(layer "In4.Cu")
	)
	(gr_line
		(start 356.44836 -290.773612)
		(end 356.448868 -290.773866)
		(stroke
			(width 0.05715)
			(type default)
		)
		(layer "In4.Cu")
	)
	(gr_line
		(start 356.448868 -294.658034)
		(end 356.448106 -294.658542)
		(stroke
			(width 0.05715)
			(type default)
		)
		(layer "In4.Cu")
	)
	(gr_line
		(start 356.448868 -294.01389)
		(end 356.451662 -294.015414)
		(stroke
			(width 0.05715)
			(type default)
		)
		(layer "In4.Cu")
	)
	(gr_line
		(start 356.448868 -293.038022)
		(end 356.448106 -293.03853)
		(stroke
			(width 0.05715)
			(type default)
		)
		(layer "In4.Cu")
	)
	(gr_line
		(start 356.448868 -292.393878)
		(end 356.451662 -292.395402)
		(stroke
			(width 0.05715)
			(type default)
		)
		(layer "In4.Cu")
	)
	(gr_line
		(start 356.448868 -291.41801)
		(end 356.448106 -291.418518)
		(stroke
			(width 0.05715)
			(type default)
		)
		(layer "In4.Cu")
	)
	(gr_line
		(start 356.448868 -290.773866)
		(end 356.451662 -290.77539)
		(stroke
			(width 0.05715)
			(type default)
		)
		(layer "In4.Cu")
	)
	(gr_line
		(start 356.450646 -294.657018)
		(end 356.448868 -294.658034)
		(stroke
			(width 0.05715)
			(type default)
		)
		(layer "In4.Cu")
	)
	(gr_line
		(start 356.450646 -293.037006)
		(end 356.448868 -293.038022)
		(stroke
			(width 0.05715)
			(type default)
		)
		(layer "In4.Cu")
	)
	(gr_line
		(start 356.450646 -291.416994)
		(end 356.448868 -291.41801)
		(stroke
			(width 0.05715)
			(type default)
		)
		(layer "In4.Cu")
	)
	(gr_line
		(start 356.532688 -294.830246)
		(end 356.531164 -294.831008)
		(stroke
			(width 0.05715)
			(type default)
		)
		(layer "In4.Cu")
	)
	(gr_line
		(start 356.532688 -293.210234)
		(end 356.531164 -293.210996)
		(stroke
			(width 0.05715)
			(type default)
		)
		(layer "In4.Cu")
	)
	(gr_line
		(start 356.532688 -291.590222)
		(end 356.531164 -291.590984)
		(stroke
			(width 0.05715)
			(type default)
		)
		(layer "In4.Cu")
	)
	(gr_line
		(start 356.535228 -294.828722)
		(end 356.53472 -294.828976)
		(stroke
			(width 0.05715)
			(type default)
		)
		(layer "In4.Cu")
	)
	(gr_line
		(start 356.535228 -293.20871)
		(end 356.53472 -293.208964)
		(stroke
			(width 0.05715)
			(type default)
		)
		(layer "In4.Cu")
	)
	(gr_line
		(start 356.535228 -291.588698)
		(end 356.53472 -291.588952)
		(stroke
			(width 0.05715)
			(type default)
		)
		(layer "In4.Cu")
	)
	(gr_line
		(start 356.537768 -294.827198)
		(end 356.537006 -294.827706)
		(stroke
			(width 0.05715)
			(type default)
		)
		(layer "In4.Cu")
	)
	(gr_line
		(start 356.537768 -293.207186)
		(end 356.537006 -293.207694)
		(stroke
			(width 0.05715)
			(type default)
		)
		(layer "In4.Cu")
	)
	(gr_line
		(start 356.537768 -291.587174)
		(end 356.537006 -291.587682)
		(stroke
			(width 0.05715)
			(type default)
		)
		(layer "In4.Cu")
	)
	(gr_line
		(start 356.539292 -294.826182)
		(end 356.537768 -294.827198)
		(stroke
			(width 0.05715)
			(type default)
		)
		(layer "In4.Cu")
	)
	(gr_line
		(start 356.539292 -293.20617)
		(end 356.537768 -293.207186)
		(stroke
			(width 0.05715)
			(type default)
		)
		(layer "In4.Cu")
	)
	(gr_line
		(start 356.539292 -291.586158)
		(end 356.537768 -291.587174)
		(stroke
			(width 0.05715)
			(type default)
		)
		(layer "In4.Cu")
	)
	(gr_line
		(start 356.540308 -294.825674)
		(end 356.539292 -294.826182)
		(stroke
			(width 0.05715)
			(type default)
		)
		(layer "In4.Cu")
	)
	(gr_line
		(start 356.540308 -293.205662)
		(end 356.539292 -293.20617)
		(stroke
			(width 0.05715)
			(type default)
		)
		(layer "In4.Cu")
	)
	(gr_line
		(start 356.540308 -291.58565)
		(end 356.539292 -291.586158)
		(stroke
			(width 0.05715)
			(type default)
		)
		(layer "In4.Cu")
	)
	(gr_line
		(start 356.544118 -294.823388)
		(end 356.543356 -294.823896)
		(stroke
			(width 0.05715)
			(type default)
		)
		(layer "In4.Cu")
	)
	(gr_line
		(start 356.544118 -293.848536)
		(end 356.545134 -293.849044)
		(stroke
			(width 0.05715)
			(type default)
		)
		(layer "In4.Cu")
	)
	(gr_line
		(start 356.544118 -293.203376)
		(end 356.543356 -293.203884)
		(stroke
			(width 0.05715)
			(type default)
		)
		(layer "In4.Cu")
	)
	(gr_line
		(start 356.544118 -292.228524)
		(end 356.545134 -292.229032)
		(stroke
			(width 0.05715)
			(type default)
		)
		(layer "In4.Cu")
	)
	(gr_line
		(start 356.544118 -291.583364)
		(end 356.543356 -291.583872)
		(stroke
			(width 0.05715)
			(type default)
		)
		(layer "In4.Cu")
	)
	(gr_line
		(start 356.544118 -290.608512)
		(end 356.545134 -290.60902)
		(stroke
			(width 0.05715)
			(type default)
		)
		(layer "In4.Cu")
	)
	(gr_line
		(start 356.545134 -294.82288)
		(end 356.544118 -294.823388)
		(stroke
			(width 0.05715)
			(type default)
		)
		(layer "In4.Cu")
	)
	(gr_line
		(start 356.545134 -293.849044)
		(end 356.546658 -293.85006)
		(stroke
			(width 0.05715)
			(type default)
		)
		(layer "In4.Cu")
	)
	(gr_line
		(start 356.545134 -293.202868)
		(end 356.544118 -293.203376)
		(stroke
			(width 0.05715)
			(type default)
		)
		(layer "In4.Cu")
	)
	(gr_line
		(start 356.545134 -292.229032)
		(end 356.546658 -292.230048)
		(stroke
			(width 0.05715)
			(type default)
		)
		(layer "In4.Cu")
	)
	(gr_line
		(start 356.545134 -291.582856)
		(end 356.544118 -291.583364)
		(stroke
			(width 0.05715)
			(type default)
		)
		(layer "In4.Cu")
	)
	(gr_line
		(start 356.545134 -290.60902)
		(end 356.546658 -290.610036)
		(stroke
			(width 0.05715)
			(type default)
		)
		(layer "In4.Cu")
	)
	(gr_line
		(start 356.546658 -293.85006)
		(end 356.547674 -293.850568)
		(stroke
			(width 0.05715)
			(type default)
		)
		(layer "In4.Cu")
	)
	(gr_line
		(start 356.546658 -292.230048)
		(end 356.547674 -292.230556)
		(stroke
			(width 0.05715)
			(type default)
		)
		(layer "In4.Cu")
	)
	(gr_line
		(start 356.546658 -290.610036)
		(end 356.547674 -290.610544)
		(stroke
			(width 0.05715)
			(type default)
		)
		(layer "In4.Cu")
	)
	(gr_line
		(start 356.54742 -294.821356)
		(end 356.546658 -294.821864)
		(stroke
			(width 0.05715)
			(type default)
		)
		(layer "In4.Cu")
	)
	(gr_line
		(start 356.54742 -293.201344)
		(end 356.546658 -293.201852)
		(stroke
			(width 0.05715)
			(type default)
		)
		(layer "In4.Cu")
	)
	(gr_line
		(start 356.54742 -291.581332)
		(end 356.546658 -291.58184)
		(stroke
			(width 0.05715)
			(type default)
		)
		(layer "In4.Cu")
	)
	(gr_line
		(start 356.547674 -293.850568)
		(end 356.552754 -293.853616)
		(stroke
			(width 0.05715)
			(type default)
		)
		(layer "In4.Cu")
	)
	(gr_line
		(start 356.547674 -292.230556)
		(end 356.552754 -292.233604)
		(stroke
			(width 0.05715)
			(type default)
		)
		(layer "In4.Cu")
	)
	(gr_line
		(start 356.547674 -290.610544)
		(end 356.552754 -290.613592)
		(stroke
			(width 0.05715)
			(type default)
		)
		(layer "In4.Cu")
	)
	(gr_line
		(start 356.731062 -290.285932)
		(end 357.029004 -290.285932)
		(stroke
			(width 0.05715)
			(type default)
		)
		(layer "In4.Cu")
	)
	(gr_line
		(start 356.731062 -288.66592)
		(end 357.029004 -288.66592)
		(stroke
			(width 0.05715)
			(type default)
		)
		(layer "In4.Cu")
	)
	(gr_line
		(start 356.731062 -287.045908)
		(end 357.029004 -287.045908)
		(stroke
			(width 0.05715)
			(type default)
		)
		(layer "In4.Cu")
	)
	(gr_line
		(start 357.029004 -290.285932)
		(end 357.111808 -290.368736)
		(stroke
			(width 0.05715)
			(type default)
		)
		(layer "In4.Cu")
	)
	(gr_line
		(start 357.029004 -288.66592)
		(end 357.111808 -288.748724)
		(stroke
			(width 0.05715)
			(type default)
		)
		(layer "In4.Cu")
	)
	(gr_line
		(start 357.029004 -287.045908)
		(end 357.111808 -287.128712)
		(stroke
			(width 0.05715)
			(type default)
		)
		(layer "In4.Cu")
	)
	(gr_line
		(start 357.034846 -319.991994)
		(end 357.034846 -319.99174)
		(stroke
			(width 0.07112)
			(type default)
		)
		(layer "In4.Cu")
	)
	(gr_line
		(start 357.059992 -295.528746)
		(end 357.059992 -295.557194)
		(stroke
			(width 0.05715)
			(type default)
		)
		(layer "In4.Cu")
	)
	(gr_line
		(start 357.105712 -295.483026)
		(end 357.059992 -295.528746)
		(stroke
			(width 0.05715)
			(type default)
		)
		(layer "In4.Cu")
	)
	(gr_arc
		(start 357.111808 -290.368736)
		(mid 357.113599 -290.380058)
		(end 357.115618 -290.391342)
		(stroke
			(width 0.05715)
			(type default)
		)
		(layer "In4.Cu")
	)
	(gr_arc
		(start 357.111808 -288.748724)
		(mid 357.113852 -288.760049)
		(end 357.116126 -288.77133)
		(stroke
			(width 0.05715)
			(type default)
		)
		(layer "In4.Cu")
	)
	(gr_arc
		(start 357.111808 -287.128712)
		(mid 357.113503 -287.138506)
		(end 357.115364 -287.14827)
		(stroke
			(width 0.05715)
			(type default)
		)
		(layer "In4.Cu")
	)
	(gr_arc
		(start 357.115364 -287.14827)
		(mid 357.115616 -287.149667)
		(end 357.115872 -287.151064)
		(stroke
			(width 0.05715)
			(type default)
		)
		(layer "In4.Cu")
	)
	(gr_line
		(start 357.260398 -360.888026)
		(end 357.25989 -360.888534)
		(stroke
			(width 0.07112)
			(type default)
		)
		(layer "In4.Cu")
	)
	(gr_line
		(start 357.296212 -295.483026)
		(end 357.341932 -295.528746)
		(stroke
			(width 0.05715)
			(type default)
		)
		(layer "In4.Cu")
	)
	(gr_line
		(start 357.341932 -295.528746)
		(end 357.341932 -295.557194)
		(stroke
			(width 0.05715)
			(type default)
		)
		(layer "In4.Cu")
	)
	(gr_arc
		(start 357.349044 -294.681402)
		(mid 357.345095 -294.684179)
		(end 357.34117 -294.68699)
		(stroke
			(width 0.05715)
			(type default)
		)
		(layer "In4.Cu")
	)
	(gr_line
		(start 357.35387 -294.678608)
		(end 357.349044 -294.681402)
		(stroke
			(width 0.05715)
			(type default)
		)
		(layer "In4.Cu")
	)
	(gr_line
		(start 357.354378 -294.678354)
		(end 357.35387 -294.678608)
		(stroke
			(width 0.05715)
			(type default)
		)
		(layer "In4.Cu")
	)
	(gr_line
		(start 357.360474 -377.1265)
		(end 357.069644 -377.41733)
		(stroke
			(width 0.07112)
			(type default)
		)
		(layer "In4.Cu")
	)
	(gr_line
		(start 357.361236 -294.674036)
		(end 357.358188 -294.676068)
		(stroke
			(width 0.05715)
			(type default)
		)
		(layer "In4.Cu")
	)
	(gr_arc
		(start 357.372158 -294.00373)
		(mid 357.374947 -294.005516)
		(end 357.377746 -294.007286)
		(stroke
			(width 0.05715)
			(type default)
		)
		(layer "In4.Cu")
	)
	(gr_line
		(start 357.373174 -290.285932)
		(end 357.303832 -290.355274)
		(stroke
			(width 0.05715)
			(type default)
		)
		(layer "In4.Cu")
	)
	(gr_line
		(start 357.373174 -288.66592)
		(end 357.303324 -288.73577)
		(stroke
			(width 0.05715)
			(type default)
		)
		(layer "In4.Cu")
	)
	(gr_line
		(start 357.373174 -287.045908)
		(end 357.304086 -287.114996)
		(stroke
			(width 0.05715)
			(type default)
		)
		(layer "In4.Cu")
	)
	(gr_arc
		(start 357.38181 -293.042086)
		(mid 357.379902 -293.043352)
		(end 357.378 -293.044626)
		(stroke
			(width 0.05715)
			(type default)
		)
		(layer "In4.Cu")
	)
	(gr_line
		(start 357.38816 -293.03853)
		(end 357.387906 -293.03853)
		(stroke
			(width 0.05715)
			(type default)
		)
		(layer "In4.Cu")
	)
	(gr_line
		(start 357.389938 -294.014398)
		(end 357.3907 -294.014906)
		(stroke
			(width 0.05715)
			(type default)
		)
		(layer "In4.Cu")
	)
	(gr_line
		(start 357.392732 -293.03599)
		(end 357.3907 -293.037006)
		(stroke
			(width 0.05715)
			(type default)
		)
		(layer "In4.Cu")
	)
	(gr_line
		(start 357.39324 -291.41547)
		(end 357.388922 -291.41801)
		(stroke
			(width 0.05715)
			(type default)
		)
		(layer "In4.Cu")
	)
	(gr_line
		(start 357.439214 -290.805362)
		(end 357.439722 -290.80587)
		(stroke
			(width 0.05715)
			(type default)
		)
		(layer "In4.Cu")
	)
	(gr_line
		(start 357.483664 -293.848282)
		(end 357.48595 -293.849552)
		(stroke
			(width 0.05715)
			(type default)
		)
		(layer "In4.Cu")
	)
	(gr_line
		(start 357.484172 -291.583364)
		(end 357.483664 -291.583618)
		(stroke
			(width 0.05715)
			(type default)
		)
		(layer "In4.Cu")
	)
	(gr_line
		(start 357.48595 -293.849552)
		(end 357.486458 -293.85006)
		(stroke
			(width 0.05715)
			(type default)
		)
		(layer "In4.Cu")
	)
	(gr_arc
		(start 357.486458 -294.822118)
		(mid 357.487602 -294.821484)
		(end 357.488744 -294.820848)
		(stroke
			(width 0.05715)
			(type default)
		)
		(layer "In4.Cu")
	)
	(gr_line
		(start 357.488744 -293.200582)
		(end 357.483918 -293.20363)
		(stroke
			(width 0.05715)
			(type default)
		)
		(layer "In4.Cu")
	)
	(gr_arc
		(start 357.503476 -292.240208)
		(mid 357.503984 -292.240589)
		(end 357.504492 -292.24097)
		(stroke
			(width 0.05715)
			(type default)
		)
		(layer "In4.Cu")
	)
	(gr_line
		(start 357.642414 -377.1265)
		(end 357.933244 -377.41733)
		(stroke
			(width 0.07112)
			(type default)
		)
		(layer "In4.Cu")
	)
	(gr_line
		(start 357.671116 -290.285932)
		(end 357.373174 -290.285932)
		(stroke
			(width 0.05715)
			(type default)
		)
		(layer "In4.Cu")
	)
	(gr_line
		(start 357.671116 -288.66592)
		(end 357.373174 -288.66592)
		(stroke
			(width 0.05715)
			(type default)
		)
		(layer "In4.Cu")
	)
	(gr_line
		(start 357.671116 -287.045908)
		(end 357.373174 -287.045908)
		(stroke
			(width 0.05715)
			(type default)
		)
		(layer "In4.Cu")
	)
	(gr_line
		(start 357.762556 -289.439858)
		(end 357.76281 -289.441128)
		(stroke
			(width 0.05715)
			(type default)
		)
		(layer "In4.Cu")
	)
	(gr_line
		(start 357.762556 -287.819592)
		(end 357.76281 -287.820862)
		(stroke
			(width 0.05715)
			(type default)
		)
		(layer "In4.Cu")
	)
	(gr_line
		(start 357.766366 -289.484308)
		(end 357.766366 -289.485578)
		(stroke
			(width 0.05715)
			(type default)
		)
		(layer "In4.Cu")
	)
	(gr_line
		(start 357.766366 -287.863788)
		(end 357.766366 -287.865566)
		(stroke
			(width 0.05715)
			(type default)
		)
		(layer "In4.Cu")
	)
	(gr_line
		(start 357.951278 -288.177478)
		(end 357.957374 -288.18078)
		(stroke
			(width 0.05715)
			(type default)
		)
		(layer "In4.Cu")
	)
	(gr_line
		(start 358.000046 -295.528746)
		(end 358.000046 -295.557194)
		(stroke
			(width 0.05715)
			(type default)
		)
		(layer "In4.Cu")
	)
	(gr_line
		(start 358.045766 -295.483026)
		(end 358.000046 -295.528746)
		(stroke
			(width 0.05715)
			(type default)
		)
		(layer "In4.Cu")
	)
	(gr_line
		(start 358.236266 -295.483026)
		(end 358.281986 -295.528746)
		(stroke
			(width 0.05715)
			(type default)
		)
		(layer "In4.Cu")
	)
	(gr_line
		(start 358.281986 -295.528746)
		(end 358.281986 -295.557194)
		(stroke
			(width 0.05715)
			(type default)
		)
		(layer "In4.Cu")
	)
	(gr_arc
		(start 358.289098 -291.441378)
		(mid 358.285915 -291.443653)
		(end 358.282748 -291.44595)
		(stroke
			(width 0.05715)
			(type default)
		)
		(layer "In4.Cu")
	)
	(gr_arc
		(start 358.290622 -291.440362)
		(mid 358.28986 -291.440869)
		(end 358.289098 -291.441378)
		(stroke
			(width 0.05715)
			(type default)
		)
		(layer "In4.Cu")
	)
	(gr_line
		(start 358.29748 -291.436298)
		(end 358.290622 -291.440362)
		(stroke
			(width 0.05715)
			(type default)
		)
		(layer "In4.Cu")
	)
	(gr_arc
		(start 358.315514 -294.006016)
		(mid 358.317544 -294.007163)
		(end 358.319578 -294.008302)
		(stroke
			(width 0.05715)
			(type default)
		)
		(layer "In4.Cu")
	)
	(gr_line
		(start 358.327198 -290.77285)
		(end 358.32796 -290.773358)
		(stroke
			(width 0.05715)
			(type default)
		)
		(layer "In4.Cu")
	)
	(gr_line
		(start 358.32796 -294.013382)
		(end 358.328214 -294.013382)
		(stroke
			(width 0.05715)
			(type default)
		)
		(layer "In4.Cu")
	)
	(gr_line
		(start 358.32796 -289.153346)
		(end 358.328214 -289.153346)
		(stroke
			(width 0.05715)
			(type default)
		)
		(layer "In4.Cu")
	)
	(gr_line
		(start 358.328214 -293.03853)
		(end 358.32796 -293.038784)
		(stroke
			(width 0.05715)
			(type default)
		)
		(layer "In4.Cu")
	)
	(gr_line
		(start 358.423972 -290.608512)
		(end 358.424226 -290.608766)
		(stroke
			(width 0.05715)
			(type default)
		)
		(layer "In4.Cu")
	)
	(gr_line
		(start 358.423972 -288.9885)
		(end 358.424226 -288.988754)
		(stroke
			(width 0.05715)
			(type default)
		)
		(layer "In4.Cu")
	)
	(gr_line
		(start 358.424226 -291.583364)
		(end 358.423972 -291.583364)
		(stroke
			(width 0.05715)
			(type default)
		)
		(layer "In4.Cu")
	)
	(gr_arc
		(start 358.432608 -291.578284)
		(mid 358.434642 -291.577145)
		(end 358.436672 -291.575998)
		(stroke
			(width 0.05715)
			(type default)
		)
		(layer "In4.Cu")
	)
	(gr_line
		(start 358.445562 -293.19093)
		(end 358.445308 -293.19093)
		(stroke
			(width 0.05715)
			(type default)
		)
		(layer "In4.Cu")
	)
	(gr_line
		(start 358.45623 -293.867332)
		(end 358.461564 -293.87038)
		(stroke
			(width 0.05715)
			(type default)
		)
		(layer "In4.Cu")
	)
	(gr_line
		(start 358.456484 -293.184326)
		(end 358.455722 -293.184834)
		(stroke
			(width 0.05715)
			(type default)
		)
		(layer "In4.Cu")
	)
	(gr_arc
		(start 358.463088 -293.871396)
		(mid 358.462326 -293.870887)
		(end 358.461564 -293.87038)
		(stroke
			(width 0.05715)
			(type default)
		)
		(layer "In4.Cu")
	)
	(gr_line
		(start 358.463088 -293.871396)
		(end 358.468676 -293.875206)
		(stroke
			(width 0.05715)
			(type default)
		)
		(layer "In4.Cu")
	)
	(gr_line
		(start 358.463088 -293.180516)
		(end 358.456484 -293.184326)
		(stroke
			(width 0.05715)
			(type default)
		)
		(layer "In4.Cu")
	)
	(gr_arc
		(start 358.463088 -293.180516)
		(mid 358.464232 -293.179756)
		(end 358.465374 -293.178992)
		(stroke
			(width 0.05715)
			(type default)
		)
		(layer "In4.Cu")
	)
	(gr_arc
		(start 358.466136 -293.178484)
		(mid 358.468937 -293.176461)
		(end 358.471724 -293.17442)
		(stroke
			(width 0.05715)
			(type default)
		)
		(layer "In4.Cu")
	)
	(gr_line
		(start 358.515412 -292.728904)
		(end 358.515412 -292.72992)
		(stroke
			(width 0.05715)
			(type default)
		)
		(layer "In4.Cu")
	)
	(gr_arc
		(start 358.705912 -292.737032)
		(mid 358.706051 -292.733476)
		(end 358.706166 -292.72992)
		(stroke
			(width 0.05715)
			(type default)
		)
		(layer "In4.Cu")
	)
	(gr_line
		(start 358.706166 -292.71595)
		(end 358.70642 -292.71595)
		(stroke
			(width 0.05715)
			(type default)
		)
		(layer "In4.Cu")
	)
	(gr_line
		(start 359.13949 -290.25342)
		(end 359.13949 -290.281868)
		(stroke
			(width 0.05715)
			(type default)
		)
		(layer "In4.Cu")
	)
	(gr_line
		(start 359.18521 -290.2077)
		(end 359.13949 -290.25342)
		(stroke
			(width 0.05715)
			(type default)
		)
		(layer "In4.Cu")
	)
	(gr_line
		(start 359.228898 -212.734398)
		(end 359.229152 -212.734398)
		(stroke
			(width 0.07112)
			(type default)
		)
		(layer "In4.Cu")
	)
	(gr_line
		(start 359.309924 -383.275332)
		(end 359.117646 -383.275332)
		(stroke
			(width 0.07112)
			(type default)
		)
		(layer "In4.Cu")
	)
	(gr_line
		(start 359.37571 -290.2077)
		(end 359.42143 -290.25342)
		(stroke
			(width 0.05715)
			(type default)
		)
		(layer "In4.Cu")
	)
	(gr_line
		(start 359.41254 -382.57988)
		(end 358.916478 -383.075942)
		(stroke
			(width 0.07112)
			(type default)
		)
		(layer "In4.Cu")
	)
	(gr_line
		(start 359.42143 -290.25342)
		(end 359.42143 -290.281868)
		(stroke
			(width 0.05715)
			(type default)
		)
		(layer "In4.Cu")
	)
	(gr_line
		(start 359.514394 -385.047998)
		(end 359.805224 -385.338828)
		(stroke
			(width 0.07112)
			(type default)
		)
		(layer "In4.Cu")
	)
	(gr_line
		(start 359.514394 -384.766058)
		(end 359.805224 -384.475228)
		(stroke
			(width 0.07112)
			(type default)
		)
		(layer "In4.Cu")
	)
	(gr_line
		(start 359.61193 -382.973326)
		(end 359.309924 -383.275332)
		(stroke
			(width 0.07112)
			(type default)
		)
		(layer "In4.Cu")
	)
	(gr_line
		(start 359.61193 -382.781048)
		(end 359.61193 -382.973326)
		(stroke
			(width 0.07112)
			(type default)
		)
		(layer "In4.Cu")
	)
	(gr_line
		(start 360.096054 -388.451598)
		(end 359.805224 -388.742428)
		(stroke
			(width 0.07112)
			(type default)
		)
		(layer "In4.Cu")
	)
	(gr_line
		(start 360.096054 -388.169658)
		(end 359.805224 -387.878828)
		(stroke
			(width 0.07112)
			(type default)
		)
		(layer "In4.Cu")
	)
	(gr_line
		(start 360.107484 -382.477772)
		(end 359.915206 -382.477772)
		(stroke
			(width 0.07112)
			(type default)
		)
		(layer "In4.Cu")
	)
	(gr_line
		(start 360.2101 -381.78232)
		(end 359.714038 -382.278382)
		(stroke
			(width 0.07112)
			(type default)
		)
		(layer "In4.Cu")
	)
	(gr_line
		(start 360.40949 -382.175766)
		(end 360.107484 -382.477772)
		(stroke
			(width 0.07112)
			(type default)
		)
		(layer "In4.Cu")
	)
	(gr_line
		(start 360.40949 -381.983488)
		(end 360.40949 -382.175766)
		(stroke
			(width 0.07112)
			(type default)
		)
		(layer "In4.Cu")
	)
	(gr_line
		(start 360.790744 -233.200956)
		(end 360.770678 -233.18089)
		(stroke
			(width 0.05715)
			(type default)
		)
		(layer "In4.Cu")
	)
	(gr_line
		(start 360.798364 -206.653638)
		(end 360.798618 -206.653638)
		(stroke
			(width 0.07112)
			(type default)
		)
		(layer "In4.Cu")
	)
	(gr_line
		(start 360.854752 -233.200702)
		(end 360.790744 -233.200956)
		(stroke
			(width 0.05715)
			(type default)
		)
		(layer "In4.Cu")
	)
	(gr_line
		(start 360.85526 -233.201464)
		(end 360.854752 -233.200702)
		(stroke
			(width 0.05715)
			(type default)
		)
		(layer "In4.Cu")
	)
	(gr_line
		(start 360.961686 -289.548316)
		(end 360.981752 -289.52825)
		(stroke
			(width 0.05715)
			(type default)
		)
		(layer "In4.Cu")
	)
	(gr_line
		(start 360.961686 -289.548062)
		(end 360.961686 -289.548316)
		(stroke
			(width 0.05715)
			(type default)
		)
		(layer "In4.Cu")
	)
	(gr_line
		(start 360.970068 -232.9815)
		(end 360.990134 -233.001566)
		(stroke
			(width 0.05715)
			(type default)
		)
		(layer "In4.Cu")
	)
	(gr_line
		(start 360.981752 -289.52825)
		(end 361.04576 -289.52825)
		(stroke
			(width 0.05715)
			(type default)
		)
		(layer "In4.Cu")
	)
	(gr_line
		(start 360.990134 -233.001566)
		(end 360.990134 -233.06532)
		(stroke
			(width 0.05715)
			(type default)
		)
		(layer "In4.Cu")
	)
	(gr_line
		(start 361.029758 -231.524048)
		(end 361.029504 -231.524048)
		(stroke
			(width 0.05715)
			(type default)
		)
		(layer "In4.Cu")
	)
	(gr_line
		(start 361.04576 -289.52825)
		(end 361.046268 -289.527488)
		(stroke
			(width 0.05715)
			(type default)
		)
		(layer "In4.Cu")
	)
	(gr_line
		(start 361.161076 -289.747452)
		(end 361.181142 -289.727386)
		(stroke
			(width 0.05715)
			(type default)
		)
		(layer "In4.Cu")
	)
	(gr_line
		(start 361.181142 -289.727386)
		(end 361.181142 -289.663632)
		(stroke
			(width 0.05715)
			(type default)
		)
		(layer "In4.Cu")
	)
	(gr_line
		(start 361.220258 -231.524048)
		(end 361.220512 -231.524048)
		(stroke
			(width 0.05715)
			(type default)
		)
		(layer "In4.Cu")
	)
	(gr_line
		(start 361.289854 -387.041136)
		(end 361.425744 -387.177026)
		(stroke
			(width 0.07112)
			(type default)
		)
		(layer "In4.Cu")
	)
	(gr_line
		(start 361.289854 -386.614416)
		(end 361.289854 -387.041136)
		(stroke
			(width 0.07112)
			(type default)
		)
		(layer "In4.Cu")
	)
	(gr_line
		(start 361.289854 -385.913376)
		(end 361.425744 -386.049266)
		(stroke
			(width 0.07112)
			(type default)
		)
		(layer "In4.Cu")
	)
	(gr_line
		(start 361.289854 -385.486656)
		(end 361.289854 -385.913376)
		(stroke
			(width 0.07112)
			(type default)
		)
		(layer "In4.Cu")
	)
	(gr_line
		(start 361.289854 -384.785616)
		(end 361.425744 -384.921506)
		(stroke
			(width 0.07112)
			(type default)
		)
		(layer "In4.Cu")
	)
	(gr_line
		(start 361.289854 -384.358896)
		(end 361.289854 -384.785616)
		(stroke
			(width 0.07112)
			(type default)
		)
		(layer "In4.Cu")
	)
	(gr_line
		(start 361.289854 -383.646934)
		(end 361.425744 -383.782824)
		(stroke
			(width 0.07112)
			(type default)
		)
		(layer "In4.Cu")
	)
	(gr_line
		(start 361.289854 -383.220214)
		(end 361.289854 -383.646934)
		(stroke
			(width 0.07112)
			(type default)
		)
		(layer "In4.Cu")
	)
	(gr_line
		(start 361.311698 -233.631232)
		(end 361.311952 -233.631486)
		(stroke
			(width 0.05715)
			(type default)
		)
		(layer "In4.Cu")
	)
	(gr_line
		(start 361.405932 -231.205532)
		(end 361.4039 -231.206548)
		(stroke
			(width 0.05715)
			(type default)
		)
		(layer "In4.Cu")
	)
	(gr_line
		(start 361.425744 -386.478526)
		(end 361.289854 -386.614416)
		(stroke
			(width 0.07112)
			(type default)
		)
		(layer "In4.Cu")
	)
	(gr_line
		(start 361.425744 -385.350766)
		(end 361.289854 -385.486656)
		(stroke
			(width 0.07112)
			(type default)
		)
		(layer "In4.Cu")
	)
	(gr_line
		(start 361.425744 -384.223006)
		(end 361.289854 -384.358896)
		(stroke
			(width 0.07112)
			(type default)
		)
		(layer "In4.Cu")
	)
	(gr_line
		(start 361.425744 -383.084324)
		(end 361.289854 -383.220214)
		(stroke
			(width 0.07112)
			(type default)
		)
		(layer "In4.Cu")
	)
	(gr_line
		(start 361.611672 -288.988754)
		(end 361.611926 -288.9885)
		(stroke
			(width 0.05715)
			(type default)
		)
		(layer "In4.Cu")
	)
	(gr_line
		(start 361.708954 -386.477256)
		(end 361.708954 -387.178296)
		(stroke
			(width 0.07112)
			(type default)
		)
		(layer "In4.Cu")
	)
	(gr_line
		(start 361.708954 -385.349496)
		(end 361.708954 -386.050536)
		(stroke
			(width 0.07112)
			(type default)
		)
		(layer "In4.Cu")
	)
	(gr_line
		(start 361.708954 -384.221736)
		(end 361.708954 -384.922776)
		(stroke
			(width 0.07112)
			(type default)
		)
		(layer "In4.Cu")
	)
	(gr_line
		(start 361.708954 -383.083054)
		(end 361.708954 -383.784094)
		(stroke
			(width 0.07112)
			(type default)
		)
		(layer "In4.Cu")
	)
	(gr_arc
		(start 361.734862 -234.413044)
		(mid 361.738787 -234.415855)
		(end 361.742736 -234.418632)
		(stroke
			(width 0.05715)
			(type default)
		)
		(layer "In4.Cu")
	)
	(gr_line
		(start 361.749594 -234.422696)
		(end 361.742736 -234.418632)
		(stroke
			(width 0.05715)
			(type default)
		)
		(layer "In4.Cu")
	)
	(gr_line
		(start 361.750356 -234.423204)
		(end 361.749594 -234.422696)
		(stroke
			(width 0.05715)
			(type default)
		)
		(layer "In4.Cu")
	)
	(gr_line
		(start 361.751118 -234.423712)
		(end 361.750356 -234.423204)
		(stroke
			(width 0.05715)
			(type default)
		)
		(layer "In4.Cu")
	)
	(gr_line
		(start 361.777534 -234.438952)
		(end 361.776518 -234.438444)
		(stroke
			(width 0.05715)
			(type default)
		)
		(layer "In4.Cu")
	)
	(gr_line
		(start 361.799378 -288.66592)
		(end 361.799632 -288.66592)
		(stroke
			(width 0.05715)
			(type default)
		)
		(layer "In4.Cu")
	)
	(gr_line
		(start 361.870244 -234.272328)
		(end 361.871768 -234.27309)
		(stroke
			(width 0.05715)
			(type default)
		)
		(layer "In4.Cu")
	)
	(gr_line
		(start 361.871768 -234.27309)
		(end 361.873292 -234.274106)
		(stroke
			(width 0.05715)
			(type default)
		)
		(layer "In4.Cu")
	)
	(gr_line
		(start 361.875832 -234.275376)
		(end 361.877102 -234.276138)
		(stroke
			(width 0.05715)
			(type default)
		)
		(layer "In4.Cu")
	)
	(gr_line
		(start 361.877102 -234.276138)
		(end 361.877864 -234.276646)
		(stroke
			(width 0.05715)
			(type default)
		)
		(layer "In4.Cu")
	)
	(gr_line
		(start 361.969558 -221.308676)
		(end 361.969304 -221.30893)
		(stroke
			(width 0.05715)
			(type default)
		)
		(layer "In4.Cu")
	)
	(gr_line
		(start 361.969558 -221.128844)
		(end 361.923838 -221.083124)
		(stroke
			(width 0.05715)
			(type default)
		)
		(layer "In4.Cu")
	)
	(gr_arc
		(start 362.034836 -290.74491)
		(mid 362.038761 -290.747721)
		(end 362.04271 -290.750498)
		(stroke
			(width 0.05715)
			(type default)
		)
		(layer "In4.Cu")
	)
	(gr_arc
		(start 362.040678 -288.202878)
		(mid 362.036345 -288.205905)
		(end 362.032042 -288.208974)
		(stroke
			(width 0.05715)
			(type default)
		)
		(layer "In4.Cu")
	)
	(gr_line
		(start 362.040678 -288.202878)
		(end 362.042202 -288.201862)
		(stroke
			(width 0.05715)
			(type default)
		)
		(layer "In4.Cu")
	)
	(gr_line
		(start 362.042202 -288.201862)
		(end 362.043726 -288.2011)
		(stroke
			(width 0.05715)
			(type default)
		)
		(layer "In4.Cu")
	)
	(gr_arc
		(start 362.043472 -290.751006)
		(mid 362.043091 -290.750752)
		(end 362.04271 -290.750498)
		(stroke
			(width 0.05715)
			(type default)
		)
		(layer "In4.Cu")
	)
	(gr_line
		(start 362.043726 -288.2011)
		(end 362.044488 -288.200084)
		(stroke
			(width 0.05715)
			(type default)
		)
		(layer "In4.Cu")
	)
	(gr_line
		(start 362.044488 -288.200084)
		(end 362.048044 -288.198052)
		(stroke
			(width 0.05715)
			(type default)
		)
		(layer "In4.Cu")
	)
	(gr_line
		(start 362.048044 -288.198052)
		(end 362.048298 -288.197798)
		(stroke
			(width 0.05715)
			(type default)
		)
		(layer "In4.Cu")
	)
	(gr_line
		(start 362.051092 -290.755324)
		(end 362.043472 -290.751006)
		(stroke
			(width 0.05715)
			(type default)
		)
		(layer "In4.Cu")
	)
	(gr_line
		(start 362.064808 -235.574078)
		(end 362.36275 -235.574078)
		(stroke
			(width 0.05715)
			(type default)
		)
		(layer "In4.Cu")
	)
	(gr_line
		(start 362.064808 -233.954066)
		(end 362.36275 -233.954066)
		(stroke
			(width 0.05715)
			(type default)
		)
		(layer "In4.Cu")
	)
	(gr_line
		(start 362.064808 -232.334054)
		(end 362.36275 -232.334054)
		(stroke
			(width 0.05715)
			(type default)
		)
		(layer "In4.Cu")
	)
	(gr_line
		(start 362.072174 -374.170956)
		(end 361.704636 -374.704356)
		(stroke
			(width 0.07112)
			(type default)
		)
		(layer "In4.Cu")
	)
	(gr_line
		(start 362.081826 -288.17824)
		(end 362.082842 -288.177732)
		(stroke
			(width 0.05715)
			(type default)
		)
		(layer "In4.Cu")
	)
	(gr_line
		(start 362.090208 -374.836182)
		(end 361.93857 -374.864122)
		(stroke
			(width 0.07112)
			(type default)
		)
		(layer "In4.Cu")
	)
	(gr_arc
		(start 362.160058 -234.764072)
		(mid 362.160068 -234.76077)
		(end 362.160058 -234.757468)
		(stroke
			(width 0.05715)
			(type default)
		)
		(layer "In4.Cu")
	)
	(gr_line
		(start 362.160058 -221.38767)
		(end 362.159804 -221.387924)
		(stroke
			(width 0.05715)
			(type default)
		)
		(layer "In4.Cu")
	)
	(gr_line
		(start 362.177838 -288.343594)
		(end 362.178346 -288.342832)
		(stroke
			(width 0.05715)
			(type default)
		)
		(layer "In4.Cu")
	)
	(gr_arc
		(start 362.181648 -289.961066)
		(mid 362.182537 -289.960559)
		(end 362.183426 -289.96005)
		(stroke
			(width 0.05715)
			(type default)
		)
		(layer "In4.Cu")
	)
	(gr_line
		(start 362.205778 -221.083124)
		(end 362.160058 -221.128844)
		(stroke
			(width 0.05715)
			(type default)
		)
		(layer "In4.Cu")
	)
	(gr_line
		(start 362.223812 -296.35831)
		(end 362.223812 -296.329862)
		(stroke
			(width 0.05715)
			(type default)
		)
		(layer "In4.Cu")
	)
	(gr_line
		(start 362.223812 -296.329862)
		(end 362.269532 -296.284142)
		(stroke
			(width 0.05715)
			(type default)
		)
		(layer "In4.Cu")
	)
	(gr_arc
		(start 362.234988 -228.762052)
		(mid 362.238283 -228.764095)
		(end 362.241592 -228.766116)
		(stroke
			(width 0.05715)
			(type default)
		)
		(layer "In4.Cu")
	)
	(gr_arc
		(start 362.241592 -227.80244)
		(mid 362.238283 -227.804461)
		(end 362.234988 -227.806504)
		(stroke
			(width 0.05715)
			(type default)
		)
		(layer "In4.Cu")
	)
	(gr_line
		(start 362.251752 -231.036622)
		(end 362.252514 -231.036114)
		(stroke
			(width 0.05715)
			(type default)
		)
		(layer "In4.Cu")
	)
	(gr_line
		(start 362.252006 -230.391462)
		(end 362.251752 -230.391716)
		(stroke
			(width 0.05715)
			(type default)
		)
		(layer "In4.Cu")
	)
	(gr_line
		(start 362.25226 -232.011728)
		(end 362.251752 -232.011474)
		(stroke
			(width 0.05715)
			(type default)
		)
		(layer "In4.Cu")
	)
	(gr_line
		(start 362.252514 -235.252006)
		(end 362.252006 -235.251752)
		(stroke
			(width 0.05715)
			(type default)
		)
		(layer "In4.Cu")
	)
	(gr_line
		(start 362.253784 -235.252768)
		(end 362.252514 -235.252006)
		(stroke
			(width 0.05715)
			(type default)
		)
		(layer "In4.Cu")
	)
	(gr_line
		(start 362.2548 -235.253276)
		(end 362.253784 -235.252768)
		(stroke
			(width 0.05715)
			(type default)
		)
		(layer "In4.Cu")
	)
	(gr_line
		(start 362.25607 -227.794312)
		(end 362.25734 -227.79355)
		(stroke
			(width 0.05715)
			(type default)
		)
		(layer "In4.Cu")
	)
	(gr_line
		(start 362.257086 -235.254546)
		(end 362.25607 -235.254038)
		(stroke
			(width 0.05715)
			(type default)
		)
		(layer "In4.Cu")
	)
	(gr_line
		(start 362.25734 -227.79355)
		(end 362.258356 -227.793042)
		(stroke
			(width 0.05715)
			(type default)
		)
		(layer "In4.Cu")
	)
	(gr_line
		(start 362.257848 -235.255054)
		(end 362.257086 -235.254546)
		(stroke
			(width 0.05715)
			(type default)
		)
		(layer "In4.Cu")
	)
	(gr_line
		(start 362.258356 -227.793042)
		(end 362.259118 -227.792534)
		(stroke
			(width 0.05715)
			(type default)
		)
		(layer "In4.Cu")
	)
	(gr_line
		(start 362.258864 -235.255562)
		(end 362.257848 -235.255054)
		(stroke
			(width 0.05715)
			(type default)
		)
		(layer "In4.Cu")
	)
	(gr_line
		(start 362.26115 -228.776784)
		(end 362.257848 -228.77526)
		(stroke
			(width 0.05715)
			(type default)
		)
		(layer "In4.Cu")
	)
	(gr_line
		(start 362.27004 -287.852612)
		(end 362.27004 -287.852358)
		(stroke
			(width 0.05715)
			(type default)
		)
		(layer "In4.Cu")
	)
	(gr_line
		(start 362.304584 -374.332754)
		(end 362.332524 -374.484392)
		(stroke
			(width 0.07112)
			(type default)
		)
		(layer "In4.Cu")
	)
	(gr_line
		(start 362.332524 -374.484392)
		(end 362.090208 -374.836182)
		(stroke
			(width 0.07112)
			(type default)
		)
		(layer "In4.Cu")
	)
	(gr_line
		(start 362.335318 -287.59023)
		(end 362.335572 -287.589722)
		(stroke
			(width 0.05715)
			(type default)
		)
		(layer "In4.Cu")
	)
	(gr_line
		(start 362.342684 -235.083604)
		(end 362.343446 -235.084112)
		(stroke
			(width 0.05715)
			(type default)
		)
		(layer "In4.Cu")
	)
	(gr_line
		(start 362.345732 -235.085382)
		(end 362.347002 -235.086144)
		(stroke
			(width 0.05715)
			(type default)
		)
		(layer "In4.Cu")
	)
	(gr_line
		(start 362.34624 -230.225854)
		(end 362.347256 -230.226362)
		(stroke
			(width 0.05715)
			(type default)
		)
		(layer "In4.Cu")
	)
	(gr_line
		(start 362.347002 -235.086144)
		(end 362.347764 -235.086652)
		(stroke
			(width 0.05715)
			(type default)
		)
		(layer "In4.Cu")
	)
	(gr_line
		(start 362.347256 -228.60635)
		(end 362.352336 -228.609398)
		(stroke
			(width 0.05715)
			(type default)
		)
		(layer "In4.Cu")
	)
	(gr_line
		(start 362.347256 -226.341686)
		(end 362.346494 -226.342194)
		(stroke
			(width 0.05715)
			(type default)
		)
		(layer "In4.Cu")
	)
	(gr_line
		(start 362.347764 -235.086652)
		(end 362.34878 -235.08716)
		(stroke
			(width 0.05715)
			(type default)
		)
		(layer "In4.Cu")
	)
	(gr_line
		(start 362.349034 -230.227378)
		(end 362.35259 -230.22941)
		(stroke
			(width 0.05715)
			(type default)
		)
		(layer "In4.Cu")
	)
	(gr_line
		(start 362.349542 -227.960682)
		(end 362.34878 -227.96119)
		(stroke
			(width 0.05715)
			(type default)
		)
		(layer "In4.Cu")
	)
	(gr_line
		(start 362.352082 -235.089192)
		(end 362.353098 -235.0897)
		(stroke
			(width 0.05715)
			(type default)
		)
		(layer "In4.Cu")
	)
	(gr_line
		(start 362.352336 -228.609398)
		(end 362.353098 -228.609906)
		(stroke
			(width 0.05715)
			(type default)
		)
		(layer "In4.Cu")
	)
	(gr_line
		(start 362.352336 -226.338892)
		(end 362.351828 -226.339146)
		(stroke
			(width 0.05715)
			(type default)
		)
		(layer "In4.Cu")
	)
	(gr_line
		(start 362.35259 -230.22941)
		(end 362.353352 -230.229918)
		(stroke
			(width 0.05715)
			(type default)
		)
		(layer "In4.Cu")
	)
	(gr_line
		(start 362.353098 -235.0897)
		(end 362.354368 -235.090462)
		(stroke
			(width 0.05715)
			(type default)
		)
		(layer "In4.Cu")
	)
	(gr_line
		(start 362.353098 -228.609906)
		(end 362.355892 -228.61143)
		(stroke
			(width 0.05715)
			(type default)
		)
		(layer "In4.Cu")
	)
	(gr_line
		(start 362.353098 -226.338384)
		(end 362.352336 -226.338892)
		(stroke
			(width 0.05715)
			(type default)
		)
		(layer "In4.Cu")
	)
	(gr_line
		(start 362.354368 -235.090462)
		(end 362.355892 -235.091478)
		(stroke
			(width 0.05715)
			(type default)
		)
		(layer "In4.Cu")
	)
	(gr_line
		(start 362.355892 -228.61143)
		(end 362.357416 -228.612446)
		(stroke
			(width 0.05715)
			(type default)
		)
		(layer "In4.Cu")
	)
	(gr_line
		(start 362.357924 -227.955856)
		(end 362.355638 -227.957126)
		(stroke
			(width 0.05715)
			(type default)
		)
		(layer "In4.Cu")
	)
	(gr_line
		(start 362.359702 -227.95484)
		(end 362.358686 -227.955602)
		(stroke
			(width 0.05715)
			(type default)
		)
		(layer "In4.Cu")
	)
	(gr_line
		(start 362.362242 -227.953316)
		(end 362.360718 -227.954332)
		(stroke
			(width 0.05715)
			(type default)
		)
		(layer "In4.Cu")
	)
	(gr_line
		(start 362.36275 -235.574078)
		(end 362.432092 -235.504736)
		(stroke
			(width 0.05715)
			(type default)
		)
		(layer "In4.Cu")
	)
	(gr_line
		(start 362.36275 -233.954066)
		(end 362.432092 -233.884724)
		(stroke
			(width 0.05715)
			(type default)
		)
		(layer "In4.Cu")
	)
	(gr_line
		(start 362.36275 -232.334054)
		(end 362.432092 -232.264712)
		(stroke
			(width 0.05715)
			(type default)
		)
		(layer "In4.Cu")
	)
	(gr_line
		(start 362.36275 -227.953062)
		(end 362.362242 -227.953316)
		(stroke
			(width 0.05715)
			(type default)
		)
		(layer "In4.Cu")
	)
	(gr_line
		(start 362.378752 -230.24465)
		(end 362.37926 -230.244904)
		(stroke
			(width 0.05715)
			(type default)
		)
		(layer "In4.Cu")
	)
	(gr_line
		(start 362.37926 -230.244904)
		(end 362.380022 -230.245412)
		(stroke
			(width 0.05715)
			(type default)
		)
		(layer "In4.Cu")
	)
	(gr_line
		(start 362.380022 -230.245412)
		(end 362.38434 -230.247952)
		(stroke
			(width 0.05715)
			(type default)
		)
		(layer "In4.Cu")
	)
	(gr_line
		(start 362.386118 -227.939346)
		(end 362.37926 -227.94341)
		(stroke
			(width 0.05715)
			(type default)
		)
		(layer "In4.Cu")
	)
	(gr_line
		(start 362.386118 -226.319334)
		(end 362.378498 -226.323652)
		(stroke
			(width 0.05715)
			(type default)
		)
		(layer "In4.Cu")
	)
	(gr_arc
		(start 362.38688 -227.938838)
		(mid 362.386499 -227.939092)
		(end 362.386118 -227.939346)
		(stroke
			(width 0.05715)
			(type default)
		)
		(layer "In4.Cu")
	)
	(gr_arc
		(start 362.38688 -227.938838)
		(mid 362.390829 -227.936061)
		(end 362.394754 -227.93325)
		(stroke
			(width 0.05715)
			(type default)
		)
		(layer "In4.Cu")
	)
	(gr_arc
		(start 362.38688 -226.318826)
		(mid 362.386499 -226.31908)
		(end 362.386118 -226.319334)
		(stroke
			(width 0.05715)
			(type default)
		)
		(layer "In4.Cu")
	)
	(gr_arc
		(start 362.38688 -226.318826)
		(mid 362.390829 -226.316049)
		(end 362.394754 -226.313238)
		(stroke
			(width 0.05715)
			(type default)
		)
		(layer "In4.Cu")
	)
	(gr_line
		(start 362.388912 -231.177338)
		(end 362.381038 -231.18191)
		(stroke
			(width 0.05715)
			(type default)
		)
		(layer "In4.Cu")
	)
	(gr_line
		(start 362.389166 -231.177338)
		(end 362.388912 -231.177338)
		(stroke
			(width 0.05715)
			(type default)
		)
		(layer "In4.Cu")
	)
	(gr_arc
		(start 362.389166 -231.177338)
		(mid 362.39337 -231.174436)
		(end 362.397548 -231.171496)
		(stroke
			(width 0.05715)
			(type default)
		)
		(layer "In4.Cu")
	)
	(gr_arc
		(start 362.394754 -230.255318)
		(mid 362.389568 -230.251605)
		(end 362.38434 -230.247952)
		(stroke
			(width 0.05715)
			(type default)
		)
		(layer "In4.Cu")
	)
	(gr_line
		(start 362.46054 -287.853628)
		(end 362.46054 -287.852612)
		(stroke
			(width 0.05715)
			(type default)
		)
		(layer "In4.Cu")
	)
	(gr_arc
		(start 362.46054 -287.852612)
		(mid 362.46054 -287.852358)
		(end 362.46054 -287.852104)
		(stroke
			(width 0.05715)
			(type default)
		)
		(layer "In4.Cu")
	)
	(gr_line
		(start 362.460794 -291.101018)
		(end 362.461048 -291.101018)
		(stroke
			(width 0.05715)
			(type default)
		)
		(layer "In4.Cu")
	)
	(gr_arc
		(start 362.481876 -291.535104)
		(mid 362.484789 -291.537906)
		(end 362.487718 -291.540692)
		(stroke
			(width 0.05715)
			(type default)
		)
		(layer "In4.Cu")
	)
	(gr_arc
		(start 362.487718 -291.540692)
		(mid 362.491135 -291.543501)
		(end 362.494576 -291.54628)
		(stroke
			(width 0.05715)
			(type default)
		)
		(layer "In4.Cu")
	)
	(gr_line
		(start 362.505752 -296.35831)
		(end 362.505752 -296.329862)
		(stroke
			(width 0.05715)
			(type default)
		)
		(layer "In4.Cu")
	)
	(gr_line
		(start 362.505752 -296.329862)
		(end 362.460032 -296.284142)
		(stroke
			(width 0.05715)
			(type default)
		)
		(layer "In4.Cu")
	)
	(gr_line
		(start 362.509816 -373.535702)
		(end 362.322364 -373.80799)
		(stroke
			(width 0.07112)
			(type default)
		)
		(layer "In4.Cu")
	)
	(gr_line
		(start 362.545884 -292.23208)
		(end 362.549186 -292.230048)
		(stroke
			(width 0.05715)
			(type default)
		)
		(layer "In4.Cu")
	)
	(gr_line
		(start 362.546138 -295.47185)
		(end 362.547408 -295.471088)
		(stroke
			(width 0.05715)
			(type default)
		)
		(layer "In4.Cu")
	)
	(gr_line
		(start 362.547408 -295.471088)
		(end 362.549186 -295.470072)
		(stroke
			(width 0.05715)
			(type default)
		)
		(layer "In4.Cu")
	)
	(gr_line
		(start 362.548932 -288.990024)
		(end 362.551218 -288.988754)
		(stroke
			(width 0.05715)
			(type default)
		)
		(layer "In4.Cu")
	)
	(gr_line
		(start 362.549186 -295.470072)
		(end 362.55071 -295.469056)
		(stroke
			(width 0.05715)
			(type default)
		)
		(layer "In4.Cu")
	)
	(gr_line
		(start 362.549186 -292.230048)
		(end 362.55071 -292.229032)
		(stroke
			(width 0.05715)
			(type default)
		)
		(layer "In4.Cu")
	)
	(gr_line
		(start 362.55071 -295.469056)
		(end 362.551726 -295.468548)
		(stroke
			(width 0.05715)
			(type default)
		)
		(layer "In4.Cu")
	)
	(gr_line
		(start 362.55071 -292.229032)
		(end 362.551726 -292.228524)
		(stroke
			(width 0.05715)
			(type default)
		)
		(layer "In4.Cu")
	)
	(gr_line
		(start 362.55071 -291.582856)
		(end 362.549948 -291.582348)
		(stroke
			(width 0.05715)
			(type default)
		)
		(layer "In4.Cu")
	)
	(gr_line
		(start 362.551726 -295.468548)
		(end 362.552742 -295.46804)
		(stroke
			(width 0.05715)
			(type default)
		)
		(layer "In4.Cu")
	)
	(gr_line
		(start 362.551726 -293.848536)
		(end 362.552234 -293.848282)
		(stroke
			(width 0.05715)
			(type default)
		)
		(layer "In4.Cu")
	)
	(gr_line
		(start 362.551726 -292.228524)
		(end 362.552996 -292.227762)
		(stroke
			(width 0.05715)
			(type default)
		)
		(layer "In4.Cu")
	)
	(gr_line
		(start 362.551726 -291.583364)
		(end 362.55071 -291.582856)
		(stroke
			(width 0.05715)
			(type default)
		)
		(layer "In4.Cu")
	)
	(gr_line
		(start 362.552488 -294.823896)
		(end 362.551726 -294.823388)
		(stroke
			(width 0.05715)
			(type default)
		)
		(layer "In4.Cu")
	)
	(gr_line
		(start 362.553758 -293.204646)
		(end 362.552488 -293.203884)
		(stroke
			(width 0.05715)
			(type default)
		)
		(layer "In4.Cu")
	)
	(gr_line
		(start 362.557568 -294.82669)
		(end 362.552488 -294.823896)
		(stroke
			(width 0.05715)
			(type default)
		)
		(layer "In4.Cu")
	)
	(gr_arc
		(start 362.579158 -287.59404)
		(mid 362.578777 -287.594293)
		(end 362.578396 -287.594548)
		(stroke
			(width 0.05715)
			(type default)
		)
		(layer "In4.Cu")
	)
	(gr_arc
		(start 362.624116 -235.491274)
		(mid 362.622325 -235.479952)
		(end 362.620306 -235.468668)
		(stroke
			(width 0.05715)
			(type default)
		)
		(layer "In4.Cu")
	)
	(gr_line
		(start 362.624116 -235.491274)
		(end 362.70692 -235.574078)
		(stroke
			(width 0.05715)
			(type default)
		)
		(layer "In4.Cu")
	)
	(gr_arc
		(start 362.624116 -233.871262)
		(mid 362.622451 -233.859941)
		(end 362.62056 -233.848656)
		(stroke
			(width 0.05715)
			(type default)
		)
		(layer "In4.Cu")
	)
	(gr_line
		(start 362.624116 -233.871262)
		(end 362.70692 -233.954066)
		(stroke
			(width 0.05715)
			(type default)
		)
		(layer "In4.Cu")
	)
	(gr_arc
		(start 362.624116 -232.25125)
		(mid 362.62245 -232.239929)
		(end 362.62056 -232.228644)
		(stroke
			(width 0.05715)
			(type default)
		)
		(layer "In4.Cu")
	)
	(gr_line
		(start 362.624116 -232.25125)
		(end 362.70692 -232.334054)
		(stroke
			(width 0.05715)
			(type default)
		)
		(layer "In4.Cu")
	)
	(gr_line
		(start 362.640118 -295.637966)
		(end 362.641642 -295.63695)
		(stroke
			(width 0.05715)
			(type default)
		)
		(layer "In4.Cu")
	)
	(gr_line
		(start 362.641642 -295.63695)
		(end 362.642404 -295.636442)
		(stroke
			(width 0.05715)
			(type default)
		)
		(layer "In4.Cu")
	)
	(gr_line
		(start 362.64342 -295.635934)
		(end 362.644182 -295.635426)
		(stroke
			(width 0.05715)
			(type default)
		)
		(layer "In4.Cu")
	)
	(gr_arc
		(start 362.64342 -289.155886)
		(mid 362.641256 -289.157148)
		(end 362.639102 -289.158426)
		(stroke
			(width 0.05715)
			(type default)
		)
		(layer "In4.Cu")
	)
	(gr_line
		(start 362.644182 -295.635426)
		(end 362.646468 -295.634156)
		(stroke
			(width 0.05715)
			(type default)
		)
		(layer "In4.Cu")
	)
	(gr_line
		(start 362.645198 -292.394894)
		(end 362.646976 -292.393878)
		(stroke
			(width 0.05715)
			(type default)
		)
		(layer "In4.Cu")
	)
	(gr_line
		(start 362.646722 -291.41801)
		(end 362.646214 -291.417756)
		(stroke
			(width 0.05715)
			(type default)
		)
		(layer "In4.Cu")
	)
	(gr_line
		(start 362.646976 -292.393878)
		(end 362.647738 -292.39337)
		(stroke
			(width 0.05715)
			(type default)
		)
		(layer "In4.Cu")
	)
	(gr_line
		(start 362.647738 -293.03853)
		(end 362.64723 -293.038276)
		(stroke
			(width 0.05715)
			(type default)
		)
		(layer "In4.Cu")
	)
	(gr_line
		(start 362.647738 -292.39337)
		(end 362.649008 -292.392608)
		(stroke
			(width 0.05715)
			(type default)
		)
		(layer "In4.Cu")
	)
	(gr_line
		(start 362.648754 -293.039038)
		(end 362.647738 -293.03853)
		(stroke
			(width 0.05715)
			(type default)
		)
		(layer "In4.Cu")
	)
	(gr_line
		(start 362.651294 -295.631362)
		(end 362.652056 -295.630854)
		(stroke
			(width 0.05715)
			(type default)
		)
		(layer "In4.Cu")
	)
	(gr_line
		(start 362.662724 -290.285932)
		(end 362.364782 -290.285932)
		(stroke
			(width 0.05715)
			(type default)
		)
		(layer "In4.Cu")
	)
	(gr_line
		(start 362.662724 -288.66592)
		(end 362.364782 -288.66592)
		(stroke
			(width 0.05715)
			(type default)
		)
		(layer "In4.Cu")
	)
	(gr_line
		(start 362.662724 -287.045908)
		(end 362.364782 -287.045908)
		(stroke
			(width 0.05715)
			(type default)
		)
		(layer "In4.Cu")
	)
	(gr_line
		(start 362.70692 -235.574078)
		(end 363.004862 -235.574078)
		(stroke
			(width 0.05715)
			(type default)
		)
		(layer "In4.Cu")
	)
	(gr_line
		(start 362.70692 -233.954066)
		(end 363.004862 -233.954066)
		(stroke
			(width 0.05715)
			(type default)
		)
		(layer "In4.Cu")
	)
	(gr_line
		(start 362.70692 -232.334054)
		(end 363.004862 -232.334054)
		(stroke
			(width 0.05715)
			(type default)
		)
		(layer "In4.Cu")
	)
	(gr_line
		(start 362.732066 -288.735262)
		(end 362.662724 -288.66592)
		(stroke
			(width 0.05715)
			(type default)
		)
		(layer "In4.Cu")
	)
	(gr_line
		(start 362.732066 -287.11525)
		(end 362.662724 -287.045908)
		(stroke
			(width 0.05715)
			(type default)
		)
		(layer "In4.Cu")
	)
	(gr_line
		(start 362.741972 -373.695722)
		(end 362.55452 -373.967756)
		(stroke
			(width 0.07112)
			(type default)
		)
		(layer "In4.Cu")
	)
	(gr_line
		(start 362.745528 -290.368736)
		(end 362.662724 -290.285932)
		(stroke
			(width 0.05715)
			(type default)
		)
		(layer "In4.Cu")
	)
	(gr_arc
		(start 362.745528 -290.368736)
		(mid 362.747314 -290.380186)
		(end 362.749338 -290.391596)
		(stroke
			(width 0.05715)
			(type default)
		)
		(layer "In4.Cu")
	)
	(gr_line
		(start 362.907834 -372.958106)
		(end 362.509816 -373.535702)
		(stroke
			(width 0.07112)
			(type default)
		)
		(layer "In4.Cu")
	)
	(gr_line
		(start 362.914438 -221.128844)
		(end 362.868718 -221.083124)
		(stroke
			(width 0.05715)
			(type default)
		)
		(layer "In4.Cu")
	)
	(gr_line
		(start 362.920026 -287.151572)
		(end 362.92028 -287.151572)
		(stroke
			(width 0.05715)
			(type default)
		)
		(layer "In4.Cu")
	)
	(gr_arc
		(start 362.92028 -288.771584)
		(mid 362.922303 -288.760174)
		(end 362.92409 -288.748724)
		(stroke
			(width 0.05715)
			(type default)
		)
		(layer "In4.Cu")
	)
	(gr_arc
		(start 362.92028 -287.151572)
		(mid 362.922302 -287.140162)
		(end 362.92409 -287.128712)
		(stroke
			(width 0.05715)
			(type default)
		)
		(layer "In4.Cu")
	)
	(gr_line
		(start 362.92409 -288.748724)
		(end 363.006894 -288.66592)
		(stroke
			(width 0.05715)
			(type default)
		)
		(layer "In4.Cu")
	)
	(gr_line
		(start 362.92409 -287.128712)
		(end 363.006894 -287.045908)
		(stroke
			(width 0.05715)
			(type default)
		)
		(layer "In4.Cu")
	)
	(gr_line
		(start 362.932726 -373.66067)
		(end 362.74375 -373.695468)
		(stroke
			(width 0.07112)
			(type default)
		)
		(layer "In4.Cu")
	)
	(gr_line
		(start 362.937552 -290.355274)
		(end 363.006894 -290.285932)
		(stroke
			(width 0.05715)
			(type default)
		)
		(layer "In4.Cu")
	)
	(gr_line
		(start 363.006894 -290.285932)
		(end 363.304836 -290.285932)
		(stroke
			(width 0.05715)
			(type default)
		)
		(layer "In4.Cu")
	)
	(gr_line
		(start 363.006894 -288.66592)
		(end 363.304836 -288.66592)
		(stroke
			(width 0.05715)
			(type default)
		)
		(layer "In4.Cu")
	)
	(gr_line
		(start 363.006894 -287.045908)
		(end 363.304836 -287.045908)
		(stroke
			(width 0.05715)
			(type default)
		)
		(layer "In4.Cu")
	)
	(gr_line
		(start 363.099858 -221.804484)
		(end 363.100112 -221.80423)
		(stroke
			(width 0.05715)
			(type default)
		)
		(layer "In4.Cu")
	)
	(gr_line
		(start 363.140244 -373.119904)
		(end 363.175042 -373.30888)
		(stroke
			(width 0.07112)
			(type default)
		)
		(layer "In4.Cu")
	)
	(gr_arc
		(start 363.144562 -223.88322)
		(mid 363.147982 -223.885646)
		(end 363.15142 -223.888046)
		(stroke
			(width 0.05715)
			(type default)
		)
		(layer "In4.Cu")
	)
	(gr_arc
		(start 363.144816 -230.363014)
		(mid 363.150002 -230.366727)
		(end 363.15523 -230.37038)
		(stroke
			(width 0.05715)
			(type default)
		)
		(layer "In4.Cu")
	)
	(gr_line
		(start 363.150658 -221.083124)
		(end 363.104938 -221.128844)
		(stroke
			(width 0.05715)
			(type default)
		)
		(layer "In4.Cu")
	)
	(gr_arc
		(start 363.15142 -223.8883)
		(mid 363.152435 -223.888936)
		(end 363.153452 -223.88957)
		(stroke
			(width 0.05715)
			(type default)
		)
		(layer "In4.Cu")
	)
	(gr_line
		(start 363.15142 -223.888046)
		(end 363.15142 -223.8883)
		(stroke
			(width 0.05715)
			(type default)
		)
		(layer "In4.Cu")
	)
	(gr_line
		(start 363.159802 -230.373174)
		(end 363.15523 -230.37038)
		(stroke
			(width 0.05715)
			(type default)
		)
		(layer "In4.Cu")
	)
	(gr_line
		(start 363.160818 -230.373682)
		(end 363.159802 -230.373174)
		(stroke
			(width 0.05715)
			(type default)
		)
		(layer "In4.Cu")
	)
	(gr_line
		(start 363.161072 -223.893888)
		(end 363.153452 -223.88957)
		(stroke
			(width 0.05715)
			(type default)
		)
		(layer "In4.Cu")
	)
	(gr_line
		(start 363.163866 -296.35831)
		(end 363.163866 -296.329862)
		(stroke
			(width 0.05715)
			(type default)
		)
		(layer "In4.Cu")
	)
	(gr_line
		(start 363.163866 -296.329862)
		(end 363.209586 -296.284142)
		(stroke
			(width 0.05715)
			(type default)
		)
		(layer "In4.Cu")
	)
	(gr_line
		(start 363.175042 -373.30888)
		(end 362.932726 -373.66067)
		(stroke
			(width 0.07112)
			(type default)
		)
		(layer "In4.Cu")
	)
	(gr_line
		(start 363.185456 -227.800662)
		(end 363.189266 -227.798376)
		(stroke
			(width 0.05715)
			(type default)
		)
		(layer "In4.Cu")
	)
	(gr_line
		(start 363.185456 -226.18065)
		(end 363.189266 -226.178364)
		(stroke
			(width 0.05715)
			(type default)
		)
		(layer "In4.Cu")
	)
	(gr_line
		(start 363.189266 -227.798376)
		(end 363.190028 -227.797868)
		(stroke
			(width 0.05715)
			(type default)
		)
		(layer "In4.Cu")
	)
	(gr_line
		(start 363.189266 -226.178364)
		(end 363.190028 -226.177856)
		(stroke
			(width 0.05715)
			(type default)
		)
		(layer "In4.Cu")
	)
	(gr_line
		(start 363.190536 -230.390954)
		(end 363.189266 -230.390192)
		(stroke
			(width 0.05715)
			(type default)
		)
		(layer "In4.Cu")
	)
	(gr_line
		(start 363.191806 -232.011474)
		(end 363.19079 -232.010966)
		(stroke
			(width 0.05715)
			(type default)
		)
		(layer "In4.Cu")
	)
	(gr_line
		(start 363.191806 -228.771704)
		(end 363.19079 -228.771196)
		(stroke
			(width 0.05715)
			(type default)
		)
		(layer "In4.Cu")
	)
	(gr_line
		(start 363.191806 -227.796852)
		(end 363.192568 -227.796344)
		(stroke
			(width 0.05715)
			(type default)
		)
		(layer "In4.Cu")
	)
	(gr_line
		(start 363.191806 -227.151692)
		(end 363.19079 -227.151184)
		(stroke
			(width 0.05715)
			(type default)
		)
		(layer "In4.Cu")
	)
	(gr_line
		(start 363.191806 -226.17684)
		(end 363.192568 -226.176332)
		(stroke
			(width 0.05715)
			(type default)
		)
		(layer "In4.Cu")
	)
	(gr_line
		(start 363.191806 -222.291656)
		(end 363.19079 -222.291148)
		(stroke
			(width 0.05715)
			(type default)
		)
		(layer "In4.Cu")
	)
	(gr_line
		(start 363.19206 -224.556574)
		(end 363.192568 -224.55632)
		(stroke
			(width 0.05715)
			(type default)
		)
		(layer "In4.Cu")
	)
	(gr_line
		(start 363.192568 -224.55632)
		(end 363.194346 -224.555558)
		(stroke
			(width 0.05715)
			(type default)
		)
		(layer "In4.Cu")
	)
	(gr_line
		(start 363.193076 -222.292418)
		(end 363.191806 -222.291656)
		(stroke
			(width 0.05715)
			(type default)
		)
		(layer "In4.Cu")
	)
	(gr_line
		(start 363.197648 -230.395272)
		(end 363.19587 -230.394256)
		(stroke
			(width 0.05715)
			(type default)
		)
		(layer "In4.Cu")
	)
	(gr_line
		(start 363.198664 -230.39578)
		(end 363.197648 -230.395272)
		(stroke
			(width 0.05715)
			(type default)
		)
		(layer "In4.Cu")
	)
	(gr_line
		(start 363.200696 -227.791772)
		(end 363.20222 -227.79101)
		(stroke
			(width 0.05715)
			(type default)
		)
		(layer "In4.Cu")
	)
	(gr_line
		(start 363.200696 -226.17176)
		(end 363.20222 -226.170998)
		(stroke
			(width 0.05715)
			(type default)
		)
		(layer "In4.Cu")
	)
	(gr_line
		(start 363.20222 -230.397812)
		(end 363.201712 -230.397558)
		(stroke
			(width 0.05715)
			(type default)
		)
		(layer "In4.Cu")
	)
	(gr_line
		(start 363.204506 -230.399082)
		(end 363.203236 -230.39832)
		(stroke
			(width 0.05715)
			(type default)
		)
		(layer "In4.Cu")
	)
	(gr_line
		(start 363.205268 -230.39959)
		(end 363.204506 -230.399082)
		(stroke
			(width 0.05715)
			(type default)
		)
		(layer "In4.Cu")
	)
	(gr_line
		(start 363.207554 -230.40086)
		(end 363.206538 -230.400098)
		(stroke
			(width 0.05715)
			(type default)
		)
		(layer "In4.Cu")
	)
	(gr_line
		(start 363.284008 -227.963984)
		(end 363.2835 -227.964238)
		(stroke
			(width 0.05715)
			(type default)
		)
		(layer "In4.Cu")
	)
	(gr_line
		(start 363.284008 -226.343972)
		(end 363.2835 -226.344226)
		(stroke
			(width 0.05715)
			(type default)
		)
		(layer "In4.Cu")
	)
	(gr_line
		(start 363.285786 -231.845358)
		(end 363.287056 -231.84612)
		(stroke
			(width 0.05715)
			(type default)
		)
		(layer "In4.Cu")
	)
	(gr_line
		(start 363.285786 -230.225346)
		(end 363.286548 -230.225854)
		(stroke
			(width 0.05715)
			(type default)
		)
		(layer "In4.Cu")
	)
	(gr_line
		(start 363.285786 -228.605588)
		(end 363.287056 -228.60635)
		(stroke
			(width 0.05715)
			(type default)
		)
		(layer "In4.Cu")
	)
	(gr_line
		(start 363.285786 -226.985576)
		(end 363.287056 -226.986338)
		(stroke
			(width 0.05715)
			(type default)
		)
		(layer "In4.Cu")
	)
	(gr_line
		(start 363.285786 -222.12554)
		(end 363.287056 -222.126302)
		(stroke
			(width 0.05715)
			(type default)
		)
		(layer "In4.Cu")
	)
	(gr_line
		(start 363.287056 -231.84612)
		(end 363.287818 -231.846628)
		(stroke
			(width 0.05715)
			(type default)
		)
		(layer "In4.Cu")
	)
	(gr_line
		(start 363.287056 -228.60635)
		(end 363.287818 -228.606858)
		(stroke
			(width 0.05715)
			(type default)
		)
		(layer "In4.Cu")
	)
	(gr_line
		(start 363.287056 -226.986338)
		(end 363.287818 -226.986846)
		(stroke
			(width 0.05715)
			(type default)
		)
		(layer "In4.Cu")
	)
	(gr_line
		(start 363.287056 -224.722182)
		(end 363.285786 -224.722944)
		(stroke
			(width 0.05715)
			(type default)
		)
		(layer "In4.Cu")
	)
	(gr_line
		(start 363.287818 -224.721674)
		(end 363.287056 -224.722182)
		(stroke
			(width 0.05715)
			(type default)
		)
		(layer "In4.Cu")
	)
	(gr_line
		(start 363.288326 -230.22687)
		(end 363.288834 -230.227124)
		(stroke
			(width 0.05715)
			(type default)
		)
		(layer "In4.Cu")
	)
	(gr_line
		(start 363.288834 -230.227124)
		(end 363.290104 -230.227886)
		(stroke
			(width 0.05715)
			(type default)
		)
		(layer "In4.Cu")
	)
	(gr_line
		(start 363.288834 -227.96119)
		(end 363.287818 -227.961698)
		(stroke
			(width 0.05715)
			(type default)
		)
		(layer "In4.Cu")
	)
	(gr_line
		(start 363.288834 -226.341178)
		(end 363.287818 -226.341686)
		(stroke
			(width 0.05715)
			(type default)
		)
		(layer "In4.Cu")
	)
	(gr_line
		(start 363.290104 -230.227886)
		(end 363.290866 -230.228394)
		(stroke
			(width 0.05715)
			(type default)
		)
		(layer "In4.Cu")
	)
	(gr_line
		(start 363.290104 -224.720404)
		(end 363.287818 -224.721674)
		(stroke
			(width 0.05715)
			(type default)
		)
		(layer "In4.Cu")
	)
	(gr_arc
		(start 363.290104 -224.720404)
		(mid 363.291121 -224.71977)
		(end 363.292136 -224.719134)
		(stroke
			(width 0.05715)
			(type default)
		)
		(layer "In4.Cu")
	)
	(gr_line
		(start 363.290358 -227.960174)
		(end 363.288834 -227.96119)
		(stroke
			(width 0.05715)
			(type default)
		)
		(layer "In4.Cu")
	)
	(gr_line
		(start 363.290358 -226.340162)
		(end 363.288834 -226.341178)
		(stroke
			(width 0.05715)
			(type default)
		)
		(layer "In4.Cu")
	)
	(gr_line
		(start 363.290866 -230.228394)
		(end 363.291882 -230.228902)
		(stroke
			(width 0.05715)
			(type default)
		)
		(layer "In4.Cu")
	)
	(gr_line
		(start 363.291374 -227.959666)
		(end 363.290358 -227.960174)
		(stroke
			(width 0.05715)
			(type default)
		)
		(layer "In4.Cu")
	)
	(gr_line
		(start 363.291374 -226.339654)
		(end 363.290358 -226.340162)
		(stroke
			(width 0.05715)
			(type default)
		)
		(layer "In4.Cu")
	)
	(gr_line
		(start 363.291882 -230.228902)
		(end 363.293152 -230.229664)
		(stroke
			(width 0.05715)
			(type default)
		)
		(layer "In4.Cu")
	)
	(gr_line
		(start 363.293152 -230.229664)
		(end 363.293914 -230.230172)
		(stroke
			(width 0.05715)
			(type default)
		)
		(layer "In4.Cu")
	)
	(gr_line
		(start 363.293914 -230.230172)
		(end 363.29493 -230.23068)
		(stroke
			(width 0.05715)
			(type default)
		)
		(layer "In4.Cu")
	)
	(gr_line
		(start 363.295184 -227.95738)
		(end 363.291374 -227.959666)
		(stroke
			(width 0.05715)
			(type default)
		)
		(layer "In4.Cu")
	)
	(gr_line
		(start 363.295184 -226.337368)
		(end 363.291374 -226.339654)
		(stroke
			(width 0.05715)
			(type default)
		)
		(layer "In4.Cu")
	)
	(gr_line
		(start 363.298232 -227.955602)
		(end 363.297724 -227.955856)
		(stroke
			(width 0.05715)
			(type default)
		)
		(layer "In4.Cu")
	)
	(gr_line
		(start 363.298232 -226.33559)
		(end 363.297724 -226.335844)
		(stroke
			(width 0.05715)
			(type default)
		)
		(layer "In4.Cu")
	)
	(gr_line
		(start 363.301026 -230.234236)
		(end 363.302042 -230.234998)
		(stroke
			(width 0.05715)
			(type default)
		)
		(layer "In4.Cu")
	)
	(gr_line
		(start 363.302042 -230.234998)
		(end 363.303058 -230.235506)
		(stroke
			(width 0.05715)
			(type default)
		)
		(layer "In4.Cu")
	)
	(gr_line
		(start 363.318552 -231.864408)
		(end 363.319314 -231.864916)
		(stroke
			(width 0.05715)
			(type default)
		)
		(layer "In4.Cu")
	)
	(gr_line
		(start 363.318552 -228.624638)
		(end 363.319314 -228.625146)
		(stroke
			(width 0.05715)
			(type default)
		)
		(layer "In4.Cu")
	)
	(gr_line
		(start 363.318552 -227.004626)
		(end 363.319314 -227.005134)
		(stroke
			(width 0.05715)
			(type default)
		)
		(layer "In4.Cu")
	)
	(gr_line
		(start 363.319314 -231.864916)
		(end 363.320076 -231.865424)
		(stroke
			(width 0.05715)
			(type default)
		)
		(layer "In4.Cu")
	)
	(gr_line
		(start 363.319314 -230.244904)
		(end 363.324394 -230.247952)
		(stroke
			(width 0.05715)
			(type default)
		)
		(layer "In4.Cu")
	)
	(gr_line
		(start 363.319314 -228.625146)
		(end 363.320076 -228.625654)
		(stroke
			(width 0.05715)
			(type default)
		)
		(layer "In4.Cu")
	)
	(gr_line
		(start 363.319314 -227.005134)
		(end 363.320076 -227.005642)
		(stroke
			(width 0.05715)
			(type default)
		)
		(layer "In4.Cu")
	)
	(gr_line
		(start 363.320076 -231.865424)
		(end 363.326934 -231.869488)
		(stroke
			(width 0.05715)
			(type default)
		)
		(layer "In4.Cu")
	)
	(gr_line
		(start 363.320076 -228.625654)
		(end 363.326934 -228.629718)
		(stroke
			(width 0.05715)
			(type default)
		)
		(layer "In4.Cu")
	)
	(gr_line
		(start 363.320076 -227.005642)
		(end 363.326934 -227.009706)
		(stroke
			(width 0.05715)
			(type default)
		)
		(layer "In4.Cu")
	)
	(gr_line
		(start 363.334554 -223.774762)
		(end 363.341412 -223.780096)
		(stroke
			(width 0.05715)
			(type default)
		)
		(layer "In4.Cu")
	)
	(gr_arc
		(start 363.334808 -231.875076)
		(mid 363.330883 -231.872265)
		(end 363.326934 -231.869488)
		(stroke
			(width 0.05715)
			(type default)
		)
		(layer "In4.Cu")
	)
	(gr_arc
		(start 363.334808 -230.255318)
		(mid 363.329622 -230.251605)
		(end 363.324394 -230.247952)
		(stroke
			(width 0.05715)
			(type default)
		)
		(layer "In4.Cu")
	)
	(gr_arc
		(start 363.334808 -228.635306)
		(mid 363.330883 -228.632495)
		(end 363.326934 -228.629718)
		(stroke
			(width 0.05715)
			(type default)
		)
		(layer "In4.Cu")
	)
	(gr_arc
		(start 363.334808 -227.015294)
		(mid 363.330883 -227.012483)
		(end 363.326934 -227.009706)
		(stroke
			(width 0.05715)
			(type default)
		)
		(layer "In4.Cu")
	)
	(gr_line
		(start 363.445806 -296.35831)
		(end 363.445806 -296.329862)
		(stroke
			(width 0.05715)
			(type default)
		)
		(layer "In4.Cu")
	)
	(gr_line
		(start 363.445806 -296.329862)
		(end 363.400086 -296.284142)
		(stroke
			(width 0.05715)
			(type default)
		)
		(layer "In4.Cu")
	)
	(gr_arc
		(start 363.452664 -295.491408)
		(mid 363.448716 -295.494186)
		(end 363.44479 -295.496996)
		(stroke
			(width 0.05715)
			(type default)
		)
		(layer "In4.Cu")
	)
	(gr_line
		(start 363.452664 -295.491408)
		(end 363.459522 -295.487344)
		(stroke
			(width 0.05715)
			(type default)
		)
		(layer "In4.Cu")
	)
	(gr_line
		(start 363.459522 -295.487344)
		(end 363.460284 -295.486836)
		(stroke
			(width 0.05715)
			(type default)
		)
		(layer "In4.Cu")
	)
	(gr_line
		(start 363.460284 -295.486836)
		(end 363.460792 -295.486582)
		(stroke
			(width 0.05715)
			(type default)
		)
		(layer "In4.Cu")
	)
	(gr_line
		(start 363.48289 -294.818308)
		(end 363.481874 -294.8178)
		(stroke
			(width 0.05715)
			(type default)
		)
		(layer "In4.Cu")
	)
	(gr_line
		(start 363.48289 -293.198296)
		(end 363.481874 -293.197788)
		(stroke
			(width 0.05715)
			(type default)
		)
		(layer "In4.Cu")
	)
	(gr_line
		(start 363.48289 -291.578284)
		(end 363.481874 -291.577776)
		(stroke
			(width 0.05715)
			(type default)
		)
		(layer "In4.Cu")
	)
	(gr_line
		(start 363.484922 -293.8526)
		(end 363.49305 -293.848028)
		(stroke
			(width 0.05715)
			(type default)
		)
		(layer "In4.Cu")
	)
	(gr_line
		(start 363.484922 -292.232588)
		(end 363.49305 -292.228016)
		(stroke
			(width 0.05715)
			(type default)
		)
		(layer "In4.Cu")
	)
	(gr_line
		(start 363.48543 -295.472358)
		(end 363.487716 -295.471088)
		(stroke
			(width 0.05715)
			(type default)
		)
		(layer "In4.Cu")
	)
	(gr_line
		(start 363.488986 -295.470326)
		(end 363.493304 -295.467786)
		(stroke
			(width 0.05715)
			(type default)
		)
		(layer "In4.Cu")
	)
	(gr_line
		(start 363.493304 -295.467786)
		(end 363.494066 -295.467278)
		(stroke
			(width 0.05715)
			(type default)
		)
		(layer "In4.Cu")
	)
	(gr_line
		(start 363.500924 -294.828722)
		(end 363.499654 -294.82796)
		(stroke
			(width 0.05715)
			(type default)
		)
		(layer "In4.Cu")
	)
	(gr_line
		(start 363.500924 -293.20871)
		(end 363.499654 -293.207948)
		(stroke
			(width 0.05715)
			(type default)
		)
		(layer "In4.Cu")
	)
	(gr_line
		(start 363.500924 -291.588698)
		(end 363.499654 -291.587936)
		(stroke
			(width 0.05715)
			(type default)
		)
		(layer "In4.Cu")
	)
	(gr_line
		(start 363.50194 -294.82923)
		(end 363.500924 -294.828722)
		(stroke
			(width 0.05715)
			(type default)
		)
		(layer "In4.Cu")
	)
	(gr_line
		(start 363.50194 -293.209218)
		(end 363.500924 -293.20871)
		(stroke
			(width 0.05715)
			(type default)
		)
		(layer "In4.Cu")
	)
	(gr_line
		(start 363.50194 -291.589206)
		(end 363.500924 -291.588698)
		(stroke
			(width 0.05715)
			(type default)
		)
		(layer "In4.Cu")
	)
	(gr_arc
		(start 363.570012 -224.226374)
		(mid 363.569891 -224.223834)
		(end 363.569758 -224.221294)
		(stroke
			(width 0.05715)
			(type default)
		)
		(layer "In4.Cu")
	)
	(gr_line
		(start 363.570012 -224.226374)
		(end 363.570012 -224.232978)
		(stroke
			(width 0.05715)
			(type default)
		)
		(layer "In4.Cu")
	)
	(gr_line
		(start 363.584236 -294.65651)
		(end 363.582204 -294.655494)
		(stroke
			(width 0.05715)
			(type default)
		)
		(layer "In4.Cu")
	)
	(gr_line
		(start 363.584236 -293.036498)
		(end 363.582204 -293.035482)
		(stroke
			(width 0.05715)
			(type default)
		)
		(layer "In4.Cu")
	)
	(gr_line
		(start 363.584236 -291.416486)
		(end 363.582204 -291.41547)
		(stroke
			(width 0.05715)
			(type default)
		)
		(layer "In4.Cu")
	)
	(gr_line
		(start 363.586268 -294.65778)
		(end 363.584998 -294.657018)
		(stroke
			(width 0.05715)
			(type default)
		)
		(layer "In4.Cu")
	)
	(gr_line
		(start 363.586268 -293.037768)
		(end 363.584998 -293.037006)
		(stroke
			(width 0.05715)
			(type default)
		)
		(layer "In4.Cu")
	)
	(gr_line
		(start 363.586268 -291.417756)
		(end 363.584998 -291.416994)
		(stroke
			(width 0.05715)
			(type default)
		)
		(layer "In4.Cu")
	)
	(gr_line
		(start 363.588808 -295.632886)
		(end 363.590586 -295.63187)
		(stroke
			(width 0.05715)
			(type default)
		)
		(layer "In4.Cu")
	)
	(gr_line
		(start 363.590586 -295.63187)
		(end 363.594142 -295.629838)
		(stroke
			(width 0.05715)
			(type default)
		)
		(layer "In4.Cu")
	)
	(gr_line
		(start 363.590586 -294.66032)
		(end 363.587792 -294.658542)
		(stroke
			(width 0.05715)
			(type default)
		)
		(layer "In4.Cu")
	)
	(gr_line
		(start 363.590586 -293.040308)
		(end 363.587792 -293.03853)
		(stroke
			(width 0.05715)
			(type default)
		)
		(layer "In4.Cu")
	)
	(gr_line
		(start 363.590586 -291.420296)
		(end 363.587792 -291.418518)
		(stroke
			(width 0.05715)
			(type default)
		)
		(layer "In4.Cu")
	)
	(gr_line
		(start 363.592618 -294.661336)
		(end 363.59211 -294.661082)
		(stroke
			(width 0.05715)
			(type default)
		)
		(layer "In4.Cu")
	)
	(gr_line
		(start 363.592618 -293.041324)
		(end 363.59211 -293.04107)
		(stroke
			(width 0.05715)
			(type default)
		)
		(layer "In4.Cu")
	)
	(gr_line
		(start 363.592618 -291.421312)
		(end 363.59211 -291.421058)
		(stroke
			(width 0.05715)
			(type default)
		)
		(layer "In4.Cu")
	)
	(gr_line
		(start 363.595158 -294.66286)
		(end 363.594142 -294.662352)
		(stroke
			(width 0.05715)
			(type default)
		)
		(layer "In4.Cu")
	)
	(gr_line
		(start 363.595158 -293.042848)
		(end 363.594142 -293.04234)
		(stroke
			(width 0.05715)
			(type default)
		)
		(layer "In4.Cu")
	)
	(gr_line
		(start 363.595158 -291.422836)
		(end 363.594142 -291.422328)
		(stroke
			(width 0.05715)
			(type default)
		)
		(layer "In4.Cu")
	)
	(gr_line
		(start 363.597698 -294.664384)
		(end 363.59719 -294.66413)
		(stroke
			(width 0.05715)
			(type default)
		)
		(layer "In4.Cu")
	)
	(gr_line
		(start 363.597698 -293.044372)
		(end 363.59719 -293.044118)
		(stroke
			(width 0.05715)
			(type default)
		)
		(layer "In4.Cu")
	)
	(gr_line
		(start 363.597698 -291.42436)
		(end 363.59719 -291.424106)
		(stroke
			(width 0.05715)
			(type default)
		)
		(layer "In4.Cu")
	)
	(gr_arc
		(start 363.64291 -307.24094)
		(mid 363.643544 -307.24183)
		(end 363.64418 -307.242718)
		(stroke
			(width 0.07112)
			(type default)
		)
		(layer "In4.Cu")
	)
	(gr_arc
		(start 363.64418 -307.242718)
		(mid 363.652317 -307.253855)
		(end 363.66069 -307.264816)
		(stroke
			(width 0.07112)
			(type default)
		)
		(layer "In4.Cu")
	)
	(gr_arc
		(start 363.661452 -307.265832)
		(mid 363.661071 -307.265324)
		(end 363.66069 -307.264816)
		(stroke
			(width 0.07112)
			(type default)
		)
		(layer "In4.Cu")
	)
	(gr_line
		(start 363.813344 -221.083124)
		(end 363.813344 -221.054676)
		(stroke
			(width 0.05715)
			(type default)
		)
		(layer "In4.Cu")
	)
	(gr_line
		(start 363.859064 -221.128844)
		(end 363.813344 -221.083124)
		(stroke
			(width 0.05715)
			(type default)
		)
		(layer "In4.Cu")
	)
	(gr_line
		(start 363.87532 -307.081174)
		(end 363.878622 -307.086)
		(stroke
			(width 0.07112)
			(type default)
		)
		(layer "In4.Cu")
	)
	(gr_line
		(start 363.878622 -307.086)
		(end 363.882178 -307.090318)
		(stroke
			(width 0.07112)
			(type default)
		)
		(layer "In4.Cu")
	)
	(gr_arc
		(start 363.916468 -290.745926)
		(mid 363.919635 -290.748223)
		(end 363.922818 -290.750498)
		(stroke
			(width 0.05715)
			(type default)
		)
		(layer "In4.Cu")
	)
	(gr_arc
		(start 363.922818 -290.750498)
		(mid 363.92358 -290.751007)
		(end 363.924342 -290.751514)
		(stroke
			(width 0.05715)
			(type default)
		)
		(layer "In4.Cu")
	)
	(gr_line
		(start 363.930946 -290.755324)
		(end 363.924342 -290.751514)
		(stroke
			(width 0.05715)
			(type default)
		)
		(layer "In4.Cu")
	)
	(gr_line
		(start 363.969554 -290.77793)
		(end 363.969046 -290.777676)
		(stroke
			(width 0.05715)
			(type default)
		)
		(layer "In4.Cu")
	)
	(gr_line
		(start 363.986318 -336.302858)
		(end 363.996732 -336.33283)
		(stroke
			(width 0.07112)
			(type default)
		)
		(layer "In4.Cu")
	)
	(gr_line
		(start 363.996732 -336.33283)
		(end 364.002574 -336.365342)
		(stroke
			(width 0.07112)
			(type default)
		)
		(layer "In4.Cu")
	)
	(gr_line
		(start 364.004098 -336.373724)
		(end 364.004098 -336.373978)
		(stroke
			(width 0.07112)
			(type default)
		)
		(layer "In4.Cu")
	)
	(gr_line
		(start 364.040166 -221.804484)
		(end 364.04042 -221.80423)
		(stroke
			(width 0.05715)
			(type default)
		)
		(layer "In4.Cu")
	)
	(gr_line
		(start 364.06582 -290.613338)
		(end 364.065312 -290.613084)
		(stroke
			(width 0.05715)
			(type default)
		)
		(layer "In4.Cu")
	)
	(gr_line
		(start 364.095284 -221.083124)
		(end 364.049564 -221.128844)
		(stroke
			(width 0.05715)
			(type default)
		)
		(layer "In4.Cu")
	)
	(gr_line
		(start 364.095284 -221.054676)
		(end 364.095284 -221.083124)
		(stroke
			(width 0.05715)
			(type default)
		)
		(layer "In4.Cu")
	)
	(gr_line
		(start 364.104174 -296.35831)
		(end 364.104174 -296.329862)
		(stroke
			(width 0.05715)
			(type default)
		)
		(layer "In4.Cu")
	)
	(gr_line
		(start 364.104174 -296.329862)
		(end 364.149894 -296.284142)
		(stroke
			(width 0.05715)
			(type default)
		)
		(layer "In4.Cu")
	)
	(gr_line
		(start 364.129066 -223.910144)
		(end 364.128304 -223.909636)
		(stroke
			(width 0.05715)
			(type default)
		)
		(layer "In4.Cu")
	)
	(gr_line
		(start 364.131606 -223.911668)
		(end 364.13059 -223.91116)
		(stroke
			(width 0.05715)
			(type default)
		)
		(layer "In4.Cu")
	)
	(gr_line
		(start 364.13186 -233.631486)
		(end 364.130844 -233.630978)
		(stroke
			(width 0.05715)
			(type default)
		)
		(layer "In4.Cu")
	)
	(gr_line
		(start 364.132114 -223.911922)
		(end 364.131606 -223.911668)
		(stroke
			(width 0.05715)
			(type default)
		)
		(layer "In4.Cu")
	)
	(gr_line
		(start 364.132622 -233.631994)
		(end 364.13186 -233.631486)
		(stroke
			(width 0.05715)
			(type default)
		)
		(layer "In4.Cu")
	)
	(gr_line
		(start 364.149386 -295.952164)
		(end 364.149386 -295.947592)
		(stroke
			(width 0.05715)
			(type default)
		)
		(layer "In4.Cu")
	)
	(gr_arc
		(start 364.14964 -295.942766)
		(mid 364.149508 -295.945179)
		(end 364.149386 -295.947592)
		(stroke
			(width 0.05715)
			(type default)
		)
		(layer "In4.Cu")
	)
	(gr_line
		(start 364.16361 -222.918528)
		(end 364.16361 -222.918274)
		(stroke
			(width 0.05715)
			(type default)
		)
		(layer "In4.Cu")
	)
	(gr_line
		(start 364.223808 -223.744536)
		(end 364.225586 -223.745552)
		(stroke
			(width 0.05715)
			(type default)
		)
		(layer "In4.Cu")
	)
	(gr_line
		(start 364.225586 -223.745552)
		(end 364.226856 -223.746314)
		(stroke
			(width 0.05715)
			(type default)
		)
		(layer "In4.Cu")
	)
	(gr_line
		(start 364.22584 -233.46537)
		(end 364.22711 -233.466132)
		(stroke
			(width 0.05715)
			(type default)
		)
		(layer "In4.Cu")
	)
	(gr_line
		(start 364.22711 -233.466132)
		(end 364.234222 -233.470704)
		(stroke
			(width 0.05715)
			(type default)
		)
		(layer "In4.Cu")
	)
	(gr_line
		(start 364.234222 -233.470704)
		(end 364.235238 -233.471212)
		(stroke
			(width 0.05715)
			(type default)
		)
		(layer "In4.Cu")
	)
	(gr_line
		(start 364.236762 -233.472228)
		(end 364.237524 -233.472736)
		(stroke
			(width 0.05715)
			(type default)
		)
		(layer "In4.Cu")
	)
	(gr_arc
		(start 364.26267 -336.241898)
		(mid 364.258476 -336.227763)
		(end 364.254034 -336.213704)
		(stroke
			(width 0.07112)
			(type default)
		)
		(layer "In4.Cu")
	)
	(gr_arc
		(start 364.269528 -223.077024)
		(mid 364.274501 -223.073496)
		(end 364.279434 -223.069912)
		(stroke
			(width 0.05715)
			(type default)
		)
		(layer "In4.Cu")
	)
	(gr_arc
		(start 364.273338 -336.283046)
		(mid 364.268267 -336.262404)
		(end 364.26267 -336.241898)
		(stroke
			(width 0.07112)
			(type default)
		)
		(layer "In4.Cu")
	)
	(gr_arc
		(start 364.279688 -336.313526)
		(mid 364.276656 -336.298256)
		(end 364.273338 -336.283046)
		(stroke
			(width 0.07112)
			(type default)
		)
		(layer "In4.Cu")
	)
	(gr_arc
		(start 364.289848 -224.68078)
		(mid 364.292905 -224.678251)
		(end 364.295944 -224.6757)
		(stroke
			(width 0.05715)
			(type default)
		)
		(layer "In4.Cu")
	)
	(gr_arc
		(start 364.295944 -224.6757)
		(mid 364.298618 -224.67304)
		(end 364.301278 -224.670366)
		(stroke
			(width 0.05715)
			(type default)
		)
		(layer "In4.Cu")
	)
	(gr_line
		(start 364.340394 -295.977818)
		(end 364.340394 -295.969436)
		(stroke
			(width 0.05715)
			(type default)
		)
		(layer "In4.Cu")
	)
	(gr_arc
		(start 364.385098 -295.496742)
		(mid 364.381532 -295.499268)
		(end 364.377986 -295.501822)
		(stroke
			(width 0.05715)
			(type default)
		)
		(layer "In4.Cu")
	)
	(gr_line
		(start 364.386114 -296.35831)
		(end 364.386114 -296.329862)
		(stroke
			(width 0.05715)
			(type default)
		)
		(layer "In4.Cu")
	)
	(gr_line
		(start 364.386114 -296.329862)
		(end 364.340394 -296.284142)
		(stroke
			(width 0.05715)
			(type default)
		)
		(layer "In4.Cu")
	)
	(gr_arc
		(start 364.393226 -295.4909)
		(mid 364.390936 -295.492546)
		(end 364.388654 -295.494202)
		(stroke
			(width 0.05715)
			(type default)
		)
		(layer "In4.Cu")
	)
	(gr_line
		(start 364.414816 -234.764072)
		(end 364.712758 -234.764072)
		(stroke
			(width 0.05715)
			(type default)
		)
		(layer "In4.Cu")
	)
	(gr_line
		(start 364.414816 -233.14406)
		(end 364.712758 -233.14406)
		(stroke
			(width 0.05715)
			(type default)
		)
		(layer "In4.Cu")
	)
	(gr_line
		(start 364.414816 -231.524048)
		(end 364.712758 -231.524048)
		(stroke
			(width 0.05715)
			(type default)
		)
		(layer "In4.Cu")
	)
	(gr_line
		(start 364.420658 -293.85514)
		(end 364.42142 -293.854632)
		(stroke
			(width 0.05715)
			(type default)
		)
		(layer "In4.Cu")
	)
	(gr_line
		(start 364.420658 -292.235128)
		(end 364.42142 -292.23462)
		(stroke
			(width 0.05715)
			(type default)
		)
		(layer "In4.Cu")
	)
	(gr_line
		(start 364.420658 -288.995104)
		(end 364.42142 -288.994596)
		(stroke
			(width 0.05715)
			(type default)
		)
		(layer "In4.Cu")
	)
	(gr_line
		(start 364.424214 -291.578792)
		(end 364.422944 -291.57803)
		(stroke
			(width 0.05715)
			(type default)
		)
		(layer "In4.Cu")
	)
	(gr_line
		(start 364.424468 -293.852854)
		(end 364.428278 -293.850568)
		(stroke
			(width 0.05715)
			(type default)
		)
		(layer "In4.Cu")
	)
	(gr_line
		(start 364.424468 -292.232842)
		(end 364.428278 -292.230556)
		(stroke
			(width 0.05715)
			(type default)
		)
		(layer "In4.Cu")
	)
	(gr_line
		(start 364.424468 -288.992818)
		(end 364.428278 -288.990532)
		(stroke
			(width 0.05715)
			(type default)
		)
		(layer "In4.Cu")
	)
	(gr_line
		(start 364.424722 -291.579046)
		(end 364.424214 -291.578792)
		(stroke
			(width 0.05715)
			(type default)
		)
		(layer "In4.Cu")
	)
	(gr_line
		(start 364.427008 -291.58057)
		(end 364.425738 -291.579808)
		(stroke
			(width 0.05715)
			(type default)
		)
		(layer "In4.Cu")
	)
	(gr_line
		(start 364.428278 -293.850568)
		(end 364.429294 -293.85006)
		(stroke
			(width 0.05715)
			(type default)
		)
		(layer "In4.Cu")
	)
	(gr_line
		(start 364.428278 -292.230556)
		(end 364.429294 -292.230048)
		(stroke
			(width 0.05715)
			(type default)
		)
		(layer "In4.Cu")
	)
	(gr_line
		(start 364.428278 -288.990532)
		(end 364.429294 -288.990024)
		(stroke
			(width 0.05715)
			(type default)
		)
		(layer "In4.Cu")
	)
	(gr_line
		(start 364.429294 -293.85006)
		(end 364.430818 -293.849044)
		(stroke
			(width 0.05715)
			(type default)
		)
		(layer "In4.Cu")
	)
	(gr_line
		(start 364.429294 -292.230048)
		(end 364.430818 -292.229032)
		(stroke
			(width 0.05715)
			(type default)
		)
		(layer "In4.Cu")
	)
	(gr_line
		(start 364.429294 -288.990024)
		(end 364.430818 -288.989008)
		(stroke
			(width 0.05715)
			(type default)
		)
		(layer "In4.Cu")
	)
	(gr_line
		(start 364.430818 -291.582856)
		(end 364.429802 -291.582348)
		(stroke
			(width 0.05715)
			(type default)
		)
		(layer "In4.Cu")
	)
	(gr_line
		(start 364.431834 -293.848536)
		(end 364.432596 -293.848028)
		(stroke
			(width 0.05715)
			(type default)
		)
		(layer "In4.Cu")
	)
	(gr_line
		(start 364.431834 -292.228524)
		(end 364.432596 -292.228016)
		(stroke
			(width 0.05715)
			(type default)
		)
		(layer "In4.Cu")
	)
	(gr_line
		(start 364.431834 -291.583364)
		(end 364.430818 -291.582856)
		(stroke
			(width 0.05715)
			(type default)
		)
		(layer "In4.Cu")
	)
	(gr_line
		(start 364.431834 -288.9885)
		(end 364.432596 -288.987992)
		(stroke
			(width 0.05715)
			(type default)
		)
		(layer "In4.Cu")
	)
	(gr_line
		(start 364.432596 -291.583872)
		(end 364.431834 -291.583364)
		(stroke
			(width 0.05715)
			(type default)
		)
		(layer "In4.Cu")
	)
	(gr_line
		(start 364.433866 -294.824658)
		(end 364.432596 -294.823896)
		(stroke
			(width 0.05715)
			(type default)
		)
		(layer "In4.Cu")
	)
	(gr_line
		(start 364.433866 -293.204646)
		(end 364.432596 -293.203884)
		(stroke
			(width 0.05715)
			(type default)
		)
		(layer "In4.Cu")
	)
	(gr_line
		(start 364.435644 -294.825674)
		(end 364.433866 -294.824658)
		(stroke
			(width 0.05715)
			(type default)
		)
		(layer "In4.Cu")
	)
	(gr_line
		(start 364.435644 -293.84625)
		(end 364.436152 -293.845996)
		(stroke
			(width 0.05715)
			(type default)
		)
		(layer "In4.Cu")
	)
	(gr_line
		(start 364.435644 -292.226238)
		(end 364.436152 -292.225984)
		(stroke
			(width 0.05715)
			(type default)
		)
		(layer "In4.Cu")
	)
	(gr_line
		(start 364.435644 -288.986214)
		(end 364.436152 -288.98596)
		(stroke
			(width 0.05715)
			(type default)
		)
		(layer "In4.Cu")
	)
	(gr_line
		(start 364.438946 -291.587428)
		(end 364.43793 -291.58692)
		(stroke
			(width 0.05715)
			(type default)
		)
		(layer "In4.Cu")
	)
	(gr_line
		(start 364.439454 -291.587682)
		(end 364.438946 -291.587428)
		(stroke
			(width 0.05715)
			(type default)
		)
		(layer "In4.Cu")
	)
	(gr_line
		(start 364.509812 -224.234248)
		(end 364.509812 -224.235518)
		(stroke
			(width 0.05715)
			(type default)
		)
		(layer "In4.Cu")
	)
	(gr_line
		(start 364.510066 -224.234248)
		(end 364.509812 -224.234248)
		(stroke
			(width 0.05715)
			(type default)
		)
		(layer "In4.Cu")
	)
	(gr_arc
		(start 364.510066 -224.234248)
		(mid 364.509973 -224.227897)
		(end 364.509812 -224.221548)
		(stroke
			(width 0.05715)
			(type default)
		)
		(layer "In4.Cu")
	)
	(gr_line
		(start 364.517686 -294.019224)
		(end 364.518448 -294.018716)
		(stroke
			(width 0.05715)
			(type default)
		)
		(layer "In4.Cu")
	)
	(gr_line
		(start 364.517686 -292.399212)
		(end 364.518448 -292.398704)
		(stroke
			(width 0.05715)
			(type default)
		)
		(layer "In4.Cu")
	)
	(gr_line
		(start 364.517686 -289.159188)
		(end 364.518448 -289.15868)
		(stroke
			(width 0.05715)
			(type default)
		)
		(layer "In4.Cu")
	)
	(gr_line
		(start 364.519464 -291.413692)
		(end 364.518448 -291.413184)
		(stroke
			(width 0.05715)
			(type default)
		)
		(layer "In4.Cu")
	)
	(gr_line
		(start 364.523528 -291.415978)
		(end 364.522004 -291.415216)
		(stroke
			(width 0.05715)
			(type default)
		)
		(layer "In4.Cu")
	)
	(gr_line
		(start 364.52556 -294.014652)
		(end 364.527084 -294.01389)
		(stroke
			(width 0.05715)
			(type default)
		)
		(layer "In4.Cu")
	)
	(gr_line
		(start 364.52556 -292.39464)
		(end 364.527084 -292.393878)
		(stroke
			(width 0.05715)
			(type default)
		)
		(layer "In4.Cu")
	)
	(gr_line
		(start 364.52556 -289.154616)
		(end 364.527084 -289.153854)
		(stroke
			(width 0.05715)
			(type default)
		)
		(layer "In4.Cu")
	)
	(gr_line
		(start 364.527084 -294.01389)
		(end 364.527846 -294.013382)
		(stroke
			(width 0.05715)
			(type default)
		)
		(layer "In4.Cu")
	)
	(gr_line
		(start 364.527084 -292.393878)
		(end 364.527846 -292.39337)
		(stroke
			(width 0.05715)
			(type default)
		)
		(layer "In4.Cu")
	)
	(gr_line
		(start 364.527084 -291.41801)
		(end 364.526576 -291.417756)
		(stroke
			(width 0.05715)
			(type default)
		)
		(layer "In4.Cu")
	)
	(gr_line
		(start 364.527084 -289.153854)
		(end 364.527846 -289.153346)
		(stroke
			(width 0.05715)
			(type default)
		)
		(layer "In4.Cu")
	)
	(gr_line
		(start 364.527846 -294.658542)
		(end 364.527338 -294.658288)
		(stroke
			(width 0.05715)
			(type default)
		)
		(layer "In4.Cu")
	)
	(gr_line
		(start 364.527846 -294.013382)
		(end 364.528862 -294.012874)
		(stroke
			(width 0.05715)
			(type default)
		)
		(layer "In4.Cu")
	)
	(gr_line
		(start 364.527846 -293.03853)
		(end 364.527338 -293.038276)
		(stroke
			(width 0.05715)
			(type default)
		)
		(layer "In4.Cu")
	)
	(gr_line
		(start 364.527846 -292.39337)
		(end 364.528862 -292.392862)
		(stroke
			(width 0.05715)
			(type default)
		)
		(layer "In4.Cu")
	)
	(gr_line
		(start 364.527846 -291.418518)
		(end 364.527084 -291.41801)
		(stroke
			(width 0.05715)
			(type default)
		)
		(layer "In4.Cu")
	)
	(gr_line
		(start 364.527846 -289.153346)
		(end 364.528862 -289.152838)
		(stroke
			(width 0.05715)
			(type default)
		)
		(layer "In4.Cu")
	)
	(gr_line
		(start 364.528608 -294.658796)
		(end 364.527846 -294.658542)
		(stroke
			(width 0.05715)
			(type default)
		)
		(layer "In4.Cu")
	)
	(gr_line
		(start 364.528862 -294.012874)
		(end 364.530386 -294.011858)
		(stroke
			(width 0.05715)
			(type default)
		)
		(layer "In4.Cu")
	)
	(gr_line
		(start 364.528862 -293.039038)
		(end 364.527846 -293.03853)
		(stroke
			(width 0.05715)
			(type default)
		)
		(layer "In4.Cu")
	)
	(gr_line
		(start 364.528862 -292.392862)
		(end 364.530386 -292.391846)
		(stroke
			(width 0.05715)
			(type default)
		)
		(layer "In4.Cu")
	)
	(gr_line
		(start 364.528862 -291.419026)
		(end 364.527846 -291.418518)
		(stroke
			(width 0.05715)
			(type default)
		)
		(layer "In4.Cu")
	)
	(gr_line
		(start 364.528862 -289.152838)
		(end 364.530386 -289.151822)
		(stroke
			(width 0.05715)
			(type default)
		)
		(layer "In4.Cu")
	)
	(gr_line
		(start 364.53064 -294.66032)
		(end 364.530386 -294.660066)
		(stroke
			(width 0.05715)
			(type default)
		)
		(layer "In4.Cu")
	)
	(gr_line
		(start 364.53064 -291.420042)
		(end 364.528862 -291.419026)
		(stroke
			(width 0.05715)
			(type default)
		)
		(layer "In4.Cu")
	)
	(gr_line
		(start 364.532164 -294.010842)
		(end 364.534196 -294.009572)
		(stroke
			(width 0.05715)
			(type default)
		)
		(layer "In4.Cu")
	)
	(gr_line
		(start 364.532164 -292.39083)
		(end 364.534196 -292.38956)
		(stroke
			(width 0.05715)
			(type default)
		)
		(layer "In4.Cu")
	)
	(gr_line
		(start 364.532164 -289.150806)
		(end 364.534196 -289.149536)
		(stroke
			(width 0.05715)
			(type default)
		)
		(layer "In4.Cu")
	)
	(gr_line
		(start 364.53318 -291.421566)
		(end 364.532164 -291.421058)
		(stroke
			(width 0.05715)
			(type default)
		)
		(layer "In4.Cu")
	)
	(gr_line
		(start 364.534196 -291.422328)
		(end 364.53318 -291.421566)
		(stroke
			(width 0.05715)
			(type default)
		)
		(layer "In4.Cu")
	)
	(gr_line
		(start 364.539276 -348.255082)
		(end 364.53953 -348.255082)
		(stroke
			(width 0.07112)
			(type default)
		)
		(layer "In4.Cu")
	)
	(gr_line
		(start 364.559342 -291.436806)
		(end 364.558834 -291.436552)
		(stroke
			(width 0.05715)
			(type default)
		)
		(layer "In4.Cu")
	)
	(gr_line
		(start 364.560104 -291.437314)
		(end 364.559342 -291.436806)
		(stroke
			(width 0.05715)
			(type default)
		)
		(layer "In4.Cu")
	)
	(gr_arc
		(start 364.562644 -225.389694)
		(mid 364.558695 -225.392471)
		(end 364.55477 -225.395282)
		(stroke
			(width 0.05715)
			(type default)
		)
		(layer "In4.Cu")
	)
	(gr_line
		(start 364.562644 -225.389694)
		(end 364.569502 -225.38563)
		(stroke
			(width 0.05715)
			(type default)
		)
		(layer "In4.Cu")
	)
	(gr_line
		(start 364.566962 -291.441378)
		(end 364.560104 -291.437314)
		(stroke
			(width 0.05715)
			(type default)
		)
		(layer "In4.Cu")
	)
	(gr_line
		(start 364.569502 -225.38563)
		(end 364.570264 -225.385122)
		(stroke
			(width 0.05715)
			(type default)
		)
		(layer "In4.Cu")
	)
	(gr_line
		(start 364.570264 -225.385122)
		(end 364.571026 -225.384614)
		(stroke
			(width 0.05715)
			(type default)
		)
		(layer "In4.Cu")
	)
	(gr_arc
		(start 364.574836 -291.446966)
		(mid 364.570911 -291.444155)
		(end 364.566962 -291.441378)
		(stroke
			(width 0.05715)
			(type default)
		)
		(layer "In4.Cu")
	)
	(gr_arc
		(start 364.598458 -345.994228)
		(mid 364.599608 -345.986736)
		(end 364.600744 -345.979242)
		(stroke
			(width 0.07112)
			(type default)
		)
		(layer "In4.Cu")
	)
	(gr_line
		(start 364.60176 -345.978734)
		(end 364.600744 -345.979242)
		(stroke
			(width 0.07112)
			(type default)
		)
		(layer "In4.Cu")
	)
	(gr_line
		(start 364.60176 -345.951048)
		(end 364.60176 -345.978734)
		(stroke
			(width 0.07112)
			(type default)
		)
		(layer "In4.Cu")
	)
	(gr_line
		(start 364.602014 -225.36658)
		(end 364.602522 -225.366326)
		(stroke
			(width 0.05715)
			(type default)
		)
		(layer "In4.Cu")
	)
	(gr_line
		(start 364.602522 -225.366326)
		(end 364.603792 -225.365564)
		(stroke
			(width 0.05715)
			(type default)
		)
		(layer "In4.Cu")
	)
	(gr_line
		(start 364.698788 -225.531172)
		(end 364.697772 -225.53168)
		(stroke
			(width 0.05715)
			(type default)
		)
		(layer "In4.Cu")
	)
	(gr_line
		(start 364.712758 -234.764072)
		(end 364.782608 -234.694222)
		(stroke
			(width 0.05715)
			(type default)
		)
		(layer "In4.Cu")
	)
	(gr_line
		(start 364.712758 -233.14406)
		(end 364.795562 -233.061256)
		(stroke
			(width 0.05715)
			(type default)
		)
		(layer "In4.Cu")
	)
	(gr_line
		(start 364.712758 -231.524048)
		(end 364.7821 -231.454706)
		(stroke
			(width 0.05715)
			(type default)
		)
		(layer "In4.Cu")
	)
	(gr_line
		(start 364.75797 -221.083124)
		(end 364.75797 -221.054676)
		(stroke
			(width 0.05715)
			(type default)
		)
		(layer "In4.Cu")
	)
	(gr_arc
		(start 364.799372 -233.038396)
		(mid 364.797351 -233.049807)
		(end 364.795562 -233.061256)
		(stroke
			(width 0.05715)
			(type default)
		)
		(layer "In4.Cu")
	)
	(gr_line
		(start 364.80369 -221.128844)
		(end 364.75797 -221.083124)
		(stroke
			(width 0.05715)
			(type default)
		)
		(layer "In4.Cu")
	)
	(gr_arc
		(start 364.974124 -234.681268)
		(mid 364.97208 -234.669943)
		(end 364.969806 -234.658662)
		(stroke
			(width 0.05715)
			(type default)
		)
		(layer "In4.Cu")
	)
	(gr_line
		(start 364.974124 -234.681268)
		(end 365.056928 -234.764072)
		(stroke
			(width 0.05715)
			(type default)
		)
		(layer "In4.Cu")
	)
	(gr_arc
		(start 364.974124 -231.441244)
		(mid 364.972337 -231.429794)
		(end 364.970314 -231.418384)
		(stroke
			(width 0.05715)
			(type default)
		)
		(layer "In4.Cu")
	)
	(gr_line
		(start 364.974124 -231.441244)
		(end 365.056928 -231.524048)
		(stroke
			(width 0.05715)
			(type default)
		)
		(layer "In4.Cu")
	)
	(gr_line
		(start 364.979966 -221.804484)
		(end 364.98022 -221.80423)
		(stroke
			(width 0.05715)
			(type default)
		)
		(layer "In4.Cu")
	)
	(gr_line
		(start 364.987586 -233.074718)
		(end 365.056928 -233.14406)
		(stroke
			(width 0.05715)
			(type default)
		)
		(layer "In4.Cu")
	)
	(gr_line
		(start 365.012732 -291.095938)
		(end 364.71479 -291.095938)
		(stroke
			(width 0.05715)
			(type default)
		)
		(layer "In4.Cu")
	)
	(gr_line
		(start 365.012732 -289.475926)
		(end 364.71479 -289.475926)
		(stroke
			(width 0.05715)
			(type default)
		)
		(layer "In4.Cu")
	)
	(gr_line
		(start 365.012732 -287.856168)
		(end 364.71479 -287.856168)
		(stroke
			(width 0.05715)
			(type default)
		)
		(layer "In4.Cu")
	)
	(gr_line
		(start 365.03991 -221.083124)
		(end 364.99419 -221.128844)
		(stroke
			(width 0.05715)
			(type default)
		)
		(layer "In4.Cu")
	)
	(gr_line
		(start 365.03991 -221.054676)
		(end 365.03991 -221.083124)
		(stroke
			(width 0.05715)
			(type default)
		)
		(layer "In4.Cu")
	)
	(gr_line
		(start 365.051848 -296.362628)
		(end 365.051848 -296.33418)
		(stroke
			(width 0.05715)
			(type default)
		)
		(layer "In4.Cu")
	)
	(gr_line
		(start 365.051848 -296.33418)
		(end 365.097568 -296.28846)
		(stroke
			(width 0.05715)
			(type default)
		)
		(layer "In4.Cu")
	)
	(gr_line
		(start 365.056928 -234.764072)
		(end 365.35487 -234.764072)
		(stroke
			(width 0.05715)
			(type default)
		)
		(layer "In4.Cu")
	)
	(gr_line
		(start 365.056928 -233.14406)
		(end 365.35487 -233.14406)
		(stroke
			(width 0.05715)
			(type default)
		)
		(layer "In4.Cu")
	)
	(gr_line
		(start 365.056928 -231.524048)
		(end 365.35487 -231.524048)
		(stroke
			(width 0.05715)
			(type default)
		)
		(layer "In4.Cu")
	)
	(gr_line
		(start 365.065818 -222.2881)
		(end 365.064802 -222.287338)
		(stroke
			(width 0.05715)
			(type default)
		)
		(layer "In4.Cu")
	)
	(gr_line
		(start 365.068358 -222.289624)
		(end 365.065818 -222.2881)
		(stroke
			(width 0.05715)
			(type default)
		)
		(layer "In4.Cu")
	)
	(gr_line
		(start 365.069374 -222.290132)
		(end 365.068358 -222.289624)
		(stroke
			(width 0.05715)
			(type default)
		)
		(layer "In4.Cu")
	)
	(gr_line
		(start 365.070898 -232.657142)
		(end 365.071914 -232.656634)
		(stroke
			(width 0.05715)
			(type default)
		)
		(layer "In4.Cu")
	)
	(gr_line
		(start 365.070898 -227.79736)
		(end 365.071914 -227.796852)
		(stroke
			(width 0.05715)
			(type default)
		)
		(layer "In4.Cu")
	)
	(gr_line
		(start 365.070898 -226.177348)
		(end 365.071914 -226.17684)
		(stroke
			(width 0.05715)
			(type default)
		)
		(layer "In4.Cu")
	)
	(gr_line
		(start 365.070898 -222.291148)
		(end 365.069374 -222.290132)
		(stroke
			(width 0.05715)
			(type default)
		)
		(layer "In4.Cu")
	)
	(gr_line
		(start 365.071914 -232.656634)
		(end 365.072676 -232.656126)
		(stroke
			(width 0.05715)
			(type default)
		)
		(layer "In4.Cu")
	)
	(gr_line
		(start 365.071914 -228.771704)
		(end 365.070898 -228.771196)
		(stroke
			(width 0.05715)
			(type default)
		)
		(layer "In4.Cu")
	)
	(gr_line
		(start 365.071914 -227.151692)
		(end 365.070898 -227.151184)
		(stroke
			(width 0.05715)
			(type default)
		)
		(layer "In4.Cu")
	)
	(gr_line
		(start 365.071914 -226.17684)
		(end 365.072676 -226.176332)
		(stroke
			(width 0.05715)
			(type default)
		)
		(layer "In4.Cu")
	)
	(gr_line
		(start 365.071914 -222.291656)
		(end 365.070898 -222.291148)
		(stroke
			(width 0.05715)
			(type default)
		)
		(layer "In4.Cu")
	)
	(gr_line
		(start 365.072422 -222.29191)
		(end 365.071914 -222.291656)
		(stroke
			(width 0.05715)
			(type default)
		)
		(layer "In4.Cu")
	)
	(gr_line
		(start 365.072676 -232.656126)
		(end 365.07674 -232.65384)
		(stroke
			(width 0.05715)
			(type default)
		)
		(layer "In4.Cu")
	)
	(gr_line
		(start 365.072676 -226.176332)
		(end 365.07547 -226.174808)
		(stroke
			(width 0.05715)
			(type default)
		)
		(layer "In4.Cu")
	)
	(gr_line
		(start 365.075978 -230.396796)
		(end 365.07166 -230.394256)
		(stroke
			(width 0.05715)
			(type default)
		)
		(layer "In4.Cu")
	)
	(gr_line
		(start 365.082074 -287.92551)
		(end 365.012732 -287.856168)
		(stroke
			(width 0.05715)
			(type default)
		)
		(layer "In4.Cu")
	)
	(gr_line
		(start 365.095536 -291.178742)
		(end 365.012732 -291.095938)
		(stroke
			(width 0.05715)
			(type default)
		)
		(layer "In4.Cu")
	)
	(gr_line
		(start 365.095536 -289.55873)
		(end 365.012732 -289.475926)
		(stroke
			(width 0.05715)
			(type default)
		)
		(layer "In4.Cu")
	)
	(gr_arc
		(start 365.095536 -289.55873)
		(mid 365.097327 -289.570052)
		(end 365.099346 -289.581336)
		(stroke
			(width 0.05715)
			(type default)
		)
		(layer "In4.Cu")
	)
	(gr_line
		(start 365.09579 -291.178742)
		(end 365.095536 -291.178742)
		(stroke
			(width 0.05715)
			(type default)
		)
		(layer "In4.Cu")
	)
	(gr_arc
		(start 365.09579 -291.178742)
		(mid 365.097581 -291.189937)
		(end 365.0996 -291.201094)
		(stroke
			(width 0.05715)
			(type default)
		)
		(layer "In4.Cu")
	)
	(gr_line
		(start 365.13643 -229.599744)
		(end 365.136176 -229.599998)
		(stroke
			(width 0.05715)
			(type default)
		)
		(layer "In4.Cu")
	)
	(gr_line
		(start 365.160306 -222.122492)
		(end 365.161322 -222.123)
		(stroke
			(width 0.05715)
			(type default)
		)
		(layer "In4.Cu")
	)
	(gr_line
		(start 365.161322 -222.123)
		(end 365.162084 -222.123508)
		(stroke
			(width 0.05715)
			(type default)
		)
		(layer "In4.Cu")
	)
	(gr_line
		(start 365.162084 -222.123508)
		(end 365.163608 -222.12427)
		(stroke
			(width 0.05715)
			(type default)
		)
		(layer "In4.Cu")
	)
	(gr_line
		(start 365.163608 -222.12427)
		(end 365.16437 -222.124778)
		(stroke
			(width 0.05715)
			(type default)
		)
		(layer "In4.Cu")
	)
	(gr_line
		(start 365.165894 -228.605588)
		(end 365.167164 -228.60635)
		(stroke
			(width 0.05715)
			(type default)
		)
		(layer "In4.Cu")
	)
	(gr_line
		(start 365.165894 -226.985576)
		(end 365.167164 -226.986338)
		(stroke
			(width 0.05715)
			(type default)
		)
		(layer "In4.Cu")
	)
	(gr_line
		(start 365.166656 -222.126048)
		(end 365.167164 -222.126302)
		(stroke
			(width 0.05715)
			(type default)
		)
		(layer "In4.Cu")
	)
	(gr_line
		(start 365.167164 -228.60635)
		(end 365.167926 -228.606858)
		(stroke
			(width 0.05715)
			(type default)
		)
		(layer "In4.Cu")
	)
	(gr_line
		(start 365.167164 -227.962206)
		(end 365.165894 -227.962968)
		(stroke
			(width 0.05715)
			(type default)
		)
		(layer "In4.Cu")
	)
	(gr_line
		(start 365.167164 -226.986338)
		(end 365.167926 -226.986846)
		(stroke
			(width 0.05715)
			(type default)
		)
		(layer "In4.Cu")
	)
	(gr_line
		(start 365.167164 -226.342194)
		(end 365.165894 -226.342956)
		(stroke
			(width 0.05715)
			(type default)
		)
		(layer "In4.Cu")
	)
	(gr_line
		(start 365.167672 -227.961952)
		(end 365.167164 -227.962206)
		(stroke
			(width 0.05715)
			(type default)
		)
		(layer "In4.Cu")
	)
	(gr_line
		(start 365.167926 -226.341686)
		(end 365.167164 -226.342194)
		(stroke
			(width 0.05715)
			(type default)
		)
		(layer "In4.Cu")
	)
	(gr_line
		(start 365.25962 -222.614236)
		(end 365.259366 -222.614236)
		(stroke
			(width 0.05715)
			(type default)
		)
		(layer "In4.Cu")
	)
	(gr_arc
		(start 365.270288 -287.961832)
		(mid 365.27231 -287.950421)
		(end 365.274098 -287.938972)
		(stroke
			(width 0.05715)
			(type default)
		)
		(layer "In4.Cu")
	)
	(gr_line
		(start 365.274098 -287.938972)
		(end 365.356902 -287.856168)
		(stroke
			(width 0.05715)
			(type default)
		)
		(layer "In4.Cu")
	)
	(gr_line
		(start 365.28756 -289.545268)
		(end 365.356902 -289.475926)
		(stroke
			(width 0.05715)
			(type default)
		)
		(layer "In4.Cu")
	)
	(gr_line
		(start 365.287814 -291.165026)
		(end 365.356902 -291.095938)
		(stroke
			(width 0.05715)
			(type default)
		)
		(layer "In4.Cu")
	)
	(gr_line
		(start 365.288068 -295.964102)
		(end 365.288068 -295.885108)
		(stroke
			(width 0.05715)
			(type default)
		)
		(layer "In4.Cu")
	)
	(gr_arc
		(start 365.322104 -294.792908)
		(mid 365.321596 -294.792527)
		(end 365.321088 -294.792146)
		(stroke
			(width 0.05715)
			(type default)
		)
		(layer "In4.Cu")
	)
	(gr_line
		(start 365.32312 -338.4423)
		(end 365.32947 -338.477098)
		(stroke
			(width 0.07112)
			(type default)
		)
		(layer "In4.Cu")
	)
	(gr_arc
		(start 365.324644 -289.934904)
		(mid 365.328696 -289.937716)
		(end 365.332772 -289.940492)
		(stroke
			(width 0.05715)
			(type default)
		)
		(layer "In4.Cu")
	)
	(gr_line
		(start 365.32947 -346.044012)
		(end 365.329216 -346.043758)
		(stroke
			(width 0.07112)
			(type default)
		)
		(layer "In4.Cu")
	)
	(gr_line
		(start 365.32947 -338.477098)
		(end 365.32947 -338.515452)
		(stroke
			(width 0.07112)
			(type default)
		)
		(layer "In4.Cu")
	)
	(gr_arc
		(start 365.333534 -289.941)
		(mid 365.333153 -289.940746)
		(end 365.332772 -289.940492)
		(stroke
			(width 0.05715)
			(type default)
		)
		(layer "In4.Cu")
	)
	(gr_line
		(start 365.333788 -296.362628)
		(end 365.333788 -296.33418)
		(stroke
			(width 0.05715)
			(type default)
		)
		(layer "In4.Cu")
	)
	(gr_line
		(start 365.333788 -296.33418)
		(end 365.288068 -296.28846)
		(stroke
			(width 0.05715)
			(type default)
		)
		(layer "In4.Cu")
	)
	(gr_line
		(start 365.340646 -289.945064)
		(end 365.333534 -289.941)
		(stroke
			(width 0.05715)
			(type default)
		)
		(layer "In4.Cu")
	)
	(gr_line
		(start 365.356902 -291.095938)
		(end 365.654844 -291.095938)
		(stroke
			(width 0.05715)
			(type default)
		)
		(layer "In4.Cu")
	)
	(gr_line
		(start 365.356902 -289.475926)
		(end 365.654844 -289.475926)
		(stroke
			(width 0.05715)
			(type default)
		)
		(layer "In4.Cu")
	)
	(gr_line
		(start 365.356902 -287.856168)
		(end 365.654844 -287.856168)
		(stroke
			(width 0.05715)
			(type default)
		)
		(layer "In4.Cu")
	)
	(gr_line
		(start 365.365538 -293.852346)
		(end 365.37265 -293.848282)
		(stroke
			(width 0.05715)
			(type default)
		)
		(layer "In4.Cu")
	)
	(gr_line
		(start 365.372396 -289.963606)
		(end 365.371634 -289.963098)
		(stroke
			(width 0.05715)
			(type default)
		)
		(layer "In4.Cu")
	)
	(gr_line
		(start 365.37265 -293.20363)
		(end 365.371888 -293.203376)
		(stroke
			(width 0.05715)
			(type default)
		)
		(layer "In4.Cu")
	)
	(gr_line
		(start 365.37519 -289.96513)
		(end 365.372396 -289.963606)
		(stroke
			(width 0.05715)
			(type default)
		)
		(layer "In4.Cu")
	)
	(gr_arc
		(start 365.45012 -229.094284)
		(mid 365.45013 -229.090982)
		(end 365.45012 -229.08768)
		(stroke
			(width 0.05715)
			(type default)
		)
		(layer "In4.Cu")
	)
	(gr_line
		(start 365.45012 -225.85426)
		(end 365.45012 -225.861372)
		(stroke
			(width 0.05715)
			(type default)
		)
		(layer "In4.Cu")
	)
	(gr_line
		(start 365.450374 -222.614236)
		(end 365.45012 -222.614236)
		(stroke
			(width 0.05715)
			(type default)
		)
		(layer "In4.Cu")
	)
	(gr_line
		(start 365.461296 -294.016938)
		(end 365.461804 -294.016684)
		(stroke
			(width 0.05715)
			(type default)
		)
		(layer "In4.Cu")
	)
	(gr_line
		(start 365.463074 -293.035736)
		(end 365.45774 -293.032688)
		(stroke
			(width 0.05715)
			(type default)
		)
		(layer "In4.Cu")
	)
	(gr_line
		(start 365.4679 -289.798506)
		(end 365.466884 -289.797998)
		(stroke
			(width 0.05715)
			(type default)
		)
		(layer "In4.Cu")
	)
	(gr_line
		(start 365.470694 -289.800284)
		(end 365.4679 -289.798506)
		(stroke
			(width 0.05715)
			(type default)
		)
		(layer "In4.Cu")
	)
	(gr_arc
		(start 365.479838 -294.006524)
		(mid 365.482254 -294.005133)
		(end 365.484664 -294.00373)
		(stroke
			(width 0.05715)
			(type default)
		)
		(layer "In4.Cu")
	)
	(gr_arc
		(start 365.48568 -293.048944)
		(mid 365.482638 -293.047029)
		(end 365.479584 -293.045134)
		(stroke
			(width 0.05715)
			(type default)
		)
		(layer "In4.Cu")
	)
	(gr_line
		(start 365.536988 -225.369374)
		(end 365.538004 -225.368866)
		(stroke
			(width 0.05715)
			(type default)
		)
		(layer "In4.Cu")
	)
	(gr_line
		(start 365.538004 -225.368866)
		(end 365.54029 -225.367596)
		(stroke
			(width 0.05715)
			(type default)
		)
		(layer "In4.Cu")
	)
	(gr_line
		(start 365.54029 -225.367596)
		(end 365.541306 -225.367088)
		(stroke
			(width 0.05715)
			(type default)
		)
		(layer "In4.Cu")
	)
	(gr_line
		(start 365.541306 -225.367088)
		(end 365.543592 -225.365818)
		(stroke
			(width 0.05715)
			(type default)
		)
		(layer "In4.Cu")
	)
	(gr_line
		(start 365.59236 -314.059824)
		(end 365.592614 -314.059824)
		(stroke
			(width 0.07112)
			(type default)
		)
		(layer "In4.Cu")
	)
	(gr_arc
		(start 365.606076 -338.427314)
		(mid 365.603743 -338.410265)
		(end 365.600996 -338.393278)
		(stroke
			(width 0.07112)
			(type default)
		)
		(layer "In4.Cu")
	)
	(gr_arc
		(start 365.610394 -338.477098)
		(mid 365.608672 -338.452168)
		(end 365.606076 -338.427314)
		(stroke
			(width 0.07112)
			(type default)
		)
		(layer "In4.Cu")
	)
	(gr_arc
		(start 365.61141 -338.515452)
		(mid 365.611162 -338.496268)
		(end 365.610394 -338.477098)
		(stroke
			(width 0.07112)
			(type default)
		)
		(layer "In4.Cu")
	)
	(gr_line
		(start 365.63427 -225.533712)
		(end 365.633508 -225.53422)
		(stroke
			(width 0.05715)
			(type default)
		)
		(layer "In4.Cu")
	)
	(gr_line
		(start 365.659924 -329.478132)
		(end 365.660178 -329.478132)
		(stroke
			(width 0.07112)
			(type default)
		)
		(layer "In4.Cu")
	)
	(gr_line
		(start 365.67618 -231.989122)
		(end 365.66856 -231.99344)
		(stroke
			(width 0.05715)
			(type default)
		)
		(layer "In4.Cu")
	)
	(gr_arc
		(start 365.676942 -231.988614)
		(mid 365.676561 -231.988868)
		(end 365.67618 -231.989122)
		(stroke
			(width 0.05715)
			(type default)
		)
		(layer "In4.Cu")
	)
	(gr_arc
		(start 365.676942 -231.988614)
		(mid 365.680891 -231.985837)
		(end 365.684816 -231.983026)
		(stroke
			(width 0.05715)
			(type default)
		)
		(layer "In4.Cu")
	)
	(gr_line
		(start 365.749078 -221.128844)
		(end 365.703358 -221.083124)
		(stroke
			(width 0.05715)
			(type default)
		)
		(layer "In4.Cu")
	)
	(gr_line
		(start 365.759492 -387.84784)
		(end 365.686086 -387.669786)
		(stroke
			(width 0.07112)
			(type default)
		)
		(layer "In4.Cu")
	)
	(gr_line
		(start 365.771938 -335.608422)
		(end 365.782098 -335.638394)
		(stroke
			(width 0.07112)
			(type default)
		)
		(layer "In4.Cu")
	)
	(gr_line
		(start 365.782098 -335.638394)
		(end 365.78794 -335.670398)
		(stroke
			(width 0.07112)
			(type default)
		)
		(layer "In4.Cu")
	)
	(gr_line
		(start 365.84255 -290.773866)
		(end 365.841788 -290.773358)
		(stroke
			(width 0.05715)
			(type default)
		)
		(layer "In4.Cu")
	)
	(gr_line
		(start 365.84382 -290.774628)
		(end 365.84255 -290.773866)
		(stroke
			(width 0.05715)
			(type default)
		)
		(layer "In4.Cu")
	)
	(gr_line
		(start 365.847884 -290.776914)
		(end 365.84636 -290.775898)
		(stroke
			(width 0.05715)
			(type default)
		)
		(layer "In4.Cu")
	)
	(gr_line
		(start 365.8489 -290.777422)
		(end 365.847884 -290.776914)
		(stroke
			(width 0.05715)
			(type default)
		)
		(layer "In4.Cu")
	)
	(gr_line
		(start 365.849408 -290.777676)
		(end 365.8489 -290.777422)
		(stroke
			(width 0.05715)
			(type default)
		)
		(layer "In4.Cu")
	)
	(gr_line
		(start 365.920274 -225.044254)
		(end 365.92002 -225.044254)
		(stroke
			(width 0.05715)
			(type default)
		)
		(layer "In4.Cu")
	)
	(gr_line
		(start 365.943134 -290.61156)
		(end 365.942118 -290.611052)
		(stroke
			(width 0.05715)
			(type default)
		)
		(layer "In4.Cu")
	)
	(gr_line
		(start 365.94415 -290.612322)
		(end 365.943134 -290.61156)
		(stroke
			(width 0.05715)
			(type default)
		)
		(layer "In4.Cu")
	)
	(gr_line
		(start 365.969296 -290.6268)
		(end 365.968788 -290.626546)
		(stroke
			(width 0.05715)
			(type default)
		)
		(layer "In4.Cu")
	)
	(gr_line
		(start 365.970058 -290.627308)
		(end 365.969296 -290.6268)
		(stroke
			(width 0.05715)
			(type default)
		)
		(layer "In4.Cu")
	)
	(gr_line
		(start 365.976916 -290.631372)
		(end 365.970058 -290.627308)
		(stroke
			(width 0.05715)
			(type default)
		)
		(layer "In4.Cu")
	)
	(gr_line
		(start 365.984028 -296.35831)
		(end 365.984028 -296.329862)
		(stroke
			(width 0.05715)
			(type default)
		)
		(layer "In4.Cu")
	)
	(gr_line
		(start 365.984028 -296.329862)
		(end 366.029748 -296.284142)
		(stroke
			(width 0.05715)
			(type default)
		)
		(layer "In4.Cu")
	)
	(gr_arc
		(start 365.98479 -290.63696)
		(mid 365.980865 -290.634149)
		(end 365.976916 -290.631372)
		(stroke
			(width 0.05715)
			(type default)
		)
		(layer "In4.Cu")
	)
	(gr_line
		(start 365.985298 -221.083124)
		(end 365.939578 -221.128844)
		(stroke
			(width 0.05715)
			(type default)
		)
		(layer "In4.Cu")
	)
	(gr_arc
		(start 366.048036 -335.547462)
		(mid 366.043844 -335.533326)
		(end 366.0394 -335.519268)
		(stroke
			(width 0.07112)
			(type default)
		)
		(layer "In4.Cu")
	)
	(gr_arc
		(start 366.058704 -335.58861)
		(mid 366.053632 -335.567968)
		(end 366.048036 -335.547462)
		(stroke
			(width 0.07112)
			(type default)
		)
		(layer "In4.Cu")
	)
	(gr_arc
		(start 366.065054 -335.618328)
		(mid 366.062016 -335.60344)
		(end 366.058704 -335.58861)
		(stroke
			(width 0.07112)
			(type default)
		)
		(layer "In4.Cu")
	)
	(gr_arc
		(start 366.110012 -222.131382)
		(mid 366.108489 -222.130491)
		(end 366.106964 -222.129604)
		(stroke
			(width 0.05715)
			(type default)
		)
		(layer "In4.Cu")
	)
	(gr_line
		(start 366.153954 -388.011162)
		(end 365.759492 -387.84784)
		(stroke
			(width 0.07112)
			(type default)
		)
		(layer "In4.Cu")
	)
	(gr_line
		(start 366.245394 -346.760546)
		(end 366.245394 -346.7608)
		(stroke
			(width 0.07112)
			(type default)
		)
		(layer "In4.Cu")
	)
	(gr_line
		(start 366.265968 -296.35831)
		(end 366.265968 -296.329862)
		(stroke
			(width 0.05715)
			(type default)
		)
		(layer "In4.Cu")
	)
	(gr_line
		(start 366.265968 -296.329862)
		(end 366.220248 -296.284142)
		(stroke
			(width 0.05715)
			(type default)
		)
		(layer "In4.Cu")
	)
	(gr_line
		(start 366.331754 -387.937502)
		(end 366.153954 -388.011162)
		(stroke
			(width 0.07112)
			(type default)
		)
		(layer "In4.Cu")
	)
	(gr_line
		(start 366.407954 -313.57951)
		(end 366.408208 -313.579256)
		(stroke
			(width 0.07112)
			(type default)
		)
		(layer "In4.Cu")
	)
	(gr_line
		(start 366.408208 -313.579256)
		(end 366.677956 -313.907932)
		(stroke
			(width 0.07112)
			(type default)
		)
		(layer "In4.Cu")
	)
	(gr_arc
		(start 366.43691 -231.873298)
		(mid 366.43117 -231.877199)
		(end 366.42548 -231.881172)
		(stroke
			(width 0.05715)
			(type default)
		)
		(layer "In4.Cu")
	)
	(gr_line
		(start 366.441228 -387.67639)
		(end 365.793274 -387.407658)
		(stroke
			(width 0.07112)
			(type default)
		)
		(layer "In4.Cu")
	)
	(gr_line
		(start 366.475518 -225.370644)
		(end 366.47628 -225.370136)
		(stroke
			(width 0.05715)
			(type default)
		)
		(layer "In4.Cu")
	)
	(gr_line
		(start 366.47628 -232.818178)
		(end 366.47374 -232.816654)
		(stroke
			(width 0.05715)
			(type default)
		)
		(layer "In4.Cu")
	)
	(gr_line
		(start 366.47628 -225.370136)
		(end 366.47755 -225.369374)
		(stroke
			(width 0.05715)
			(type default)
		)
		(layer "In4.Cu")
	)
	(gr_arc
		(start 366.481614 -231.846628)
		(mid 366.480216 -231.847388)
		(end 366.47882 -231.848152)
		(stroke
			(width 0.05715)
			(type default)
		)
		(layer "In4.Cu")
	)
	(gr_line
		(start 366.481868 -231.846628)
		(end 366.481614 -231.846628)
		(stroke
			(width 0.05715)
			(type default)
		)
		(layer "In4.Cu")
	)
	(gr_line
		(start 366.481868 -231.846628)
		(end 366.482884 -231.84612)
		(stroke
			(width 0.05715)
			(type default)
		)
		(layer "In4.Cu")
	)
	(gr_line
		(start 366.485424 -232.823258)
		(end 366.48263 -232.821734)
		(stroke
			(width 0.05715)
			(type default)
		)
		(layer "In4.Cu")
	)
	(gr_line
		(start 366.486694 -232.82402)
		(end 366.485424 -232.823258)
		(stroke
			(width 0.05715)
			(type default)
		)
		(layer "In4.Cu")
	)
	(gr_arc
		(start 366.487964 -225.363278)
		(mid 366.488599 -225.362898)
		(end 366.489234 -225.362516)
		(stroke
			(width 0.05715)
			(type default)
		)
		(layer "In4.Cu")
	)
	(gr_line
		(start 366.572038 -225.534982)
		(end 366.57153 -225.535236)
		(stroke
			(width 0.05715)
			(type default)
		)
		(layer "In4.Cu")
	)
	(gr_line
		(start 366.574324 -225.533712)
		(end 366.573562 -225.53422)
		(stroke
			(width 0.05715)
			(type default)
		)
		(layer "In4.Cu")
	)
	(gr_line
		(start 366.577118 -232.656126)
		(end 366.57788 -232.656634)
		(stroke
			(width 0.05715)
			(type default)
		)
		(layer "In4.Cu")
	)
	(gr_line
		(start 366.577118 -232.011982)
		(end 366.572038 -232.01503)
		(stroke
			(width 0.05715)
			(type default)
		)
		(layer "In4.Cu")
	)
	(gr_line
		(start 366.577118 -225.532188)
		(end 366.575594 -225.53295)
		(stroke
			(width 0.05715)
			(type default)
		)
		(layer "In4.Cu")
	)
	(gr_line
		(start 366.577626 -225.531934)
		(end 366.577118 -225.532188)
		(stroke
			(width 0.05715)
			(type default)
		)
		(layer "In4.Cu")
	)
	(gr_line
		(start 366.57788 -232.656634)
		(end 366.578896 -232.657142)
		(stroke
			(width 0.05715)
			(type default)
		)
		(layer "In4.Cu")
	)
	(gr_line
		(start 366.578642 -232.010966)
		(end 366.577118 -232.011982)
		(stroke
			(width 0.05715)
			(type default)
		)
		(layer "In4.Cu")
	)
	(gr_line
		(start 366.578896 -232.657142)
		(end 366.579658 -232.65765)
		(stroke
			(width 0.05715)
			(type default)
		)
		(layer "In4.Cu")
	)
	(gr_line
		(start 366.579658 -232.65765)
		(end 366.58169 -232.658666)
		(stroke
			(width 0.05715)
			(type default)
		)
		(layer "In4.Cu")
	)
	(gr_line
		(start 366.58169 -232.658666)
		(end 366.583468 -232.659682)
		(stroke
			(width 0.05715)
			(type default)
		)
		(layer "In4.Cu")
	)
	(gr_line
		(start 366.58931 -232.663238)
		(end 366.591088 -232.664254)
		(stroke
			(width 0.05715)
			(type default)
		)
		(layer "In4.Cu")
	)
	(gr_line
		(start 366.620044 -377.737624)
		(end 366.61979 -377.737878)
		(stroke
			(width 0.07112)
			(type default)
		)
		(layer "In4.Cu")
	)
	(gr_line
		(start 366.62614 -313.40044)
		(end 366.895888 -313.729116)
		(stroke
			(width 0.07112)
			(type default)
		)
		(layer "In4.Cu")
	)
	(gr_arc
		(start 366.689386 -335.377536)
		(mid 366.684434 -335.357151)
		(end 366.678972 -335.336896)
		(stroke
			(width 0.07112)
			(type default)
		)
		(layer "In4.Cu")
	)
	(gr_line
		(start 366.693958 -221.128844)
		(end 366.648238 -221.083124)
		(stroke
			(width 0.05715)
			(type default)
		)
		(layer "In4.Cu")
	)
	(gr_line
		(start 366.923574 -296.456862)
		(end 366.923574 -296.428414)
		(stroke
			(width 0.05715)
			(type default)
		)
		(layer "In4.Cu")
	)
	(gr_line
		(start 366.923574 -296.428414)
		(end 366.969294 -296.382694)
		(stroke
			(width 0.05715)
			(type default)
		)
		(layer "In4.Cu")
	)
	(gr_line
		(start 366.930178 -221.083124)
		(end 366.884458 -221.128844)
		(stroke
			(width 0.05715)
			(type default)
		)
		(layer "In4.Cu")
	)
	(gr_line
		(start 366.942116 -224.562416)
		(end 366.945418 -224.560384)
		(stroke
			(width 0.05715)
			(type default)
		)
		(layer "In4.Cu")
	)
	(gr_line
		(start 366.945418 -222.940626)
		(end 366.94618 -222.940118)
		(stroke
			(width 0.05715)
			(type default)
		)
		(layer "In4.Cu")
	)
	(gr_line
		(start 366.94618 -222.940118)
		(end 366.94745 -222.939356)
		(stroke
			(width 0.05715)
			(type default)
		)
		(layer "In4.Cu")
	)
	(gr_line
		(start 366.94745 -222.939356)
		(end 366.949228 -222.93834)
		(stroke
			(width 0.05715)
			(type default)
		)
		(layer "In4.Cu")
	)
	(gr_line
		(start 366.948974 -335.251552)
		(end 366.960658 -335.285588)
		(stroke
			(width 0.07112)
			(type default)
		)
		(layer "In4.Cu")
	)
	(gr_line
		(start 366.949228 -222.93834)
		(end 366.950752 -222.937324)
		(stroke
			(width 0.05715)
			(type default)
		)
		(layer "In4.Cu")
	)
	(gr_line
		(start 366.950752 -222.937324)
		(end 366.951768 -222.936816)
		(stroke
			(width 0.05715)
			(type default)
		)
		(layer "In4.Cu")
	)
	(gr_line
		(start 366.951768 -223.911668)
		(end 366.950752 -223.91116)
		(stroke
			(width 0.05715)
			(type default)
		)
		(layer "In4.Cu")
	)
	(gr_line
		(start 366.951768 -222.936816)
		(end 366.95253 -222.936308)
		(stroke
			(width 0.05715)
			(type default)
		)
		(layer "In4.Cu")
	)
	(gr_line
		(start 366.95253 -223.912176)
		(end 366.951768 -223.911668)
		(stroke
			(width 0.05715)
			(type default)
		)
		(layer "In4.Cu")
	)
	(gr_line
		(start 366.9538 -223.912938)
		(end 366.95253 -223.912176)
		(stroke
			(width 0.05715)
			(type default)
		)
		(layer "In4.Cu")
	)
	(gr_line
		(start 366.955324 -223.9137)
		(end 366.9538 -223.912938)
		(stroke
			(width 0.05715)
			(type default)
		)
		(layer "In4.Cu")
	)
	(gr_line
		(start 366.956086 -223.914208)
		(end 366.955324 -223.9137)
		(stroke
			(width 0.05715)
			(type default)
		)
		(layer "In4.Cu")
	)
	(gr_line
		(start 366.957102 -223.914716)
		(end 366.956086 -223.914208)
		(stroke
			(width 0.05715)
			(type default)
		)
		(layer "In4.Cu")
	)
	(gr_line
		(start 366.957864 -223.915224)
		(end 366.957102 -223.914716)
		(stroke
			(width 0.05715)
			(type default)
		)
		(layer "In4.Cu")
	)
	(gr_line
		(start 366.960658 -335.285588)
		(end 366.967008 -335.320894)
		(stroke
			(width 0.07112)
			(type default)
		)
		(layer "In4.Cu")
	)
	(gr_line
		(start 366.969294 -295.952164)
		(end 366.969294 -295.9481)
		(stroke
			(width 0.05715)
			(type default)
		)
		(layer "In4.Cu")
	)
	(gr_arc
		(start 366.969548 -295.94302)
		(mid 366.969416 -295.94556)
		(end 366.969294 -295.9481)
		(stroke
			(width 0.05715)
			(type default)
		)
		(layer "In4.Cu")
	)
	(gr_line
		(start 367.041938 -223.104964)
		(end 367.04143 -223.105218)
		(stroke
			(width 0.05715)
			(type default)
		)
		(layer "In4.Cu")
	)
	(gr_line
		(start 367.044224 -223.103694)
		(end 367.043462 -223.104202)
		(stroke
			(width 0.05715)
			(type default)
		)
		(layer "In4.Cu")
	)
	(gr_line
		(start 367.045748 -223.745552)
		(end 367.047018 -223.746314)
		(stroke
			(width 0.05715)
			(type default)
		)
		(layer "In4.Cu")
	)
	(gr_line
		(start 367.047018 -223.746314)
		(end 367.04778 -223.746822)
		(stroke
			(width 0.05715)
			(type default)
		)
		(layer "In4.Cu")
	)
	(gr_line
		(start 367.047018 -223.10217)
		(end 367.045494 -223.102932)
		(stroke
			(width 0.05715)
			(type default)
		)
		(layer "In4.Cu")
	)
	(gr_line
		(start 367.04778 -223.746822)
		(end 367.048796 -223.74733)
		(stroke
			(width 0.05715)
			(type default)
		)
		(layer "In4.Cu")
	)
	(gr_line
		(start 367.04778 -223.101662)
		(end 367.047018 -223.10217)
		(stroke
			(width 0.05715)
			(type default)
		)
		(layer "In4.Cu")
	)
	(gr_line
		(start 367.048796 -223.74733)
		(end 367.05032 -223.748346)
		(stroke
			(width 0.05715)
			(type default)
		)
		(layer "In4.Cu")
	)
	(gr_line
		(start 367.048796 -223.101154)
		(end 367.04778 -223.101662)
		(stroke
			(width 0.05715)
			(type default)
		)
		(layer "In4.Cu")
	)
	(gr_line
		(start 367.052098 -223.749362)
		(end 367.05413 -223.750632)
		(stroke
			(width 0.05715)
			(type default)
		)
		(layer "In4.Cu")
	)
	(gr_line
		(start 367.052606 -388.38378)
		(end 366.978946 -388.20598)
		(stroke
			(width 0.07112)
			(type default)
		)
		(layer "In4.Cu")
	)
	(gr_line
		(start 367.086134 -224.699322)
		(end 367.078768 -224.70364)
		(stroke
			(width 0.05715)
			(type default)
		)
		(layer "In4.Cu")
	)
	(gr_arc
		(start 367.086896 -224.698814)
		(mid 367.086515 -224.699068)
		(end 367.086134 -224.699322)
		(stroke
			(width 0.05715)
			(type default)
		)
		(layer "In4.Cu")
	)
	(gr_arc
		(start 367.086896 -224.698814)
		(mid 367.090845 -224.696037)
		(end 367.09477 -224.693226)
		(stroke
			(width 0.05715)
			(type default)
		)
		(layer "In4.Cu")
	)
	(gr_line
		(start 367.139728 -233.954066)
		(end 367.139474 -233.954066)
		(stroke
			(width 0.05715)
			(type default)
		)
		(layer "In4.Cu")
	)
	(gr_line
		(start 367.15573 -313.002168)
		(end 367.15573 -313.001914)
		(stroke
			(width 0.07112)
			(type default)
		)
		(layer "In4.Cu")
	)
	(gr_line
		(start 367.205514 -296.456862)
		(end 367.205514 -296.428414)
		(stroke
			(width 0.05715)
			(type default)
		)
		(layer "In4.Cu")
	)
	(gr_line
		(start 367.205514 -296.428414)
		(end 367.159794 -296.382694)
		(stroke
			(width 0.05715)
			(type default)
		)
		(layer "In4.Cu")
	)
	(gr_arc
		(start 367.213134 -295.4909)
		(mid 367.205598 -295.496173)
		(end 367.198148 -295.501568)
		(stroke
			(width 0.05715)
			(type default)
		)
		(layer "In4.Cu")
	)
	(gr_arc
		(start 367.213134 -295.4909)
		(mid 367.213515 -295.490646)
		(end 367.213896 -295.490392)
		(stroke
			(width 0.05715)
			(type default)
		)
		(layer "In4.Cu")
	)
	(gr_line
		(start 367.224056 -347.6244)
		(end 367.224056 -347.637354)
		(stroke
			(width 0.07112)
			(type default)
		)
		(layer "In4.Cu")
	)
	(gr_line
		(start 367.224056 -347.497654)
		(end 367.224056 -347.597984)
		(stroke
			(width 0.07112)
			(type default)
		)
		(layer "In4.Cu")
	)
	(gr_line
		(start 367.224056 -347.458538)
		(end 367.224056 -347.471238)
		(stroke
			(width 0.07112)
			(type default)
		)
		(layer "In4.Cu")
	)
	(gr_line
		(start 367.234724 -234.764072)
		(end 367.532666 -234.764072)
		(stroke
			(width 0.05715)
			(type default)
		)
		(layer "In4.Cu")
	)
	(gr_line
		(start 367.234724 -233.14406)
		(end 367.532666 -233.14406)
		(stroke
			(width 0.05715)
			(type default)
		)
		(layer "In4.Cu")
	)
	(gr_line
		(start 367.234724 -231.524048)
		(end 367.532666 -231.524048)
		(stroke
			(width 0.05715)
			(type default)
		)
		(layer "In4.Cu")
	)
	(gr_line
		(start 367.244376 -293.852854)
		(end 367.248186 -293.850568)
		(stroke
			(width 0.05715)
			(type default)
		)
		(layer "In4.Cu")
	)
	(gr_line
		(start 367.244376 -292.232842)
		(end 367.248186 -292.230556)
		(stroke
			(width 0.05715)
			(type default)
		)
		(layer "In4.Cu")
	)
	(gr_line
		(start 367.244376 -288.992818)
		(end 367.248186 -288.990532)
		(stroke
			(width 0.05715)
			(type default)
		)
		(layer "In4.Cu")
	)
	(gr_line
		(start 367.24463 -291.579046)
		(end 367.242598 -291.577776)
		(stroke
			(width 0.05715)
			(type default)
		)
		(layer "In4.Cu")
	)
	(gr_line
		(start 367.246154 -291.580062)
		(end 367.245646 -291.579808)
		(stroke
			(width 0.05715)
			(type default)
		)
		(layer "In4.Cu")
	)
	(gr_line
		(start 367.248186 -293.850568)
		(end 367.249202 -293.85006)
		(stroke
			(width 0.05715)
			(type default)
		)
		(layer "In4.Cu")
	)
	(gr_line
		(start 367.248186 -292.230556)
		(end 367.249202 -292.230048)
		(stroke
			(width 0.05715)
			(type default)
		)
		(layer "In4.Cu")
	)
	(gr_line
		(start 367.248186 -288.990532)
		(end 367.249202 -288.990024)
		(stroke
			(width 0.05715)
			(type default)
		)
		(layer "In4.Cu")
	)
	(gr_line
		(start 367.249202 -293.85006)
		(end 367.250726 -293.849044)
		(stroke
			(width 0.05715)
			(type default)
		)
		(layer "In4.Cu")
	)
	(gr_line
		(start 367.249202 -292.230048)
		(end 367.250726 -292.229032)
		(stroke
			(width 0.05715)
			(type default)
		)
		(layer "In4.Cu")
	)
	(gr_line
		(start 367.249202 -291.58184)
		(end 367.248186 -291.581332)
		(stroke
			(width 0.05715)
			(type default)
		)
		(layer "In4.Cu")
	)
	(gr_line
		(start 367.249202 -288.990024)
		(end 367.250726 -288.989008)
		(stroke
			(width 0.05715)
			(type default)
		)
		(layer "In4.Cu")
	)
	(gr_line
		(start 367.250726 -293.849044)
		(end 367.251742 -293.848536)
		(stroke
			(width 0.05715)
			(type default)
		)
		(layer "In4.Cu")
	)
	(gr_line
		(start 367.250726 -292.229032)
		(end 367.251742 -292.228524)
		(stroke
			(width 0.05715)
			(type default)
		)
		(layer "In4.Cu")
	)
	(gr_line
		(start 367.250726 -291.582856)
		(end 367.249202 -291.58184)
		(stroke
			(width 0.05715)
			(type default)
		)
		(layer "In4.Cu")
	)
	(gr_line
		(start 367.250726 -288.989008)
		(end 367.251742 -288.9885)
		(stroke
			(width 0.05715)
			(type default)
		)
		(layer "In4.Cu")
	)
	(gr_line
		(start 367.251742 -293.848536)
		(end 367.252504 -293.848028)
		(stroke
			(width 0.05715)
			(type default)
		)
		(layer "In4.Cu")
	)
	(gr_line
		(start 367.251742 -292.228524)
		(end 367.252504 -292.228016)
		(stroke
			(width 0.05715)
			(type default)
		)
		(layer "In4.Cu")
	)
	(gr_line
		(start 367.251742 -291.583364)
		(end 367.250726 -291.582856)
		(stroke
			(width 0.05715)
			(type default)
		)
		(layer "In4.Cu")
	)
	(gr_line
		(start 367.251742 -288.9885)
		(end 367.252504 -288.987992)
		(stroke
			(width 0.05715)
			(type default)
		)
		(layer "In4.Cu")
	)
	(gr_line
		(start 367.252504 -291.583872)
		(end 367.251742 -291.583364)
		(stroke
			(width 0.05715)
			(type default)
		)
		(layer "In4.Cu")
	)
	(gr_line
		(start 367.253774 -294.824658)
		(end 367.252504 -294.823896)
		(stroke
			(width 0.05715)
			(type default)
		)
		(layer "In4.Cu")
	)
	(gr_line
		(start 367.253774 -293.204646)
		(end 367.252504 -293.203884)
		(stroke
			(width 0.05715)
			(type default)
		)
		(layer "In4.Cu")
	)
	(gr_line
		(start 367.255552 -293.84625)
		(end 367.25606 -293.845996)
		(stroke
			(width 0.05715)
			(type default)
		)
		(layer "In4.Cu")
	)
	(gr_line
		(start 367.255552 -292.226238)
		(end 367.25606 -292.225984)
		(stroke
			(width 0.05715)
			(type default)
		)
		(layer "In4.Cu")
	)
	(gr_line
		(start 367.255552 -288.986214)
		(end 367.25606 -288.98596)
		(stroke
			(width 0.05715)
			(type default)
		)
		(layer "In4.Cu")
	)
	(gr_line
		(start 367.258854 -291.587428)
		(end 367.257838 -291.58692)
		(stroke
			(width 0.05715)
			(type default)
		)
		(layer "In4.Cu")
	)
	(gr_line
		(start 367.259362 -291.587682)
		(end 367.258854 -291.587428)
		(stroke
			(width 0.05715)
			(type default)
		)
		(layer "In4.Cu")
	)
	(gr_line
		(start 367.337594 -294.019224)
		(end 367.338356 -294.018716)
		(stroke
			(width 0.05715)
			(type default)
		)
		(layer "In4.Cu")
	)
	(gr_line
		(start 367.337594 -292.399212)
		(end 367.338356 -292.398704)
		(stroke
			(width 0.05715)
			(type default)
		)
		(layer "In4.Cu")
	)
	(gr_line
		(start 367.337594 -289.159188)
		(end 367.338356 -289.15868)
		(stroke
			(width 0.05715)
			(type default)
		)
		(layer "In4.Cu")
	)
	(gr_line
		(start 367.343436 -291.415978)
		(end 367.341912 -291.415216)
		(stroke
			(width 0.05715)
			(type default)
		)
		(layer "In4.Cu")
	)
	(gr_line
		(start 367.345468 -294.014652)
		(end 367.346992 -294.01389)
		(stroke
			(width 0.05715)
			(type default)
		)
		(layer "In4.Cu")
	)
	(gr_line
		(start 367.345468 -292.39464)
		(end 367.346992 -292.393878)
		(stroke
			(width 0.05715)
			(type default)
		)
		(layer "In4.Cu")
	)
	(gr_line
		(start 367.345468 -289.154616)
		(end 367.346992 -289.153854)
		(stroke
			(width 0.05715)
			(type default)
		)
		(layer "In4.Cu")
	)
	(gr_line
		(start 367.346992 -294.01389)
		(end 367.347754 -294.013382)
		(stroke
			(width 0.05715)
			(type default)
		)
		(layer "In4.Cu")
	)
	(gr_line
		(start 367.346992 -292.393878)
		(end 367.347754 -292.39337)
		(stroke
			(width 0.05715)
			(type default)
		)
		(layer "In4.Cu")
	)
	(gr_line
		(start 367.346992 -291.41801)
		(end 367.346484 -291.417756)
		(stroke
			(width 0.05715)
			(type default)
		)
		(layer "In4.Cu")
	)
	(gr_line
		(start 367.346992 -289.153854)
		(end 367.347754 -289.153346)
		(stroke
			(width 0.05715)
			(type default)
		)
		(layer "In4.Cu")
	)
	(gr_line
		(start 367.347754 -294.658542)
		(end 367.347246 -294.658288)
		(stroke
			(width 0.05715)
			(type default)
		)
		(layer "In4.Cu")
	)
	(gr_line
		(start 367.347754 -294.013382)
		(end 367.34877 -294.012874)
		(stroke
			(width 0.05715)
			(type default)
		)
		(layer "In4.Cu")
	)
	(gr_line
		(start 367.347754 -293.03853)
		(end 367.347246 -293.038276)
		(stroke
			(width 0.05715)
			(type default)
		)
		(layer "In4.Cu")
	)
	(gr_line
		(start 367.347754 -292.39337)
		(end 367.34877 -292.392862)
		(stroke
			(width 0.05715)
			(type default)
		)
		(layer "In4.Cu")
	)
	(gr_line
		(start 367.347754 -291.418518)
		(end 367.346992 -291.41801)
		(stroke
			(width 0.05715)
			(type default)
		)
		(layer "In4.Cu")
	)
	(gr_line
		(start 367.347754 -289.153346)
		(end 367.34877 -289.152838)
		(stroke
			(width 0.05715)
			(type default)
		)
		(layer "In4.Cu")
	)
	(gr_line
		(start 367.34877 -294.65905)
		(end 367.347754 -294.658542)
		(stroke
			(width 0.05715)
			(type default)
		)
		(layer "In4.Cu")
	)
	(gr_line
		(start 367.34877 -294.012874)
		(end 367.350294 -294.011858)
		(stroke
			(width 0.05715)
			(type default)
		)
		(layer "In4.Cu")
	)
	(gr_line
		(start 367.34877 -293.039038)
		(end 367.347754 -293.03853)
		(stroke
			(width 0.05715)
			(type default)
		)
		(layer "In4.Cu")
	)
	(gr_line
		(start 367.34877 -292.392862)
		(end 367.350294 -292.391846)
		(stroke
			(width 0.05715)
			(type default)
		)
		(layer "In4.Cu")
	)
	(gr_line
		(start 367.34877 -291.419026)
		(end 367.347754 -291.418518)
		(stroke
			(width 0.05715)
			(type default)
		)
		(layer "In4.Cu")
	)
	(gr_line
		(start 367.34877 -289.152838)
		(end 367.350294 -289.151822)
		(stroke
			(width 0.05715)
			(type default)
		)
		(layer "In4.Cu")
	)
	(gr_line
		(start 367.350548 -291.420042)
		(end 367.34877 -291.419026)
		(stroke
			(width 0.05715)
			(type default)
		)
		(layer "In4.Cu")
	)
	(gr_line
		(start 367.352072 -294.010842)
		(end 367.354104 -294.009572)
		(stroke
			(width 0.05715)
			(type default)
		)
		(layer "In4.Cu")
	)
	(gr_line
		(start 367.352072 -292.39083)
		(end 367.354104 -292.38956)
		(stroke
			(width 0.05715)
			(type default)
		)
		(layer "In4.Cu")
	)
	(gr_line
		(start 367.352072 -289.150806)
		(end 367.354104 -289.149536)
		(stroke
			(width 0.05715)
			(type default)
		)
		(layer "In4.Cu")
	)
	(gr_line
		(start 367.353088 -291.421566)
		(end 367.352072 -291.421058)
		(stroke
			(width 0.05715)
			(type default)
		)
		(layer "In4.Cu")
	)
	(gr_line
		(start 367.354104 -291.422328)
		(end 367.353088 -291.421566)
		(stroke
			(width 0.05715)
			(type default)
		)
		(layer "In4.Cu")
	)
	(gr_line
		(start 367.37925 -291.436806)
		(end 367.378742 -291.436552)
		(stroke
			(width 0.05715)
			(type default)
		)
		(layer "In4.Cu")
	)
	(gr_line
		(start 367.380012 -291.437314)
		(end 367.37925 -291.436806)
		(stroke
			(width 0.05715)
			(type default)
		)
		(layer "In4.Cu")
	)
	(gr_arc
		(start 367.382552 -225.389694)
		(mid 367.378603 -225.392471)
		(end 367.374678 -225.395282)
		(stroke
			(width 0.05715)
			(type default)
		)
		(layer "In4.Cu")
	)
	(gr_line
		(start 367.382552 -225.389694)
		(end 367.38941 -225.38563)
		(stroke
			(width 0.05715)
			(type default)
		)
		(layer "In4.Cu")
	)
	(gr_line
		(start 367.38687 -291.441378)
		(end 367.380012 -291.437314)
		(stroke
			(width 0.05715)
			(type default)
		)
		(layer "In4.Cu")
	)
	(gr_line
		(start 367.38941 -225.38563)
		(end 367.390172 -225.385122)
		(stroke
			(width 0.05715)
			(type default)
		)
		(layer "In4.Cu")
	)
	(gr_line
		(start 367.390172 -225.385122)
		(end 367.390934 -225.384614)
		(stroke
			(width 0.05715)
			(type default)
		)
		(layer "In4.Cu")
	)
	(gr_arc
		(start 367.394744 -291.446966)
		(mid 367.390819 -291.444155)
		(end 367.38687 -291.441378)
		(stroke
			(width 0.05715)
			(type default)
		)
		(layer "In4.Cu")
	)
	(gr_line
		(start 367.421922 -225.36658)
		(end 367.42243 -225.366326)
		(stroke
			(width 0.05715)
			(type default)
		)
		(layer "In4.Cu")
	)
	(gr_line
		(start 367.42243 -225.366326)
		(end 367.4237 -225.365564)
		(stroke
			(width 0.05715)
			(type default)
		)
		(layer "In4.Cu")
	)
	(gr_line
		(start 367.439702 -295.146222)
		(end 367.439702 -295.145968)
		(stroke
			(width 0.05715)
			(type default)
		)
		(layer "In4.Cu")
	)
	(gr_line
		(start 367.447068 -388.547356)
		(end 367.052606 -388.38378)
		(stroke
			(width 0.07112)
			(type default)
		)
		(layer "In4.Cu")
	)
	(gr_line
		(start 367.505996 -338.407502)
		(end 367.505996 -338.40801)
		(stroke
			(width 0.07112)
			(type default)
		)
		(layer "In4.Cu")
	)
	(gr_arc
		(start 367.507266 -347.602048)
		(mid 367.508012 -347.547819)
		(end 367.507266 -347.49359)
		(stroke
			(width 0.07112)
			(type default)
		)
		(layer "In4.Cu")
	)
	(gr_line
		(start 367.518696 -225.531172)
		(end 367.51768 -225.53168)
		(stroke
			(width 0.05715)
			(type default)
		)
		(layer "In4.Cu")
	)
	(gr_line
		(start 367.532666 -234.764072)
		(end 367.602008 -234.69473)
		(stroke
			(width 0.05715)
			(type default)
		)
		(layer "In4.Cu")
	)
	(gr_line
		(start 367.532666 -233.14406)
		(end 367.61547 -233.061256)
		(stroke
			(width 0.05715)
			(type default)
		)
		(layer "In4.Cu")
	)
	(gr_line
		(start 367.532666 -231.524048)
		(end 367.602008 -231.454706)
		(stroke
			(width 0.05715)
			(type default)
		)
		(layer "In4.Cu")
	)
	(gr_line
		(start 367.587784 -335.109058)
		(end 367.597944 -335.13903)
		(stroke
			(width 0.07112)
			(type default)
		)
		(layer "In4.Cu")
	)
	(gr_line
		(start 367.597944 -335.13903)
		(end 367.603532 -335.17078)
		(stroke
			(width 0.07112)
			(type default)
		)
		(layer "In4.Cu")
	)
	(gr_arc
		(start 367.61928 -233.038396)
		(mid 367.617259 -233.049807)
		(end 367.61547 -233.061256)
		(stroke
			(width 0.05715)
			(type default)
		)
		(layer "In4.Cu")
	)
	(gr_line
		(start 367.625122 -388.473696)
		(end 367.447068 -388.547356)
		(stroke
			(width 0.07112)
			(type default)
		)
		(layer "In4.Cu")
	)
	(gr_line
		(start 367.630202 -295.146476)
		(end 367.630202 -295.145968)
		(stroke
			(width 0.05715)
			(type default)
		)
		(layer "In4.Cu")
	)
	(gr_line
		(start 367.644172 -221.128844)
		(end 367.598452 -221.083124)
		(stroke
			(width 0.05715)
			(type default)
		)
		(layer "In4.Cu")
	)
	(gr_line
		(start 367.734342 -388.21233)
		(end 367.086388 -387.943852)
		(stroke
			(width 0.07112)
			(type default)
		)
		(layer "In4.Cu")
	)
	(gr_arc
		(start 367.794032 -234.681268)
		(mid 367.792246 -234.669818)
		(end 367.790222 -234.658408)
		(stroke
			(width 0.05715)
			(type default)
		)
		(layer "In4.Cu")
	)
	(gr_line
		(start 367.794032 -234.681268)
		(end 367.876836 -234.764072)
		(stroke
			(width 0.05715)
			(type default)
		)
		(layer "In4.Cu")
	)
	(gr_arc
		(start 367.794032 -231.441244)
		(mid 367.792245 -231.429794)
		(end 367.790222 -231.418384)
		(stroke
			(width 0.05715)
			(type default)
		)
		(layer "In4.Cu")
	)
	(gr_line
		(start 367.794032 -231.441244)
		(end 367.876836 -231.524048)
		(stroke
			(width 0.05715)
			(type default)
		)
		(layer "In4.Cu")
	)
	(gr_line
		(start 367.799874 -221.804484)
		(end 367.800128 -221.80423)
		(stroke
			(width 0.05715)
			(type default)
		)
		(layer "In4.Cu")
	)
	(gr_line
		(start 367.807494 -233.074718)
		(end 367.876836 -233.14406)
		(stroke
			(width 0.05715)
			(type default)
		)
		(layer "In4.Cu")
	)
	(gr_line
		(start 367.83264 -291.095938)
		(end 367.534698 -291.095938)
		(stroke
			(width 0.05715)
			(type default)
		)
		(layer "In4.Cu")
	)
	(gr_line
		(start 367.83264 -289.475926)
		(end 367.534698 -289.475926)
		(stroke
			(width 0.05715)
			(type default)
		)
		(layer "In4.Cu")
	)
	(gr_line
		(start 367.83264 -287.856168)
		(end 367.534698 -287.856168)
		(stroke
			(width 0.05715)
			(type default)
		)
		(layer "In4.Cu")
	)
	(gr_arc
		(start 367.863882 -335.048098)
		(mid 367.859689 -335.033963)
		(end 367.855246 -335.019904)
		(stroke
			(width 0.07112)
			(type default)
		)
		(layer "In4.Cu")
	)
	(gr_line
		(start 367.863882 -296.46245)
		(end 367.863882 -296.434002)
		(stroke
			(width 0.05715)
			(type default)
		)
		(layer "In4.Cu")
	)
	(gr_line
		(start 367.863882 -296.434002)
		(end 367.909602 -296.388282)
		(stroke
			(width 0.05715)
			(type default)
		)
		(layer "In4.Cu")
	)
	(gr_arc
		(start 367.87455 -335.089246)
		(mid 367.869482 -335.068603)
		(end 367.863882 -335.048098)
		(stroke
			(width 0.07112)
			(type default)
		)
		(layer "In4.Cu")
	)
	(gr_line
		(start 367.876836 -234.764072)
		(end 368.174778 -234.764072)
		(stroke
			(width 0.05715)
			(type default)
		)
		(layer "In4.Cu")
	)
	(gr_line
		(start 367.876836 -233.14406)
		(end 368.174778 -233.14406)
		(stroke
			(width 0.05715)
			(type default)
		)
		(layer "In4.Cu")
	)
	(gr_line
		(start 367.876836 -231.524048)
		(end 368.174778 -231.524048)
		(stroke
			(width 0.05715)
			(type default)
		)
		(layer "In4.Cu")
	)
	(gr_line
		(start 367.880392 -221.083124)
		(end 367.834672 -221.128844)
		(stroke
			(width 0.05715)
			(type default)
		)
		(layer "In4.Cu")
	)
	(gr_arc
		(start 367.880646 -335.11871)
		(mid 367.87773 -335.103951)
		(end 367.87455 -335.089246)
		(stroke
			(width 0.07112)
			(type default)
		)
		(layer "In4.Cu")
	)
	(gr_line
		(start 367.882424 -222.286068)
		(end 367.881916 -222.285814)
		(stroke
			(width 0.05715)
			(type default)
		)
		(layer "In4.Cu")
	)
	(gr_line
		(start 367.88344 -222.286576)
		(end 367.882424 -222.286068)
		(stroke
			(width 0.05715)
			(type default)
		)
		(layer "In4.Cu")
	)
	(gr_line
		(start 367.885726 -222.2881)
		(end 367.88344 -222.286576)
		(stroke
			(width 0.05715)
			(type default)
		)
		(layer "In4.Cu")
	)
	(gr_line
		(start 367.888266 -222.289624)
		(end 367.885726 -222.2881)
		(stroke
			(width 0.05715)
			(type default)
		)
		(layer "In4.Cu")
	)
	(gr_line
		(start 367.889282 -222.290132)
		(end 367.888266 -222.289624)
		(stroke
			(width 0.05715)
			(type default)
		)
		(layer "In4.Cu")
	)
	(gr_line
		(start 367.890298 -222.290894)
		(end 367.889282 -222.290132)
		(stroke
			(width 0.05715)
			(type default)
		)
		(layer "In4.Cu")
	)
	(gr_line
		(start 367.890806 -232.657142)
		(end 367.891822 -232.656634)
		(stroke
			(width 0.05715)
			(type default)
		)
		(layer "In4.Cu")
	)
	(gr_line
		(start 367.890806 -227.79736)
		(end 367.891822 -227.796852)
		(stroke
			(width 0.05715)
			(type default)
		)
		(layer "In4.Cu")
	)
	(gr_line
		(start 367.890806 -226.177348)
		(end 367.891822 -226.17684)
		(stroke
			(width 0.05715)
			(type default)
		)
		(layer "In4.Cu")
	)
	(gr_line
		(start 367.891822 -232.656634)
		(end 367.892584 -232.656126)
		(stroke
			(width 0.05715)
			(type default)
		)
		(layer "In4.Cu")
	)
	(gr_line
		(start 367.891822 -228.771704)
		(end 367.890806 -228.771196)
		(stroke
			(width 0.05715)
			(type default)
		)
		(layer "In4.Cu")
	)
	(gr_line
		(start 367.891822 -227.151692)
		(end 367.890806 -227.151184)
		(stroke
			(width 0.05715)
			(type default)
		)
		(layer "In4.Cu")
	)
	(gr_line
		(start 367.891822 -226.17684)
		(end 367.892584 -226.176332)
		(stroke
			(width 0.05715)
			(type default)
		)
		(layer "In4.Cu")
	)
	(gr_line
		(start 367.892584 -232.656126)
		(end 367.896648 -232.65384)
		(stroke
			(width 0.05715)
			(type default)
		)
		(layer "In4.Cu")
	)
	(gr_line
		(start 367.892584 -226.176332)
		(end 367.895378 -226.174808)
		(stroke
			(width 0.05715)
			(type default)
		)
		(layer "In4.Cu")
	)
	(gr_line
		(start 367.895886 -230.396796)
		(end 367.891568 -230.394256)
		(stroke
			(width 0.05715)
			(type default)
		)
		(layer "In4.Cu")
	)
	(gr_line
		(start 367.901982 -287.92551)
		(end 367.83264 -287.856168)
		(stroke
			(width 0.05715)
			(type default)
		)
		(layer "In4.Cu")
	)
	(gr_line
		(start 367.915444 -291.178742)
		(end 367.83264 -291.095938)
		(stroke
			(width 0.05715)
			(type default)
		)
		(layer "In4.Cu")
	)
	(gr_line
		(start 367.915444 -289.55873)
		(end 367.83264 -289.475926)
		(stroke
			(width 0.05715)
			(type default)
		)
		(layer "In4.Cu")
	)
	(gr_arc
		(start 367.915444 -289.55873)
		(mid 367.917235 -289.570052)
		(end 367.919254 -289.581336)
		(stroke
			(width 0.05715)
			(type default)
		)
		(layer "In4.Cu")
	)
	(gr_line
		(start 367.915698 -291.178742)
		(end 367.915444 -291.178742)
		(stroke
			(width 0.05715)
			(type default)
		)
		(layer "In4.Cu")
	)
	(gr_arc
		(start 367.915698 -291.178742)
		(mid 367.917489 -291.190064)
		(end 367.919508 -291.201348)
		(stroke
			(width 0.05715)
			(type default)
		)
		(layer "In4.Cu")
	)
	(gr_line
		(start 367.956338 -229.599744)
		(end 367.956084 -229.599998)
		(stroke
			(width 0.05715)
			(type default)
		)
		(layer "In4.Cu")
	)
	(gr_line
		(start 367.97742 -222.120714)
		(end 367.977928 -222.120968)
		(stroke
			(width 0.05715)
			(type default)
		)
		(layer "In4.Cu")
	)
	(gr_line
		(start 367.977928 -222.120968)
		(end 367.979198 -222.12173)
		(stroke
			(width 0.05715)
			(type default)
		)
		(layer "In4.Cu")
	)
	(gr_line
		(start 367.980468 -222.122492)
		(end 367.98123 -222.123)
		(stroke
			(width 0.05715)
			(type default)
		)
		(layer "In4.Cu")
	)
	(gr_line
		(start 367.98123 -222.123)
		(end 367.981992 -222.123508)
		(stroke
			(width 0.05715)
			(type default)
		)
		(layer "In4.Cu")
	)
	(gr_line
		(start 367.981992 -222.123508)
		(end 367.983516 -222.12427)
		(stroke
			(width 0.05715)
			(type default)
		)
		(layer "In4.Cu")
	)
	(gr_line
		(start 367.983516 -222.12427)
		(end 367.984278 -222.124778)
		(stroke
			(width 0.05715)
			(type default)
		)
		(layer "In4.Cu")
	)
	(gr_line
		(start 367.985802 -228.605588)
		(end 367.987072 -228.60635)
		(stroke
			(width 0.05715)
			(type default)
		)
		(layer "In4.Cu")
	)
	(gr_line
		(start 367.985802 -226.985576)
		(end 367.987072 -226.986338)
		(stroke
			(width 0.05715)
			(type default)
		)
		(layer "In4.Cu")
	)
	(gr_line
		(start 367.986564 -222.126048)
		(end 367.987072 -222.126302)
		(stroke
			(width 0.05715)
			(type default)
		)
		(layer "In4.Cu")
	)
	(gr_line
		(start 367.987072 -228.60635)
		(end 367.987834 -228.606858)
		(stroke
			(width 0.05715)
			(type default)
		)
		(layer "In4.Cu")
	)
	(gr_line
		(start 367.987072 -227.962206)
		(end 367.985802 -227.962968)
		(stroke
			(width 0.05715)
			(type default)
		)
		(layer "In4.Cu")
	)
	(gr_line
		(start 367.987072 -226.986338)
		(end 367.987834 -226.986846)
		(stroke
			(width 0.05715)
			(type default)
		)
		(layer "In4.Cu")
	)
	(gr_line
		(start 367.987072 -226.342194)
		(end 367.985802 -226.342956)
		(stroke
			(width 0.05715)
			(type default)
		)
		(layer "In4.Cu")
	)
	(gr_line
		(start 367.98758 -227.961952)
		(end 367.987072 -227.962206)
		(stroke
			(width 0.05715)
			(type default)
		)
		(layer "In4.Cu")
	)
	(gr_line
		(start 367.987834 -226.341686)
		(end 367.987072 -226.342194)
		(stroke
			(width 0.05715)
			(type default)
		)
		(layer "In4.Cu")
	)
	(gr_line
		(start 368.079528 -222.614236)
		(end 368.079274 -222.614236)
		(stroke
			(width 0.05715)
			(type default)
		)
		(layer "In4.Cu")
	)
	(gr_arc
		(start 368.090196 -287.961832)
		(mid 368.092218 -287.950421)
		(end 368.094006 -287.938972)
		(stroke
			(width 0.05715)
			(type default)
		)
		(layer "In4.Cu")
	)
	(gr_line
		(start 368.094006 -287.938972)
		(end 368.17681 -287.856168)
		(stroke
			(width 0.05715)
			(type default)
		)
		(layer "In4.Cu")
	)
	(gr_line
		(start 368.107468 -289.545268)
		(end 368.17681 -289.475926)
		(stroke
			(width 0.05715)
			(type default)
		)
		(layer "In4.Cu")
	)
	(gr_line
		(start 368.107722 -379.562106)
		(end 368.107722 -379.561598)
		(stroke
			(width 0.07112)
			(type default)
		)
		(layer "In4.Cu")
	)
	(gr_line
		(start 368.107722 -291.165026)
		(end 368.17681 -291.095938)
		(stroke
			(width 0.05715)
			(type default)
		)
		(layer "In4.Cu")
	)
	(gr_arc
		(start 368.144552 -289.934904)
		(mid 368.148604 -289.937716)
		(end 368.15268 -289.940492)
		(stroke
			(width 0.05715)
			(type default)
		)
		(layer "In4.Cu")
	)
	(gr_line
		(start 368.145822 -296.46245)
		(end 368.145822 -296.434002)
		(stroke
			(width 0.05715)
			(type default)
		)
		(layer "In4.Cu")
	)
	(gr_line
		(start 368.145822 -296.434002)
		(end 368.100102 -296.388282)
		(stroke
			(width 0.05715)
			(type default)
		)
		(layer "In4.Cu")
	)
	(gr_arc
		(start 368.153442 -289.941)
		(mid 368.153061 -289.940746)
		(end 368.15268 -289.940492)
		(stroke
			(width 0.05715)
			(type default)
		)
		(layer "In4.Cu")
	)
	(gr_line
		(start 368.160554 -289.945064)
		(end 368.153442 -289.941)
		(stroke
			(width 0.05715)
			(type default)
		)
		(layer "In4.Cu")
	)
	(gr_line
		(start 368.167412 -347.849698)
		(end 368.167158 -347.850206)
		(stroke
			(width 0.07112)
			(type default)
		)
		(layer "In4.Cu")
	)
	(gr_line
		(start 368.17681 -291.095938)
		(end 368.474752 -291.095938)
		(stroke
			(width 0.05715)
			(type default)
		)
		(layer "In4.Cu")
	)
	(gr_line
		(start 368.17681 -289.475926)
		(end 368.474752 -289.475926)
		(stroke
			(width 0.05715)
			(type default)
		)
		(layer "In4.Cu")
	)
	(gr_line
		(start 368.17681 -287.856168)
		(end 368.474752 -287.856168)
		(stroke
			(width 0.05715)
			(type default)
		)
		(layer "In4.Cu")
	)
	(gr_line
		(start 368.1857 -293.851838)
		(end 368.18824 -293.85006)
		(stroke
			(width 0.05715)
			(type default)
		)
		(layer "In4.Cu")
	)
	(gr_line
		(start 368.18824 -293.85006)
		(end 368.189256 -293.849552)
		(stroke
			(width 0.05715)
			(type default)
		)
		(layer "In4.Cu")
	)
	(gr_line
		(start 368.189256 -293.849552)
		(end 368.190018 -293.849044)
		(stroke
			(width 0.05715)
			(type default)
		)
		(layer "In4.Cu")
	)
	(gr_line
		(start 368.190018 -293.849044)
		(end 368.191034 -293.848536)
		(stroke
			(width 0.05715)
			(type default)
		)
		(layer "In4.Cu")
	)
	(gr_line
		(start 368.191034 -293.848536)
		(end 368.19205 -293.847774)
		(stroke
			(width 0.05715)
			(type default)
		)
		(layer "In4.Cu")
	)
	(gr_line
		(start 368.192304 -289.963606)
		(end 368.191542 -289.963098)
		(stroke
			(width 0.05715)
			(type default)
		)
		(layer "In4.Cu")
	)
	(gr_line
		(start 368.195098 -289.96513)
		(end 368.192304 -289.963606)
		(stroke
			(width 0.05715)
			(type default)
		)
		(layer "In4.Cu")
	)
	(gr_line
		(start 368.19713 -293.844472)
		(end 368.222784 -293.827454)
		(stroke
			(width 0.05715)
			(type default)
		)
		(layer "In4.Cu")
	)
	(gr_arc
		(start 368.270028 -229.094284)
		(mid 368.270038 -229.090982)
		(end 368.270028 -229.08768)
		(stroke
			(width 0.05715)
			(type default)
		)
		(layer "In4.Cu")
	)
	(gr_line
		(start 368.270028 -225.85426)
		(end 368.270028 -225.861372)
		(stroke
			(width 0.05715)
			(type default)
		)
		(layer "In4.Cu")
	)
	(gr_line
		(start 368.270282 -222.614236)
		(end 368.270028 -222.614236)
		(stroke
			(width 0.05715)
			(type default)
		)
		(layer "In4.Cu")
	)
	(gr_line
		(start 368.275108 -294.020494)
		(end 368.275616 -294.02024)
		(stroke
			(width 0.05715)
			(type default)
		)
		(layer "In4.Cu")
	)
	(gr_line
		(start 368.276632 -294.019732)
		(end 368.281458 -294.016938)
		(stroke
			(width 0.05715)
			(type default)
		)
		(layer "In4.Cu")
	)
	(gr_line
		(start 368.278664 -295.638728)
		(end 368.287046 -295.633902)
		(stroke
			(width 0.05715)
			(type default)
		)
		(layer "In4.Cu")
	)
	(gr_line
		(start 368.281458 -294.016938)
		(end 368.28349 -294.015922)
		(stroke
			(width 0.05715)
			(type default)
		)
		(layer "In4.Cu")
	)
	(gr_line
		(start 368.28349 -294.015922)
		(end 368.284252 -294.015414)
		(stroke
			(width 0.05715)
			(type default)
		)
		(layer "In4.Cu")
	)
	(gr_line
		(start 368.284252 -294.015414)
		(end 368.285268 -294.014906)
		(stroke
			(width 0.05715)
			(type default)
		)
		(layer "In4.Cu")
	)
	(gr_line
		(start 368.285268 -294.014906)
		(end 368.28603 -294.014398)
		(stroke
			(width 0.05715)
			(type default)
		)
		(layer "In4.Cu")
	)
	(gr_line
		(start 368.28603 -294.014398)
		(end 368.287046 -294.01389)
		(stroke
			(width 0.05715)
			(type default)
		)
		(layer "In4.Cu")
	)
	(gr_line
		(start 368.287046 -295.633902)
		(end 368.287808 -295.633394)
		(stroke
			(width 0.05715)
			(type default)
		)
		(layer "In4.Cu")
	)
	(gr_line
		(start 368.2873 -292.393624)
		(end 368.287808 -292.39337)
		(stroke
			(width 0.05715)
			(type default)
		)
		(layer "In4.Cu")
	)
	(gr_line
		(start 368.287554 -294.658288)
		(end 368.28222 -294.65524)
		(stroke
			(width 0.05715)
			(type default)
		)
		(layer "In4.Cu")
	)
	(gr_line
		(start 368.287554 -293.038276)
		(end 368.28222 -293.035228)
		(stroke
			(width 0.05715)
			(type default)
		)
		(layer "In4.Cu")
	)
	(gr_line
		(start 368.287808 -295.633394)
		(end 368.288316 -295.633394)
		(stroke
			(width 0.05715)
			(type default)
		)
		(layer "In4.Cu")
	)
	(gr_line
		(start 368.287808 -291.418518)
		(end 368.2873 -291.418264)
		(stroke
			(width 0.05715)
			(type default)
		)
		(layer "In4.Cu")
	)
	(gr_line
		(start 368.287808 -289.798506)
		(end 368.286792 -289.797998)
		(stroke
			(width 0.05715)
			(type default)
		)
		(layer "In4.Cu")
	)
	(gr_arc
		(start 368.288316 -295.633394)
		(mid 368.289587 -295.632634)
		(end 368.290856 -295.63187)
		(stroke
			(width 0.05715)
			(type default)
		)
		(layer "In4.Cu")
	)
	(gr_arc
		(start 368.290348 -294.012112)
		(mid 368.291492 -294.011478)
		(end 368.292634 -294.010842)
		(stroke
			(width 0.05715)
			(type default)
		)
		(layer "In4.Cu")
	)
	(gr_line
		(start 368.290602 -289.800284)
		(end 368.287808 -289.798506)
		(stroke
			(width 0.05715)
			(type default)
		)
		(layer "In4.Cu")
	)
	(gr_arc
		(start 368.295682 -294.009064)
		(mid 368.295047 -294.009445)
		(end 368.294412 -294.009826)
		(stroke
			(width 0.05715)
			(type default)
		)
		(layer "In4.Cu")
	)
	(gr_arc
		(start 368.299746 -294.006524)
		(mid 368.315795 -293.996375)
		(end 368.331496 -293.985696)
		(stroke
			(width 0.05715)
			(type default)
		)
		(layer "In4.Cu")
	)
	(gr_arc
		(start 368.301778 -295.625266)
		(mid 368.316667 -295.615723)
		(end 368.331242 -295.605708)
		(stroke
			(width 0.05715)
			(type default)
		)
		(layer "In4.Cu")
	)
	(gr_arc
		(start 368.307874 -294.67048)
		(mid 368.304706 -294.668438)
		(end 368.301524 -294.666416)
		(stroke
			(width 0.05715)
			(type default)
		)
		(layer "In4.Cu")
	)
	(gr_arc
		(start 368.307874 -293.050468)
		(mid 368.304705 -293.048426)
		(end 368.301524 -293.046404)
		(stroke
			(width 0.05715)
			(type default)
		)
		(layer "In4.Cu")
	)
	(gr_arc
		(start 368.33556 -293.982648)
		(mid 368.340917 -293.978743)
		(end 368.346228 -293.974774)
		(stroke
			(width 0.05715)
			(type default)
		)
		(layer "In4.Cu")
	)
	(gr_arc
		(start 368.335814 -295.60266)
		(mid 368.341044 -295.598753)
		(end 368.346228 -295.594786)
		(stroke
			(width 0.05715)
			(type default)
		)
		(layer "In4.Cu")
	)
	(gr_line
		(start 368.356896 -225.369374)
		(end 368.357912 -225.368866)
		(stroke
			(width 0.05715)
			(type default)
		)
		(layer "In4.Cu")
	)
	(gr_line
		(start 368.357912 -225.368866)
		(end 368.360198 -225.367596)
		(stroke
			(width 0.05715)
			(type default)
		)
		(layer "In4.Cu")
	)
	(gr_line
		(start 368.360198 -225.367596)
		(end 368.361214 -225.367088)
		(stroke
			(width 0.05715)
			(type default)
		)
		(layer "In4.Cu")
	)
	(gr_line
		(start 368.361214 -225.367088)
		(end 368.3635 -225.365818)
		(stroke
			(width 0.05715)
			(type default)
		)
		(layer "In4.Cu")
	)
	(gr_line
		(start 368.454178 -225.533712)
		(end 368.453416 -225.53422)
		(stroke
			(width 0.05715)
			(type default)
		)
		(layer "In4.Cu")
	)
	(gr_line
		(start 368.456464 -347.795596)
		(end 368.456464 -347.796612)
		(stroke
			(width 0.07112)
			(type default)
		)
		(layer "In4.Cu")
	)
	(gr_line
		(start 368.456464 -338.409534)
		(end 368.456464 -338.410042)
		(stroke
			(width 0.07112)
			(type default)
		)
		(layer "In4.Cu")
	)
	(gr_line
		(start 368.465608 -334.65897)
		(end 368.478054 -334.695038)
		(stroke
			(width 0.07112)
			(type default)
		)
		(layer "In4.Cu")
	)
	(gr_line
		(start 368.478054 -334.695038)
		(end 368.484404 -334.730344)
		(stroke
			(width 0.07112)
			(type default)
		)
		(layer "In4.Cu")
	)
	(gr_line
		(start 368.496088 -231.989122)
		(end 368.488468 -231.99344)
		(stroke
			(width 0.05715)
			(type default)
		)
		(layer "In4.Cu")
	)
	(gr_arc
		(start 368.49685 -231.988614)
		(mid 368.496469 -231.988868)
		(end 368.496088 -231.989122)
		(stroke
			(width 0.05715)
			(type default)
		)
		(layer "In4.Cu")
	)
	(gr_arc
		(start 368.49685 -231.988614)
		(mid 368.500799 -231.985837)
		(end 368.504724 -231.983026)
		(stroke
			(width 0.05715)
			(type default)
		)
		(layer "In4.Cu")
	)
	(gr_line
		(start 368.50066 -385.584954)
		(end 368.50066 -385.392676)
		(stroke
			(width 0.07112)
			(type default)
		)
		(layer "In4.Cu")
	)
	(gr_line
		(start 368.543586 -307.992018)
		(end 368.54384 -307.992018)
		(stroke
			(width 0.07112)
			(type default)
		)
		(layer "In4.Cu")
	)
	(gr_line
		(start 368.662458 -290.773866)
		(end 368.661696 -290.773358)
		(stroke
			(width 0.05715)
			(type default)
		)
		(layer "In4.Cu")
	)
	(gr_line
		(start 368.663728 -290.774628)
		(end 368.662458 -290.773866)
		(stroke
			(width 0.05715)
			(type default)
		)
		(layer "In4.Cu")
	)
	(gr_line
		(start 368.667792 -290.776914)
		(end 368.666268 -290.775898)
		(stroke
			(width 0.05715)
			(type default)
		)
		(layer "In4.Cu")
	)
	(gr_line
		(start 368.668808 -290.777422)
		(end 368.667792 -290.776914)
		(stroke
			(width 0.05715)
			(type default)
		)
		(layer "In4.Cu")
	)
	(gr_line
		(start 368.669316 -290.777676)
		(end 368.668808 -290.777422)
		(stroke
			(width 0.05715)
			(type default)
		)
		(layer "In4.Cu")
	)
	(gr_line
		(start 368.740182 -225.044254)
		(end 368.739928 -225.044254)
		(stroke
			(width 0.05715)
			(type default)
		)
		(layer "In4.Cu")
	)
	(gr_arc
		(start 368.743738 -334.604106)
		(mid 368.738475 -334.586265)
		(end 368.732816 -334.568546)
		(stroke
			(width 0.07112)
			(type default)
		)
		(layer "In4.Cu")
	)
	(gr_arc
		(start 368.75466 -334.645254)
		(mid 368.749458 -334.624611)
		(end 368.743738 -334.604106)
		(stroke
			(width 0.07112)
			(type default)
		)
		(layer "In4.Cu")
	)
	(gr_arc
		(start 368.761518 -334.679036)
		(mid 368.758264 -334.66211)
		(end 368.75466 -334.645254)
		(stroke
			(width 0.07112)
			(type default)
		)
		(layer "In4.Cu")
	)
	(gr_line
		(start 368.763042 -290.61156)
		(end 368.762026 -290.611052)
		(stroke
			(width 0.05715)
			(type default)
		)
		(layer "In4.Cu")
	)
	(gr_line
		(start 368.764058 -290.612322)
		(end 368.763042 -290.61156)
		(stroke
			(width 0.05715)
			(type default)
		)
		(layer "In4.Cu")
	)
	(gr_line
		(start 368.785394 -230.363522)
		(end 368.784886 -230.363014)
		(stroke
			(width 0.05715)
			(type default)
		)
		(layer "In4.Cu")
	)
	(gr_line
		(start 368.789204 -290.6268)
		(end 368.788696 -290.626546)
		(stroke
			(width 0.05715)
			(type default)
		)
		(layer "In4.Cu")
	)
	(gr_line
		(start 368.789966 -290.627308)
		(end 368.789204 -290.6268)
		(stroke
			(width 0.05715)
			(type default)
		)
		(layer "In4.Cu")
	)
	(gr_line
		(start 368.796824 -290.631372)
		(end 368.789966 -290.627308)
		(stroke
			(width 0.05715)
			(type default)
		)
		(layer "In4.Cu")
	)
	(gr_line
		(start 368.802666 -385.88696)
		(end 368.50066 -385.584954)
		(stroke
			(width 0.07112)
			(type default)
		)
		(layer "In4.Cu")
	)
	(gr_line
		(start 368.803936 -296.462958)
		(end 368.803936 -296.43451)
		(stroke
			(width 0.05715)
			(type default)
		)
		(layer "In4.Cu")
	)
	(gr_line
		(start 368.803936 -296.43451)
		(end 368.849656 -296.38879)
		(stroke
			(width 0.05715)
			(type default)
		)
		(layer "In4.Cu")
	)
	(gr_arc
		(start 368.804698 -290.63696)
		(mid 368.800773 -290.634149)
		(end 368.796824 -290.631372)
		(stroke
			(width 0.05715)
			(type default)
		)
		(layer "In4.Cu")
	)
	(gr_line
		(start 368.830352 -232.657396)
		(end 368.83086 -232.657142)
		(stroke
			(width 0.05715)
			(type default)
		)
		(layer "In4.Cu")
	)
	(gr_line
		(start 368.83086 -232.657142)
		(end 368.831876 -232.656634)
		(stroke
			(width 0.05715)
			(type default)
		)
		(layer "In4.Cu")
	)
	(gr_line
		(start 368.831368 -233.631232)
		(end 368.830352 -233.630724)
		(stroke
			(width 0.05715)
			(type default)
		)
		(layer "In4.Cu")
	)
	(gr_line
		(start 368.831876 -232.656634)
		(end 368.832638 -232.656126)
		(stroke
			(width 0.05715)
			(type default)
		)
		(layer "In4.Cu")
	)
	(gr_line
		(start 368.832384 -228.771704)
		(end 368.831876 -228.771704)
		(stroke
			(width 0.05715)
			(type default)
		)
		(layer "In4.Cu")
	)
	(gr_line
		(start 368.832384 -227.151946)
		(end 368.83213 -227.151946)
		(stroke
			(width 0.05715)
			(type default)
		)
		(layer "In4.Cu")
	)
	(gr_line
		(start 368.832638 -233.631994)
		(end 368.831368 -233.631232)
		(stroke
			(width 0.05715)
			(type default)
		)
		(layer "In4.Cu")
	)
	(gr_line
		(start 368.8334 -228.772212)
		(end 368.832384 -228.771704)
		(stroke
			(width 0.05715)
			(type default)
		)
		(layer "In4.Cu")
	)
	(gr_line
		(start 368.838226 -226.173284)
		(end 368.840258 -226.172014)
		(stroke
			(width 0.05715)
			(type default)
		)
		(layer "In4.Cu")
	)
	(gr_line
		(start 368.840258 -226.172014)
		(end 368.842544 -226.170744)
		(stroke
			(width 0.05715)
			(type default)
		)
		(layer "In4.Cu")
	)
	(gr_line
		(start 368.842544 -226.170744)
		(end 368.84356 -226.170236)
		(stroke
			(width 0.05715)
			(type default)
		)
		(layer "In4.Cu")
	)
	(gr_line
		(start 368.910108 -233.45648)
		(end 368.912648 -233.45775)
		(stroke
			(width 0.05715)
			(type default)
		)
		(layer "In4.Cu")
	)
	(gr_line
		(start 368.925856 -228.605588)
		(end 368.927126 -228.60635)
		(stroke
			(width 0.05715)
			(type default)
		)
		(layer "In4.Cu")
	)
	(gr_line
		(start 368.927126 -228.60635)
		(end 368.927888 -228.606858)
		(stroke
			(width 0.05715)
			(type default)
		)
		(layer "In4.Cu")
	)
	(gr_line
		(start 368.927634 -232.82148)
		(end 368.92611 -232.822496)
		(stroke
			(width 0.05715)
			(type default)
		)
		(layer "In4.Cu")
	)
	(gr_line
		(start 368.927888 -228.606858)
		(end 368.929412 -228.60762)
		(stroke
			(width 0.05715)
			(type default)
		)
		(layer "In4.Cu")
	)
	(gr_arc
		(start 368.927888 -226.34194)
		(mid 368.928269 -226.341686)
		(end 368.92865 -226.341432)
		(stroke
			(width 0.05715)
			(type default)
		)
		(layer "In4.Cu")
	)
	(gr_arc
		(start 368.930682 -227.96246)
		(mid 368.932717 -227.961195)
		(end 368.934746 -227.95992)
		(stroke
			(width 0.05715)
			(type default)
		)
		(layer "In4.Cu")
	)
	(gr_line
		(start 368.931698 -226.339654)
		(end 368.92865 -226.341432)
		(stroke
			(width 0.05715)
			(type default)
		)
		(layer "In4.Cu")
	)
	(gr_arc
		(start 368.933222 -233.469688)
		(mid 368.930812 -233.468285)
		(end 368.928396 -233.466894)
		(stroke
			(width 0.05715)
			(type default)
		)
		(layer "In4.Cu")
	)
	(gr_line
		(start 368.938302 -226.335844)
		(end 368.93627 -226.33686)
		(stroke
			(width 0.05715)
			(type default)
		)
		(layer "In4.Cu")
	)
	(gr_line
		(start 368.939064 -226.335336)
		(end 368.938302 -226.335844)
		(stroke
			(width 0.05715)
			(type default)
		)
		(layer "In4.Cu")
	)
	(gr_line
		(start 368.94008 -226.334828)
		(end 368.939064 -226.335336)
		(stroke
			(width 0.05715)
			(type default)
		)
		(layer "In4.Cu")
	)
	(gr_line
		(start 368.940842 -226.33432)
		(end 368.94008 -226.334828)
		(stroke
			(width 0.05715)
			(type default)
		)
		(layer "In4.Cu")
	)
	(gr_line
		(start 368.941858 -226.333812)
		(end 368.940842 -226.33432)
		(stroke
			(width 0.05715)
			(type default)
		)
		(layer "In4.Cu")
	)
	(gr_line
		(start 368.942366 -226.333558)
		(end 368.941858 -226.333812)
		(stroke
			(width 0.05715)
			(type default)
		)
		(layer "In4.Cu")
	)
	(gr_line
		(start 368.942874 -226.33305)
		(end 368.943128 -226.33305)
		(stroke
			(width 0.05715)
			(type default)
		)
		(layer "In4.Cu")
	)
	(gr_line
		(start 368.955066 -228.622606)
		(end 368.96421 -228.62794)
		(stroke
			(width 0.05715)
			(type default)
		)
		(layer "In4.Cu")
	)
	(gr_line
		(start 368.96421 -229.560628)
		(end 368.961416 -229.562152)
		(stroke
			(width 0.05715)
			(type default)
		)
		(layer "In4.Cu")
	)
	(gr_arc
		(start 368.96421 -229.560628)
		(mid 368.970848 -229.555977)
		(end 368.977418 -229.55123)
		(stroke
			(width 0.05715)
			(type default)
		)
		(layer "In4.Cu")
	)
	(gr_arc
		(start 368.973862 -228.635052)
		(mid 368.969433 -228.631729)
		(end 368.964972 -228.628448)
		(stroke
			(width 0.05715)
			(type default)
		)
		(layer "In4.Cu")
	)
	(gr_line
		(start 368.994944 -385.88696)
		(end 368.802666 -385.88696)
		(stroke
			(width 0.07112)
			(type default)
		)
		(layer "In4.Cu")
	)
	(gr_arc
		(start 368.995706 -228.652578)
		(mid 368.991657 -228.649258)
		(end 368.987578 -228.645974)
		(stroke
			(width 0.05715)
			(type default)
		)
		(layer "In4.Cu")
	)
	(gr_arc
		(start 369.002056 -228.658674)
		(mid 368.998891 -228.655616)
		(end 368.995706 -228.652578)
		(stroke
			(width 0.05715)
			(type default)
		)
		(layer "In4.Cu")
	)
	(gr_line
		(start 369.085876 -296.462958)
		(end 369.085876 -296.43451)
		(stroke
			(width 0.05715)
			(type default)
		)
		(layer "In4.Cu")
	)
	(gr_line
		(start 369.085876 -296.43451)
		(end 369.040156 -296.38879)
		(stroke
			(width 0.05715)
			(type default)
		)
		(layer "In4.Cu")
	)
	(gr_line
		(start 369.196112 -385.68757)
		(end 368.70005 -385.191508)
		(stroke
			(width 0.07112)
			(type default)
		)
		(layer "In4.Cu")
	)
	(gr_arc
		(start 369.210082 -229.080568)
		(mid 369.209224 -229.07396)
		(end 369.208304 -229.06736)
		(stroke
			(width 0.05715)
			(type default)
		)
		(layer "In4.Cu")
	)
	(gr_arc
		(start 369.210336 -229.094284)
		(mid 369.210251 -229.087425)
		(end 369.210082 -229.080568)
		(stroke
			(width 0.05715)
			(type default)
		)
		(layer "In4.Cu")
	)
	(gr_line
		(start 369.29822 -386.382514)
		(end 369.29822 -386.190236)
		(stroke
			(width 0.07112)
			(type default)
		)
		(layer "In4.Cu")
	)
	(gr_arc
		(start 369.29949 -231.847898)
		(mid 369.298346 -231.848532)
		(end 369.297204 -231.849168)
		(stroke
			(width 0.05715)
			(type default)
		)
		(layer "In4.Cu")
	)
	(gr_line
		(start 369.29949 -231.847898)
		(end 369.301776 -231.846628)
		(stroke
			(width 0.05715)
			(type default)
		)
		(layer "In4.Cu")
	)
	(gr_arc
		(start 369.29949 -225.368104)
		(mid 369.298473 -225.368738)
		(end 369.297458 -225.369374)
		(stroke
			(width 0.05715)
			(type default)
		)
		(layer "In4.Cu")
	)
	(gr_line
		(start 369.29949 -225.368104)
		(end 369.301776 -225.366834)
		(stroke
			(width 0.05715)
			(type default)
		)
		(layer "In4.Cu")
	)
	(gr_line
		(start 369.301776 -234.441492)
		(end 369.29949 -234.439968)
		(stroke
			(width 0.05715)
			(type default)
		)
		(layer "In4.Cu")
	)
	(gr_line
		(start 369.301776 -231.846628)
		(end 369.302538 -231.84612)
		(stroke
			(width 0.05715)
			(type default)
		)
		(layer "In4.Cu")
	)
	(gr_line
		(start 369.301776 -225.366834)
		(end 369.302538 -225.366326)
		(stroke
			(width 0.05715)
			(type default)
		)
		(layer "In4.Cu")
	)
	(gr_line
		(start 369.302284 -234.441746)
		(end 369.301776 -234.441492)
		(stroke
			(width 0.05715)
			(type default)
		)
		(layer "In4.Cu")
	)
	(gr_line
		(start 369.302538 -222.126302)
		(end 369.309904 -222.122238)
		(stroke
			(width 0.05715)
			(type default)
		)
		(layer "In4.Cu")
	)
	(gr_line
		(start 369.3795 -334.401668)
		(end 369.391946 -334.437736)
		(stroke
			(width 0.07112)
			(type default)
		)
		(layer "In4.Cu")
	)
	(gr_line
		(start 369.391946 -334.437736)
		(end 369.398296 -334.472788)
		(stroke
			(width 0.07112)
			(type default)
		)
		(layer "In4.Cu")
	)
	(gr_line
		(start 369.395248 -234.275122)
		(end 369.397026 -234.276138)
		(stroke
			(width 0.05715)
			(type default)
		)
		(layer "In4.Cu")
	)
	(gr_line
		(start 369.397026 -232.011982)
		(end 369.395248 -232.012744)
		(stroke
			(width 0.05715)
			(type default)
		)
		(layer "In4.Cu")
	)
	(gr_line
		(start 369.397026 -225.532188)
		(end 369.395248 -225.53295)
		(stroke
			(width 0.05715)
			(type default)
		)
		(layer "In4.Cu")
	)
	(gr_line
		(start 369.397788 -232.011474)
		(end 369.397026 -232.011982)
		(stroke
			(width 0.05715)
			(type default)
		)
		(layer "In4.Cu")
	)
	(gr_line
		(start 369.397788 -225.53168)
		(end 369.397026 -225.532188)
		(stroke
			(width 0.05715)
			(type default)
		)
		(layer "In4.Cu")
	)
	(gr_line
		(start 369.398804 -232.010966)
		(end 369.397788 -232.011474)
		(stroke
			(width 0.05715)
			(type default)
		)
		(layer "In4.Cu")
	)
	(gr_line
		(start 369.398804 -225.531172)
		(end 369.397788 -225.53168)
		(stroke
			(width 0.05715)
			(type default)
		)
		(layer "In4.Cu")
	)
	(gr_line
		(start 369.400836 -232.00995)
		(end 369.398804 -232.010966)
		(stroke
			(width 0.05715)
			(type default)
		)
		(layer "In4.Cu")
	)
	(gr_line
		(start 369.400836 -225.530156)
		(end 369.398804 -225.531172)
		(stroke
			(width 0.05715)
			(type default)
		)
		(layer "In4.Cu")
	)
	(gr_arc
		(start 369.401344 -347.985334)
		(mid 369.402119 -347.981781)
		(end 369.402868 -347.978222)
		(stroke
			(width 0.07112)
			(type default)
		)
		(layer "In4.Cu")
	)
	(gr_line
		(start 369.402868 -222.288608)
		(end 369.402106 -222.289116)
		(stroke
			(width 0.05715)
			(type default)
		)
		(layer "In4.Cu")
	)
	(gr_line
		(start 369.403884 -222.2881)
		(end 369.402868 -222.288608)
		(stroke
			(width 0.05715)
			(type default)
		)
		(layer "In4.Cu")
	)
	(gr_line
		(start 369.405662 -222.287084)
		(end 369.403884 -222.2881)
		(stroke
			(width 0.05715)
			(type default)
		)
		(layer "In4.Cu")
	)
	(gr_line
		(start 369.414552 -347.867224)
		(end 369.414552 -347.86824)
		(stroke
			(width 0.07112)
			(type default)
		)
		(layer "In4.Cu")
	)
	(gr_line
		(start 369.414552 -338.398866)
		(end 369.414552 -338.399374)
		(stroke
			(width 0.07112)
			(type default)
		)
		(layer "In4.Cu")
	)
	(gr_line
		(start 369.430046 -231.992678)
		(end 369.429284 -231.993186)
		(stroke
			(width 0.05715)
			(type default)
		)
		(layer "In4.Cu")
	)
	(gr_line
		(start 369.430046 -225.512884)
		(end 369.429284 -225.513392)
		(stroke
			(width 0.05715)
			(type default)
		)
		(layer "In4.Cu")
	)
	(gr_line
		(start 369.436904 -231.988614)
		(end 369.430046 -231.992678)
		(stroke
			(width 0.05715)
			(type default)
		)
		(layer "In4.Cu")
	)
	(gr_arc
		(start 369.436904 -231.988614)
		(mid 369.440853 -231.985837)
		(end 369.444778 -231.983026)
		(stroke
			(width 0.05715)
			(type default)
		)
		(layer "In4.Cu")
	)
	(gr_line
		(start 369.436904 -225.50882)
		(end 369.430046 -225.512884)
		(stroke
			(width 0.05715)
			(type default)
		)
		(layer "In4.Cu")
	)
	(gr_arc
		(start 369.436904 -225.50882)
		(mid 369.440853 -225.506043)
		(end 369.444778 -225.503232)
		(stroke
			(width 0.05715)
			(type default)
		)
		(layer "In4.Cu")
	)
	(gr_line
		(start 369.489482 -221.128844)
		(end 369.443762 -221.083124)
		(stroke
			(width 0.05715)
			(type default)
		)
		(layer "In4.Cu")
	)
	(gr_line
		(start 369.600226 -386.68452)
		(end 369.29822 -386.382514)
		(stroke
			(width 0.07112)
			(type default)
		)
		(layer "In4.Cu")
	)
	(gr_arc
		(start 369.65763 -334.346804)
		(mid 369.652368 -334.328836)
		(end 369.646708 -334.31099)
		(stroke
			(width 0.07112)
			(type default)
		)
		(layer "In4.Cu")
	)
	(gr_line
		(start 369.667536 -349.562674)
		(end 369.667536 -349.562928)
		(stroke
			(width 0.07112)
			(type default)
		)
		(layer "In4.Cu")
	)
	(gr_arc
		(start 369.668552 -334.387952)
		(mid 369.663353 -334.367308)
		(end 369.65763 -334.346804)
		(stroke
			(width 0.07112)
			(type default)
		)
		(layer "In4.Cu")
	)
	(gr_arc
		(start 369.67541 -334.42148)
		(mid 369.672151 -334.404681)
		(end 369.668552 -334.387952)
		(stroke
			(width 0.07112)
			(type default)
		)
		(layer "In4.Cu")
	)
	(gr_line
		(start 369.725702 -221.083124)
		(end 369.679982 -221.128844)
		(stroke
			(width 0.05715)
			(type default)
		)
		(layer "In4.Cu")
	)
	(gr_line
		(start 369.743736 -296.456354)
		(end 369.743736 -296.427906)
		(stroke
			(width 0.05715)
			(type default)
		)
		(layer "In4.Cu")
	)
	(gr_line
		(start 369.743736 -296.427906)
		(end 369.789456 -296.382186)
		(stroke
			(width 0.05715)
			(type default)
		)
		(layer "In4.Cu")
	)
	(gr_arc
		(start 369.789456 -295.9481)
		(mid 369.789443 -295.952037)
		(end 369.789456 -295.955974)
		(stroke
			(width 0.05715)
			(type default)
		)
		(layer "In4.Cu")
	)
	(gr_line
		(start 369.792504 -386.68452)
		(end 369.600226 -386.68452)
		(stroke
			(width 0.07112)
			(type default)
		)
		(layer "In4.Cu")
	)
	(gr_line
		(start 369.922552 -311.150762)
		(end 369.922806 -311.150762)
		(stroke
			(width 0.07112)
			(type default)
		)
		(layer "In4.Cu")
	)
	(gr_line
		(start 369.993672 -386.48513)
		(end 369.49761 -385.989068)
		(stroke
			(width 0.07112)
			(type default)
		)
		(layer "In4.Cu")
	)
	(gr_line
		(start 370.025676 -296.456354)
		(end 370.025676 -296.427906)
		(stroke
			(width 0.05715)
			(type default)
		)
		(layer "In4.Cu")
	)
	(gr_line
		(start 370.025676 -296.427906)
		(end 369.979956 -296.382186)
		(stroke
			(width 0.05715)
			(type default)
		)
		(layer "In4.Cu")
	)
	(gr_arc
		(start 370.033296 -295.4909)
		(mid 370.02563 -295.496297)
		(end 370.018056 -295.501822)
		(stroke
			(width 0.05715)
			(type default)
		)
		(layer "In4.Cu")
	)
	(gr_arc
		(start 370.033296 -295.4909)
		(mid 370.033677 -295.490646)
		(end 370.034058 -295.490392)
		(stroke
			(width 0.05715)
			(type default)
		)
		(layer "In4.Cu")
	)
	(gr_line
		(start 370.034058 -295.490392)
		(end 370.040662 -295.486582)
		(stroke
			(width 0.05715)
			(type default)
		)
		(layer "In4.Cu")
	)
	(gr_line
		(start 370.035328 -292.24986)
		(end 370.038122 -292.248336)
		(stroke
			(width 0.05715)
			(type default)
		)
		(layer "In4.Cu")
	)
	(gr_line
		(start 370.038884 -292.247828)
		(end 370.041678 -292.246304)
		(stroke
			(width 0.05715)
			(type default)
		)
		(layer "In4.Cu")
	)
	(gr_line
		(start 370.054886 -236.384084)
		(end 370.352828 -236.384084)
		(stroke
			(width 0.05715)
			(type default)
		)
		(layer "In4.Cu")
	)
	(gr_line
		(start 370.054886 -234.764072)
		(end 370.352828 -234.764072)
		(stroke
			(width 0.05715)
			(type default)
		)
		(layer "In4.Cu")
	)
	(gr_line
		(start 370.054886 -233.14406)
		(end 370.352828 -233.14406)
		(stroke
			(width 0.05715)
			(type default)
		)
		(layer "In4.Cu")
	)
	(gr_line
		(start 370.054886 -231.524048)
		(end 370.352828 -231.524048)
		(stroke
			(width 0.05715)
			(type default)
		)
		(layer "In4.Cu")
	)
	(gr_line
		(start 370.05768 -291.574728)
		(end 370.05641 -291.573712)
		(stroke
			(width 0.05715)
			(type default)
		)
		(layer "In4.Cu")
	)
	(gr_line
		(start 370.059966 -292.23462)
		(end 370.062252 -292.233096)
		(stroke
			(width 0.05715)
			(type default)
		)
		(layer "In4.Cu")
	)
	(gr_line
		(start 370.061236 -291.57676)
		(end 370.058442 -291.575236)
		(stroke
			(width 0.05715)
			(type default)
		)
		(layer "In4.Cu")
	)
	(gr_line
		(start 370.062252 -292.233096)
		(end 370.06784 -292.229794)
		(stroke
			(width 0.05715)
			(type default)
		)
		(layer "In4.Cu")
	)
	(gr_line
		(start 370.063522 -291.578284)
		(end 370.061998 -291.577268)
		(stroke
			(width 0.05715)
			(type default)
		)
		(layer "In4.Cu")
	)
	(gr_line
		(start 370.064792 -291.579046)
		(end 370.063522 -291.578284)
		(stroke
			(width 0.05715)
			(type default)
		)
		(layer "In4.Cu")
	)
	(gr_line
		(start 370.06784 -292.229794)
		(end 370.080794 -292.223698)
		(stroke
			(width 0.05715)
			(type default)
		)
		(layer "In4.Cu")
	)
	(gr_line
		(start 370.06911 -293.850314)
		(end 370.070888 -293.849044)
		(stroke
			(width 0.05715)
			(type default)
		)
		(layer "In4.Cu")
	)
	(gr_line
		(start 370.069364 -288.98977)
		(end 370.069618 -288.98977)
		(stroke
			(width 0.05715)
			(type default)
		)
		(layer "In4.Cu")
	)
	(gr_line
		(start 370.070888 -294.82288)
		(end 370.068856 -294.82161)
		(stroke
			(width 0.05715)
			(type default)
		)
		(layer "In4.Cu")
	)
	(gr_line
		(start 370.070888 -293.849044)
		(end 370.071904 -293.848536)
		(stroke
			(width 0.05715)
			(type default)
		)
		(layer "In4.Cu")
	)
	(gr_line
		(start 370.070888 -293.202868)
		(end 370.069872 -293.20236)
		(stroke
			(width 0.05715)
			(type default)
		)
		(layer "In4.Cu")
	)
	(gr_line
		(start 370.071396 -294.823134)
		(end 370.070888 -294.82288)
		(stroke
			(width 0.05715)
			(type default)
		)
		(layer "In4.Cu")
	)
	(gr_line
		(start 370.071904 -293.848536)
		(end 370.072666 -293.848028)
		(stroke
			(width 0.05715)
			(type default)
		)
		(layer "In4.Cu")
	)
	(gr_line
		(start 370.071904 -293.203376)
		(end 370.070888 -293.202868)
		(stroke
			(width 0.05715)
			(type default)
		)
		(layer "In4.Cu")
	)
	(gr_line
		(start 370.073936 -294.824658)
		(end 370.073174 -294.82415)
		(stroke
			(width 0.05715)
			(type default)
		)
		(layer "In4.Cu")
	)
	(gr_line
		(start 370.079524 -293.208456)
		(end 370.071904 -293.203376)
		(stroke
			(width 0.05715)
			(type default)
		)
		(layer "In4.Cu")
	)
	(gr_line
		(start 370.082064 -293.20998)
		(end 370.080794 -293.209218)
		(stroke
			(width 0.05715)
			(type default)
		)
		(layer "In4.Cu")
	)
	(gr_line
		(start 370.084096 -293.210996)
		(end 370.08308 -293.210488)
		(stroke
			(width 0.05715)
			(type default)
		)
		(layer "In4.Cu")
	)
	(gr_line
		(start 370.08562 -293.839646)
		(end 370.087906 -293.838122)
		(stroke
			(width 0.05715)
			(type default)
		)
		(layer "In4.Cu")
	)
	(gr_line
		(start 370.087906 -293.838122)
		(end 370.09451 -293.834312)
		(stroke
			(width 0.05715)
			(type default)
		)
		(layer "In4.Cu")
	)
	(gr_line
		(start 370.091462 -376.426222)
		(end 370.091716 -376.426476)
		(stroke
			(width 0.07112)
			(type default)
		)
		(layer "In4.Cu")
	)
	(gr_line
		(start 370.09578 -387.180074)
		(end 370.09578 -386.987796)
		(stroke
			(width 0.07112)
			(type default)
		)
		(layer "In4.Cu")
	)
	(gr_line
		(start 370.118132 -385.238752)
		(end 370.118132 -385.046474)
		(stroke
			(width 0.07112)
			(type default)
		)
		(layer "In4.Cu")
	)
	(gr_line
		(start 370.145564 -292.406324)
		(end 370.148358 -292.404546)
		(stroke
			(width 0.05715)
			(type default)
		)
		(layer "In4.Cu")
	)
	(gr_line
		(start 370.148358 -292.404546)
		(end 370.15293 -292.401752)
		(stroke
			(width 0.05715)
			(type default)
		)
		(layer "In4.Cu")
	)
	(gr_line
		(start 370.154962 -294.021764)
		(end 370.160804 -294.018462)
		(stroke
			(width 0.05715)
			(type default)
		)
		(layer "In4.Cu")
	)
	(gr_line
		(start 370.160804 -294.018462)
		(end 370.1669 -294.014398)
		(stroke
			(width 0.05715)
			(type default)
		)
		(layer "In4.Cu")
	)
	(gr_line
		(start 370.165376 -294.657018)
		(end 370.165376 -294.657272)
		(stroke
			(width 0.05715)
			(type default)
		)
		(layer "In4.Cu")
	)
	(gr_line
		(start 370.165884 -289.154108)
		(end 370.167662 -289.153092)
		(stroke
			(width 0.05715)
			(type default)
		)
		(layer "In4.Cu")
	)
	(gr_line
		(start 370.166138 -294.657526)
		(end 370.165376 -294.657018)
		(stroke
			(width 0.05715)
			(type default)
		)
		(layer "In4.Cu")
	)
	(gr_line
		(start 370.166646 -293.037768)
		(end 370.16563 -293.03726)
		(stroke
			(width 0.05715)
			(type default)
		)
		(layer "In4.Cu")
	)
	(gr_line
		(start 370.1669 -294.014398)
		(end 370.168424 -294.013382)
		(stroke
			(width 0.05715)
			(type default)
		)
		(layer "In4.Cu")
	)
	(gr_line
		(start 370.1669 -292.393878)
		(end 370.16944 -292.392608)
		(stroke
			(width 0.05715)
			(type default)
		)
		(layer "In4.Cu")
	)
	(gr_line
		(start 370.167154 -291.41801)
		(end 370.166646 -291.417756)
		(stroke
			(width 0.05715)
			(type default)
		)
		(layer "In4.Cu")
	)
	(gr_line
		(start 370.167916 -294.658542)
		(end 370.166138 -294.657526)
		(stroke
			(width 0.05715)
			(type default)
		)
		(layer "In4.Cu")
	)
	(gr_line
		(start 370.167916 -293.03853)
		(end 370.166646 -293.037768)
		(stroke
			(width 0.05715)
			(type default)
		)
		(layer "In4.Cu")
	)
	(gr_line
		(start 370.167916 -291.418518)
		(end 370.167154 -291.41801)
		(stroke
			(width 0.05715)
			(type default)
		)
		(layer "In4.Cu")
	)
	(gr_line
		(start 370.168932 -294.65905)
		(end 370.167916 -294.658542)
		(stroke
			(width 0.05715)
			(type default)
		)
		(layer "In4.Cu")
	)
	(gr_line
		(start 370.168932 -294.013128)
		(end 370.168932 -294.012874)
		(stroke
			(width 0.05715)
			(type default)
		)
		(layer "In4.Cu")
	)
	(gr_line
		(start 370.168932 -293.039038)
		(end 370.167916 -293.03853)
		(stroke
			(width 0.05715)
			(type default)
		)
		(layer "In4.Cu")
	)
	(gr_line
		(start 370.168932 -291.419026)
		(end 370.167916 -291.418518)
		(stroke
			(width 0.05715)
			(type default)
		)
		(layer "In4.Cu")
	)
	(gr_line
		(start 370.170456 -293.040054)
		(end 370.168932 -293.039038)
		(stroke
			(width 0.05715)
			(type default)
		)
		(layer "In4.Cu")
	)
	(gr_line
		(start 370.17071 -293.0398)
		(end 370.170456 -293.040054)
		(stroke
			(width 0.05715)
			(type default)
		)
		(layer "In4.Cu")
	)
	(gr_line
		(start 370.17071 -291.420042)
		(end 370.168932 -291.419026)
		(stroke
			(width 0.05715)
			(type default)
		)
		(layer "In4.Cu")
	)
	(gr_line
		(start 370.17325 -291.421566)
		(end 370.172234 -291.421058)
		(stroke
			(width 0.05715)
			(type default)
		)
		(layer "In4.Cu")
	)
	(gr_line
		(start 370.17452 -293.042594)
		(end 370.17071 -293.0398)
		(stroke
			(width 0.05715)
			(type default)
		)
		(layer "In4.Cu")
	)
	(gr_line
		(start 370.175282 -291.422836)
		(end 370.17325 -291.421566)
		(stroke
			(width 0.05715)
			(type default)
		)
		(layer "In4.Cu")
	)
	(gr_line
		(start 370.175282 -291.422582)
		(end 370.175282 -291.422836)
		(stroke
			(width 0.05715)
			(type default)
		)
		(layer "In4.Cu")
	)
	(gr_arc
		(start 370.177314 -289.147758)
		(mid 370.179094 -289.146745)
		(end 370.18087 -289.145726)
		(stroke
			(width 0.05715)
			(type default)
		)
		(layer "In4.Cu")
	)
	(gr_line
		(start 370.177822 -291.42436)
		(end 370.17706 -291.423852)
		(stroke
			(width 0.05715)
			(type default)
		)
		(layer "In4.Cu")
	)
	(gr_line
		(start 370.178584 -294.006778)
		(end 370.181886 -294.004492)
		(stroke
			(width 0.05715)
			(type default)
		)
		(layer "In4.Cu")
	)
	(gr_line
		(start 370.179854 -291.42563)
		(end 370.178584 -291.424868)
		(stroke
			(width 0.05715)
			(type default)
		)
		(layer "In4.Cu")
	)
	(gr_line
		(start 370.233194 -225.371914)
		(end 370.235226 -225.370644)
		(stroke
			(width 0.05715)
			(type default)
		)
		(layer "In4.Cu")
	)
	(gr_line
		(start 370.236242 -225.370136)
		(end 370.238274 -225.368866)
		(stroke
			(width 0.05715)
			(type default)
		)
		(layer "In4.Cu")
	)
	(gr_line
		(start 370.237512 -236.058964)
		(end 370.234464 -236.057186)
		(stroke
			(width 0.05715)
			(type default)
		)
		(layer "In4.Cu")
	)
	(gr_line
		(start 370.238274 -225.368866)
		(end 370.23929 -225.368358)
		(stroke
			(width 0.05715)
			(type default)
		)
		(layer "In4.Cu")
	)
	(gr_line
		(start 370.23929 -236.05998)
		(end 370.238274 -236.059472)
		(stroke
			(width 0.05715)
			(type default)
		)
		(layer "In4.Cu")
	)
	(gr_line
		(start 370.23929 -225.368358)
		(end 370.240814 -225.367342)
		(stroke
			(width 0.05715)
			(type default)
		)
		(layer "In4.Cu")
	)
	(gr_line
		(start 370.240814 -236.060996)
		(end 370.23929 -236.05998)
		(stroke
			(width 0.05715)
			(type default)
		)
		(layer "In4.Cu")
	)
	(gr_line
		(start 370.24183 -236.061504)
		(end 370.240814 -236.060996)
		(stroke
			(width 0.05715)
			(type default)
		)
		(layer "In4.Cu")
	)
	(gr_line
		(start 370.24564 -225.364548)
		(end 370.246148 -225.364294)
		(stroke
			(width 0.05715)
			(type default)
		)
		(layer "In4.Cu")
	)
	(gr_line
		(start 370.246148 -236.064044)
		(end 370.245386 -236.063536)
		(stroke
			(width 0.05715)
			(type default)
		)
		(layer "In4.Cu")
	)
	(gr_line
		(start 370.25453 -333.92745)
		(end 370.266976 -333.963518)
		(stroke
			(width 0.07112)
			(type default)
		)
		(layer "In4.Cu")
	)
	(gr_line
		(start 370.259864 -295.146222)
		(end 370.259864 -295.145968)
		(stroke
			(width 0.05715)
			(type default)
		)
		(layer "In4.Cu")
	)
	(gr_line
		(start 370.266976 -333.963518)
		(end 370.273326 -333.99857)
		(stroke
			(width 0.07112)
			(type default)
		)
		(layer "In4.Cu")
	)
	(gr_line
		(start 370.334794 -235.89488)
		(end 370.33708 -235.89615)
		(stroke
			(width 0.05715)
			(type default)
		)
		(layer "In4.Cu")
	)
	(gr_line
		(start 370.33708 -235.89615)
		(end 370.337842 -235.896658)
		(stroke
			(width 0.05715)
			(type default)
		)
		(layer "In4.Cu")
	)
	(gr_line
		(start 370.33708 -225.532188)
		(end 370.334286 -225.533712)
		(stroke
			(width 0.05715)
			(type default)
		)
		(layer "In4.Cu")
	)
	(gr_line
		(start 370.337842 -235.896658)
		(end 370.338858 -235.897166)
		(stroke
			(width 0.05715)
			(type default)
		)
		(layer "In4.Cu")
	)
	(gr_line
		(start 370.337842 -225.53168)
		(end 370.33708 -225.532188)
		(stroke
			(width 0.05715)
			(type default)
		)
		(layer "In4.Cu")
	)
	(gr_line
		(start 370.338858 -235.897166)
		(end 370.340382 -235.898182)
		(stroke
			(width 0.05715)
			(type default)
		)
		(layer "In4.Cu")
	)
	(gr_line
		(start 370.338858 -225.531172)
		(end 370.337842 -225.53168)
		(stroke
			(width 0.05715)
			(type default)
		)
		(layer "In4.Cu")
	)
	(gr_line
		(start 370.34089 -225.529902)
		(end 370.338858 -225.531172)
		(stroke
			(width 0.05715)
			(type default)
		)
		(layer "In4.Cu")
	)
	(gr_line
		(start 370.34216 -235.899198)
		(end 370.34343 -235.89996)
		(stroke
			(width 0.05715)
			(type default)
		)
		(layer "In4.Cu")
	)
	(gr_line
		(start 370.34343 -235.89996)
		(end 370.344192 -235.900468)
		(stroke
			(width 0.05715)
			(type default)
		)
		(layer "In4.Cu")
	)
	(gr_arc
		(start 370.351304 -348.027752)
		(mid 370.351817 -348.025467)
		(end 370.35232 -348.02318)
		(stroke
			(width 0.07112)
			(type default)
		)
		(layer "In4.Cu")
	)
	(gr_line
		(start 370.352828 -236.384084)
		(end 370.42217 -236.314742)
		(stroke
			(width 0.05715)
			(type default)
		)
		(layer "In4.Cu")
	)
	(gr_line
		(start 370.352828 -234.764072)
		(end 370.435632 -234.681268)
		(stroke
			(width 0.05715)
			(type default)
		)
		(layer "In4.Cu")
	)
	(gr_line
		(start 370.352828 -233.14406)
		(end 370.435632 -233.061256)
		(stroke
			(width 0.05715)
			(type default)
		)
		(layer "In4.Cu")
	)
	(gr_line
		(start 370.352828 -231.524048)
		(end 370.42217 -231.454706)
		(stroke
			(width 0.05715)
			(type default)
		)
		(layer "In4.Cu")
	)
	(gr_line
		(start 370.36502 -338.34578)
		(end 370.36502 -338.346288)
		(stroke
			(width 0.07112)
			(type default)
		)
		(layer "In4.Cu")
	)
	(gr_line
		(start 370.369338 -225.513392)
		(end 370.36883 -225.513646)
		(stroke
			(width 0.05715)
			(type default)
		)
		(layer "In4.Cu")
	)
	(gr_line
		(start 370.3701 -225.512884)
		(end 370.369338 -225.513392)
		(stroke
			(width 0.05715)
			(type default)
		)
		(layer "In4.Cu")
	)
	(gr_line
		(start 370.376958 -225.50882)
		(end 370.3701 -225.512884)
		(stroke
			(width 0.05715)
			(type default)
		)
		(layer "In4.Cu")
	)
	(gr_arc
		(start 370.376958 -225.50882)
		(mid 370.380907 -225.506043)
		(end 370.384832 -225.503232)
		(stroke
			(width 0.05715)
			(type default)
		)
		(layer "In4.Cu")
	)
	(gr_line
		(start 370.397786 -387.48208)
		(end 370.09578 -387.180074)
		(stroke
			(width 0.07112)
			(type default)
		)
		(layer "In4.Cu")
	)
	(gr_line
		(start 370.420138 -385.540758)
		(end 370.118132 -385.238752)
		(stroke
			(width 0.07112)
			(type default)
		)
		(layer "In4.Cu")
	)
	(gr_arc
		(start 370.439442 -234.658408)
		(mid 370.437421 -234.669819)
		(end 370.435632 -234.681268)
		(stroke
			(width 0.05715)
			(type default)
		)
		(layer "In4.Cu")
	)
	(gr_arc
		(start 370.439442 -233.038396)
		(mid 370.437421 -233.049807)
		(end 370.435632 -233.061256)
		(stroke
			(width 0.05715)
			(type default)
		)
		(layer "In4.Cu")
	)
	(gr_arc
		(start 370.45011 -288.682176)
		(mid 370.450256 -288.677605)
		(end 370.450364 -288.673032)
		(stroke
			(width 0.05715)
			(type default)
		)
		(layer "In4.Cu")
	)
	(gr_line
		(start 370.450364 -295.146476)
		(end 370.450364 -295.145968)
		(stroke
			(width 0.05715)
			(type default)
		)
		(layer "In4.Cu")
	)
	(gr_line
		(start 370.450364 -288.66592)
		(end 370.45011 -288.66592)
		(stroke
			(width 0.05715)
			(type default)
		)
		(layer "In4.Cu")
	)
	(gr_line
		(start 370.460524 -221.128844)
		(end 370.414804 -221.083124)
		(stroke
			(width 0.05715)
			(type default)
		)
		(layer "In4.Cu")
	)
	(gr_arc
		(start 370.53266 -333.872586)
		(mid 370.527398 -333.854745)
		(end 370.521738 -333.837026)
		(stroke
			(width 0.07112)
			(type default)
		)
		(layer "In4.Cu")
	)
	(gr_arc
		(start 370.543582 -333.913734)
		(mid 370.538384 -333.89309)
		(end 370.53266 -333.872586)
		(stroke
			(width 0.07112)
			(type default)
		)
		(layer "In4.Cu")
	)
	(gr_arc
		(start 370.55044 -333.947262)
		(mid 370.547183 -333.930463)
		(end 370.543582 -333.913734)
		(stroke
			(width 0.07112)
			(type default)
		)
		(layer "In4.Cu")
	)
	(gr_line
		(start 370.590064 -387.48208)
		(end 370.397786 -387.48208)
		(stroke
			(width 0.07112)
			(type default)
		)
		(layer "In4.Cu")
	)
	(gr_line
		(start 370.612416 -385.540758)
		(end 370.420138 -385.540758)
		(stroke
			(width 0.07112)
			(type default)
		)
		(layer "In4.Cu")
	)
	(gr_arc
		(start 370.614194 -236.30128)
		(mid 370.612403 -236.289958)
		(end 370.610384 -236.278674)
		(stroke
			(width 0.05715)
			(type default)
		)
		(layer "In4.Cu")
	)
	(gr_line
		(start 370.614194 -236.30128)
		(end 370.696998 -236.384084)
		(stroke
			(width 0.05715)
			(type default)
		)
		(layer "In4.Cu")
	)
	(gr_arc
		(start 370.614194 -231.441244)
		(mid 370.612408 -231.429794)
		(end 370.610384 -231.418384)
		(stroke
			(width 0.05715)
			(type default)
		)
		(layer "In4.Cu")
	)
	(gr_line
		(start 370.614194 -231.441244)
		(end 370.696998 -231.524048)
		(stroke
			(width 0.05715)
			(type default)
		)
		(layer "In4.Cu")
	)
	(gr_line
		(start 370.627656 -234.69473)
		(end 370.696998 -234.764072)
		(stroke
			(width 0.05715)
			(type default)
		)
		(layer "In4.Cu")
	)
	(gr_line
		(start 370.627656 -233.074718)
		(end 370.696998 -233.14406)
		(stroke
			(width 0.05715)
			(type default)
		)
		(layer "In4.Cu")
	)
	(gr_line
		(start 370.652802 -291.095938)
		(end 370.35486 -291.095938)
		(stroke
			(width 0.05715)
			(type default)
		)
		(layer "In4.Cu")
	)
	(gr_line
		(start 370.652802 -289.475926)
		(end 370.35486 -289.475926)
		(stroke
			(width 0.05715)
			(type default)
		)
		(layer "In4.Cu")
	)
	(gr_line
		(start 370.652802 -287.856168)
		(end 370.35486 -287.856168)
		(stroke
			(width 0.05715)
			(type default)
		)
		(layer "In4.Cu")
	)
	(gr_arc
		(start 370.671344 -224.580704)
		(mid 370.668926 -224.582476)
		(end 370.666518 -224.58426)
		(stroke
			(width 0.05715)
			(type default)
		)
		(layer "In4.Cu")
	)
	(gr_line
		(start 370.672868 -310.586374)
		(end 370.673122 -310.586374)
		(stroke
			(width 0.07112)
			(type default)
		)
		(layer "In4.Cu")
	)
	(gr_line
		(start 370.684044 -296.489374)
		(end 370.684044 -296.460926)
		(stroke
			(width 0.05715)
			(type default)
		)
		(layer "In4.Cu")
	)
	(gr_line
		(start 370.684044 -296.460926)
		(end 370.729764 -296.415206)
		(stroke
			(width 0.05715)
			(type default)
		)
		(layer "In4.Cu")
	)
	(gr_line
		(start 370.696744 -221.083124)
		(end 370.651024 -221.128844)
		(stroke
			(width 0.05715)
			(type default)
		)
		(layer "In4.Cu")
	)
	(gr_line
		(start 370.696998 -236.384084)
		(end 370.994686 -236.384084)
		(stroke
			(width 0.05715)
			(type default)
		)
		(layer "In4.Cu")
	)
	(gr_line
		(start 370.696998 -234.764072)
		(end 370.994686 -234.764072)
		(stroke
			(width 0.05715)
			(type default)
		)
		(layer "In4.Cu")
	)
	(gr_line
		(start 370.696998 -233.14406)
		(end 370.994686 -233.14406)
		(stroke
			(width 0.05715)
			(type default)
		)
		(layer "In4.Cu")
	)
	(gr_line
		(start 370.696998 -231.524048)
		(end 370.994686 -231.524048)
		(stroke
			(width 0.05715)
			(type default)
		)
		(layer "In4.Cu")
	)
	(gr_line
		(start 370.710968 -234.277154)
		(end 370.711984 -234.276646)
		(stroke
			(width 0.05715)
			(type default)
		)
		(layer "In4.Cu")
	)
	(gr_line
		(start 370.710968 -232.657142)
		(end 370.711984 -232.656634)
		(stroke
			(width 0.05715)
			(type default)
		)
		(layer "In4.Cu")
	)
	(gr_line
		(start 370.710968 -227.79736)
		(end 370.711984 -227.796852)
		(stroke
			(width 0.05715)
			(type default)
		)
		(layer "In4.Cu")
	)
	(gr_line
		(start 370.710968 -226.177348)
		(end 370.711984 -226.17684)
		(stroke
			(width 0.05715)
			(type default)
		)
		(layer "In4.Cu")
	)
	(gr_line
		(start 370.711984 -234.276646)
		(end 370.712492 -234.276646)
		(stroke
			(width 0.05715)
			(type default)
		)
		(layer "In4.Cu")
	)
	(gr_line
		(start 370.711984 -232.656634)
		(end 370.712746 -232.656126)
		(stroke
			(width 0.05715)
			(type default)
		)
		(layer "In4.Cu")
	)
	(gr_line
		(start 370.711984 -228.771704)
		(end 370.710968 -228.771196)
		(stroke
			(width 0.05715)
			(type default)
		)
		(layer "In4.Cu")
	)
	(gr_line
		(start 370.711984 -227.151692)
		(end 370.710968 -227.151184)
		(stroke
			(width 0.05715)
			(type default)
		)
		(layer "In4.Cu")
	)
	(gr_line
		(start 370.711984 -226.17684)
		(end 370.712746 -226.176332)
		(stroke
			(width 0.05715)
			(type default)
		)
		(layer "In4.Cu")
	)
	(gr_line
		(start 370.712746 -232.656126)
		(end 370.71681 -232.65384)
		(stroke
			(width 0.05715)
			(type default)
		)
		(layer "In4.Cu")
	)
	(gr_line
		(start 370.712746 -226.176332)
		(end 370.71554 -226.174808)
		(stroke
			(width 0.05715)
			(type default)
		)
		(layer "In4.Cu")
	)
	(gr_line
		(start 370.716048 -230.396796)
		(end 370.71173 -230.394256)
		(stroke
			(width 0.05715)
			(type default)
		)
		(layer "In4.Cu")
	)
	(gr_line
		(start 370.722144 -287.92551)
		(end 370.652802 -287.856168)
		(stroke
			(width 0.05715)
			(type default)
		)
		(layer "In4.Cu")
	)
	(gr_line
		(start 370.735606 -291.178742)
		(end 370.652802 -291.095938)
		(stroke
			(width 0.05715)
			(type default)
		)
		(layer "In4.Cu")
	)
	(gr_line
		(start 370.735606 -289.55873)
		(end 370.652802 -289.475926)
		(stroke
			(width 0.05715)
			(type default)
		)
		(layer "In4.Cu")
	)
	(gr_arc
		(start 370.735606 -289.55873)
		(mid 370.737397 -289.570052)
		(end 370.739416 -289.581336)
		(stroke
			(width 0.05715)
			(type default)
		)
		(layer "In4.Cu")
	)
	(gr_line
		(start 370.73586 -291.178742)
		(end 370.735606 -291.178742)
		(stroke
			(width 0.05715)
			(type default)
		)
		(layer "In4.Cu")
	)
	(gr_arc
		(start 370.73586 -291.178742)
		(mid 370.737651 -291.189937)
		(end 370.73967 -291.201094)
		(stroke
			(width 0.05715)
			(type default)
		)
		(layer "In4.Cu")
	)
	(gr_line
		(start 370.7765 -229.599744)
		(end 370.776246 -229.599998)
		(stroke
			(width 0.05715)
			(type default)
		)
		(layer "In4.Cu")
	)
	(gr_line
		(start 370.791232 -387.28269)
		(end 370.29517 -386.786628)
		(stroke
			(width 0.07112)
			(type default)
		)
		(layer "In4.Cu")
	)
	(gr_line
		(start 370.805964 -228.605588)
		(end 370.807234 -228.60635)
		(stroke
			(width 0.05715)
			(type default)
		)
		(layer "In4.Cu")
	)
	(gr_line
		(start 370.805964 -226.985576)
		(end 370.807234 -226.986338)
		(stroke
			(width 0.05715)
			(type default)
		)
		(layer "In4.Cu")
	)
	(gr_line
		(start 370.807234 -234.442)
		(end 370.805964 -234.442762)
		(stroke
			(width 0.05715)
			(type default)
		)
		(layer "In4.Cu")
	)
	(gr_line
		(start 370.807234 -228.60635)
		(end 370.807996 -228.606858)
		(stroke
			(width 0.05715)
			(type default)
		)
		(layer "In4.Cu")
	)
	(gr_line
		(start 370.807234 -227.962206)
		(end 370.805964 -227.962968)
		(stroke
			(width 0.05715)
			(type default)
		)
		(layer "In4.Cu")
	)
	(gr_line
		(start 370.807234 -226.986338)
		(end 370.807996 -226.986846)
		(stroke
			(width 0.05715)
			(type default)
		)
		(layer "In4.Cu")
	)
	(gr_line
		(start 370.807234 -226.342194)
		(end 370.805964 -226.342956)
		(stroke
			(width 0.05715)
			(type default)
		)
		(layer "In4.Cu")
	)
	(gr_line
		(start 370.807742 -227.961952)
		(end 370.807234 -227.962206)
		(stroke
			(width 0.05715)
			(type default)
		)
		(layer "In4.Cu")
	)
	(gr_line
		(start 370.807996 -234.441492)
		(end 370.807234 -234.442)
		(stroke
			(width 0.05715)
			(type default)
		)
		(layer "In4.Cu")
	)
	(gr_line
		(start 370.807996 -226.341686)
		(end 370.807234 -226.342194)
		(stroke
			(width 0.05715)
			(type default)
		)
		(layer "In4.Cu")
	)
	(gr_line
		(start 370.813584 -385.341368)
		(end 370.317522 -384.845306)
		(stroke
			(width 0.07112)
			(type default)
		)
		(layer "In4.Cu")
	)
	(gr_line
		(start 370.891308 -393.69238)
		(end 371.244622 -393.787376)
		(stroke
			(width 0.07112)
			(type default)
		)
		(layer "In4.Cu")
	)
	(gr_arc
		(start 370.89842 -389.55726)
		(mid 370.898801 -389.557641)
		(end 370.899182 -389.558022)
		(stroke
			(width 0.07112)
			(type default)
		)
		(layer "In4.Cu")
	)
	(gr_arc
		(start 370.910358 -287.961832)
		(mid 370.91238 -287.950421)
		(end 370.914168 -287.938972)
		(stroke
			(width 0.05715)
			(type default)
		)
		(layer "In4.Cu")
	)
	(gr_line
		(start 370.914168 -287.938972)
		(end 370.996972 -287.856168)
		(stroke
			(width 0.05715)
			(type default)
		)
		(layer "In4.Cu")
	)
	(gr_line
		(start 370.915692 -386.036312)
		(end 370.915692 -385.844034)
		(stroke
			(width 0.07112)
			(type default)
		)
		(layer "In4.Cu")
	)
	(gr_line
		(start 370.92763 -289.545268)
		(end 370.996972 -289.475926)
		(stroke
			(width 0.05715)
			(type default)
		)
		(layer "In4.Cu")
	)
	(gr_line
		(start 370.927884 -291.165026)
		(end 370.996972 -291.095938)
		(stroke
			(width 0.05715)
			(type default)
		)
		(layer "In4.Cu")
	)
	(gr_line
		(start 370.961412 -384.184652)
		(end 370.961412 -383.992374)
		(stroke
			(width 0.07112)
			(type default)
		)
		(layer "In4.Cu")
	)
	(gr_arc
		(start 370.964714 -289.934904)
		(mid 370.968766 -289.937716)
		(end 370.972842 -289.940492)
		(stroke
			(width 0.05715)
			(type default)
		)
		(layer "In4.Cu")
	)
	(gr_line
		(start 370.965984 -296.489374)
		(end 370.965984 -296.460926)
		(stroke
			(width 0.05715)
			(type default)
		)
		(layer "In4.Cu")
	)
	(gr_line
		(start 370.965984 -296.460926)
		(end 370.920264 -296.415206)
		(stroke
			(width 0.05715)
			(type default)
		)
		(layer "In4.Cu")
	)
	(gr_arc
		(start 370.973604 -289.941)
		(mid 370.973223 -289.940746)
		(end 370.972842 -289.940492)
		(stroke
			(width 0.05715)
			(type default)
		)
		(layer "In4.Cu")
	)
	(gr_line
		(start 370.980716 -289.945064)
		(end 370.973604 -289.941)
		(stroke
			(width 0.05715)
			(type default)
		)
		(layer "In4.Cu")
	)
	(gr_line
		(start 370.996972 -291.095938)
		(end 371.294914 -291.095938)
		(stroke
			(width 0.05715)
			(type default)
		)
		(layer "In4.Cu")
	)
	(gr_line
		(start 370.996972 -289.475926)
		(end 371.294914 -289.475926)
		(stroke
			(width 0.05715)
			(type default)
		)
		(layer "In4.Cu")
	)
	(gr_line
		(start 370.996972 -287.856168)
		(end 371.294914 -287.856168)
		(stroke
			(width 0.05715)
			(type default)
		)
		(layer "In4.Cu")
	)
	(gr_line
		(start 371.006116 -293.852092)
		(end 371.01272 -293.848282)
		(stroke
			(width 0.05715)
			(type default)
		)
		(layer "In4.Cu")
	)
	(gr_line
		(start 371.011958 -295.468548)
		(end 371.012466 -295.468294)
		(stroke
			(width 0.05715)
			(type default)
		)
		(layer "In4.Cu")
	)
	(gr_line
		(start 371.012466 -289.963606)
		(end 371.011704 -289.963098)
		(stroke
			(width 0.05715)
			(type default)
		)
		(layer "In4.Cu")
	)
	(gr_line
		(start 371.01526 -289.96513)
		(end 371.012466 -289.963606)
		(stroke
			(width 0.05715)
			(type default)
		)
		(layer "In4.Cu")
	)
	(gr_arc
		(start 371.09019 -229.094284)
		(mid 371.0902 -229.090982)
		(end 371.09019 -229.08768)
		(stroke
			(width 0.05715)
			(type default)
		)
		(layer "In4.Cu")
	)
	(gr_line
		(start 371.09019 -225.85426)
		(end 371.09019 -225.861372)
		(stroke
			(width 0.05715)
			(type default)
		)
		(layer "In4.Cu")
	)
	(gr_line
		(start 371.105684 -295.634664)
		(end 371.107208 -295.633902)
		(stroke
			(width 0.05715)
			(type default)
		)
		(layer "In4.Cu")
	)
	(gr_line
		(start 371.10797 -294.658542)
		(end 371.107462 -294.658288)
		(stroke
			(width 0.05715)
			(type default)
		)
		(layer "In4.Cu")
	)
	(gr_line
		(start 371.10797 -293.03853)
		(end 371.107462 -293.038276)
		(stroke
			(width 0.05715)
			(type default)
		)
		(layer "In4.Cu")
	)
	(gr_line
		(start 371.10797 -291.418518)
		(end 371.107462 -291.418264)
		(stroke
			(width 0.05715)
			(type default)
		)
		(layer "In4.Cu")
	)
	(gr_line
		(start 371.10797 -289.798506)
		(end 371.106954 -289.797998)
		(stroke
			(width 0.05715)
			(type default)
		)
		(layer "In4.Cu")
	)
	(gr_line
		(start 371.108478 -294.658542)
		(end 371.10797 -294.658542)
		(stroke
			(width 0.05715)
			(type default)
		)
		(layer "In4.Cu")
	)
	(gr_line
		(start 371.108478 -293.03853)
		(end 371.10797 -293.03853)
		(stroke
			(width 0.05715)
			(type default)
		)
		(layer "In4.Cu")
	)
	(gr_line
		(start 371.110764 -289.800284)
		(end 371.10797 -289.798506)
		(stroke
			(width 0.05715)
			(type default)
		)
		(layer "In4.Cu")
	)
	(gr_arc
		(start 371.118892 -295.627298)
		(mid 371.121818 -295.625528)
		(end 371.124734 -295.623742)
		(stroke
			(width 0.05715)
			(type default)
		)
		(layer "In4.Cu")
	)
	(gr_arc
		(start 371.1194 -294.006778)
		(mid 371.122071 -294.005261)
		(end 371.124734 -294.00373)
		(stroke
			(width 0.05715)
			(type default)
		)
		(layer "In4.Cu")
	)
	(gr_arc
		(start 371.12575 -294.668956)
		(mid 371.122708 -294.667041)
		(end 371.119654 -294.665146)
		(stroke
			(width 0.05715)
			(type default)
		)
		(layer "In4.Cu")
	)
	(gr_arc
		(start 371.12575 -293.048944)
		(mid 371.122708 -293.047029)
		(end 371.119654 -293.045134)
		(stroke
			(width 0.05715)
			(type default)
		)
		(layer "In4.Cu")
	)
	(gr_line
		(start 371.134894 -233.495088)
		(end 371.135148 -233.495342)
		(stroke
			(width 0.05715)
			(type default)
		)
		(layer "In4.Cu")
	)
	(gr_line
		(start 371.162834 -321.837558)
		(end 371.178582 -321.868038)
		(stroke
			(width 0.07112)
			(type default)
		)
		(layer "In4.Cu")
	)
	(gr_line
		(start 371.177058 -225.369374)
		(end 371.178074 -225.368866)
		(stroke
			(width 0.05715)
			(type default)
		)
		(layer "In4.Cu")
	)
	(gr_line
		(start 371.178074 -225.368866)
		(end 371.18036 -225.367596)
		(stroke
			(width 0.05715)
			(type default)
		)
		(layer "In4.Cu")
	)
	(gr_line
		(start 371.178582 -321.868038)
		(end 371.190266 -321.902582)
		(stroke
			(width 0.07112)
			(type default)
		)
		(layer "In4.Cu")
	)
	(gr_line
		(start 371.18036 -225.367596)
		(end 371.181376 -225.367088)
		(stroke
			(width 0.05715)
			(type default)
		)
		(layer "In4.Cu")
	)
	(gr_arc
		(start 371.181122 -233.465116)
		(mid 371.167284 -233.473429)
		(end 371.15369 -233.482134)
		(stroke
			(width 0.05715)
			(type default)
		)
		(layer "In4.Cu")
	)
	(gr_line
		(start 371.181376 -233.465116)
		(end 371.181122 -233.465116)
		(stroke
			(width 0.05715)
			(type default)
		)
		(layer "In4.Cu")
	)
	(gr_line
		(start 371.181376 -233.465116)
		(end 371.183916 -233.463592)
		(stroke
			(width 0.05715)
			(type default)
		)
		(layer "In4.Cu")
	)
	(gr_line
		(start 371.181376 -225.367088)
		(end 371.183662 -225.365818)
		(stroke
			(width 0.05715)
			(type default)
		)
		(layer "In4.Cu")
	)
	(gr_line
		(start 371.183916 -233.463592)
		(end 371.18544 -233.46283)
		(stroke
			(width 0.05715)
			(type default)
		)
		(layer "In4.Cu")
	)
	(gr_line
		(start 371.184932 -412.55569)
		(end 370.894102 -412.84652)
		(stroke
			(width 0.07112)
			(type default)
		)
		(layer "In4.Cu")
	)
	(gr_arc
		(start 371.18544 -233.46283)
		(mid 371.254942 -233.411057)
		(end 371.310408 -233.344466)
		(stroke
			(width 0.05715)
			(type default)
		)
		(layer "In4.Cu")
	)
	(gr_line
		(start 371.217698 -386.338318)
		(end 370.915692 -386.036312)
		(stroke
			(width 0.07112)
			(type default)
		)
		(layer "In4.Cu")
	)
	(gr_line
		(start 371.244622 -393.787376)
		(end 371.24513 -393.786868)
		(stroke
			(width 0.07112)
			(type default)
		)
		(layer "In4.Cu")
	)
	(gr_arc
		(start 371.246654 -233.650282)
		(mid 371.24449 -233.651798)
		(end 371.242336 -233.65333)
		(stroke
			(width 0.05715)
			(type default)
		)
		(layer "In4.Cu")
	)
	(gr_line
		(start 371.263418 -384.486658)
		(end 370.961412 -384.184652)
		(stroke
			(width 0.07112)
			(type default)
		)
		(layer "In4.Cu")
	)
	(gr_arc
		(start 371.265196 -233.638852)
		(mid 371.261116 -233.641238)
		(end 371.257068 -233.643678)
		(stroke
			(width 0.05715)
			(type default)
		)
		(layer "In4.Cu")
	)
	(gr_line
		(start 371.27434 -225.533712)
		(end 371.273578 -225.53422)
		(stroke
			(width 0.05715)
			(type default)
		)
		(layer "In4.Cu")
	)
	(gr_line
		(start 371.28704 -333.979774)
		(end 371.299232 -334.015588)
		(stroke
			(width 0.07112)
			(type default)
		)
		(layer "In4.Cu")
	)
	(gr_line
		(start 371.291358 -394.385292)
		(end 371.3861 -394.031724)
		(stroke
			(width 0.07112)
			(type default)
		)
		(layer "In4.Cu")
	)
	(gr_line
		(start 371.299232 -334.015588)
		(end 371.305582 -334.050386)
		(stroke
			(width 0.07112)
			(type default)
		)
		(layer "In4.Cu")
	)
	(gr_line
		(start 371.31625 -231.989122)
		(end 371.30863 -231.99344)
		(stroke
			(width 0.05715)
			(type default)
		)
		(layer "In4.Cu")
	)
	(gr_line
		(start 371.317012 -233.608626)
		(end 371.265196 -233.638852)
		(stroke
			(width 0.05715)
			(type default)
		)
		(layer "In4.Cu")
	)
	(gr_arc
		(start 371.317012 -233.608626)
		(mid 371.402327 -233.536045)
		(end 371.471698 -233.448098)
		(stroke
			(width 0.05715)
			(type default)
		)
		(layer "In4.Cu")
	)
	(gr_arc
		(start 371.317012 -231.988614)
		(mid 371.316631 -231.988868)
		(end 371.31625 -231.989122)
		(stroke
			(width 0.05715)
			(type default)
		)
		(layer "In4.Cu")
	)
	(gr_arc
		(start 371.317012 -231.988614)
		(mid 371.320961 -231.985837)
		(end 371.324886 -231.983026)
		(stroke
			(width 0.05715)
			(type default)
		)
		(layer "In4.Cu")
	)
	(gr_arc
		(start 371.327172 -348.164658)
		(mid 371.328078 -348.160471)
		(end 371.32895 -348.156276)
		(stroke
			(width 0.07112)
			(type default)
		)
		(layer "In4.Cu")
	)
	(gr_line
		(start 371.340634 -348.047818)
		(end 371.340634 -348.04858)
		(stroke
			(width 0.07112)
			(type default)
		)
		(layer "In4.Cu")
	)
	(gr_arc
		(start 371.340634 -348.04731)
		(mid 371.340634 -348.047564)
		(end 371.340634 -348.047818)
		(stroke
			(width 0.07112)
			(type default)
		)
		(layer "In4.Cu")
	)
	(gr_line
		(start 371.340634 -338.431632)
		(end 371.340634 -338.43214)
		(stroke
			(width 0.07112)
			(type default)
		)
		(layer "In4.Cu")
	)
	(gr_line
		(start 371.409976 -386.338318)
		(end 371.217698 -386.338318)
		(stroke
			(width 0.07112)
			(type default)
		)
		(layer "In4.Cu")
	)
	(gr_arc
		(start 371.428264 -321.739514)
		(mid 371.421546 -321.724843)
		(end 371.414548 -321.710304)
		(stroke
			(width 0.07112)
			(type default)
		)
		(layer "In4.Cu")
	)
	(gr_arc
		(start 371.444774 -321.777868)
		(mid 371.436752 -321.758591)
		(end 371.428264 -321.739514)
		(stroke
			(width 0.07112)
			(type default)
		)
		(layer "In4.Cu")
	)
	(gr_line
		(start 371.455696 -384.486658)
		(end 371.263418 -384.486658)
		(stroke
			(width 0.07112)
			(type default)
		)
		(layer "In4.Cu")
	)
	(gr_arc
		(start 371.456966 -321.811142)
		(mid 371.451044 -321.794441)
		(end 371.444774 -321.777868)
		(stroke
			(width 0.07112)
			(type default)
		)
		(layer "In4.Cu")
	)
	(gr_line
		(start 371.466872 -412.55569)
		(end 371.757702 -412.84652)
		(stroke
			(width 0.07112)
			(type default)
		)
		(layer "In4.Cu")
	)
	(gr_line
		(start 371.474492 -350.299782)
		(end 371.474492 -350.30029)
		(stroke
			(width 0.07112)
			(type default)
		)
		(layer "In4.Cu")
	)
	(gr_line
		(start 371.48262 -290.773866)
		(end 371.481858 -290.773358)
		(stroke
			(width 0.05715)
			(type default)
		)
		(layer "In4.Cu")
	)
	(gr_line
		(start 371.48389 -290.774628)
		(end 371.48262 -290.773866)
		(stroke
			(width 0.05715)
			(type default)
		)
		(layer "In4.Cu")
	)
	(gr_line
		(start 371.487954 -290.776914)
		(end 371.48643 -290.775898)
		(stroke
			(width 0.05715)
			(type default)
		)
		(layer "In4.Cu")
	)
	(gr_line
		(start 371.48897 -290.777422)
		(end 371.487954 -290.776914)
		(stroke
			(width 0.05715)
			(type default)
		)
		(layer "In4.Cu")
	)
	(gr_line
		(start 371.489478 -290.777676)
		(end 371.48897 -290.777422)
		(stroke
			(width 0.05715)
			(type default)
		)
		(layer "In4.Cu")
	)
	(gr_line
		(start 371.507766 -393.961112)
		(end 371.560598 -393.930632)
		(stroke
			(width 0.07112)
			(type default)
		)
		(layer "In4.Cu")
	)
	(gr_line
		(start 371.560344 -225.044254)
		(end 371.56009 -225.044254)
		(stroke
			(width 0.05715)
			(type default)
		)
		(layer "In4.Cu")
	)
	(gr_line
		(start 371.560598 -393.930632)
		(end 371.648736 -393.842494)
		(stroke
			(width 0.07112)
			(type default)
		)
		(layer "In4.Cu")
	)
	(gr_arc
		(start 371.564916 -333.924656)
		(mid 371.55965 -333.906943)
		(end 371.553994 -333.88935)
		(stroke
			(width 0.07112)
			(type default)
		)
		(layer "In4.Cu")
	)
	(gr_arc
		(start 371.575838 -333.965804)
		(mid 371.570641 -333.94516)
		(end 371.564916 -333.924656)
		(stroke
			(width 0.07112)
			(type default)
		)
		(layer "In4.Cu")
	)
	(gr_arc
		(start 371.582696 -333.999078)
		(mid 371.579436 -333.982406)
		(end 371.575838 -333.965804)
		(stroke
			(width 0.07112)
			(type default)
		)
		(layer "In4.Cu")
	)
	(gr_line
		(start 371.583204 -290.61156)
		(end 371.582188 -290.611052)
		(stroke
			(width 0.05715)
			(type default)
		)
		(layer "In4.Cu")
	)
	(gr_line
		(start 371.58422 -290.612322)
		(end 371.583204 -290.61156)
		(stroke
			(width 0.05715)
			(type default)
		)
		(layer "In4.Cu")
	)
	(gr_line
		(start 371.609366 -290.6268)
		(end 371.608858 -290.626546)
		(stroke
			(width 0.05715)
			(type default)
		)
		(layer "In4.Cu")
	)
	(gr_line
		(start 371.610128 -290.627308)
		(end 371.609366 -290.6268)
		(stroke
			(width 0.05715)
			(type default)
		)
		(layer "In4.Cu")
	)
	(gr_line
		(start 371.611144 -386.138928)
		(end 371.115082 -385.642866)
		(stroke
			(width 0.07112)
			(type default)
		)
		(layer "In4.Cu")
	)
	(gr_arc
		(start 371.611398 -224.580704)
		(mid 371.608981 -224.582476)
		(end 371.606572 -224.58426)
		(stroke
			(width 0.05715)
			(type default)
		)
		(layer "In4.Cu")
	)
	(gr_arc
		(start 371.612668 -222.959676)
		(mid 371.608719 -222.962453)
		(end 371.604794 -222.965264)
		(stroke
			(width 0.05715)
			(type default)
		)
		(layer "In4.Cu")
	)
	(gr_line
		(start 371.612668 -222.959676)
		(end 371.615462 -222.957644)
		(stroke
			(width 0.05715)
			(type default)
		)
		(layer "In4.Cu")
	)
	(gr_line
		(start 371.615462 -222.957644)
		(end 371.62105 -222.954342)
		(stroke
			(width 0.05715)
			(type default)
		)
		(layer "In4.Cu")
	)
	(gr_line
		(start 371.616986 -290.631372)
		(end 371.610128 -290.627308)
		(stroke
			(width 0.05715)
			(type default)
		)
		(layer "In4.Cu")
	)
	(gr_line
		(start 371.624098 -296.422826)
		(end 371.624098 -296.394378)
		(stroke
			(width 0.05715)
			(type default)
		)
		(layer "In4.Cu")
	)
	(gr_line
		(start 371.624098 -296.394378)
		(end 371.669818 -296.348658)
		(stroke
			(width 0.05715)
			(type default)
		)
		(layer "In4.Cu")
	)
	(gr_arc
		(start 371.62486 -290.63696)
		(mid 371.620935 -290.634149)
		(end 371.616986 -290.631372)
		(stroke
			(width 0.05715)
			(type default)
		)
		(layer "In4.Cu")
	)
	(gr_line
		(start 371.648736 -393.842494)
		(end 371.648736 -393.716764)
		(stroke
			(width 0.07112)
			(type default)
		)
		(layer "In4.Cu")
	)
	(gr_line
		(start 371.652038 -222.936562)
		(end 371.652546 -222.936308)
		(stroke
			(width 0.05715)
			(type default)
		)
		(layer "In4.Cu")
	)
	(gr_line
		(start 371.652546 -222.936308)
		(end 371.653816 -222.935546)
		(stroke
			(width 0.05715)
			(type default)
		)
		(layer "In4.Cu")
	)
	(gr_line
		(start 371.656864 -384.287268)
		(end 371.160802 -383.791206)
		(stroke
			(width 0.07112)
			(type default)
		)
		(layer "In4.Cu")
	)
	(gr_line
		(start 371.664484 -375.70918)
		(end 371.664738 -375.70918)
		(stroke
			(width 0.07112)
			(type default)
		)
		(layer "In4.Cu")
	)
	(gr_line
		(start 371.68328 -376.760994)
		(end 371.683534 -376.761248)
		(stroke
			(width 0.07112)
			(type default)
		)
		(layer "In4.Cu")
	)
	(gr_line
		(start 371.713252 -386.833618)
		(end 371.713252 -386.641594)
		(stroke
			(width 0.07112)
			(type default)
		)
		(layer "In4.Cu")
	)
	(gr_line
		(start 371.747796 -223.101662)
		(end 371.747034 -223.10217)
		(stroke
			(width 0.05715)
			(type default)
		)
		(layer "In4.Cu")
	)
	(gr_line
		(start 371.748812 -223.101154)
		(end 371.747796 -223.101662)
		(stroke
			(width 0.05715)
			(type default)
		)
		(layer "In4.Cu")
	)
	(gr_line
		(start 371.758972 -384.982212)
		(end 371.758972 -384.789934)
		(stroke
			(width 0.07112)
			(type default)
		)
		(layer "In4.Cu")
	)
	(gr_line
		(start 371.906038 -296.422826)
		(end 371.906038 -296.394378)
		(stroke
			(width 0.05715)
			(type default)
		)
		(layer "In4.Cu")
	)
	(gr_line
		(start 371.906038 -296.394378)
		(end 371.860318 -296.348658)
		(stroke
			(width 0.05715)
			(type default)
		)
		(layer "In4.Cu")
	)
	(gr_line
		(start 371.93474 -321.2084)
		(end 371.945154 -321.228466)
		(stroke
			(width 0.07112)
			(type default)
		)
		(layer "In4.Cu")
	)
	(gr_line
		(start 371.945154 -321.228466)
		(end 371.952774 -321.25031)
		(stroke
			(width 0.07112)
			(type default)
		)
		(layer "In4.Cu")
	)
	(gr_line
		(start 372.015258 -387.135624)
		(end 371.713252 -386.833618)
		(stroke
			(width 0.07112)
			(type default)
		)
		(layer "In4.Cu")
	)
	(gr_line
		(start 372.060978 -385.284218)
		(end 371.758972 -384.982212)
		(stroke
			(width 0.07112)
			(type default)
		)
		(layer "In4.Cu")
	)
	(gr_line
		(start 372.091204 -393.69238)
		(end 372.444518 -393.787376)
		(stroke
			(width 0.07112)
			(type default)
		)
		(layer "In4.Cu")
	)
	(gr_line
		(start 372.120922 -231.847136)
		(end 372.121938 -231.846628)
		(stroke
			(width 0.05715)
			(type default)
		)
		(layer "In4.Cu")
	)
	(gr_line
		(start 372.120922 -225.367342)
		(end 372.121938 -225.366834)
		(stroke
			(width 0.05715)
			(type default)
		)
		(layer "In4.Cu")
	)
	(gr_line
		(start 372.121938 -231.846628)
		(end 372.1227 -231.84612)
		(stroke
			(width 0.05715)
			(type default)
		)
		(layer "In4.Cu")
	)
	(gr_line
		(start 372.121938 -225.366834)
		(end 372.1227 -225.366326)
		(stroke
			(width 0.05715)
			(type default)
		)
		(layer "In4.Cu")
	)
	(gr_line
		(start 372.1227 -231.84612)
		(end 372.12397 -231.845358)
		(stroke
			(width 0.05715)
			(type default)
		)
		(layer "In4.Cu")
	)
	(gr_line
		(start 372.1227 -225.366326)
		(end 372.12397 -225.365564)
		(stroke
			(width 0.05715)
			(type default)
		)
		(layer "In4.Cu")
	)
	(gr_line
		(start 372.125494 -411.58922)
		(end 371.945916 -411.519878)
		(stroke
			(width 0.07112)
			(type default)
		)
		(layer "In4.Cu")
	)
	(gr_line
		(start 372.12651 -231.844088)
		(end 372.128034 -231.843072)
		(stroke
			(width 0.05715)
			(type default)
		)
		(layer "In4.Cu")
	)
	(gr_line
		(start 372.12651 -225.364294)
		(end 372.128034 -225.363278)
		(stroke
			(width 0.05715)
			(type default)
		)
		(layer "In4.Cu")
	)
	(gr_line
		(start 372.128034 -231.843072)
		(end 372.129558 -231.84231)
		(stroke
			(width 0.05715)
			(type default)
		)
		(layer "In4.Cu")
	)
	(gr_line
		(start 372.128034 -225.363278)
		(end 372.129558 -225.362516)
		(stroke
			(width 0.05715)
			(type default)
		)
		(layer "In4.Cu")
	)
	(gr_line
		(start 372.18112 -317.646558)
		(end 372.18112 -317.646812)
		(stroke
			(width 0.07112)
			(type default)
		)
		(layer "In4.Cu")
	)
	(gr_line
		(start 372.187724 -333.649066)
		(end 372.20017 -333.685134)
		(stroke
			(width 0.07112)
			(type default)
		)
		(layer "In4.Cu")
	)
	(gr_arc
		(start 372.194328 -321.098164)
		(mid 372.190562 -321.090015)
		(end 372.186708 -321.081908)
		(stroke
			(width 0.07112)
			(type default)
		)
		(layer "In4.Cu")
	)
	(gr_line
		(start 372.20017 -333.685134)
		(end 372.20652 -333.719932)
		(stroke
			(width 0.07112)
			(type default)
		)
		(layer "In4.Cu")
	)
	(gr_line
		(start 372.207282 -387.135624)
		(end 372.015258 -387.135624)
		(stroke
			(width 0.07112)
			(type default)
		)
		(layer "In4.Cu")
	)
	(gr_arc
		(start 372.211092 -321.137534)
		(mid 372.202963 -321.117741)
		(end 372.194328 -321.098164)
		(stroke
			(width 0.07112)
			(type default)
		)
		(layer "In4.Cu")
	)
	(gr_line
		(start 372.217188 -232.011982)
		(end 372.215918 -232.012744)
		(stroke
			(width 0.05715)
			(type default)
		)
		(layer "In4.Cu")
	)
	(gr_line
		(start 372.217188 -225.532188)
		(end 372.215918 -225.53295)
		(stroke
			(width 0.05715)
			(type default)
		)
		(layer "In4.Cu")
	)
	(gr_arc
		(start 372.21795 -321.15506)
		(mid 372.214569 -321.146278)
		(end 372.211092 -321.137534)
		(stroke
			(width 0.07112)
			(type default)
		)
		(layer "In4.Cu")
	)
	(gr_line
		(start 372.21795 -232.011474)
		(end 372.217188 -232.011982)
		(stroke
			(width 0.05715)
			(type default)
		)
		(layer "In4.Cu")
	)
	(gr_line
		(start 372.21795 -225.53168)
		(end 372.217188 -225.532188)
		(stroke
			(width 0.05715)
			(type default)
		)
		(layer "In4.Cu")
	)
	(gr_line
		(start 372.218966 -232.010966)
		(end 372.21795 -232.011474)
		(stroke
			(width 0.05715)
			(type default)
		)
		(layer "In4.Cu")
	)
	(gr_line
		(start 372.218966 -225.531172)
		(end 372.21795 -225.53168)
		(stroke
			(width 0.05715)
			(type default)
		)
		(layer "In4.Cu")
	)
	(gr_line
		(start 372.220744 -232.00995)
		(end 372.218966 -232.010966)
		(stroke
			(width 0.05715)
			(type default)
		)
		(layer "In4.Cu")
	)
	(gr_line
		(start 372.220744 -225.530156)
		(end 372.218966 -225.531172)
		(stroke
			(width 0.05715)
			(type default)
		)
		(layer "In4.Cu")
	)
	(gr_line
		(start 372.22303 -232.008426)
		(end 372.222268 -232.008934)
		(stroke
			(width 0.05715)
			(type default)
		)
		(layer "In4.Cu")
	)
	(gr_line
		(start 372.22303 -225.528632)
		(end 372.222268 -225.52914)
		(stroke
			(width 0.05715)
			(type default)
		)
		(layer "In4.Cu")
	)
	(gr_line
		(start 372.249446 -231.993186)
		(end 372.248684 -231.993694)
		(stroke
			(width 0.05715)
			(type default)
		)
		(layer "In4.Cu")
	)
	(gr_line
		(start 372.249446 -225.513392)
		(end 372.248684 -225.5139)
		(stroke
			(width 0.05715)
			(type default)
		)
		(layer "In4.Cu")
	)
	(gr_line
		(start 372.250208 -231.992678)
		(end 372.249446 -231.993186)
		(stroke
			(width 0.05715)
			(type default)
		)
		(layer "In4.Cu")
	)
	(gr_line
		(start 372.250208 -225.512884)
		(end 372.249446 -225.513392)
		(stroke
			(width 0.05715)
			(type default)
		)
		(layer "In4.Cu")
	)
	(gr_line
		(start 372.253256 -385.284218)
		(end 372.060978 -385.284218)
		(stroke
			(width 0.07112)
			(type default)
		)
		(layer "In4.Cu")
	)
	(gr_line
		(start 372.257066 -231.988614)
		(end 372.250208 -231.992678)
		(stroke
			(width 0.05715)
			(type default)
		)
		(layer "In4.Cu")
	)
	(gr_arc
		(start 372.257066 -231.988614)
		(mid 372.261015 -231.985837)
		(end 372.26494 -231.983026)
		(stroke
			(width 0.05715)
			(type default)
		)
		(layer "In4.Cu")
	)
	(gr_line
		(start 372.257066 -225.50882)
		(end 372.250208 -225.512884)
		(stroke
			(width 0.05715)
			(type default)
		)
		(layer "In4.Cu")
	)
	(gr_arc
		(start 372.257066 -225.50882)
		(mid 372.261015 -225.506043)
		(end 372.26494 -225.503232)
		(stroke
			(width 0.05715)
			(type default)
		)
		(layer "In4.Cu")
	)
	(gr_line
		(start 372.26367 -221.202758)
		(end 372.26367 -221.17431)
		(stroke
			(width 0.05715)
			(type default)
		)
		(layer "In4.Cu")
	)
	(gr_arc
		(start 372.26748 -348.273878)
		(mid 372.267864 -348.272228)
		(end 372.268242 -348.270576)
		(stroke
			(width 0.07112)
			(type default)
		)
		(layer "In4.Cu")
	)
	(gr_line
		(start 372.281196 -348.152974)
		(end 372.281196 -348.154244)
		(stroke
			(width 0.07112)
			(type default)
		)
		(layer "In4.Cu")
	)
	(gr_line
		(start 372.281196 -337.974178)
		(end 372.281196 -337.974686)
		(stroke
			(width 0.07112)
			(type default)
		)
		(layer "In4.Cu")
	)
	(gr_line
		(start 372.307104 -350.896428)
		(end 372.307104 -350.896682)
		(stroke
			(width 0.07112)
			(type default)
		)
		(layer "In4.Cu")
	)
	(gr_line
		(start 372.30939 -221.248478)
		(end 372.26367 -221.202758)
		(stroke
			(width 0.05715)
			(type default)
		)
		(layer "In4.Cu")
	)
	(gr_line
		(start 372.40591 -380.8603)
		(end 372.405656 -380.8603)
		(stroke
			(width 0.07112)
			(type default)
		)
		(layer "In4.Cu")
	)
	(gr_line
		(start 372.40845 -386.936234)
		(end 371.912642 -386.440426)
		(stroke
			(width 0.07112)
			(type default)
		)
		(layer "In4.Cu")
	)
	(gr_line
		(start 372.43639 -289.777424)
		(end 372.437152 -289.776916)
		(stroke
			(width 0.05715)
			(type default)
		)
		(layer "In4.Cu")
	)
	(gr_line
		(start 372.444518 -393.787376)
		(end 372.445026 -393.786868)
		(stroke
			(width 0.07112)
			(type default)
		)
		(layer "In4.Cu")
	)
	(gr_arc
		(start 372.445534 -317.537592)
		(mid 372.445154 -317.53683)
		(end 372.444772 -317.536068)
		(stroke
			(width 0.07112)
			(type default)
		)
		(layer "In4.Cu")
	)
	(gr_line
		(start 372.454424 -385.084828)
		(end 371.958362 -384.588766)
		(stroke
			(width 0.07112)
			(type default)
		)
		(layer "In4.Cu")
	)
	(gr_arc
		(start 372.465854 -333.594202)
		(mid 372.460596 -333.576233)
		(end 372.454932 -333.558388)
		(stroke
			(width 0.07112)
			(type default)
		)
		(layer "In4.Cu")
	)
	(gr_line
		(start 372.471188 -410.977334)
		(end 371.830092 -411.26156)
		(stroke
			(width 0.07112)
			(type default)
		)
		(layer "In4.Cu")
	)
	(gr_arc
		(start 372.476776 -333.63535)
		(mid 372.471578 -333.614706)
		(end 372.465854 -333.594202)
		(stroke
			(width 0.07112)
			(type default)
		)
		(layer "In4.Cu")
	)
	(gr_arc
		(start 372.483634 -333.668624)
		(mid 372.480373 -333.651952)
		(end 372.476776 -333.63535)
		(stroke
			(width 0.07112)
			(type default)
		)
		(layer "In4.Cu")
	)
	(gr_line
		(start 372.491254 -394.385292)
		(end 372.585996 -394.031724)
		(stroke
			(width 0.07112)
			(type default)
		)
		(layer "In4.Cu")
	)
	(gr_line
		(start 372.515892 -411.416246)
		(end 372.125494 -411.58922)
		(stroke
			(width 0.07112)
			(type default)
		)
		(layer "In4.Cu")
	)
	(gr_line
		(start 372.54561 -221.202758)
		(end 372.49989 -221.248478)
		(stroke
			(width 0.05715)
			(type default)
		)
		(layer "In4.Cu")
	)
	(gr_line
		(start 372.54561 -221.17431)
		(end 372.54561 -221.202758)
		(stroke
			(width 0.05715)
			(type default)
		)
		(layer "In4.Cu")
	)
	(gr_arc
		(start 372.551452 -224.580704)
		(mid 372.549034 -224.582476)
		(end 372.546626 -224.58426)
		(stroke
			(width 0.05715)
			(type default)
		)
		(layer "In4.Cu")
	)
	(gr_arc
		(start 372.552722 -234.299506)
		(mid 372.548773 -234.302283)
		(end 372.544848 -234.305094)
		(stroke
			(width 0.05715)
			(type default)
		)
		(layer "In4.Cu")
	)
	(gr_line
		(start 372.552722 -234.299506)
		(end 372.55958 -234.295442)
		(stroke
			(width 0.05715)
			(type default)
		)
		(layer "In4.Cu")
	)
	(gr_arc
		(start 372.552722 -232.679494)
		(mid 372.548773 -232.682271)
		(end 372.544848 -232.685082)
		(stroke
			(width 0.05715)
			(type default)
		)
		(layer "In4.Cu")
	)
	(gr_line
		(start 372.552722 -232.679494)
		(end 372.55958 -232.67543)
		(stroke
			(width 0.05715)
			(type default)
		)
		(layer "In4.Cu")
	)
	(gr_arc
		(start 372.552722 -227.819712)
		(mid 372.548773 -227.822489)
		(end 372.544848 -227.8253)
		(stroke
			(width 0.05715)
			(type default)
		)
		(layer "In4.Cu")
	)
	(gr_line
		(start 372.552722 -227.819712)
		(end 372.55958 -227.815648)
		(stroke
			(width 0.05715)
			(type default)
		)
		(layer "In4.Cu")
	)
	(gr_arc
		(start 372.552722 -226.1997)
		(mid 372.548773 -226.202477)
		(end 372.544848 -226.205288)
		(stroke
			(width 0.05715)
			(type default)
		)
		(layer "In4.Cu")
	)
	(gr_line
		(start 372.552722 -226.1997)
		(end 372.55958 -226.195636)
		(stroke
			(width 0.05715)
			(type default)
		)
		(layer "In4.Cu")
	)
	(gr_line
		(start 372.556532 -385.779518)
		(end 372.556532 -385.587494)
		(stroke
			(width 0.07112)
			(type default)
		)
		(layer "In4.Cu")
	)
	(gr_line
		(start 372.55958 -234.295442)
		(end 372.560342 -234.294934)
		(stroke
			(width 0.05715)
			(type default)
		)
		(layer "In4.Cu")
	)
	(gr_line
		(start 372.55958 -232.67543)
		(end 372.560342 -232.674922)
		(stroke
			(width 0.05715)
			(type default)
		)
		(layer "In4.Cu")
	)
	(gr_line
		(start 372.55958 -227.815648)
		(end 372.560342 -227.81514)
		(stroke
			(width 0.05715)
			(type default)
		)
		(layer "In4.Cu")
	)
	(gr_line
		(start 372.55958 -226.195636)
		(end 372.560342 -226.195128)
		(stroke
			(width 0.05715)
			(type default)
		)
		(layer "In4.Cu")
	)
	(gr_line
		(start 372.560342 -234.294934)
		(end 372.561104 -234.294426)
		(stroke
			(width 0.05715)
			(type default)
		)
		(layer "In4.Cu")
	)
	(gr_line
		(start 372.560342 -232.674922)
		(end 372.561104 -232.674414)
		(stroke
			(width 0.05715)
			(type default)
		)
		(layer "In4.Cu")
	)
	(gr_line
		(start 372.560342 -227.81514)
		(end 372.561104 -227.814632)
		(stroke
			(width 0.05715)
			(type default)
		)
		(layer "In4.Cu")
	)
	(gr_line
		(start 372.560342 -226.195128)
		(end 372.561104 -226.19462)
		(stroke
			(width 0.05715)
			(type default)
		)
		(layer "In4.Cu")
	)
	(gr_line
		(start 372.563644 -296.43959)
		(end 372.563644 -296.411142)
		(stroke
			(width 0.05715)
			(type default)
		)
		(layer "In4.Cu")
	)
	(gr_line
		(start 372.563644 -296.411142)
		(end 372.609364 -296.365422)
		(stroke
			(width 0.05715)
			(type default)
		)
		(layer "In4.Cu")
	)
	(gr_line
		(start 372.58117 -235.245148)
		(end 372.580154 -235.24464)
		(stroke
			(width 0.05715)
			(type default)
		)
		(layer "In4.Cu")
	)
	(gr_line
		(start 372.58117 -233.625136)
		(end 372.580154 -233.624628)
		(stroke
			(width 0.05715)
			(type default)
		)
		(layer "In4.Cu")
	)
	(gr_line
		(start 372.58117 -228.765354)
		(end 372.580154 -228.764846)
		(stroke
			(width 0.05715)
			(type default)
		)
		(layer "In4.Cu")
	)
	(gr_line
		(start 372.58117 -227.145342)
		(end 372.580154 -227.144834)
		(stroke
			(width 0.05715)
			(type default)
		)
		(layer "In4.Cu")
	)
	(gr_line
		(start 372.58498 -411.236668)
		(end 372.515892 -411.416246)
		(stroke
			(width 0.07112)
			(type default)
		)
		(layer "In4.Cu")
	)
	(gr_line
		(start 372.590822 -235.25099)
		(end 372.59006 -235.250482)
		(stroke
			(width 0.05715)
			(type default)
		)
		(layer "In4.Cu")
	)
	(gr_line
		(start 372.590822 -233.630978)
		(end 372.59006 -233.63047)
		(stroke
			(width 0.05715)
			(type default)
		)
		(layer "In4.Cu")
	)
	(gr_line
		(start 372.590822 -228.771196)
		(end 372.59006 -228.770688)
		(stroke
			(width 0.05715)
			(type default)
		)
		(layer "In4.Cu")
	)
	(gr_line
		(start 372.590822 -227.151184)
		(end 372.59006 -227.150676)
		(stroke
			(width 0.05715)
			(type default)
		)
		(layer "In4.Cu")
	)
	(gr_line
		(start 372.591838 -235.251498)
		(end 372.590822 -235.25099)
		(stroke
			(width 0.05715)
			(type default)
		)
		(layer "In4.Cu")
	)
	(gr_line
		(start 372.591838 -233.631486)
		(end 372.590822 -233.630978)
		(stroke
			(width 0.05715)
			(type default)
		)
		(layer "In4.Cu")
	)
	(gr_line
		(start 372.591838 -228.771704)
		(end 372.590822 -228.771196)
		(stroke
			(width 0.05715)
			(type default)
		)
		(layer "In4.Cu")
	)
	(gr_line
		(start 372.591838 -227.151692)
		(end 372.590822 -227.151184)
		(stroke
			(width 0.05715)
			(type default)
		)
		(layer "In4.Cu")
	)
	(gr_line
		(start 372.592092 -234.276392)
		(end 372.5926 -234.276138)
		(stroke
			(width 0.05715)
			(type default)
		)
		(layer "In4.Cu")
	)
	(gr_line
		(start 372.592092 -232.65638)
		(end 372.5926 -232.656126)
		(stroke
			(width 0.05715)
			(type default)
		)
		(layer "In4.Cu")
	)
	(gr_line
		(start 372.592092 -227.796598)
		(end 372.5926 -227.796344)
		(stroke
			(width 0.05715)
			(type default)
		)
		(layer "In4.Cu")
	)
	(gr_line
		(start 372.592092 -226.176586)
		(end 372.5926 -226.176332)
		(stroke
			(width 0.05715)
			(type default)
		)
		(layer "In4.Cu")
	)
	(gr_line
		(start 372.5926 -235.252006)
		(end 372.591838 -235.251498)
		(stroke
			(width 0.05715)
			(type default)
		)
		(layer "In4.Cu")
	)
	(gr_line
		(start 372.5926 -234.276138)
		(end 372.599966 -234.272074)
		(stroke
			(width 0.05715)
			(type default)
		)
		(layer "In4.Cu")
	)
	(gr_line
		(start 372.5926 -233.631994)
		(end 372.591838 -233.631486)
		(stroke
			(width 0.05715)
			(type default)
		)
		(layer "In4.Cu")
	)
	(gr_line
		(start 372.5926 -232.656126)
		(end 372.599966 -232.652062)
		(stroke
			(width 0.05715)
			(type default)
		)
		(layer "In4.Cu")
	)
	(gr_line
		(start 372.5926 -228.772212)
		(end 372.591838 -228.771704)
		(stroke
			(width 0.05715)
			(type default)
		)
		(layer "In4.Cu")
	)
	(gr_line
		(start 372.5926 -227.796344)
		(end 372.599966 -227.79228)
		(stroke
			(width 0.05715)
			(type default)
		)
		(layer "In4.Cu")
	)
	(gr_line
		(start 372.5926 -227.1522)
		(end 372.591838 -227.151692)
		(stroke
			(width 0.05715)
			(type default)
		)
		(layer "In4.Cu")
	)
	(gr_line
		(start 372.5926 -226.176332)
		(end 372.599966 -226.172268)
		(stroke
			(width 0.05715)
			(type default)
		)
		(layer "In4.Cu")
	)
	(gr_line
		(start 372.59387 -235.252768)
		(end 372.5926 -235.252006)
		(stroke
			(width 0.05715)
			(type default)
		)
		(layer "In4.Cu")
	)
	(gr_line
		(start 372.59387 -233.632756)
		(end 372.5926 -233.631994)
		(stroke
			(width 0.05715)
			(type default)
		)
		(layer "In4.Cu")
	)
	(gr_line
		(start 372.59387 -228.772974)
		(end 372.5926 -228.772212)
		(stroke
			(width 0.05715)
			(type default)
		)
		(layer "In4.Cu")
	)
	(gr_line
		(start 372.59387 -227.152962)
		(end 372.5926 -227.1522)
		(stroke
			(width 0.05715)
			(type default)
		)
		(layer "In4.Cu")
	)
	(gr_line
		(start 372.595394 -235.25353)
		(end 372.59387 -235.252768)
		(stroke
			(width 0.05715)
			(type default)
		)
		(layer "In4.Cu")
	)
	(gr_line
		(start 372.595394 -233.633518)
		(end 372.59387 -233.632756)
		(stroke
			(width 0.05715)
			(type default)
		)
		(layer "In4.Cu")
	)
	(gr_line
		(start 372.595394 -228.773736)
		(end 372.59387 -228.772974)
		(stroke
			(width 0.05715)
			(type default)
		)
		(layer "In4.Cu")
	)
	(gr_line
		(start 372.595394 -227.153724)
		(end 372.59387 -227.152962)
		(stroke
			(width 0.05715)
			(type default)
		)
		(layer "In4.Cu")
	)
	(gr_line
		(start 372.596156 -235.254038)
		(end 372.595394 -235.25353)
		(stroke
			(width 0.05715)
			(type default)
		)
		(layer "In4.Cu")
	)
	(gr_line
		(start 372.596156 -233.634026)
		(end 372.595394 -233.633518)
		(stroke
			(width 0.05715)
			(type default)
		)
		(layer "In4.Cu")
	)
	(gr_line
		(start 372.596156 -228.774244)
		(end 372.595394 -228.773736)
		(stroke
			(width 0.05715)
			(type default)
		)
		(layer "In4.Cu")
	)
	(gr_line
		(start 372.596156 -227.154232)
		(end 372.595394 -227.153724)
		(stroke
			(width 0.05715)
			(type default)
		)
		(layer "In4.Cu")
	)
	(gr_line
		(start 372.596918 -235.254292)
		(end 372.596156 -235.254038)
		(stroke
			(width 0.05715)
			(type default)
		)
		(layer "In4.Cu")
	)
	(gr_line
		(start 372.596918 -233.63428)
		(end 372.596156 -233.634026)
		(stroke
			(width 0.05715)
			(type default)
		)
		(layer "In4.Cu")
	)
	(gr_line
		(start 372.596918 -228.774498)
		(end 372.596156 -228.774244)
		(stroke
			(width 0.05715)
			(type default)
		)
		(layer "In4.Cu")
	)
	(gr_line
		(start 372.596918 -227.154486)
		(end 372.596156 -227.154232)
		(stroke
			(width 0.05715)
			(type default)
		)
		(layer "In4.Cu")
	)
	(gr_arc
		(start 372.609364 -295.9481)
		(mid 372.609351 -295.952037)
		(end 372.609364 -295.955974)
		(stroke
			(width 0.05715)
			(type default)
		)
		(layer "In4.Cu")
	)
	(gr_line
		(start 372.677944 -235.08081)
		(end 372.679722 -235.081826)
		(stroke
			(width 0.05715)
			(type default)
		)
		(layer "In4.Cu")
	)
	(gr_line
		(start 372.677944 -233.460798)
		(end 372.679722 -233.461814)
		(stroke
			(width 0.05715)
			(type default)
		)
		(layer "In4.Cu")
	)
	(gr_line
		(start 372.677944 -228.601016)
		(end 372.679722 -228.602032)
		(stroke
			(width 0.05715)
			(type default)
		)
		(layer "In4.Cu")
	)
	(gr_line
		(start 372.677944 -226.981004)
		(end 372.679722 -226.98202)
		(stroke
			(width 0.05715)
			(type default)
		)
		(layer "In4.Cu")
	)
	(gr_line
		(start 372.680992 -235.082588)
		(end 372.681754 -235.083096)
		(stroke
			(width 0.05715)
			(type default)
		)
		(layer "In4.Cu")
	)
	(gr_line
		(start 372.680992 -233.462576)
		(end 372.681754 -233.463084)
		(stroke
			(width 0.05715)
			(type default)
		)
		(layer "In4.Cu")
	)
	(gr_line
		(start 372.680992 -228.602794)
		(end 372.681754 -228.603302)
		(stroke
			(width 0.05715)
			(type default)
		)
		(layer "In4.Cu")
	)
	(gr_line
		(start 372.680992 -226.982782)
		(end 372.681754 -226.98329)
		(stroke
			(width 0.05715)
			(type default)
		)
		(layer "In4.Cu")
	)
	(gr_line
		(start 372.68658 -235.08589)
		(end 372.687088 -235.086144)
		(stroke
			(width 0.05715)
			(type default)
		)
		(layer "In4.Cu")
	)
	(gr_line
		(start 372.68658 -233.465878)
		(end 372.687088 -233.466132)
		(stroke
			(width 0.05715)
			(type default)
		)
		(layer "In4.Cu")
	)
	(gr_line
		(start 372.68658 -228.606096)
		(end 372.687088 -228.60635)
		(stroke
			(width 0.05715)
			(type default)
		)
		(layer "In4.Cu")
	)
	(gr_line
		(start 372.68658 -226.986084)
		(end 372.687088 -226.986338)
		(stroke
			(width 0.05715)
			(type default)
		)
		(layer "In4.Cu")
	)
	(gr_line
		(start 372.687088 -235.086144)
		(end 372.68785 -235.086652)
		(stroke
			(width 0.05715)
			(type default)
		)
		(layer "In4.Cu")
	)
	(gr_line
		(start 372.687088 -233.466132)
		(end 372.68785 -233.46664)
		(stroke
			(width 0.05715)
			(type default)
		)
		(layer "In4.Cu")
	)
	(gr_line
		(start 372.687088 -228.60635)
		(end 372.68785 -228.606858)
		(stroke
			(width 0.05715)
			(type default)
		)
		(layer "In4.Cu")
	)
	(gr_line
		(start 372.687088 -226.986338)
		(end 372.68785 -226.986846)
		(stroke
			(width 0.05715)
			(type default)
		)
		(layer "In4.Cu")
	)
	(gr_line
		(start 372.68785 -235.086652)
		(end 372.688866 -235.08716)
		(stroke
			(width 0.05715)
			(type default)
		)
		(layer "In4.Cu")
	)
	(gr_line
		(start 372.68785 -233.46664)
		(end 372.688866 -233.467148)
		(stroke
			(width 0.05715)
			(type default)
		)
		(layer "In4.Cu")
	)
	(gr_line
		(start 372.68785 -228.606858)
		(end 372.688866 -228.607366)
		(stroke
			(width 0.05715)
			(type default)
		)
		(layer "In4.Cu")
	)
	(gr_line
		(start 372.68785 -226.986846)
		(end 372.688866 -226.987354)
		(stroke
			(width 0.05715)
			(type default)
		)
		(layer "In4.Cu")
	)
	(gr_line
		(start 372.688866 -235.08716)
		(end 372.69039 -235.088176)
		(stroke
			(width 0.05715)
			(type default)
		)
		(layer "In4.Cu")
	)
	(gr_line
		(start 372.688866 -233.467148)
		(end 372.69039 -233.468164)
		(stroke
			(width 0.05715)
			(type default)
		)
		(layer "In4.Cu")
	)
	(gr_line
		(start 372.688866 -228.607366)
		(end 372.69039 -228.608382)
		(stroke
			(width 0.05715)
			(type default)
		)
		(layer "In4.Cu")
	)
	(gr_line
		(start 372.688866 -226.987354)
		(end 372.69039 -226.98837)
		(stroke
			(width 0.05715)
			(type default)
		)
		(layer "In4.Cu")
	)
	(gr_line
		(start 372.69293 -235.0897)
		(end 372.694454 -235.090462)
		(stroke
			(width 0.05715)
			(type default)
		)
		(layer "In4.Cu")
	)
	(gr_line
		(start 372.69293 -234.438444)
		(end 372.692168 -234.438952)
		(stroke
			(width 0.05715)
			(type default)
		)
		(layer "In4.Cu")
	)
	(gr_line
		(start 372.69293 -233.469688)
		(end 372.694454 -233.47045)
		(stroke
			(width 0.05715)
			(type default)
		)
		(layer "In4.Cu")
	)
	(gr_line
		(start 372.69293 -232.818432)
		(end 372.692168 -232.81894)
		(stroke
			(width 0.05715)
			(type default)
		)
		(layer "In4.Cu")
	)
	(gr_line
		(start 372.69293 -228.609906)
		(end 372.694454 -228.610668)
		(stroke
			(width 0.05715)
			(type default)
		)
		(layer "In4.Cu")
	)
	(gr_line
		(start 372.69293 -227.95865)
		(end 372.692168 -227.959158)
		(stroke
			(width 0.05715)
			(type default)
		)
		(layer "In4.Cu")
	)
	(gr_line
		(start 372.69293 -226.989894)
		(end 372.694454 -226.990656)
		(stroke
			(width 0.05715)
			(type default)
		)
		(layer "In4.Cu")
	)
	(gr_line
		(start 372.69293 -226.338638)
		(end 372.692168 -226.339146)
		(stroke
			(width 0.05715)
			(type default)
		)
		(layer "In4.Cu")
	)
	(gr_line
		(start 372.693946 -234.437936)
		(end 372.69293 -234.438444)
		(stroke
			(width 0.05715)
			(type default)
		)
		(layer "In4.Cu")
	)
	(gr_line
		(start 372.693946 -232.817924)
		(end 372.69293 -232.818432)
		(stroke
			(width 0.05715)
			(type default)
		)
		(layer "In4.Cu")
	)
	(gr_line
		(start 372.693946 -227.958142)
		(end 372.69293 -227.95865)
		(stroke
			(width 0.05715)
			(type default)
		)
		(layer "In4.Cu")
	)
	(gr_line
		(start 372.693946 -226.33813)
		(end 372.69293 -226.338638)
		(stroke
			(width 0.05715)
			(type default)
		)
		(layer "In4.Cu")
	)
	(gr_line
		(start 372.694454 -235.090462)
		(end 372.695216 -235.09097)
		(stroke
			(width 0.05715)
			(type default)
		)
		(layer "In4.Cu")
	)
	(gr_line
		(start 372.694454 -233.47045)
		(end 372.695216 -233.470958)
		(stroke
			(width 0.05715)
			(type default)
		)
		(layer "In4.Cu")
	)
	(gr_line
		(start 372.694454 -228.610668)
		(end 372.695216 -228.611176)
		(stroke
			(width 0.05715)
			(type default)
		)
		(layer "In4.Cu")
	)
	(gr_line
		(start 372.694454 -226.990656)
		(end 372.695216 -226.991164)
		(stroke
			(width 0.05715)
			(type default)
		)
		(layer "In4.Cu")
	)
	(gr_line
		(start 372.695724 -234.43692)
		(end 372.693946 -234.437936)
		(stroke
			(width 0.05715)
			(type default)
		)
		(layer "In4.Cu")
	)
	(gr_line
		(start 372.695724 -232.816908)
		(end 372.693946 -232.817924)
		(stroke
			(width 0.05715)
			(type default)
		)
		(layer "In4.Cu")
	)
	(gr_line
		(start 372.695724 -227.957126)
		(end 372.693946 -227.958142)
		(stroke
			(width 0.05715)
			(type default)
		)
		(layer "In4.Cu")
	)
	(gr_line
		(start 372.695724 -226.337114)
		(end 372.693946 -226.33813)
		(stroke
			(width 0.05715)
			(type default)
		)
		(layer "In4.Cu")
	)
	(gr_line
		(start 372.707662 -393.961112)
		(end 372.760494 -393.930632)
		(stroke
			(width 0.07112)
			(type default)
		)
		(layer "In4.Cu")
	)
	(gr_line
		(start 372.760494 -393.930632)
		(end 372.848632 -393.842494)
		(stroke
			(width 0.07112)
			(type default)
		)
		(layer "In4.Cu")
	)
	(gr_arc
		(start 372.779544 -224.227644)
		(mid 372.779534 -224.230946)
		(end 372.779544 -224.234248)
		(stroke
			(width 0.05715)
			(type default)
		)
		(layer "In4.Cu")
	)
	(gr_line
		(start 372.827296 -293.868856)
		(end 372.892574 -293.847266)
		(stroke
			(width 0.05715)
			(type default)
		)
		(layer "In4.Cu")
	)
	(gr_line
		(start 372.82755 -293.882572)
		(end 372.827296 -293.868856)
		(stroke
			(width 0.05715)
			(type default)
		)
		(layer "In4.Cu")
	)
	(gr_line
		(start 372.845584 -296.43959)
		(end 372.845584 -296.411142)
		(stroke
			(width 0.05715)
			(type default)
		)
		(layer "In4.Cu")
	)
	(gr_line
		(start 372.845584 -296.411142)
		(end 372.799864 -296.365422)
		(stroke
			(width 0.05715)
			(type default)
		)
		(layer "In4.Cu")
	)
	(gr_line
		(start 372.848632 -393.842494)
		(end 372.848632 -393.716764)
		(stroke
			(width 0.07112)
			(type default)
		)
		(layer "In4.Cu")
	)
	(gr_arc
		(start 372.853204 -295.4909)
		(mid 372.845538 -295.496297)
		(end 372.837964 -295.501822)
		(stroke
			(width 0.05715)
			(type default)
		)
		(layer "In4.Cu")
	)
	(gr_arc
		(start 372.853204 -295.4909)
		(mid 372.853585 -295.490646)
		(end 372.853966 -295.490392)
		(stroke
			(width 0.05715)
			(type default)
		)
		(layer "In4.Cu")
	)
	(gr_line
		(start 372.853966 -295.490392)
		(end 372.86057 -295.486582)
		(stroke
			(width 0.05715)
			(type default)
		)
		(layer "In4.Cu")
	)
	(gr_line
		(start 372.858538 -386.081524)
		(end 372.556532 -385.779518)
		(stroke
			(width 0.07112)
			(type default)
		)
		(layer "In4.Cu")
	)
	(gr_line
		(start 372.87327 -292.237922)
		(end 372.874286 -292.236906)
		(stroke
			(width 0.05715)
			(type default)
		)
		(layer "In4.Cu")
	)
	(gr_line
		(start 372.874286 -292.236906)
		(end 372.88724 -292.230302)
		(stroke
			(width 0.05715)
			(type default)
		)
		(layer "In4.Cu")
	)
	(gr_line
		(start 372.874794 -236.384084)
		(end 373.172736 -236.384084)
		(stroke
			(width 0.05715)
			(type default)
		)
		(layer "In4.Cu")
	)
	(gr_line
		(start 372.874794 -234.764072)
		(end 373.172736 -234.764072)
		(stroke
			(width 0.05715)
			(type default)
		)
		(layer "In4.Cu")
	)
	(gr_line
		(start 372.874794 -233.14406)
		(end 373.172736 -233.14406)
		(stroke
			(width 0.05715)
			(type default)
		)
		(layer "In4.Cu")
	)
	(gr_line
		(start 372.877588 -291.574728)
		(end 372.876318 -291.573712)
		(stroke
			(width 0.05715)
			(type default)
		)
		(layer "In4.Cu")
	)
	(gr_line
		(start 372.881144 -291.57676)
		(end 372.87835 -291.575236)
		(stroke
			(width 0.05715)
			(type default)
		)
		(layer "In4.Cu")
	)
	(gr_line
		(start 372.883176 -288.99358)
		(end 372.88724 -288.99104)
		(stroke
			(width 0.05715)
			(type default)
		)
		(layer "In4.Cu")
	)
	(gr_line
		(start 372.88343 -291.578284)
		(end 372.881906 -291.577268)
		(stroke
			(width 0.05715)
			(type default)
		)
		(layer "In4.Cu")
	)
	(gr_line
		(start 372.8847 -291.579046)
		(end 372.88343 -291.578284)
		(stroke
			(width 0.05715)
			(type default)
		)
		(layer "In4.Cu")
	)
	(gr_line
		(start 372.886986 -291.58057)
		(end 372.885716 -291.579808)
		(stroke
			(width 0.05715)
			(type default)
		)
		(layer "In4.Cu")
	)
	(gr_line
		(start 372.889272 -291.58184)
		(end 372.888256 -291.581332)
		(stroke
			(width 0.05715)
			(type default)
		)
		(layer "In4.Cu")
	)
	(gr_line
		(start 372.889272 -288.990024)
		(end 372.889526 -288.98977)
		(stroke
			(width 0.05715)
			(type default)
		)
		(layer "In4.Cu")
	)
	(gr_line
		(start 372.889526 -294.822118)
		(end 372.884446 -294.818562)
		(stroke
			(width 0.05715)
			(type default)
		)
		(layer "In4.Cu")
	)
	(gr_line
		(start 372.889526 -288.98977)
		(end 372.890796 -288.989008)
		(stroke
			(width 0.05715)
			(type default)
		)
		(layer "In4.Cu")
	)
	(gr_line
		(start 372.890796 -294.82288)
		(end 372.889526 -294.822118)
		(stroke
			(width 0.05715)
			(type default)
		)
		(layer "In4.Cu")
	)
	(gr_line
		(start 372.890796 -291.582856)
		(end 372.889272 -291.58184)
		(stroke
			(width 0.05715)
			(type default)
		)
		(layer "In4.Cu")
	)
	(gr_line
		(start 372.890796 -288.989008)
		(end 372.891812 -288.9885)
		(stroke
			(width 0.05715)
			(type default)
		)
		(layer "In4.Cu")
	)
	(gr_line
		(start 372.891812 -294.823388)
		(end 372.890796 -294.82288)
		(stroke
			(width 0.05715)
			(type default)
		)
		(layer "In4.Cu")
	)
	(gr_line
		(start 372.891812 -291.583364)
		(end 372.890796 -291.582856)
		(stroke
			(width 0.05715)
			(type default)
		)
		(layer "In4.Cu")
	)
	(gr_line
		(start 372.891812 -288.9885)
		(end 372.892574 -288.987992)
		(stroke
			(width 0.05715)
			(type default)
		)
		(layer "In4.Cu")
	)
	(gr_line
		(start 372.892574 -294.823896)
		(end 372.891812 -294.823388)
		(stroke
			(width 0.05715)
			(type default)
		)
		(layer "In4.Cu")
	)
	(gr_line
		(start 372.892574 -292.228016)
		(end 372.893844 -292.227254)
		(stroke
			(width 0.05715)
			(type default)
		)
		(layer "In4.Cu")
	)
	(gr_line
		(start 372.892574 -292.227762)
		(end 372.892574 -292.228016)
		(stroke
			(width 0.05715)
			(type default)
		)
		(layer "In4.Cu")
	)
	(gr_line
		(start 372.892574 -291.583872)
		(end 372.891812 -291.583364)
		(stroke
			(width 0.05715)
			(type default)
		)
		(layer "In4.Cu")
	)
	(gr_line
		(start 372.893844 -294.824658)
		(end 372.892574 -294.823896)
		(stroke
			(width 0.05715)
			(type default)
		)
		(layer "In4.Cu")
	)
	(gr_line
		(start 372.893844 -293.204646)
		(end 372.892574 -293.203884)
		(stroke
			(width 0.05715)
			(type default)
		)
		(layer "In4.Cu")
	)
	(gr_line
		(start 372.895368 -292.226492)
		(end 372.89613 -292.225984)
		(stroke
			(width 0.05715)
			(type default)
		)
		(layer "In4.Cu")
	)
	(gr_line
		(start 372.897654 -292.225222)
		(end 372.898416 -292.224714)
		(stroke
			(width 0.05715)
			(type default)
		)
		(layer "In4.Cu")
	)
	(gr_line
		(start 372.898162 -288.984944)
		(end 372.898924 -288.984436)
		(stroke
			(width 0.05715)
			(type default)
		)
		(layer "In4.Cu")
	)
	(gr_line
		(start 372.898924 -291.587428)
		(end 372.897908 -291.58692)
		(stroke
			(width 0.05715)
			(type default)
		)
		(layer "In4.Cu")
	)
	(gr_line
		(start 372.898924 -288.984436)
		(end 372.901718 -288.982912)
		(stroke
			(width 0.05715)
			(type default)
		)
		(layer "In4.Cu")
	)
	(gr_line
		(start 372.899432 -291.587682)
		(end 372.898924 -291.587428)
		(stroke
			(width 0.05715)
			(type default)
		)
		(layer "In4.Cu")
	)
	(gr_line
		(start 372.901718 -288.982912)
		(end 372.901718 -288.982658)
		(stroke
			(width 0.05715)
			(type default)
		)
		(layer "In4.Cu")
	)
	(gr_line
		(start 372.901718 -288.982658)
		(end 372.902226 -288.98215)
		(stroke
			(width 0.05715)
			(type default)
		)
		(layer "In4.Cu")
	)
	(gr_arc
		(start 372.950232 -294.0304)
		(mid 372.946918 -294.032796)
		(end 372.943628 -294.035226)
		(stroke
			(width 0.05715)
			(type default)
		)
		(layer "In4.Cu")
	)
	(gr_line
		(start 372.962678 -294.025066)
		(end 372.974616 -294.021002)
		(stroke
			(width 0.05715)
			(type default)
		)
		(layer "In4.Cu")
	)
	(gr_line
		(start 372.96598 -292.405816)
		(end 372.970552 -292.403276)
		(stroke
			(width 0.05715)
			(type default)
		)
		(layer "In4.Cu")
	)
	(gr_arc
		(start 372.970044 -224.240852)
		(mid 372.970054 -224.23755)
		(end 372.970044 -224.234248)
		(stroke
			(width 0.05715)
			(type default)
		)
		(layer "In4.Cu")
	)
	(gr_line
		(start 372.974616 -294.021002)
		(end 372.976394 -294.019986)
		(stroke
			(width 0.05715)
			(type default)
		)
		(layer "In4.Cu")
	)
	(gr_line
		(start 372.976394 -294.019986)
		(end 372.977664 -294.019224)
		(stroke
			(width 0.05715)
			(type default)
		)
		(layer "In4.Cu")
	)
	(gr_line
		(start 372.977664 -294.019224)
		(end 372.978426 -294.018716)
		(stroke
			(width 0.05715)
			(type default)
		)
		(layer "In4.Cu")
	)
	(gr_line
		(start 372.977664 -289.159188)
		(end 372.978426 -289.15868)
		(stroke
			(width 0.05715)
			(type default)
		)
		(layer "In4.Cu")
	)
	(gr_line
		(start 372.978172 -292.399212)
		(end 372.979442 -292.398704)
		(stroke
			(width 0.05715)
			(type default)
		)
		(layer "In4.Cu")
	)
	(gr_line
		(start 372.978426 -294.018716)
		(end 372.97995 -294.017954)
		(stroke
			(width 0.05715)
			(type default)
		)
		(layer "In4.Cu")
	)
	(gr_line
		(start 372.978426 -289.15868)
		(end 372.979442 -289.158172)
		(stroke
			(width 0.05715)
			(type default)
		)
		(layer "In4.Cu")
	)
	(gr_line
		(start 372.979442 -292.398704)
		(end 372.980204 -292.398196)
		(stroke
			(width 0.05715)
			(type default)
		)
		(layer "In4.Cu")
	)
	(gr_line
		(start 372.97995 -294.017954)
		(end 372.98122 -294.017192)
		(stroke
			(width 0.05715)
			(type default)
		)
		(layer "In4.Cu")
	)
	(gr_line
		(start 372.980204 -292.398196)
		(end 372.981474 -292.397434)
		(stroke
			(width 0.05715)
			(type default)
		)
		(layer "In4.Cu")
	)
	(gr_line
		(start 372.98249 -294.01643)
		(end 372.983506 -294.015922)
		(stroke
			(width 0.05715)
			(type default)
		)
		(layer "In4.Cu")
	)
	(gr_line
		(start 372.982744 -292.396672)
		(end 372.985792 -292.39464)
		(stroke
			(width 0.05715)
			(type default)
		)
		(layer "In4.Cu")
	)
	(gr_line
		(start 372.983506 -294.015922)
		(end 372.984268 -294.015414)
		(stroke
			(width 0.05715)
			(type default)
		)
		(layer "In4.Cu")
	)
	(gr_line
		(start 372.984268 -294.015414)
		(end 372.987062 -294.01389)
		(stroke
			(width 0.05715)
			(type default)
		)
		(layer "In4.Cu")
	)
	(gr_line
		(start 372.985284 -289.15487)
		(end 372.987062 -289.153854)
		(stroke
			(width 0.05715)
			(type default)
		)
		(layer "In4.Cu")
	)
	(gr_line
		(start 372.985792 -292.39464)
		(end 372.987062 -292.393878)
		(stroke
			(width 0.05715)
			(type default)
		)
		(layer "In4.Cu")
	)
	(gr_line
		(start 372.987062 -294.01389)
		(end 372.987824 -294.013382)
		(stroke
			(width 0.05715)
			(type default)
		)
		(layer "In4.Cu")
	)
	(gr_line
		(start 372.987062 -292.393878)
		(end 372.987824 -292.39337)
		(stroke
			(width 0.05715)
			(type default)
		)
		(layer "In4.Cu")
	)
	(gr_line
		(start 372.987062 -291.41801)
		(end 372.986554 -291.417756)
		(stroke
			(width 0.05715)
			(type default)
		)
		(layer "In4.Cu")
	)
	(gr_line
		(start 372.987824 -294.013382)
		(end 372.98884 -294.012874)
		(stroke
			(width 0.05715)
			(type default)
		)
		(layer "In4.Cu")
	)
	(gr_line
		(start 372.987824 -293.03853)
		(end 372.987316 -293.038276)
		(stroke
			(width 0.05715)
			(type default)
		)
		(layer "In4.Cu")
	)
	(gr_line
		(start 372.987824 -292.39337)
		(end 372.98884 -292.392862)
		(stroke
			(width 0.05715)
			(type default)
		)
		(layer "In4.Cu")
	)
	(gr_line
		(start 372.987824 -291.418518)
		(end 372.987062 -291.41801)
		(stroke
			(width 0.05715)
			(type default)
		)
		(layer "In4.Cu")
	)
	(gr_line
		(start 372.98884 -294.012874)
		(end 372.990364 -294.011858)
		(stroke
			(width 0.05715)
			(type default)
		)
		(layer "In4.Cu")
	)
	(gr_line
		(start 372.98884 -293.039038)
		(end 372.987824 -293.03853)
		(stroke
			(width 0.05715)
			(type default)
		)
		(layer "In4.Cu")
	)
	(gr_line
		(start 372.98884 -292.392862)
		(end 372.990364 -292.391846)
		(stroke
			(width 0.05715)
			(type default)
		)
		(layer "In4.Cu")
	)
	(gr_line
		(start 372.98884 -291.419026)
		(end 372.987824 -291.418518)
		(stroke
			(width 0.05715)
			(type default)
		)
		(layer "In4.Cu")
	)
	(gr_line
		(start 372.989094 -289.152838)
		(end 372.990364 -289.152076)
		(stroke
			(width 0.05715)
			(type default)
		)
		(layer "In4.Cu")
	)
	(gr_line
		(start 372.990364 -294.011858)
		(end 372.992142 -294.010842)
		(stroke
			(width 0.05715)
			(type default)
		)
		(layer "In4.Cu")
	)
	(gr_line
		(start 372.990618 -291.420042)
		(end 372.98884 -291.419026)
		(stroke
			(width 0.05715)
			(type default)
		)
		(layer "In4.Cu")
	)
	(gr_line
		(start 372.993158 -291.421566)
		(end 372.992142 -291.421058)
		(stroke
			(width 0.05715)
			(type default)
		)
		(layer "In4.Cu")
	)
	(gr_line
		(start 372.993412 -289.150298)
		(end 372.994936 -289.149282)
		(stroke
			(width 0.05715)
			(type default)
		)
		(layer "In4.Cu")
	)
	(gr_line
		(start 372.994174 -291.422328)
		(end 372.993158 -291.421566)
		(stroke
			(width 0.05715)
			(type default)
		)
		(layer "In4.Cu")
	)
	(gr_line
		(start 373.000016 -289.146488)
		(end 373.001794 -289.145472)
		(stroke
			(width 0.05715)
			(type default)
		)
		(layer "In4.Cu")
	)
	(gr_line
		(start 373.002302 -289.145218)
		(end 373.004334 -289.143948)
		(stroke
			(width 0.05715)
			(type default)
		)
		(layer "In4.Cu")
	)
	(gr_line
		(start 373.005096 -289.143694)
		(end 373.007382 -289.14217)
		(stroke
			(width 0.05715)
			(type default)
		)
		(layer "In4.Cu")
	)
	(gr_line
		(start 373.01932 -291.436806)
		(end 373.018812 -291.436552)
		(stroke
			(width 0.05715)
			(type default)
		)
		(layer "In4.Cu")
	)
	(gr_line
		(start 373.020082 -291.437314)
		(end 373.01932 -291.436806)
		(stroke
			(width 0.05715)
			(type default)
		)
		(layer "In4.Cu")
	)
	(gr_line
		(start 373.02694 -291.441378)
		(end 373.020082 -291.437314)
		(stroke
			(width 0.05715)
			(type default)
		)
		(layer "In4.Cu")
	)
	(gr_arc
		(start 373.034814 -291.446966)
		(mid 373.030889 -291.444155)
		(end 373.02694 -291.441378)
		(stroke
			(width 0.05715)
			(type default)
		)
		(layer "In4.Cu")
	)
	(gr_line
		(start 373.050562 -386.081524)
		(end 372.858538 -386.081524)
		(stroke
			(width 0.07112)
			(type default)
		)
		(layer "In4.Cu")
	)
	(gr_line
		(start 373.079772 -295.146222)
		(end 373.079772 -295.145968)
		(stroke
			(width 0.05715)
			(type default)
		)
		(layer "In4.Cu")
	)
	(gr_line
		(start 373.081804 -333.301848)
		(end 373.081804 -333.301594)
		(stroke
			(width 0.07112)
			(type default)
		)
		(layer "In4.Cu")
	)
	(gr_line
		(start 373.15648 -411.132274)
		(end 372.976902 -411.062932)
		(stroke
			(width 0.07112)
			(type default)
		)
		(layer "In4.Cu")
	)
	(gr_line
		(start 373.167148 -351.372932)
		(end 373.167148 -351.373186)
		(stroke
			(width 0.07112)
			(type default)
		)
		(layer "In4.Cu")
	)
	(gr_line
		(start 373.172736 -236.384084)
		(end 373.242078 -236.314742)
		(stroke
			(width 0.05715)
			(type default)
		)
		(layer "In4.Cu")
	)
	(gr_line
		(start 373.172736 -234.764072)
		(end 373.25554 -234.681268)
		(stroke
			(width 0.05715)
			(type default)
		)
		(layer "In4.Cu")
	)
	(gr_line
		(start 373.172736 -233.14406)
		(end 373.25554 -233.061256)
		(stroke
			(width 0.05715)
			(type default)
		)
		(layer "In4.Cu")
	)
	(gr_line
		(start 373.203724 -221.202758)
		(end 373.203724 -221.17431)
		(stroke
			(width 0.05715)
			(type default)
		)
		(layer "In4.Cu")
	)
	(gr_arc
		(start 373.219472 -348.304612)
		(mid 373.220249 -348.300424)
		(end 373.220996 -348.29623)
		(stroke
			(width 0.07112)
			(type default)
		)
		(layer "In4.Cu")
	)
	(gr_arc
		(start 373.231664 -348.187772)
		(mid 373.231664 -348.188153)
		(end 373.231664 -348.188534)
		(stroke
			(width 0.07112)
			(type default)
		)
		(layer "In4.Cu")
	)
	(gr_line
		(start 373.231664 -337.919822)
		(end 373.231664 -337.92033)
		(stroke
			(width 0.07112)
			(type default)
		)
		(layer "In4.Cu")
	)
	(gr_arc
		(start 373.249444 -223.417638)
		(mid 373.249434 -223.42094)
		(end 373.249444 -223.424242)
		(stroke
			(width 0.05715)
			(type default)
		)
		(layer "In4.Cu")
	)
	(gr_line
		(start 373.249444 -221.248478)
		(end 373.203724 -221.202758)
		(stroke
			(width 0.05715)
			(type default)
		)
		(layer "In4.Cu")
	)
	(gr_line
		(start 373.25173 -385.882134)
		(end 372.755922 -385.386326)
		(stroke
			(width 0.07112)
			(type default)
		)
		(layer "In4.Cu")
	)
	(gr_arc
		(start 373.25935 -234.658408)
		(mid 373.257329 -234.669819)
		(end 373.25554 -234.681268)
		(stroke
			(width 0.05715)
			(type default)
		)
		(layer "In4.Cu")
	)
	(gr_arc
		(start 373.25935 -233.038396)
		(mid 373.257329 -233.049807)
		(end 373.25554 -233.061256)
		(stroke
			(width 0.05715)
			(type default)
		)
		(layer "In4.Cu")
	)
	(gr_line
		(start 373.270272 -295.146476)
		(end 373.270272 -295.145968)
		(stroke
			(width 0.05715)
			(type default)
		)
		(layer "In4.Cu")
	)
	(gr_line
		(start 373.291354 -393.69238)
		(end 373.644414 -393.787376)
		(stroke
			(width 0.07112)
			(type default)
		)
		(layer "In4.Cu")
	)
	(gr_line
		(start 373.348758 -333.210662)
		(end 373.348758 -333.210408)
		(stroke
			(width 0.07112)
			(type default)
		)
		(layer "In4.Cu")
	)
	(gr_arc
		(start 373.434102 -236.30128)
		(mid 373.432314 -236.28983)
		(end 373.430292 -236.27842)
		(stroke
			(width 0.05715)
			(type default)
		)
		(layer "In4.Cu")
	)
	(gr_line
		(start 373.434102 -236.30128)
		(end 373.516906 -236.384084)
		(stroke
			(width 0.05715)
			(type default)
		)
		(layer "In4.Cu")
	)
	(gr_arc
		(start 373.439944 -223.430846)
		(mid 373.439954 -223.427544)
		(end 373.439944 -223.424242)
		(stroke
			(width 0.05715)
			(type default)
		)
		(layer "In4.Cu")
	)
	(gr_line
		(start 373.447564 -234.69473)
		(end 373.516906 -234.764072)
		(stroke
			(width 0.05715)
			(type default)
		)
		(layer "In4.Cu")
	)
	(gr_line
		(start 373.447564 -233.074718)
		(end 373.516906 -233.14406)
		(stroke
			(width 0.05715)
			(type default)
		)
		(layer "In4.Cu")
	)
	(gr_line
		(start 373.47271 -291.095938)
		(end 373.174768 -291.095938)
		(stroke
			(width 0.05715)
			(type default)
		)
		(layer "In4.Cu")
	)
	(gr_line
		(start 373.47271 -289.475926)
		(end 373.174768 -289.475926)
		(stroke
			(width 0.05715)
			(type default)
		)
		(layer "In4.Cu")
	)
	(gr_line
		(start 373.47271 -287.856168)
		(end 373.174768 -287.856168)
		(stroke
			(width 0.05715)
			(type default)
		)
		(layer "In4.Cu")
	)
	(gr_line
		(start 373.47271 -286.236156)
		(end 373.174768 -286.236156)
		(stroke
			(width 0.05715)
			(type default)
		)
		(layer "In4.Cu")
	)
	(gr_line
		(start 373.485664 -221.202758)
		(end 373.439944 -221.248478)
		(stroke
			(width 0.05715)
			(type default)
		)
		(layer "In4.Cu")
	)
	(gr_line
		(start 373.485664 -221.17431)
		(end 373.485664 -221.202758)
		(stroke
			(width 0.05715)
			(type default)
		)
		(layer "In4.Cu")
	)
	(gr_arc
		(start 373.492776 -224.579688)
		(mid 373.488827 -224.582465)
		(end 373.484902 -224.585276)
		(stroke
			(width 0.05715)
			(type default)
		)
		(layer "In4.Cu")
	)
	(gr_line
		(start 373.492776 -224.579688)
		(end 373.493792 -224.578926)
		(stroke
			(width 0.05715)
			(type default)
		)
		(layer "In4.Cu")
	)
	(gr_line
		(start 373.493792 -224.578926)
		(end 373.500396 -224.575116)
		(stroke
			(width 0.05715)
			(type default)
		)
		(layer "In4.Cu")
	)
	(gr_arc
		(start 373.49938 -288.318956)
		(mid 373.50218 -288.316932)
		(end 373.504968 -288.314892)
		(stroke
			(width 0.05715)
			(type default)
		)
		(layer "In4.Cu")
	)
	(gr_line
		(start 373.502428 -410.520134)
		(end 372.861078 -410.804614)
		(stroke
			(width 0.07112)
			(type default)
		)
		(layer "In4.Cu")
	)
	(gr_line
		(start 373.503952 -296.350944)
		(end 373.503952 -296.322496)
		(stroke
			(width 0.05715)
			(type default)
		)
		(layer "In4.Cu")
	)
	(gr_line
		(start 373.503952 -296.322496)
		(end 373.549672 -296.276776)
		(stroke
			(width 0.05715)
			(type default)
		)
		(layer "In4.Cu")
	)
	(gr_line
		(start 373.516906 -236.384084)
		(end 373.814848 -236.384084)
		(stroke
			(width 0.05715)
			(type default)
		)
		(layer "In4.Cu")
	)
	(gr_line
		(start 373.516906 -234.764072)
		(end 373.814848 -234.764072)
		(stroke
			(width 0.05715)
			(type default)
		)
		(layer "In4.Cu")
	)
	(gr_line
		(start 373.516906 -233.14406)
		(end 373.814848 -233.14406)
		(stroke
			(width 0.05715)
			(type default)
		)
		(layer "In4.Cu")
	)
	(gr_line
		(start 373.52478 -232.660952)
		(end 373.529352 -232.658158)
		(stroke
			(width 0.05715)
			(type default)
		)
		(layer "In4.Cu")
	)
	(gr_line
		(start 373.52478 -227.80117)
		(end 373.529352 -227.798376)
		(stroke
			(width 0.05715)
			(type default)
		)
		(layer "In4.Cu")
	)
	(gr_line
		(start 373.52478 -226.181158)
		(end 373.525542 -226.18065)
		(stroke
			(width 0.05715)
			(type default)
		)
		(layer "In4.Cu")
	)
	(gr_line
		(start 373.528336 -226.178872)
		(end 373.529352 -226.178364)
		(stroke
			(width 0.05715)
			(type default)
		)
		(layer "In4.Cu")
	)
	(gr_line
		(start 373.529352 -232.658158)
		(end 373.530876 -232.657142)
		(stroke
			(width 0.05715)
			(type default)
		)
		(layer "In4.Cu")
	)
	(gr_line
		(start 373.529352 -227.798376)
		(end 373.530876 -227.79736)
		(stroke
			(width 0.05715)
			(type default)
		)
		(layer "In4.Cu")
	)
	(gr_line
		(start 373.529352 -226.178364)
		(end 373.530876 -226.177348)
		(stroke
			(width 0.05715)
			(type default)
		)
		(layer "In4.Cu")
	)
	(gr_line
		(start 373.530876 -234.277154)
		(end 373.531892 -234.276646)
		(stroke
			(width 0.05715)
			(type default)
		)
		(layer "In4.Cu")
	)
	(gr_line
		(start 373.530876 -232.657142)
		(end 373.531892 -232.656634)
		(stroke
			(width 0.05715)
			(type default)
		)
		(layer "In4.Cu")
	)
	(gr_line
		(start 373.530876 -227.79736)
		(end 373.531892 -227.796852)
		(stroke
			(width 0.05715)
			(type default)
		)
		(layer "In4.Cu")
	)
	(gr_line
		(start 373.530876 -226.177348)
		(end 373.531892 -226.17684)
		(stroke
			(width 0.05715)
			(type default)
		)
		(layer "In4.Cu")
	)
	(gr_line
		(start 373.531892 -234.276646)
		(end 373.5324 -234.276646)
		(stroke
			(width 0.05715)
			(type default)
		)
		(layer "In4.Cu")
	)
	(gr_line
		(start 373.531892 -232.656634)
		(end 373.532654 -232.656126)
		(stroke
			(width 0.05715)
			(type default)
		)
		(layer "In4.Cu")
	)
	(gr_line
		(start 373.531892 -228.771704)
		(end 373.530876 -228.771196)
		(stroke
			(width 0.05715)
			(type default)
		)
		(layer "In4.Cu")
	)
	(gr_line
		(start 373.531892 -227.151692)
		(end 373.530876 -227.151184)
		(stroke
			(width 0.05715)
			(type default)
		)
		(layer "In4.Cu")
	)
	(gr_line
		(start 373.531892 -226.17684)
		(end 373.532654 -226.176332)
		(stroke
			(width 0.05715)
			(type default)
		)
		(layer "In4.Cu")
	)
	(gr_line
		(start 373.531892 -222.936562)
		(end 373.5324 -222.936308)
		(stroke
			(width 0.05715)
			(type default)
		)
		(layer "In4.Cu")
	)
	(gr_line
		(start 373.5324 -222.936308)
		(end 373.532908 -222.936054)
		(stroke
			(width 0.05715)
			(type default)
		)
		(layer "In4.Cu")
	)
	(gr_line
		(start 373.535956 -230.396796)
		(end 373.531638 -230.394256)
		(stroke
			(width 0.05715)
			(type default)
		)
		(layer "In4.Cu")
	)
	(gr_line
		(start 373.542052 -287.92551)
		(end 373.47271 -287.856168)
		(stroke
			(width 0.05715)
			(type default)
		)
		(layer "In4.Cu")
	)
	(gr_line
		(start 373.546878 -410.9593)
		(end 373.15648 -411.132274)
		(stroke
			(width 0.07112)
			(type default)
		)
		(layer "In4.Cu")
	)
	(gr_line
		(start 373.555514 -291.178742)
		(end 373.47271 -291.095938)
		(stroke
			(width 0.05715)
			(type default)
		)
		(layer "In4.Cu")
	)
	(gr_line
		(start 373.555514 -289.55873)
		(end 373.47271 -289.475926)
		(stroke
			(width 0.05715)
			(type default)
		)
		(layer "In4.Cu")
	)
	(gr_arc
		(start 373.555514 -289.55873)
		(mid 373.557305 -289.570052)
		(end 373.559324 -289.581336)
		(stroke
			(width 0.05715)
			(type default)
		)
		(layer "In4.Cu")
	)
	(gr_line
		(start 373.555514 -286.31896)
		(end 373.47271 -286.236156)
		(stroke
			(width 0.05715)
			(type default)
		)
		(layer "In4.Cu")
	)
	(gr_arc
		(start 373.555514 -286.31896)
		(mid 373.5573 -286.33041)
		(end 373.559324 -286.34182)
		(stroke
			(width 0.05715)
			(type default)
		)
		(layer "In4.Cu")
	)
	(gr_line
		(start 373.555768 -291.178742)
		(end 373.555514 -291.178742)
		(stroke
			(width 0.05715)
			(type default)
		)
		(layer "In4.Cu")
	)
	(gr_arc
		(start 373.555768 -291.178742)
		(mid 373.557559 -291.189937)
		(end 373.559578 -291.201094)
		(stroke
			(width 0.05715)
			(type default)
		)
		(layer "In4.Cu")
	)
	(gr_line
		(start 373.596408 -229.599744)
		(end 373.596154 -229.599998)
		(stroke
			(width 0.05715)
			(type default)
		)
		(layer "In4.Cu")
	)
	(gr_line
		(start 373.615966 -410.779722)
		(end 373.546878 -410.9593)
		(stroke
			(width 0.07112)
			(type default)
		)
		(layer "In4.Cu")
	)
	(gr_line
		(start 373.625872 -228.605588)
		(end 373.627142 -228.60635)
		(stroke
			(width 0.05715)
			(type default)
		)
		(layer "In4.Cu")
	)
	(gr_line
		(start 373.625872 -226.985576)
		(end 373.627142 -226.986338)
		(stroke
			(width 0.05715)
			(type default)
		)
		(layer "In4.Cu")
	)
	(gr_line
		(start 373.627142 -234.442)
		(end 373.625872 -234.442762)
		(stroke
			(width 0.05715)
			(type default)
		)
		(layer "In4.Cu")
	)
	(gr_line
		(start 373.627142 -232.821988)
		(end 373.625364 -232.823004)
		(stroke
			(width 0.05715)
			(type default)
		)
		(layer "In4.Cu")
	)
	(gr_line
		(start 373.627142 -228.60635)
		(end 373.627904 -228.606858)
		(stroke
			(width 0.05715)
			(type default)
		)
		(layer "In4.Cu")
	)
	(gr_line
		(start 373.627142 -227.962206)
		(end 373.625364 -227.963222)
		(stroke
			(width 0.05715)
			(type default)
		)
		(layer "In4.Cu")
	)
	(gr_line
		(start 373.627142 -226.986338)
		(end 373.627904 -226.986846)
		(stroke
			(width 0.05715)
			(type default)
		)
		(layer "In4.Cu")
	)
	(gr_line
		(start 373.627142 -226.342194)
		(end 373.625364 -226.34321)
		(stroke
			(width 0.05715)
			(type default)
		)
		(layer "In4.Cu")
	)
	(gr_line
		(start 373.62765 -227.961952)
		(end 373.627142 -227.962206)
		(stroke
			(width 0.05715)
			(type default)
		)
		(layer "In4.Cu")
	)
	(gr_line
		(start 373.627904 -234.441492)
		(end 373.627142 -234.442)
		(stroke
			(width 0.05715)
			(type default)
		)
		(layer "In4.Cu")
	)
	(gr_line
		(start 373.627904 -226.341686)
		(end 373.627142 -226.342194)
		(stroke
			(width 0.05715)
			(type default)
		)
		(layer "In4.Cu")
	)
	(gr_line
		(start 373.628666 -232.820972)
		(end 373.627142 -232.821988)
		(stroke
			(width 0.05715)
			(type default)
		)
		(layer "In4.Cu")
	)
	(gr_line
		(start 373.631206 -232.819702)
		(end 373.628666 -232.820972)
		(stroke
			(width 0.05715)
			(type default)
		)
		(layer "In4.Cu")
	)
	(gr_arc
		(start 373.631206 -232.819702)
		(mid 373.631968 -232.819195)
		(end 373.63273 -232.818686)
		(stroke
			(width 0.05715)
			(type default)
		)
		(layer "In4.Cu")
	)
	(gr_line
		(start 373.636794 -223.096582)
		(end 373.634762 -223.097598)
		(stroke
			(width 0.05715)
			(type default)
		)
		(layer "In4.Cu")
	)
	(gr_line
		(start 373.644414 -393.787376)
		(end 373.644922 -393.786868)
		(stroke
			(width 0.07112)
			(type default)
		)
		(layer "In4.Cu")
	)
	(gr_line
		(start 373.647208 -320.445892)
		(end 373.647462 -320.446146)
		(stroke
			(width 0.07112)
			(type default)
		)
		(layer "In4.Cu")
	)
	(gr_line
		(start 373.69115 -394.385292)
		(end 373.785892 -394.031724)
		(stroke
			(width 0.07112)
			(type default)
		)
		(layer "In4.Cu")
	)
	(gr_arc
		(start 373.730266 -287.961832)
		(mid 373.732288 -287.950421)
		(end 373.734076 -287.938972)
		(stroke
			(width 0.05715)
			(type default)
		)
		(layer "In4.Cu")
	)
	(gr_line
		(start 373.734076 -287.938972)
		(end 373.81688 -287.856168)
		(stroke
			(width 0.05715)
			(type default)
		)
		(layer "In4.Cu")
	)
	(gr_line
		(start 373.747538 -289.545268)
		(end 373.81688 -289.475926)
		(stroke
			(width 0.05715)
			(type default)
		)
		(layer "In4.Cu")
	)
	(gr_line
		(start 373.747538 -286.305498)
		(end 373.81688 -286.236156)
		(stroke
			(width 0.05715)
			(type default)
		)
		(layer "In4.Cu")
	)
	(gr_line
		(start 373.747792 -291.165026)
		(end 373.81688 -291.095938)
		(stroke
			(width 0.05715)
			(type default)
		)
		(layer "In4.Cu")
	)
	(gr_line
		(start 373.75846 -391.19429)
		(end 373.758206 -391.194544)
		(stroke
			(width 0.07112)
			(type default)
		)
		(layer "In4.Cu")
	)
	(gr_arc
		(start 373.784622 -289.934904)
		(mid 373.788674 -289.937716)
		(end 373.79275 -289.940492)
		(stroke
			(width 0.05715)
			(type default)
		)
		(layer "In4.Cu")
	)
	(gr_line
		(start 373.785892 -296.350944)
		(end 373.785892 -296.322496)
		(stroke
			(width 0.05715)
			(type default)
		)
		(layer "In4.Cu")
	)
	(gr_line
		(start 373.785892 -296.322496)
		(end 373.740172 -296.276776)
		(stroke
			(width 0.05715)
			(type default)
		)
		(layer "In4.Cu")
	)
	(gr_arc
		(start 373.793512 -289.941)
		(mid 373.793131 -289.940746)
		(end 373.79275 -289.940492)
		(stroke
			(width 0.05715)
			(type default)
		)
		(layer "In4.Cu")
	)
	(gr_line
		(start 373.800624 -289.945064)
		(end 373.793512 -289.941)
		(stroke
			(width 0.05715)
			(type default)
		)
		(layer "In4.Cu")
	)
	(gr_line
		(start 373.81688 -291.095938)
		(end 374.114822 -291.095938)
		(stroke
			(width 0.05715)
			(type default)
		)
		(layer "In4.Cu")
	)
	(gr_line
		(start 373.81688 -289.475926)
		(end 374.114822 -289.475926)
		(stroke
			(width 0.05715)
			(type default)
		)
		(layer "In4.Cu")
	)
	(gr_line
		(start 373.81688 -287.856168)
		(end 374.114822 -287.856168)
		(stroke
			(width 0.05715)
			(type default)
		)
		(layer "In4.Cu")
	)
	(gr_line
		(start 373.81688 -286.236156)
		(end 374.114822 -286.236156)
		(stroke
			(width 0.05715)
			(type default)
		)
		(layer "In4.Cu")
	)
	(gr_line
		(start 373.83085 -293.849044)
		(end 373.831866 -293.848536)
		(stroke
			(width 0.05715)
			(type default)
		)
		(layer "In4.Cu")
	)
	(gr_line
		(start 373.831866 -293.848536)
		(end 373.832374 -293.848282)
		(stroke
			(width 0.05715)
			(type default)
		)
		(layer "In4.Cu")
	)
	(gr_line
		(start 373.832374 -289.963606)
		(end 373.831612 -289.963098)
		(stroke
			(width 0.05715)
			(type default)
		)
		(layer "In4.Cu")
	)
	(gr_line
		(start 373.835168 -289.96513)
		(end 373.832374 -289.963606)
		(stroke
			(width 0.05715)
			(type default)
		)
		(layer "In4.Cu")
	)
	(gr_arc
		(start 373.899176 -320.318892)
		(mid 373.898165 -320.316984)
		(end 373.897144 -320.315082)
		(stroke
			(width 0.07112)
			(type default)
		)
		(layer "In4.Cu")
	)
	(gr_line
		(start 373.907558 -393.961112)
		(end 373.96039 -393.930632)
		(stroke
			(width 0.07112)
			(type default)
		)
		(layer "In4.Cu")
	)
	(gr_arc
		(start 373.910098 -229.094284)
		(mid 373.910108 -229.090982)
		(end 373.910098 -229.08768)
		(stroke
			(width 0.05715)
			(type default)
		)
		(layer "In4.Cu")
	)
	(gr_line
		(start 373.910098 -225.85426)
		(end 373.910098 -225.861372)
		(stroke
			(width 0.05715)
			(type default)
		)
		(layer "In4.Cu")
	)
	(gr_line
		(start 373.925846 -294.014652)
		(end 373.927116 -294.01389)
		(stroke
			(width 0.05715)
			(type default)
		)
		(layer "In4.Cu")
	)
	(gr_line
		(start 373.92737 -295.633648)
		(end 373.927878 -295.633394)
		(stroke
			(width 0.05715)
			(type default)
		)
		(layer "In4.Cu")
	)
	(gr_line
		(start 373.927878 -294.658542)
		(end 373.926608 -294.65778)
		(stroke
			(width 0.05715)
			(type default)
		)
		(layer "In4.Cu")
	)
	(gr_line
		(start 373.927878 -293.03853)
		(end 373.92737 -293.038276)
		(stroke
			(width 0.05715)
			(type default)
		)
		(layer "In4.Cu")
	)
	(gr_line
		(start 373.927878 -291.418518)
		(end 373.92737 -291.418264)
		(stroke
			(width 0.05715)
			(type default)
		)
		(layer "In4.Cu")
	)
	(gr_line
		(start 373.927878 -289.798506)
		(end 373.926862 -289.797998)
		(stroke
			(width 0.05715)
			(type default)
		)
		(layer "In4.Cu")
	)
	(gr_line
		(start 373.928386 -293.03853)
		(end 373.927878 -293.03853)
		(stroke
			(width 0.05715)
			(type default)
		)
		(layer "In4.Cu")
	)
	(gr_line
		(start 373.930672 -289.800284)
		(end 373.927878 -289.798506)
		(stroke
			(width 0.05715)
			(type default)
		)
		(layer "In4.Cu")
	)
	(gr_arc
		(start 373.9388 -294.007286)
		(mid 373.941726 -294.005516)
		(end 373.944642 -294.00373)
		(stroke
			(width 0.05715)
			(type default)
		)
		(layer "In4.Cu")
	)
	(gr_arc
		(start 373.945658 -293.048944)
		(mid 373.942616 -293.047029)
		(end 373.939562 -293.045134)
		(stroke
			(width 0.05715)
			(type default)
		)
		(layer "In4.Cu")
	)
	(gr_line
		(start 373.954802 -233.495088)
		(end 373.955056 -233.495342)
		(stroke
			(width 0.05715)
			(type default)
		)
		(layer "In4.Cu")
	)
	(gr_line
		(start 373.96039 -393.930632)
		(end 374.048528 -393.842494)
		(stroke
			(width 0.07112)
			(type default)
		)
		(layer "In4.Cu")
	)
	(gr_line
		(start 373.996712 -225.369628)
		(end 374.000268 -225.367596)
		(stroke
			(width 0.05715)
			(type default)
		)
		(layer "In4.Cu")
	)
	(gr_line
		(start 374.000268 -225.367596)
		(end 374.001284 -225.367088)
		(stroke
			(width 0.05715)
			(type default)
		)
		(layer "In4.Cu")
	)
	(gr_arc
		(start 374.00103 -233.465116)
		(mid 373.987192 -233.473428)
		(end 373.973598 -233.482134)
		(stroke
			(width 0.05715)
			(type default)
		)
		(layer "In4.Cu")
	)
	(gr_line
		(start 374.001284 -233.465116)
		(end 374.00103 -233.465116)
		(stroke
			(width 0.05715)
			(type default)
		)
		(layer "In4.Cu")
	)
	(gr_line
		(start 374.001284 -233.465116)
		(end 374.003824 -233.463592)
		(stroke
			(width 0.05715)
			(type default)
		)
		(layer "In4.Cu")
	)
	(gr_line
		(start 374.001284 -225.367088)
		(end 374.00357 -225.365818)
		(stroke
			(width 0.05715)
			(type default)
		)
		(layer "In4.Cu")
	)
	(gr_line
		(start 374.003824 -233.463592)
		(end 374.005348 -233.46283)
		(stroke
			(width 0.05715)
			(type default)
		)
		(layer "In4.Cu")
	)
	(gr_arc
		(start 374.005348 -233.46283)
		(mid 374.074849 -233.411056)
		(end 374.130316 -233.344466)
		(stroke
			(width 0.05715)
			(type default)
		)
		(layer "In4.Cu")
	)
	(gr_line
		(start 374.021604 -333.167736)
		(end 374.021604 -333.167482)
		(stroke
			(width 0.07112)
			(type default)
		)
		(layer "In4.Cu")
	)
	(gr_line
		(start 374.048528 -393.842494)
		(end 374.048528 -393.716764)
		(stroke
			(width 0.07112)
			(type default)
		)
		(layer "In4.Cu")
	)
	(gr_arc
		(start 374.066562 -233.650282)
		(mid 374.064398 -233.651799)
		(end 374.062244 -233.65333)
		(stroke
			(width 0.05715)
			(type default)
		)
		(layer "In4.Cu")
	)
	(gr_arc
		(start 374.085104 -233.638852)
		(mid 374.081024 -233.641238)
		(end 374.076976 -233.643678)
		(stroke
			(width 0.05715)
			(type default)
		)
		(layer "In4.Cu")
	)
	(gr_line
		(start 374.094248 -225.533712)
		(end 374.093486 -225.53422)
		(stroke
			(width 0.05715)
			(type default)
		)
		(layer "In4.Cu")
	)
	(gr_line
		(start 374.106186 -351.722436)
		(end 374.092724 -351.749868)
		(stroke
			(width 0.07112)
			(type default)
		)
		(layer "In4.Cu")
	)
	(gr_line
		(start 374.11152 -351.704402)
		(end 374.108726 -351.717102)
		(stroke
			(width 0.07112)
			(type default)
		)
		(layer "In4.Cu")
	)
	(gr_line
		(start 374.12803 -351.632012)
		(end 374.127522 -351.634552)
		(stroke
			(width 0.07112)
			(type default)
		)
		(layer "In4.Cu")
	)
	(gr_line
		(start 374.136158 -231.989122)
		(end 374.128538 -231.99344)
		(stroke
			(width 0.05715)
			(type default)
		)
		(layer "In4.Cu")
	)
	(gr_line
		(start 374.13692 -233.608626)
		(end 374.085104 -233.638852)
		(stroke
			(width 0.05715)
			(type default)
		)
		(layer "In4.Cu")
	)
	(gr_arc
		(start 374.13692 -233.608626)
		(mid 374.222234 -233.536044)
		(end 374.291606 -233.448098)
		(stroke
			(width 0.05715)
			(type default)
		)
		(layer "In4.Cu")
	)
	(gr_arc
		(start 374.13692 -231.988614)
		(mid 374.136539 -231.988868)
		(end 374.136158 -231.989122)
		(stroke
			(width 0.05715)
			(type default)
		)
		(layer "In4.Cu")
	)
	(gr_arc
		(start 374.13692 -231.988614)
		(mid 374.140869 -231.985837)
		(end 374.144794 -231.983026)
		(stroke
			(width 0.05715)
			(type default)
		)
		(layer "In4.Cu")
	)
	(gr_line
		(start 374.143778 -221.202758)
		(end 374.143778 -221.17431)
		(stroke
			(width 0.05715)
			(type default)
		)
		(layer "In4.Cu")
	)
	(gr_arc
		(start 374.17502 -348.406466)
		(mid 374.175662 -348.403801)
		(end 374.17629 -348.401132)
		(stroke
			(width 0.07112)
			(type default)
		)
		(layer "In4.Cu")
	)
	(gr_line
		(start 374.18772 -410.675074)
		(end 374.008142 -410.605732)
		(stroke
			(width 0.07112)
			(type default)
		)
		(layer "In4.Cu")
	)
	(gr_line
		(start 374.189498 -348.28099)
		(end 374.189498 -348.281752)
		(stroke
			(width 0.07112)
			(type default)
		)
		(layer "In4.Cu")
	)
	(gr_line
		(start 374.189498 -221.248478)
		(end 374.143778 -221.202758)
		(stroke
			(width 0.05715)
			(type default)
		)
		(layer "In4.Cu")
	)
	(gr_line
		(start 374.248172 -412.55569)
		(end 373.957342 -412.84652)
		(stroke
			(width 0.07112)
			(type default)
		)
		(layer "In4.Cu")
	)
	(gr_line
		(start 374.279922 -378.847858)
		(end 374.280176 -378.847858)
		(stroke
			(width 0.07112)
			(type default)
		)
		(layer "In4.Cu")
	)
	(gr_arc
		(start 374.291352 -287.527492)
		(mid 374.293508 -287.528767)
		(end 374.29567 -287.530032)
		(stroke
			(width 0.05715)
			(type default)
		)
		(layer "In4.Cu")
	)
	(gr_line
		(start 374.301512 -287.533588)
		(end 374.301766 -287.533588)
		(stroke
			(width 0.05715)
			(type default)
		)
		(layer "In4.Cu")
	)
	(gr_line
		(start 374.302528 -290.773866)
		(end 374.301766 -290.773358)
		(stroke
			(width 0.05715)
			(type default)
		)
		(layer "In4.Cu")
	)
	(gr_line
		(start 374.383808 -351.779078)
		(end 374.375934 -351.81286)
		(stroke
			(width 0.07112)
			(type default)
		)
		(layer "In4.Cu")
	)
	(gr_line
		(start 374.386602 -351.766886)
		(end 374.383808 -351.779078)
		(stroke
			(width 0.07112)
			(type default)
		)
		(layer "In4.Cu")
	)
	(gr_line
		(start 374.397524 -351.719388)
		(end 374.39727 -351.72015)
		(stroke
			(width 0.07112)
			(type default)
		)
		(layer "In4.Cu")
	)
	(gr_line
		(start 374.400572 -351.705672)
		(end 374.400572 -351.70618)
		(stroke
			(width 0.07112)
			(type default)
		)
		(layer "In4.Cu")
	)
	(gr_line
		(start 374.402858 -290.611306)
		(end 374.401842 -290.610798)
		(stroke
			(width 0.05715)
			(type default)
		)
		(layer "In4.Cu")
	)
	(gr_line
		(start 374.409716 -316.17285)
		(end 374.39219 -316.15126)
		(stroke
			(width 0.07112)
			(type default)
		)
		(layer "In4.Cu")
	)
	(gr_line
		(start 374.422924 -316.197742)
		(end 374.422924 -316.197488)
		(stroke
			(width 0.07112)
			(type default)
		)
		(layer "In4.Cu")
	)
	(gr_line
		(start 374.422924 -316.197488)
		(end 374.409716 -316.17285)
		(stroke
			(width 0.07112)
			(type default)
		)
		(layer "In4.Cu")
	)
	(gr_line
		(start 374.425718 -221.202758)
		(end 374.379998 -221.248478)
		(stroke
			(width 0.05715)
			(type default)
		)
		(layer "In4.Cu")
	)
	(gr_line
		(start 374.425718 -221.17431)
		(end 374.425718 -221.202758)
		(stroke
			(width 0.05715)
			(type default)
		)
		(layer "In4.Cu")
	)
	(gr_line
		(start 374.429274 -290.6268)
		(end 374.428512 -290.626292)
		(stroke
			(width 0.05715)
			(type default)
		)
		(layer "In4.Cu")
	)
	(gr_line
		(start 374.430036 -290.627308)
		(end 374.429274 -290.6268)
		(stroke
			(width 0.05715)
			(type default)
		)
		(layer "In4.Cu")
	)
	(gr_line
		(start 374.436894 -290.631372)
		(end 374.430036 -290.627308)
		(stroke
			(width 0.05715)
			(type default)
		)
		(layer "In4.Cu")
	)
	(gr_line
		(start 374.444006 -296.400728)
		(end 374.444006 -296.37228)
		(stroke
			(width 0.05715)
			(type default)
		)
		(layer "In4.Cu")
	)
	(gr_line
		(start 374.444006 -296.37228)
		(end 374.489726 -296.32656)
		(stroke
			(width 0.05715)
			(type default)
		)
		(layer "In4.Cu")
	)
	(gr_arc
		(start 374.444768 -290.63696)
		(mid 374.440843 -290.634149)
		(end 374.436894 -290.631372)
		(stroke
			(width 0.05715)
			(type default)
		)
		(layer "In4.Cu")
	)
	(gr_line
		(start 374.471946 -222.936816)
		(end 374.473978 -222.935546)
		(stroke
			(width 0.05715)
			(type default)
		)
		(layer "In4.Cu")
	)
	(gr_arc
		(start 374.473978 -222.935546)
		(mid 374.474868 -222.935039)
		(end 374.475756 -222.93453)
		(stroke
			(width 0.05715)
			(type default)
		)
		(layer "In4.Cu")
	)
	(gr_line
		(start 374.49125 -393.69238)
		(end 374.844564 -393.787376)
		(stroke
			(width 0.07112)
			(type default)
		)
		(layer "In4.Cu")
	)
	(gr_line
		(start 374.530112 -412.55569)
		(end 374.820942 -412.84652)
		(stroke
			(width 0.07112)
			(type default)
		)
		(layer "In4.Cu")
	)
	(gr_line
		(start 374.533668 -410.062934)
		(end 373.892318 -410.347414)
		(stroke
			(width 0.07112)
			(type default)
		)
		(layer "In4.Cu")
	)
	(gr_line
		(start 374.537732 -410.061156)
		(end 374.533668 -410.062934)
		(stroke
			(width 0.07112)
			(type default)
		)
		(layer "In4.Cu")
	)
	(gr_line
		(start 374.56999 -223.100392)
		(end 374.567704 -223.101662)
		(stroke
			(width 0.05715)
			(type default)
		)
		(layer "In4.Cu")
	)
	(gr_line
		(start 374.578118 -410.5021)
		(end 374.18772 -410.675074)
		(stroke
			(width 0.07112)
			(type default)
		)
		(layer "In4.Cu")
	)
	(gr_line
		(start 374.647206 -410.322522)
		(end 374.578118 -410.5021)
		(stroke
			(width 0.07112)
			(type default)
		)
		(layer "In4.Cu")
	)
	(gr_line
		(start 374.652032 -410.318966)
		(end 374.647968 -410.320744)
		(stroke
			(width 0.07112)
			(type default)
		)
		(layer "In4.Cu")
	)
	(gr_line
		(start 374.725946 -296.400728)
		(end 374.725946 -296.37228)
		(stroke
			(width 0.05715)
			(type default)
		)
		(layer "In4.Cu")
	)
	(gr_line
		(start 374.725946 -296.37228)
		(end 374.680226 -296.32656)
		(stroke
			(width 0.05715)
			(type default)
		)
		(layer "In4.Cu")
	)
	(gr_line
		(start 374.844564 -393.787376)
		(end 374.845072 -393.786868)
		(stroke
			(width 0.07112)
			(type default)
		)
		(layer "In4.Cu")
	)
	(gr_line
		(start 374.8913 -394.385292)
		(end 374.986042 -394.031724)
		(stroke
			(width 0.07112)
			(type default)
		)
		(layer "In4.Cu")
	)
	(gr_line
		(start 374.943116 -231.845866)
		(end 374.943878 -231.845358)
		(stroke
			(width 0.05715)
			(type default)
		)
		(layer "In4.Cu")
	)
	(gr_line
		(start 374.943116 -225.366072)
		(end 374.943878 -225.365564)
		(stroke
			(width 0.05715)
			(type default)
		)
		(layer "In4.Cu")
	)
	(gr_line
		(start 374.943878 -231.845358)
		(end 374.945402 -231.844596)
		(stroke
			(width 0.05715)
			(type default)
		)
		(layer "In4.Cu")
	)
	(gr_line
		(start 374.943878 -225.365564)
		(end 374.945402 -225.364802)
		(stroke
			(width 0.05715)
			(type default)
		)
		(layer "In4.Cu")
	)
	(gr_line
		(start 374.945402 -231.844596)
		(end 374.946164 -231.844088)
		(stroke
			(width 0.05715)
			(type default)
		)
		(layer "In4.Cu")
	)
	(gr_line
		(start 374.945402 -225.364802)
		(end 374.946164 -225.364294)
		(stroke
			(width 0.05715)
			(type default)
		)
		(layer "In4.Cu")
	)
	(gr_line
		(start 375.037096 -232.011982)
		(end 375.035826 -232.012744)
		(stroke
			(width 0.05715)
			(type default)
		)
		(layer "In4.Cu")
	)
	(gr_line
		(start 375.037096 -225.532188)
		(end 375.035826 -225.53295)
		(stroke
			(width 0.05715)
			(type default)
		)
		(layer "In4.Cu")
	)
	(gr_line
		(start 375.037858 -232.011474)
		(end 375.037096 -232.011982)
		(stroke
			(width 0.05715)
			(type default)
		)
		(layer "In4.Cu")
	)
	(gr_line
		(start 375.037858 -225.53168)
		(end 375.037096 -225.532188)
		(stroke
			(width 0.05715)
			(type default)
		)
		(layer "In4.Cu")
	)
	(gr_line
		(start 375.038874 -232.010966)
		(end 375.037858 -232.011474)
		(stroke
			(width 0.05715)
			(type default)
		)
		(layer "In4.Cu")
	)
	(gr_line
		(start 375.038874 -225.531172)
		(end 375.037858 -225.53168)
		(stroke
			(width 0.05715)
			(type default)
		)
		(layer "In4.Cu")
	)
	(gr_line
		(start 375.040906 -232.009696)
		(end 375.038874 -232.010966)
		(stroke
			(width 0.05715)
			(type default)
		)
		(layer "In4.Cu")
	)
	(gr_line
		(start 375.040906 -225.529902)
		(end 375.038874 -225.531172)
		(stroke
			(width 0.05715)
			(type default)
		)
		(layer "In4.Cu")
	)
	(gr_line
		(start 375.069354 -231.993186)
		(end 375.068846 -231.99344)
		(stroke
			(width 0.05715)
			(type default)
		)
		(layer "In4.Cu")
	)
	(gr_line
		(start 375.069354 -225.513392)
		(end 375.068846 -225.513646)
		(stroke
			(width 0.05715)
			(type default)
		)
		(layer "In4.Cu")
	)
	(gr_line
		(start 375.070116 -231.992678)
		(end 375.069354 -231.993186)
		(stroke
			(width 0.05715)
			(type default)
		)
		(layer "In4.Cu")
	)
	(gr_line
		(start 375.070116 -225.512884)
		(end 375.069354 -225.513392)
		(stroke
			(width 0.05715)
			(type default)
		)
		(layer "In4.Cu")
	)
	(gr_line
		(start 375.07418 -222.270574)
		(end 375.068592 -222.273622)
		(stroke
			(width 0.05715)
			(type default)
		)
		(layer "In4.Cu")
	)
	(gr_line
		(start 375.075196 -222.270066)
		(end 375.07418 -222.270574)
		(stroke
			(width 0.05715)
			(type default)
		)
		(layer "In4.Cu")
	)
	(gr_line
		(start 375.076212 -222.269304)
		(end 375.075196 -222.270066)
		(stroke
			(width 0.05715)
			(type default)
		)
		(layer "In4.Cu")
	)
	(gr_arc
		(start 375.076212 -222.269304)
		(mid 375.080544 -222.266276)
		(end 375.084848 -222.263208)
		(stroke
			(width 0.05715)
			(type default)
		)
		(layer "In4.Cu")
	)
	(gr_line
		(start 375.076974 -231.988614)
		(end 375.070116 -231.992678)
		(stroke
			(width 0.05715)
			(type default)
		)
		(layer "In4.Cu")
	)
	(gr_arc
		(start 375.076974 -231.988614)
		(mid 375.080923 -231.985837)
		(end 375.084848 -231.983026)
		(stroke
			(width 0.05715)
			(type default)
		)
		(layer "In4.Cu")
	)
	(gr_line
		(start 375.076974 -225.50882)
		(end 375.070116 -225.512884)
		(stroke
			(width 0.05715)
			(type default)
		)
		(layer "In4.Cu")
	)
	(gr_arc
		(start 375.076974 -225.50882)
		(mid 375.080923 -225.506043)
		(end 375.084848 -225.503232)
		(stroke
			(width 0.05715)
			(type default)
		)
		(layer "In4.Cu")
	)
	(gr_line
		(start 375.083832 -221.202758)
		(end 375.083832 -221.17431)
		(stroke
			(width 0.05715)
			(type default)
		)
		(layer "In4.Cu")
	)
	(gr_line
		(start 375.107708 -393.961112)
		(end 375.16054 -393.930632)
		(stroke
			(width 0.07112)
			(type default)
		)
		(layer "In4.Cu")
	)
	(gr_line
		(start 375.129552 -221.248478)
		(end 375.083832 -221.202758)
		(stroke
			(width 0.05715)
			(type default)
		)
		(layer "In4.Cu")
	)
	(gr_line
		(start 375.16054 -393.930632)
		(end 375.248678 -393.842494)
		(stroke
			(width 0.07112)
			(type default)
		)
		(layer "In4.Cu")
	)
	(gr_line
		(start 375.163334 -411.564582)
		(end 375.16308 -411.564582)
		(stroke
			(width 0.07112)
			(type default)
		)
		(layer "In4.Cu")
	)
	(gr_line
		(start 375.235216 -290.769548)
		(end 375.233692 -290.768532)
		(stroke
			(width 0.05715)
			(type default)
		)
		(layer "In4.Cu")
	)
	(gr_line
		(start 375.237502 -290.770818)
		(end 375.235216 -290.769548)
		(stroke
			(width 0.05715)
			(type default)
		)
		(layer "In4.Cu")
	)
	(gr_line
		(start 375.240804 -290.77285)
		(end 375.23928 -290.771834)
		(stroke
			(width 0.05715)
			(type default)
		)
		(layer "In4.Cu")
	)
	(gr_line
		(start 375.24182 -290.773358)
		(end 375.240804 -290.77285)
		(stroke
			(width 0.05715)
			(type default)
		)
		(layer "In4.Cu")
	)
	(gr_line
		(start 375.242582 -290.773866)
		(end 375.24182 -290.773358)
		(stroke
			(width 0.05715)
			(type default)
		)
		(layer "In4.Cu")
	)
	(gr_line
		(start 375.248678 -393.842494)
		(end 375.248678 -393.716764)
		(stroke
			(width 0.07112)
			(type default)
		)
		(layer "In4.Cu")
	)
	(gr_line
		(start 375.28881 -387.123178)
		(end 375.395744 -386.963158)
		(stroke
			(width 0.07112)
			(type default)
		)
		(layer "In4.Cu")
	)
	(gr_line
		(start 375.333514 -290.605972)
		(end 375.332498 -290.605464)
		(stroke
			(width 0.05715)
			(type default)
		)
		(layer "In4.Cu")
	)
	(gr_line
		(start 375.334276 -290.60648)
		(end 375.333514 -290.605972)
		(stroke
			(width 0.05715)
			(type default)
		)
		(layer "In4.Cu")
	)
	(gr_line
		(start 375.3358 -290.607242)
		(end 375.334276 -290.60648)
		(stroke
			(width 0.05715)
			(type default)
		)
		(layer "In4.Cu")
	)
	(gr_line
		(start 375.33707 -290.608004)
		(end 375.3358 -290.607242)
		(stroke
			(width 0.05715)
			(type default)
		)
		(layer "In4.Cu")
	)
	(gr_line
		(start 375.337832 -290.608512)
		(end 375.33707 -290.608004)
		(stroke
			(width 0.05715)
			(type default)
		)
		(layer "In4.Cu")
	)
	(gr_line
		(start 375.338848 -290.60902)
		(end 375.337832 -290.608512)
		(stroke
			(width 0.05715)
			(type default)
		)
		(layer "In4.Cu")
	)
	(gr_line
		(start 375.33961 -290.609528)
		(end 375.338848 -290.60902)
		(stroke
			(width 0.05715)
			(type default)
		)
		(layer "In4.Cu")
	)
	(gr_line
		(start 375.34342 -290.61156)
		(end 375.34215 -290.610798)
		(stroke
			(width 0.05715)
			(type default)
		)
		(layer "In4.Cu")
	)
	(gr_line
		(start 375.344436 -411.634432)
		(end 375.164604 -411.56509)
		(stroke
			(width 0.07112)
			(type default)
		)
		(layer "In4.Cu")
	)
	(gr_line
		(start 375.365772 -221.202758)
		(end 375.320052 -221.248478)
		(stroke
			(width 0.05715)
			(type default)
		)
		(layer "In4.Cu")
	)
	(gr_line
		(start 375.365772 -221.17431)
		(end 375.365772 -221.202758)
		(stroke
			(width 0.05715)
			(type default)
		)
		(layer "In4.Cu")
	)
	(gr_line
		(start 375.369328 -290.6268)
		(end 375.368058 -290.626038)
		(stroke
			(width 0.05715)
			(type default)
		)
		(layer "In4.Cu")
	)
	(gr_line
		(start 375.37009 -290.627308)
		(end 375.369328 -290.6268)
		(stroke
			(width 0.05715)
			(type default)
		)
		(layer "In4.Cu")
	)
	(gr_line
		(start 375.371868 -387.542024)
		(end 375.28881 -387.123178)
		(stroke
			(width 0.07112)
			(type default)
		)
		(layer "In4.Cu")
	)
	(gr_arc
		(start 375.372884 -224.579688)
		(mid 375.369701 -224.581963)
		(end 375.366534 -224.58426)
		(stroke
			(width 0.05715)
			(type default)
		)
		(layer "In4.Cu")
	)
	(gr_line
		(start 375.373138 -224.579434)
		(end 375.37517 -224.57791)
		(stroke
			(width 0.05715)
			(type default)
		)
		(layer "In4.Cu")
	)
	(gr_line
		(start 375.37517 -224.57791)
		(end 375.383298 -224.573084)
		(stroke
			(width 0.05715)
			(type default)
		)
		(layer "In4.Cu")
	)
	(gr_line
		(start 375.376948 -290.631372)
		(end 375.37009 -290.627308)
		(stroke
			(width 0.05715)
			(type default)
		)
		(layer "In4.Cu")
	)
	(gr_arc
		(start 375.384822 -290.63696)
		(mid 375.380897 -290.634149)
		(end 375.376948 -290.631372)
		(stroke
			(width 0.05715)
			(type default)
		)
		(layer "In4.Cu")
	)
	(gr_line
		(start 375.410984 -222.93707)
		(end 375.411746 -222.936816)
		(stroke
			(width 0.05715)
			(type default)
		)
		(layer "In4.Cu")
	)
	(gr_line
		(start 375.411746 -222.936816)
		(end 375.412508 -222.936308)
		(stroke
			(width 0.05715)
			(type default)
		)
		(layer "In4.Cu")
	)
	(gr_line
		(start 375.412508 -222.936308)
		(end 375.413016 -222.936054)
		(stroke
			(width 0.05715)
			(type default)
		)
		(layer "In4.Cu")
	)
	(gr_line
		(start 375.420636 -222.931482)
		(end 375.42216 -222.930466)
		(stroke
			(width 0.05715)
			(type default)
		)
		(layer "In4.Cu")
	)
	(gr_line
		(start 375.429526 -296.393108)
		(end 375.429526 -296.36466)
		(stroke
			(width 0.05715)
			(type default)
		)
		(layer "In4.Cu")
	)
	(gr_line
		(start 375.429526 -296.36466)
		(end 375.475246 -296.31894)
		(stroke
			(width 0.05715)
			(type default)
		)
		(layer "In4.Cu")
	)
	(gr_line
		(start 375.508774 -388.229602)
		(end 375.615708 -388.069328)
		(stroke
			(width 0.07112)
			(type default)
		)
		(layer "In4.Cu")
	)
	(gr_line
		(start 375.515378 -223.097344)
		(end 375.51487 -223.097598)
		(stroke
			(width 0.05715)
			(type default)
		)
		(layer "In4.Cu")
	)
	(gr_line
		(start 375.532142 -387.649212)
		(end 375.371868 -387.542024)
		(stroke
			(width 0.07112)
			(type default)
		)
		(layer "In4.Cu")
	)
	(gr_line
		(start 375.581672 -212.891878)
		(end 375.578878 -212.887052)
		(stroke
			(width 0.07112)
			(type default)
		)
		(layer "In4.Cu")
	)
	(gr_line
		(start 375.591832 -388.648194)
		(end 375.508774 -388.229602)
		(stroke
			(width 0.07112)
			(type default)
		)
		(layer "In4.Cu")
	)
	(gr_line
		(start 375.62663 -224.086928)
		(end 375.626884 -224.08642)
		(stroke
			(width 0.05715)
			(type default)
		)
		(layer "In4.Cu")
	)
	(gr_line
		(start 375.69013 -411.022292)
		(end 375.04878 -411.306518)
		(stroke
			(width 0.07112)
			(type default)
		)
		(layer "In4.Cu")
	)
	(gr_line
		(start 375.691146 -393.69238)
		(end 376.04446 -393.787376)
		(stroke
			(width 0.07112)
			(type default)
		)
		(layer "In4.Cu")
	)
	(gr_line
		(start 375.711466 -296.393108)
		(end 375.711466 -296.36466)
		(stroke
			(width 0.05715)
			(type default)
		)
		(layer "In4.Cu")
	)
	(gr_line
		(start 375.711466 -296.36466)
		(end 375.665746 -296.31894)
		(stroke
			(width 0.05715)
			(type default)
		)
		(layer "In4.Cu")
	)
	(gr_line
		(start 375.718324 -295.471088)
		(end 375.726452 -295.46296)
		(stroke
			(width 0.05715)
			(type default)
		)
		(layer "In4.Cu")
	)
	(gr_line
		(start 375.726452 -295.46296)
		(end 375.736866 -295.454832)
		(stroke
			(width 0.05715)
			(type default)
		)
		(layer "In4.Cu")
	)
	(gr_line
		(start 375.728738 -389.335772)
		(end 375.835672 -389.175752)
		(stroke
			(width 0.07112)
			(type default)
		)
		(layer "In4.Cu")
	)
	(gr_line
		(start 375.734834 -411.461458)
		(end 375.344436 -411.634432)
		(stroke
			(width 0.07112)
			(type default)
		)
		(layer "In4.Cu")
	)
	(gr_arc
		(start 375.737628 -295.45407)
		(mid 375.737247 -295.454451)
		(end 375.736866 -295.454832)
		(stroke
			(width 0.05715)
			(type default)
		)
		(layer "In4.Cu")
	)
	(gr_line
		(start 375.741946 -295.717214)
		(end 375.741692 -295.717214)
		(stroke
			(width 0.05715)
			(type default)
		)
		(layer "In4.Cu")
	)
	(gr_line
		(start 375.752106 -388.755382)
		(end 375.591832 -388.648194)
		(stroke
			(width 0.07112)
			(type default)
		)
		(layer "In4.Cu")
	)
	(gr_line
		(start 375.789698 -224.256346)
		(end 375.789698 -224.255838)
		(stroke
			(width 0.05715)
			(type default)
		)
		(layer "In4.Cu")
	)
	(gr_line
		(start 375.803922 -411.281626)
		(end 375.734834 -411.461458)
		(stroke
			(width 0.07112)
			(type default)
		)
		(layer "In4.Cu")
	)
	(gr_line
		(start 375.810018 -387.59511)
		(end 375.673366 -386.907024)
		(stroke
			(width 0.07112)
			(type default)
		)
		(layer "In4.Cu")
	)
	(gr_line
		(start 375.81205 -389.754364)
		(end 375.728738 -389.335772)
		(stroke
			(width 0.07112)
			(type default)
		)
		(layer "In4.Cu")
	)
	(gr_line
		(start 375.868692 -352.50374)
		(end 375.868692 -352.503994)
		(stroke
			(width 0.07112)
			(type default)
		)
		(layer "In4.Cu")
	)
	(gr_line
		(start 375.91492 -222.107506)
		(end 375.914666 -222.10776)
		(stroke
			(width 0.05715)
			(type default)
		)
		(layer "In4.Cu")
	)
	(gr_line
		(start 375.919746 -352.388424)
		(end 375.919746 -352.388678)
		(stroke
			(width 0.07112)
			(type default)
		)
		(layer "In4.Cu")
	)
	(gr_arc
		(start 375.921778 -222.102426)
		(mid 375.922795 -222.101666)
		(end 375.92381 -222.100902)
		(stroke
			(width 0.05715)
			(type default)
		)
		(layer "In4.Cu")
	)
	(gr_line
		(start 375.97207 -389.861298)
		(end 375.81205 -389.754364)
		(stroke
			(width 0.07112)
			(type default)
		)
		(layer "In4.Cu")
	)
	(gr_line
		(start 376.023886 -221.202758)
		(end 376.023886 -221.17431)
		(stroke
			(width 0.05715)
			(type default)
		)
		(layer "In4.Cu")
	)
	(gr_line
		(start 376.029982 -388.70128)
		(end 375.89333 -388.013448)
		(stroke
			(width 0.07112)
			(type default)
		)
		(layer "In4.Cu")
	)
	(gr_line
		(start 376.04446 -393.787376)
		(end 376.044968 -393.786868)
		(stroke
			(width 0.07112)
			(type default)
		)
		(layer "In4.Cu")
	)
	(gr_line
		(start 376.069606 -221.248478)
		(end 376.023886 -221.202758)
		(stroke
			(width 0.05715)
			(type default)
		)
		(layer "In4.Cu")
	)
	(gr_arc
		(start 376.088402 -348.50705)
		(mid 376.088402 -348.507304)
		(end 376.088402 -348.507558)
		(stroke
			(width 0.07112)
			(type default)
		)
		(layer "In4.Cu")
	)
	(gr_line
		(start 376.088402 -337.853782)
		(end 376.088402 -337.85429)
		(stroke
			(width 0.07112)
			(type default)
		)
		(layer "In4.Cu")
	)
	(gr_line
		(start 376.091196 -394.385292)
		(end 376.185938 -394.031724)
		(stroke
			(width 0.07112)
			(type default)
		)
		(layer "In4.Cu")
	)
	(gr_line
		(start 376.194574 -352.451924)
		(end 376.19432 -352.452432)
		(stroke
			(width 0.07112)
			(type default)
		)
		(layer "In4.Cu")
	)
	(gr_line
		(start 376.249946 -389.807196)
		(end 376.113294 -389.119618)
		(stroke
			(width 0.07112)
			(type default)
		)
		(layer "In4.Cu")
	)
	(gr_line
		(start 376.305826 -221.202758)
		(end 376.260106 -221.248478)
		(stroke
			(width 0.05715)
			(type default)
		)
		(layer "In4.Cu")
	)
	(gr_line
		(start 376.305826 -221.17431)
		(end 376.305826 -221.202758)
		(stroke
			(width 0.05715)
			(type default)
		)
		(layer "In4.Cu")
	)
	(gr_line
		(start 376.307604 -393.961112)
		(end 376.360436 -393.930632)
		(stroke
			(width 0.07112)
			(type default)
		)
		(layer "In4.Cu")
	)
	(gr_line
		(start 376.350784 -222.937324)
		(end 376.3518 -222.936816)
		(stroke
			(width 0.05715)
			(type default)
		)
		(layer "In4.Cu")
	)
	(gr_line
		(start 376.3518 -222.936816)
		(end 376.352562 -222.936308)
		(stroke
			(width 0.05715)
			(type default)
		)
		(layer "In4.Cu")
	)
	(gr_line
		(start 376.352562 -222.936308)
		(end 376.353832 -222.935546)
		(stroke
			(width 0.05715)
			(type default)
		)
		(layer "In4.Cu")
	)
	(gr_line
		(start 376.360436 -393.930632)
		(end 376.448574 -393.842494)
		(stroke
			(width 0.07112)
			(type default)
		)
		(layer "In4.Cu")
	)
	(gr_line
		(start 376.375422 -411.177232)
		(end 376.195844 -411.10789)
		(stroke
			(width 0.07112)
			(type default)
		)
		(layer "In4.Cu")
	)
	(gr_line
		(start 376.44705 -223.10217)
		(end 376.44578 -223.102932)
		(stroke
			(width 0.05715)
			(type default)
		)
		(layer "In4.Cu")
	)
	(gr_line
		(start 376.447812 -223.101662)
		(end 376.44705 -223.10217)
		(stroke
			(width 0.05715)
			(type default)
		)
		(layer "In4.Cu")
	)
	(gr_line
		(start 376.448574 -393.842494)
		(end 376.448574 -393.716764)
		(stroke
			(width 0.07112)
			(type default)
		)
		(layer "In4.Cu")
	)
	(gr_line
		(start 376.448574 -223.101154)
		(end 376.447812 -223.101662)
		(stroke
			(width 0.05715)
			(type default)
		)
		(layer "In4.Cu")
	)
	(gr_line
		(start 376.52198 -387.275324)
		(end 376.629168 -387.11505)
		(stroke
			(width 0.07112)
			(type default)
		)
		(layer "In4.Cu")
	)
	(gr_line
		(start 376.605292 -387.693916)
		(end 376.52198 -387.275324)
		(stroke
			(width 0.07112)
			(type default)
		)
		(layer "In4.Cu")
	)
	(gr_line
		(start 376.72137 -410.565092)
		(end 376.08002 -410.849572)
		(stroke
			(width 0.07112)
			(type default)
		)
		(layer "In4.Cu")
	)
	(gr_line
		(start 376.742198 -388.381494)
		(end 376.849386 -388.22122)
		(stroke
			(width 0.07112)
			(type default)
		)
		(layer "In4.Cu")
	)
	(gr_line
		(start 376.76582 -411.004258)
		(end 376.375422 -411.177232)
		(stroke
			(width 0.07112)
			(type default)
		)
		(layer "In4.Cu")
	)
	(gr_line
		(start 376.76582 -387.801104)
		(end 376.605292 -387.693916)
		(stroke
			(width 0.07112)
			(type default)
		)
		(layer "In4.Cu")
	)
	(gr_line
		(start 376.820938 -222.127318)
		(end 376.821954 -222.12681)
		(stroke
			(width 0.05715)
			(type default)
		)
		(layer "In4.Cu")
	)
	(gr_line
		(start 376.82551 -388.80034)
		(end 376.742198 -388.381494)
		(stroke
			(width 0.07112)
			(type default)
		)
		(layer "In4.Cu")
	)
	(gr_line
		(start 376.834908 -410.824426)
		(end 376.76582 -411.004258)
		(stroke
			(width 0.07112)
			(type default)
		)
		(layer "In4.Cu")
	)
	(gr_line
		(start 376.891296 -393.69238)
		(end 377.24461 -393.787376)
		(stroke
			(width 0.07112)
			(type default)
		)
		(layer "In4.Cu")
	)
	(gr_line
		(start 376.917204 -222.292164)
		(end 376.915934 -222.292926)
		(stroke
			(width 0.05715)
			(type default)
		)
		(layer "In4.Cu")
	)
	(gr_line
		(start 376.917966 -222.291656)
		(end 376.917204 -222.292164)
		(stroke
			(width 0.05715)
			(type default)
		)
		(layer "In4.Cu")
	)
	(gr_line
		(start 376.925332 -222.287338)
		(end 376.917966 -222.291656)
		(stroke
			(width 0.05715)
			(type default)
		)
		(layer "In4.Cu")
	)
	(gr_line
		(start 376.962416 -389.487664)
		(end 377.06935 -389.32739)
		(stroke
			(width 0.07112)
			(type default)
		)
		(layer "In4.Cu")
	)
	(gr_line
		(start 376.964194 -221.57563)
		(end 376.964194 -221.547182)
		(stroke
			(width 0.05715)
			(type default)
		)
		(layer "In4.Cu")
	)
	(gr_line
		(start 376.985784 -388.907274)
		(end 376.82551 -388.80034)
		(stroke
			(width 0.07112)
			(type default)
		)
		(layer "In4.Cu")
	)
	(gr_line
		(start 377.009914 -221.62135)
		(end 376.964194 -221.57563)
		(stroke
			(width 0.05715)
			(type default)
		)
		(layer "In4.Cu")
	)
	(gr_line
		(start 377.043696 -387.747002)
		(end 376.90679 -387.058662)
		(stroke
			(width 0.07112)
			(type default)
		)
		(layer "In4.Cu")
	)
	(gr_line
		(start 377.045728 -389.90651)
		(end 376.962416 -389.487664)
		(stroke
			(width 0.07112)
			(type default)
		)
		(layer "In4.Cu")
	)
	(gr_arc
		(start 377.053856 -348.634304)
		(mid 377.053856 -348.634558)
		(end 377.053856 -348.634812)
		(stroke
			(width 0.07112)
			(type default)
		)
		(layer "In4.Cu")
	)
	(gr_line
		(start 377.053856 -337.950048)
		(end 377.053856 -337.950556)
		(stroke
			(width 0.07112)
			(type default)
		)
		(layer "In4.Cu")
	)
	(gr_line
		(start 377.200414 -221.80423)
		(end 377.200414 -221.805246)
		(stroke
			(width 0.05715)
			(type default)
		)
		(layer "In4.Cu")
	)
	(gr_line
		(start 377.205748 -390.01319)
		(end 377.045728 -389.90651)
		(stroke
			(width 0.07112)
			(type default)
		)
		(layer "In4.Cu")
	)
	(gr_line
		(start 377.21667 -390.06145)
		(end 377.207272 -390.014206)
		(stroke
			(width 0.07112)
			(type default)
		)
		(layer "In4.Cu")
	)
	(gr_line
		(start 377.24461 -393.787376)
		(end 377.245118 -393.786868)
		(stroke
			(width 0.07112)
			(type default)
		)
		(layer "In4.Cu")
	)
	(gr_line
		(start 377.246134 -221.57563)
		(end 377.200414 -221.62135)
		(stroke
			(width 0.05715)
			(type default)
		)
		(layer "In4.Cu")
	)
	(gr_line
		(start 377.246134 -221.547182)
		(end 377.246134 -221.57563)
		(stroke
			(width 0.05715)
			(type default)
		)
		(layer "In4.Cu")
	)
	(gr_line
		(start 377.26366 -388.853172)
		(end 377.127008 -388.165086)
		(stroke
			(width 0.07112)
			(type default)
		)
		(layer "In4.Cu")
	)
	(gr_line
		(start 377.291346 -394.385292)
		(end 377.386088 -394.031724)
		(stroke
			(width 0.07112)
			(type default)
		)
		(layer "In4.Cu")
	)
	(gr_line
		(start 377.311412 -412.55569)
		(end 377.020582 -412.84652)
		(stroke
			(width 0.07112)
			(type default)
		)
		(layer "In4.Cu")
	)
	(gr_line
		(start 377.406662 -410.720032)
		(end 377.227084 -410.65069)
		(stroke
			(width 0.07112)
			(type default)
		)
		(layer "In4.Cu")
	)
	(gr_line
		(start 377.483878 -389.959342)
		(end 377.346972 -389.27151)
		(stroke
			(width 0.07112)
			(type default)
		)
		(layer "In4.Cu")
	)
	(gr_line
		(start 377.493276 -390.006586)
		(end 377.483878 -389.959342)
		(stroke
			(width 0.07112)
			(type default)
		)
		(layer "In4.Cu")
	)
	(gr_line
		(start 377.507754 -393.961112)
		(end 377.560586 -393.930632)
		(stroke
			(width 0.07112)
			(type default)
		)
		(layer "In4.Cu")
	)
	(gr_line
		(start 377.560586 -393.930632)
		(end 377.648724 -393.842494)
		(stroke
			(width 0.07112)
			(type default)
		)
		(layer "In4.Cu")
	)
	(gr_line
		(start 377.593352 -412.55569)
		(end 377.884182 -412.84652)
		(stroke
			(width 0.07112)
			(type default)
		)
		(layer "In4.Cu")
	)
	(gr_line
		(start 377.648724 -393.842494)
		(end 377.648724 -393.716764)
		(stroke
			(width 0.07112)
			(type default)
		)
		(layer "In4.Cu")
	)
	(gr_arc
		(start 377.716034 -411.53588)
		(mid 377.716161 -411.535753)
		(end 377.716288 -411.535626)
		(stroke
			(width 0.07112)
			(type default)
		)
		(layer "In4.Cu")
	)
	(gr_line
		(start 377.75261 -410.107892)
		(end 377.11126 -410.392372)
		(stroke
			(width 0.07112)
			(type default)
		)
		(layer "In4.Cu")
	)
	(gr_line
		(start 377.77293 -387.579616)
		(end 377.880118 -387.419342)
		(stroke
			(width 0.07112)
			(type default)
		)
		(layer "In4.Cu")
	)
	(gr_line
		(start 377.79706 -410.547058)
		(end 377.406662 -410.720032)
		(stroke
			(width 0.07112)
			(type default)
		)
		(layer "In4.Cu")
	)
	(gr_line
		(start 377.830842 -325.251826)
		(end 377.830842 -325.25208)
		(stroke
			(width 0.07112)
			(type default)
		)
		(layer "In4.Cu")
	)
	(gr_line
		(start 377.84532 -410.066744)
		(end 377.75261 -410.107892)
		(stroke
			(width 0.07112)
			(type default)
		)
		(layer "In4.Cu")
	)
	(gr_line
		(start 377.856242 -387.998208)
		(end 377.77293 -387.579616)
		(stroke
			(width 0.07112)
			(type default)
		)
		(layer "In4.Cu")
	)
	(gr_line
		(start 377.866148 -410.36748)
		(end 377.79706 -410.547058)
		(stroke
			(width 0.07112)
			(type default)
		)
		(layer "In4.Cu")
	)
	(gr_line
		(start 377.881388 -331.94498)
		(end 377.881388 -331.945234)
		(stroke
			(width 0.07112)
			(type default)
		)
		(layer "In4.Cu")
	)
	(gr_line
		(start 377.95962 -410.324554)
		(end 377.86691 -410.365702)
		(stroke
			(width 0.07112)
			(type default)
		)
		(layer "In4.Cu")
	)
	(gr_line
		(start 377.992894 -388.685786)
		(end 378.100082 -388.525766)
		(stroke
			(width 0.07112)
			(type default)
		)
		(layer "In4.Cu")
	)
	(gr_line
		(start 378.016516 -388.105396)
		(end 377.856242 -387.998208)
		(stroke
			(width 0.07112)
			(type default)
		)
		(layer "In4.Cu")
	)
	(gr_line
		(start 378.076206 -389.104378)
		(end 377.992894 -388.685786)
		(stroke
			(width 0.07112)
			(type default)
		)
		(layer "In4.Cu")
	)
	(gr_line
		(start 378.091192 -393.69238)
		(end 378.444506 -393.787376)
		(stroke
			(width 0.07112)
			(type default)
		)
		(layer "In4.Cu")
	)
	(gr_line
		(start 378.12218 -379.39218)
		(end 378.12218 -378.96546)
		(stroke
			(width 0.07112)
			(type default)
		)
		(layer "In4.Cu")
	)
	(gr_line
		(start 378.12218 -378.96546)
		(end 378.25807 -378.82957)
		(stroke
			(width 0.07112)
			(type default)
		)
		(layer "In4.Cu")
	)
	(gr_line
		(start 378.199904 -313.370214)
		(end 378.182378 -313.348878)
		(stroke
			(width 0.07112)
			(type default)
		)
		(layer "In4.Cu")
	)
	(gr_line
		(start 378.212858 -389.791956)
		(end 378.320046 -389.631936)
		(stroke
			(width 0.07112)
			(type default)
		)
		(layer "In4.Cu")
	)
	(gr_line
		(start 378.212858 -313.394598)
		(end 378.212858 -313.394344)
		(stroke
			(width 0.07112)
			(type default)
		)
		(layer "In4.Cu")
	)
	(gr_line
		(start 378.212858 -313.394344)
		(end 378.199904 -313.370214)
		(stroke
			(width 0.07112)
			(type default)
		)
		(layer "In4.Cu")
	)
	(gr_line
		(start 378.23648 -389.211566)
		(end 378.076206 -389.104378)
		(stroke
			(width 0.07112)
			(type default)
		)
		(layer "In4.Cu")
	)
	(gr_line
		(start 378.25807 -379.52807)
		(end 378.12218 -379.39218)
		(stroke
			(width 0.07112)
			(type default)
		)
		(layer "In4.Cu")
	)
	(gr_line
		(start 378.294392 -388.051294)
		(end 378.15774 -387.363208)
		(stroke
			(width 0.07112)
			(type default)
		)
		(layer "In4.Cu")
	)
	(gr_line
		(start 378.29617 -390.210548)
		(end 378.212858 -389.791956)
		(stroke
			(width 0.07112)
			(type default)
		)
		(layer "In4.Cu")
	)
	(gr_line
		(start 378.444506 -393.787376)
		(end 378.445014 -393.786868)
		(stroke
			(width 0.07112)
			(type default)
		)
		(layer "In4.Cu")
	)
	(gr_line
		(start 378.456444 -390.317482)
		(end 378.29617 -390.210548)
		(stroke
			(width 0.07112)
			(type default)
		)
		(layer "In4.Cu")
	)
	(gr_line
		(start 378.491242 -394.385292)
		(end 378.585984 -394.031724)
		(stroke
			(width 0.07112)
			(type default)
		)
		(layer "In4.Cu")
	)
	(gr_line
		(start 378.514356 -389.157464)
		(end 378.377704 -388.469632)
		(stroke
			(width 0.07112)
			(type default)
		)
		(layer "In4.Cu")
	)
	(gr_line
		(start 378.52985 -411.618938)
		(end 378.35205 -411.545278)
		(stroke
			(width 0.07112)
			(type default)
		)
		(layer "In4.Cu")
	)
	(gr_line
		(start 378.54128 -379.52934)
		(end 378.54128 -378.8283)
		(stroke
			(width 0.07112)
			(type default)
		)
		(layer "In4.Cu")
	)
	(gr_line
		(start 378.54128 -376.05335)
		(end 378.541534 -376.053604)
		(stroke
			(width 0.07112)
			(type default)
		)
		(layer "In4.Cu")
	)
	(gr_line
		(start 378.70765 -393.961112)
		(end 378.760482 -393.930632)
		(stroke
			(width 0.07112)
			(type default)
		)
		(layer "In4.Cu")
	)
	(gr_line
		(start 378.709682 -324.936612)
		(end 378.709428 -324.936612)
		(stroke
			(width 0.07112)
			(type default)
		)
		(layer "In4.Cu")
	)
	(gr_line
		(start 378.73432 -390.263634)
		(end 378.597668 -389.575802)
		(stroke
			(width 0.07112)
			(type default)
		)
		(layer "In4.Cu")
	)
	(gr_line
		(start 378.760482 -393.930632)
		(end 378.84862 -393.842494)
		(stroke
			(width 0.07112)
			(type default)
		)
		(layer "In4.Cu")
	)
	(gr_line
		(start 378.84862 -393.842494)
		(end 378.84862 -393.716764)
		(stroke
			(width 0.07112)
			(type default)
		)
		(layer "In4.Cu")
	)
	(gr_line
		(start 378.891038 -411.015688)
		(end 378.24283 -411.283912)
		(stroke
			(width 0.07112)
			(type default)
		)
		(layer "In4.Cu")
	)
	(gr_line
		(start 378.924312 -411.455616)
		(end 378.52985 -411.618938)
		(stroke
			(width 0.07112)
			(type default)
		)
		(layer "In4.Cu")
	)
	(gr_line
		(start 378.998226 -411.277816)
		(end 378.924312 -411.455616)
		(stroke
			(width 0.07112)
			(type default)
		)
		(layer "In4.Cu")
	)
	(gr_line
		(start 379.291342 -393.69238)
		(end 379.644402 -393.787376)
		(stroke
			(width 0.07112)
			(type default)
		)
		(layer "In4.Cu")
	)
	(gr_line
		(start 379.299216 -353.268026)
		(end 379.299216 -353.267772)
		(stroke
			(width 0.07112)
			(type default)
		)
		(layer "In4.Cu")
	)
	(gr_line
		(start 379.385322 -381.311658)
		(end 379.385576 -381.311658)
		(stroke
			(width 0.07112)
			(type default)
		)
		(layer "In4.Cu")
	)
	(gr_line
		(start 379.572012 -411.187392)
		(end 379.394212 -411.113732)
		(stroke
			(width 0.07112)
			(type default)
		)
		(layer "In4.Cu")
	)
	(gr_line
		(start 379.644402 -393.787376)
		(end 379.64491 -393.786868)
		(stroke
			(width 0.07112)
			(type default)
		)
		(layer "In4.Cu")
	)
	(gr_line
		(start 379.691138 -394.385292)
		(end 379.78588 -394.031724)
		(stroke
			(width 0.07112)
			(type default)
		)
		(layer "In4.Cu")
	)
	(gr_line
		(start 379.87224 -324.581774)
		(end 379.87224 -324.58152)
		(stroke
			(width 0.07112)
			(type default)
		)
		(layer "In4.Cu")
	)
	(gr_line
		(start 379.883162 -384.6449)
		(end 379.883162 -384.21818)
		(stroke
			(width 0.07112)
			(type default)
		)
		(layer "In4.Cu")
	)
	(gr_line
		(start 379.883162 -384.21818)
		(end 380.019052 -384.08229)
		(stroke
			(width 0.07112)
			(type default)
		)
		(layer "In4.Cu")
	)
	(gr_line
		(start 379.883162 -383.51714)
		(end 379.883162 -383.09042)
		(stroke
			(width 0.07112)
			(type default)
		)
		(layer "In4.Cu")
	)
	(gr_line
		(start 379.883162 -383.09042)
		(end 380.019052 -382.95453)
		(stroke
			(width 0.07112)
			(type default)
		)
		(layer "In4.Cu")
	)
	(gr_line
		(start 379.907546 -393.961112)
		(end 379.960378 -393.930632)
		(stroke
			(width 0.07112)
			(type default)
		)
		(layer "In4.Cu")
	)
	(gr_line
		(start 379.932946 -410.584142)
		(end 379.284992 -410.852366)
		(stroke
			(width 0.07112)
			(type default)
		)
		(layer "In4.Cu")
	)
	(gr_line
		(start 379.960378 -393.930632)
		(end 380.048516 -393.842494)
		(stroke
			(width 0.07112)
			(type default)
		)
		(layer "In4.Cu")
	)
	(gr_line
		(start 379.966474 -411.02407)
		(end 379.572012 -411.187392)
		(stroke
			(width 0.07112)
			(type default)
		)
		(layer "In4.Cu")
	)
	(gr_line
		(start 380.019052 -384.78079)
		(end 379.883162 -384.6449)
		(stroke
			(width 0.07112)
			(type default)
		)
		(layer "In4.Cu")
	)
	(gr_line
		(start 380.019052 -383.65303)
		(end 379.883162 -383.51714)
		(stroke
			(width 0.07112)
			(type default)
		)
		(layer "In4.Cu")
	)
	(gr_line
		(start 380.040388 -410.84627)
		(end 379.966474 -411.02407)
		(stroke
			(width 0.07112)
			(type default)
		)
		(layer "In4.Cu")
	)
	(gr_line
		(start 380.048516 -393.842494)
		(end 380.048516 -393.716764)
		(stroke
			(width 0.07112)
			(type default)
		)
		(layer "In4.Cu")
	)
	(gr_line
		(start 380.172214 -353.69754)
		(end 380.172214 -353.697286)
		(stroke
			(width 0.07112)
			(type default)
		)
		(layer "In4.Cu")
	)
	(gr_line
		(start 380.292864 -376.36196)
		(end 380.293118 -376.362214)
		(stroke
			(width 0.07112)
			(type default)
		)
		(layer "In4.Cu")
	)
	(gr_line
		(start 380.302262 -384.78206)
		(end 380.302262 -384.08102)
		(stroke
			(width 0.07112)
			(type default)
		)
		(layer "In4.Cu")
	)
	(gr_line
		(start 380.302262 -383.6543)
		(end 380.302262 -382.95326)
		(stroke
			(width 0.07112)
			(type default)
		)
		(layer "In4.Cu")
	)
	(gr_line
		(start 380.374652 -412.55569)
		(end 380.083822 -412.84652)
		(stroke
			(width 0.07112)
			(type default)
		)
		(layer "In4.Cu")
	)
	(gr_line
		(start 380.44882 -353.752404)
		(end 380.448566 -353.753928)
		(stroke
			(width 0.07112)
			(type default)
		)
		(layer "In4.Cu")
	)
	(gr_line
		(start 380.491238 -393.69238)
		(end 380.844552 -393.787376)
		(stroke
			(width 0.07112)
			(type default)
		)
		(layer "In4.Cu")
	)
	(gr_line
		(start 380.614174 -410.755846)
		(end 380.436374 -410.682186)
		(stroke
			(width 0.07112)
			(type default)
		)
		(layer "In4.Cu")
	)
	(gr_line
		(start 380.656592 -412.55569)
		(end 380.947422 -412.84652)
		(stroke
			(width 0.07112)
			(type default)
		)
		(layer "In4.Cu")
	)
	(gr_line
		(start 380.844552 -393.787376)
		(end 380.84506 -393.786868)
		(stroke
			(width 0.07112)
			(type default)
		)
		(layer "In4.Cu")
	)
	(gr_line
		(start 380.861062 -389.97636)
		(end 380.89078 -389.550402)
		(stroke
			(width 0.07112)
			(type default)
		)
		(layer "In4.Cu")
	)
	(gr_line
		(start 380.89078 -389.550402)
		(end 381.036068 -389.424418)
		(stroke
			(width 0.07112)
			(type default)
		)
		(layer "In4.Cu")
	)
	(gr_line
		(start 380.891288 -394.385292)
		(end 380.98603 -394.031724)
		(stroke
			(width 0.07112)
			(type default)
		)
		(layer "In4.Cu")
	)
	(gr_line
		(start 380.940056 -388.85114)
		(end 380.969774 -388.425182)
		(stroke
			(width 0.07112)
			(type default)
		)
		(layer "In4.Cu")
	)
	(gr_line
		(start 380.969774 -388.425182)
		(end 381.114808 -388.299198)
		(stroke
			(width 0.07112)
			(type default)
		)
		(layer "In4.Cu")
	)
	(gr_line
		(start 380.975108 -410.152596)
		(end 380.327154 -410.42082)
		(stroke
			(width 0.07112)
			(type default)
		)
		(layer "In4.Cu")
	)
	(gr_line
		(start 380.9873 -390.121648)
		(end 380.861062 -389.97636)
		(stroke
			(width 0.07112)
			(type default)
		)
		(layer "In4.Cu")
	)
	(gr_line
		(start 381.008636 -410.592524)
		(end 380.614174 -410.755846)
		(stroke
			(width 0.07112)
			(type default)
		)
		(layer "In4.Cu")
	)
	(gr_line
		(start 381.035052 -383.73558)
		(end 381.16764 -383.59588)
		(stroke
			(width 0.07112)
			(type default)
		)
		(layer "In4.Cu")
	)
	(gr_line
		(start 381.037592 -389.423148)
		(end 381.037084 -389.422894)
		(stroke
			(width 0.07112)
			(type default)
		)
		(layer "In4.Cu")
	)
	(gr_line
		(start 381.046228 -384.1623)
		(end 381.035052 -383.73558)
		(stroke
			(width 0.07112)
			(type default)
		)
		(layer "In4.Cu")
	)
	(gr_line
		(start 381.06604 -388.996174)
		(end 380.940056 -388.85114)
		(stroke
			(width 0.07112)
			(type default)
		)
		(layer "In4.Cu")
	)
	(gr_line
		(start 381.067056 -388.997698)
		(end 381.06731 -388.997698)
		(stroke
			(width 0.07112)
			(type default)
		)
		(layer "In4.Cu")
	)
	(gr_line
		(start 381.08255 -410.41447)
		(end 381.008636 -410.592524)
		(stroke
			(width 0.07112)
			(type default)
		)
		(layer "In4.Cu")
	)
	(gr_line
		(start 381.107696 -393.961112)
		(end 381.160528 -393.930632)
		(stroke
			(width 0.07112)
			(type default)
		)
		(layer "In4.Cu")
	)
	(gr_line
		(start 381.116332 -388.297928)
		(end 381.116078 -388.297928)
		(stroke
			(width 0.07112)
			(type default)
		)
		(layer "In4.Cu")
	)
	(gr_line
		(start 381.160528 -393.930632)
		(end 381.248666 -393.842494)
		(stroke
			(width 0.07112)
			(type default)
		)
		(layer "In4.Cu")
	)
	(gr_line
		(start 381.185928 -384.294634)
		(end 381.046228 -384.1623)
		(stroke
			(width 0.07112)
			(type default)
		)
		(layer "In4.Cu")
	)
	(gr_line
		(start 381.248666 -393.842494)
		(end 381.248666 -393.716764)
		(stroke
			(width 0.07112)
			(type default)
		)
		(layer "In4.Cu")
	)
	(gr_line
		(start 381.269748 -390.142476)
		(end 381.31877 -389.442706)
		(stroke
			(width 0.07112)
			(type default)
		)
		(layer "In4.Cu")
	)
	(gr_line
		(start 381.316992 -349.392494)
		(end 381.322326 -349.365316)
		(stroke
			(width 0.07112)
			(type default)
		)
		(layer "In4.Cu")
	)
	(gr_line
		(start 381.322326 -349.365316)
		(end 381.322326 -349.337122)
		(stroke
			(width 0.07112)
			(type default)
		)
		(layer "In4.Cu")
	)
	(gr_line
		(start 381.348488 -389.01751)
		(end 381.39751 -388.31774)
		(stroke
			(width 0.07112)
			(type default)
		)
		(layer "In4.Cu")
	)
	(gr_line
		(start 381.355092 -353.804474)
		(end 381.355346 -353.804474)
		(stroke
			(width 0.07112)
			(type default)
		)
		(layer "In4.Cu")
	)
	(gr_line
		(start 381.469138 -384.288538)
		(end 381.45085 -383.587498)
		(stroke
			(width 0.07112)
			(type default)
		)
		(layer "In4.Cu")
	)
	(gr_arc
		(start 381.570484 -354.012246)
		(mid 381.570103 -354.012754)
		(end 381.569722 -354.013262)
		(stroke
			(width 0.07112)
			(type default)
		)
		(layer "In4.Cu")
	)
	(gr_line
		(start 381.691134 -393.69238)
		(end 382.044448 -393.787376)
		(stroke
			(width 0.07112)
			(type default)
		)
		(layer "In4.Cu")
	)
	(gr_line
		(start 381.81026 -411.457394)
		(end 381.63246 -411.38348)
		(stroke
			(width 0.07112)
			(type default)
		)
		(layer "In4.Cu")
	)
	(gr_line
		(start 382.026668 -390.208516)
		(end 382.056386 -389.782558)
		(stroke
			(width 0.07112)
			(type default)
		)
		(layer "In4.Cu")
	)
	(gr_line
		(start 382.044448 -393.787376)
		(end 382.044956 -393.786868)
		(stroke
			(width 0.07112)
			(type default)
		)
		(layer "In4.Cu")
	)
	(gr_line
		(start 382.056386 -389.782558)
		(end 382.201674 -389.656574)
		(stroke
			(width 0.07112)
			(type default)
		)
		(layer "In4.Cu")
	)
	(gr_line
		(start 382.091184 -394.385292)
		(end 382.185926 -394.031724)
		(stroke
			(width 0.07112)
			(type default)
		)
		(layer "In4.Cu")
	)
	(gr_line
		(start 382.105662 -389.083296)
		(end 382.13538 -388.657338)
		(stroke
			(width 0.07112)
			(type default)
		)
		(layer "In4.Cu")
	)
	(gr_line
		(start 382.13538 -388.657338)
		(end 382.280668 -388.531354)
		(stroke
			(width 0.07112)
			(type default)
		)
		(layer "In4.Cu")
	)
	(gr_line
		(start 382.152906 -390.35355)
		(end 382.026668 -390.208516)
		(stroke
			(width 0.07112)
			(type default)
		)
		(layer "In4.Cu")
	)
	(gr_line
		(start 382.16332 -384.079242)
		(end 382.295908 -383.939542)
		(stroke
			(width 0.07112)
			(type default)
		)
		(layer "In4.Cu")
	)
	(gr_line
		(start 382.171194 -410.85389)
		(end 381.522986 -411.122368)
		(stroke
			(width 0.07112)
			(type default)
		)
		(layer "In4.Cu")
	)
	(gr_line
		(start 382.174496 -384.506216)
		(end 382.16332 -384.079242)
		(stroke
			(width 0.07112)
			(type default)
		)
		(layer "In4.Cu")
	)
	(gr_line
		(start 382.203198 -389.655304)
		(end 382.202944 -389.655304)
		(stroke
			(width 0.07112)
			(type default)
		)
		(layer "In4.Cu")
	)
	(gr_line
		(start 382.204722 -411.294072)
		(end 381.81026 -411.457394)
		(stroke
			(width 0.07112)
			(type default)
		)
		(layer "In4.Cu")
	)
	(gr_line
		(start 382.231646 -389.228584)
		(end 382.105662 -389.083296)
		(stroke
			(width 0.07112)
			(type default)
		)
		(layer "In4.Cu")
	)
	(gr_line
		(start 382.23317 -323.709792)
		(end 382.233424 -323.709792)
		(stroke
			(width 0.07112)
			(type default)
		)
		(layer "In4.Cu")
	)
	(gr_line
		(start 382.278382 -411.116018)
		(end 382.204722 -411.294072)
		(stroke
			(width 0.07112)
			(type default)
		)
		(layer "In4.Cu")
	)
	(gr_line
		(start 382.282192 -388.530084)
		(end 382.281684 -388.52983)
		(stroke
			(width 0.07112)
			(type default)
		)
		(layer "In4.Cu")
	)
	(gr_line
		(start 382.307592 -393.961112)
		(end 382.360424 -393.930632)
		(stroke
			(width 0.07112)
			(type default)
		)
		(layer "In4.Cu")
	)
	(gr_line
		(start 382.314196 -384.638296)
		(end 382.174496 -384.506216)
		(stroke
			(width 0.07112)
			(type default)
		)
		(layer "In4.Cu")
	)
	(gr_line
		(start 382.360424 -393.930632)
		(end 382.448562 -393.842494)
		(stroke
			(width 0.07112)
			(type default)
		)
		(layer "In4.Cu")
	)
	(gr_line
		(start 382.435354 -390.374378)
		(end 382.484376 -389.675116)
		(stroke
			(width 0.07112)
			(type default)
		)
		(layer "In4.Cu")
	)
	(gr_line
		(start 382.448562 -393.842494)
		(end 382.448562 -393.716764)
		(stroke
			(width 0.07112)
			(type default)
		)
		(layer "In4.Cu")
	)
	(gr_line
		(start 382.514094 -389.250936)
		(end 382.56337 -388.549642)
		(stroke
			(width 0.07112)
			(type default)
		)
		(layer "In4.Cu")
	)
	(gr_line
		(start 382.597406 -384.6322)
		(end 382.578864 -383.93116)
		(stroke
			(width 0.07112)
			(type default)
		)
		(layer "In4.Cu")
	)
	(gr_line
		(start 382.852422 -411.025594)
		(end 382.674368 -410.951934)
		(stroke
			(width 0.07112)
			(type default)
		)
		(layer "In4.Cu")
	)
	(gr_line
		(start 382.891284 -393.69238)
		(end 383.244598 -393.787376)
		(stroke
			(width 0.07112)
			(type default)
		)
		(layer "In4.Cu")
	)
	(gr_line
		(start 383.213356 -410.42209)
		(end 382.565148 -410.690568)
		(stroke
			(width 0.07112)
			(type default)
		)
		(layer "In4.Cu")
	)
	(gr_line
		(start 383.223008 -333.91602)
		(end 383.223008 -333.916274)
		(stroke
			(width 0.07112)
			(type default)
		)
		(layer "In4.Cu")
	)
	(gr_line
		(start 383.244598 -393.787376)
		(end 383.245106 -393.786868)
		(stroke
			(width 0.07112)
			(type default)
		)
		(layer "In4.Cu")
	)
	(gr_line
		(start 383.246884 -410.862272)
		(end 382.852422 -411.025594)
		(stroke
			(width 0.07112)
			(type default)
		)
		(layer "In4.Cu")
	)
	(gr_line
		(start 383.27203 -388.613396)
		(end 383.292858 -388.18693)
		(stroke
			(width 0.07112)
			(type default)
		)
		(layer "In4.Cu")
	)
	(gr_line
		(start 383.291334 -394.385292)
		(end 383.386076 -394.031724)
		(stroke
			(width 0.07112)
			(type default)
		)
		(layer "In4.Cu")
	)
	(gr_line
		(start 383.292858 -388.18693)
		(end 383.435606 -388.057898)
		(stroke
			(width 0.07112)
			(type default)
		)
		(layer "In4.Cu")
	)
	(gr_line
		(start 383.297938 -383.736596)
		(end 383.430526 -383.596642)
		(stroke
			(width 0.07112)
			(type default)
		)
		(layer "In4.Cu")
	)
	(gr_line
		(start 383.309114 -384.163316)
		(end 383.297938 -383.736596)
		(stroke
			(width 0.07112)
			(type default)
		)
		(layer "In4.Cu")
	)
	(gr_line
		(start 383.32029 -410.684218)
		(end 383.246884 -410.862272)
		(stroke
			(width 0.07112)
			(type default)
		)
		(layer "In4.Cu")
	)
	(gr_line
		(start 383.327656 -384.864102)
		(end 383.460244 -384.724148)
		(stroke
			(width 0.07112)
			(type default)
		)
		(layer "In4.Cu")
	)
	(gr_line
		(start 383.338832 -385.290822)
		(end 383.327656 -384.864102)
		(stroke
			(width 0.07112)
			(type default)
		)
		(layer "In4.Cu")
	)
	(gr_line
		(start 383.401316 -388.75589)
		(end 383.27203 -388.613396)
		(stroke
			(width 0.07112)
			(type default)
		)
		(layer "In4.Cu")
	)
	(gr_line
		(start 383.437892 -412.55569)
		(end 383.147062 -412.84652)
		(stroke
			(width 0.07112)
			(type default)
		)
		(layer "In4.Cu")
	)
	(gr_line
		(start 383.448814 -384.296158)
		(end 383.309114 -384.163316)
		(stroke
			(width 0.07112)
			(type default)
		)
		(layer "In4.Cu")
	)
	(gr_line
		(start 383.479802 -385.424426)
		(end 383.338832 -385.290822)
		(stroke
			(width 0.07112)
			(type default)
		)
		(layer "In4.Cu")
	)
	(gr_line
		(start 383.48031 -385.440682)
		(end 383.480564 -385.440682)
		(stroke
			(width 0.07112)
			(type default)
		)
		(layer "In4.Cu")
	)
	(gr_line
		(start 383.507742 -393.961112)
		(end 383.560574 -393.930632)
		(stroke
			(width 0.07112)
			(type default)
		)
		(layer "In4.Cu")
	)
	(gr_line
		(start 383.560574 -393.930632)
		(end 383.648712 -393.842494)
		(stroke
			(width 0.07112)
			(type default)
		)
		(layer "In4.Cu")
	)
	(gr_arc
		(start 383.601976 -9.272016)
		(mid 384.656976 -8.83502)
		(end 385.093972 -7.78002)
		(stroke
			(width 0.2)
			(type default)
		)
		(layer "In4.Cu")
	)
	(gr_line
		(start 383.648712 -393.842494)
		(end 383.648712 -393.716764)
		(stroke
			(width 0.07112)
			(type default)
		)
		(layer "In4.Cu")
	)
	(gr_line
		(start 383.68097 -382.350772)
		(end 383.68097 -382.350264)
		(stroke
			(width 0.07112)
			(type default)
		)
		(layer "In4.Cu")
	)
	(gr_line
		(start 383.684018 -388.770876)
		(end 383.718562 -388.070344)
		(stroke
			(width 0.07112)
			(type default)
		)
		(layer "In4.Cu")
	)
	(gr_line
		(start 383.719832 -412.55569)
		(end 384.010662 -412.84652)
		(stroke
			(width 0.07112)
			(type default)
		)
		(layer "In4.Cu")
	)
	(gr_line
		(start 383.732024 -384.289554)
		(end 383.713482 -383.588514)
		(stroke
			(width 0.07112)
			(type default)
		)
		(layer "In4.Cu")
	)
	(gr_line
		(start 383.761742 -385.41452)
		(end 383.7432 -384.71602)
		(stroke
			(width 0.07112)
			(type default)
		)
		(layer "In4.Cu")
	)
	(gr_line
		(start 383.762504 -385.433316)
		(end 383.76225 -385.428998)
		(stroke
			(width 0.07112)
			(type default)
		)
		(layer "In4.Cu")
	)
	(gr_line
		(start 383.894584 -410.594048)
		(end 383.71653 -410.520134)
		(stroke
			(width 0.07112)
			(type default)
		)
		(layer "In4.Cu")
	)
	(gr_line
		(start 384.09118 -393.69238)
		(end 384.444494 -393.787376)
		(stroke
			(width 0.07112)
			(type default)
		)
		(layer "In4.Cu")
	)
	(gr_line
		(start 384.255264 -409.990544)
		(end 383.60731 -410.258768)
		(stroke
			(width 0.07112)
			(type default)
		)
		(layer "In4.Cu")
	)
	(gr_line
		(start 384.27787 -322.996814)
		(end 384.27787 -322.99656)
		(stroke
			(width 0.07112)
			(type default)
		)
		(layer "In4.Cu")
	)
	(gr_line
		(start 384.289046 -410.430726)
		(end 383.894584 -410.594048)
		(stroke
			(width 0.07112)
			(type default)
		)
		(layer "In4.Cu")
	)
	(gr_line
		(start 384.362706 -410.252418)
		(end 384.289046 -410.430726)
		(stroke
			(width 0.07112)
			(type default)
		)
		(layer "In4.Cu")
	)
	(gr_line
		(start 384.444494 -393.787376)
		(end 384.445002 -393.786868)
		(stroke
			(width 0.07112)
			(type default)
		)
		(layer "In4.Cu")
	)
	(gr_line
		(start 384.458464 -356.018084)
		(end 384.45821 -356.019354)
		(stroke
			(width 0.07112)
			(type default)
		)
		(layer "In4.Cu")
	)
	(gr_line
		(start 384.49123 -394.385292)
		(end 384.585972 -394.031724)
		(stroke
			(width 0.07112)
			(type default)
		)
		(layer "In4.Cu")
	)
	(gr_line
		(start 384.506724 -379.165866)
		(end 384.508248 -379.161802)
		(stroke
			(width 0.07112)
			(type default)
		)
		(layer "In4.Cu")
	)
	(gr_line
		(start 384.560318 -411.665674)
		(end 384.382518 -411.592014)
		(stroke
			(width 0.07112)
			(type default)
		)
		(layer "In4.Cu")
	)
	(gr_line
		(start 384.707638 -393.961112)
		(end 384.76047 -393.930632)
		(stroke
			(width 0.07112)
			(type default)
		)
		(layer "In4.Cu")
	)
	(gr_line
		(start 384.76047 -393.930632)
		(end 384.848608 -393.842494)
		(stroke
			(width 0.07112)
			(type default)
		)
		(layer "In4.Cu")
	)
	(gr_line
		(start 384.769106 -379.269752)
		(end 384.768852 -379.269752)
		(stroke
			(width 0.07112)
			(type default)
		)
		(layer "In4.Cu")
	)
	(gr_line
		(start 384.821684 -379.095762)
		(end 384.821938 -379.096016)
		(stroke
			(width 0.07112)
			(type default)
		)
		(layer "In4.Cu")
	)
	(gr_line
		(start 384.848608 -393.842494)
		(end 384.848608 -393.716764)
		(stroke
			(width 0.07112)
			(type default)
		)
		(layer "In4.Cu")
	)
	(gr_line
		(start 384.876802 -322.73875)
		(end 384.877056 -322.73875)
		(stroke
			(width 0.07112)
			(type default)
		)
		(layer "In4.Cu")
	)
	(gr_line
		(start 384.921506 -411.062424)
		(end 384.273298 -411.330902)
		(stroke
			(width 0.07112)
			(type default)
		)
		(layer "In4.Cu")
	)
	(gr_line
		(start 384.95478 -411.502352)
		(end 384.560318 -411.665674)
		(stroke
			(width 0.07112)
			(type default)
		)
		(layer "In4.Cu")
	)
	(gr_line
		(start 384.994912 -389.161782)
		(end 385.158234 -388.76732)
		(stroke
			(width 0.07112)
			(type default)
		)
		(layer "In4.Cu")
	)
	(gr_line
		(start 385.028694 -411.324552)
		(end 384.95478 -411.502352)
		(stroke
			(width 0.07112)
			(type default)
		)
		(layer "In4.Cu")
	)
	(gr_line
		(start 385.068826 -389.339582)
		(end 384.994912 -389.161782)
		(stroke
			(width 0.07112)
			(type default)
		)
		(layer "In4.Cu")
	)
	(gr_line
		(start 385.093972 -7.78002)
		(end 385.093972 0.40005)
		(stroke
			(width 0.2)
			(type default)
		)
		(layer "In4.Cu")
	)
	(gr_line
		(start 385.158234 -388.76732)
		(end 385.336034 -388.693914)
		(stroke
			(width 0.07112)
			(type default)
		)
		(layer "In4.Cu")
	)
	(gr_line
		(start 385.29133 -393.69238)
		(end 385.64439 -393.787376)
		(stroke
			(width 0.07112)
			(type default)
		)
		(layer "In4.Cu")
	)
	(gr_line
		(start 385.329938 -389.449056)
		(end 385.598416 -388.800848)
		(stroke
			(width 0.07112)
			(type default)
		)
		(layer "In4.Cu")
	)
	(gr_line
		(start 385.33832 -333.543148)
		(end 385.338066 -333.542132)
		(stroke
			(width 0.07112)
			(type default)
		)
		(layer "In4.Cu")
	)
	(gr_line
		(start 385.384802 -335.397348)
		(end 385.384802 -335.397602)
		(stroke
			(width 0.07112)
			(type default)
		)
		(layer "In4.Cu")
	)
	(gr_line
		(start 385.426712 -388.119874)
		(end 385.590034 -387.725412)
		(stroke
			(width 0.07112)
			(type default)
		)
		(layer "In4.Cu")
	)
	(gr_line
		(start 385.500372 -388.29742)
		(end 385.426712 -388.119874)
		(stroke
			(width 0.07112)
			(type default)
		)
		(layer "In4.Cu")
	)
	(gr_line
		(start 385.590034 -387.725412)
		(end 385.767834 -387.651752)
		(stroke
			(width 0.07112)
			(type default)
		)
		(layer "In4.Cu")
	)
	(gr_line
		(start 385.598416 -388.800848)
		(end 385.603242 -388.78891)
		(stroke
			(width 0.07112)
			(type default)
		)
		(layer "In4.Cu")
	)
	(gr_line
		(start 385.599432 -356.083362)
		(end 385.599432 -356.084632)
		(stroke
			(width 0.07112)
			(type default)
		)
		(layer "In4.Cu")
	)
	(gr_line
		(start 385.601972 -12.288012)
		(end 260.800088 -12.288012)
		(stroke
			(width 0.2)
			(type default)
		)
		(layer "In4.Cu")
	)
	(gr_arc
		(start 385.601972 -12.288012)
		(mid 387.375417 -11.553448)
		(end 388.109968 -9.780016)
		(stroke
			(width 0.2)
			(type default)
		)
		(layer "In4.Cu")
	)
	(gr_line
		(start 385.60248 -411.234128)
		(end 385.42468 -411.160468)
		(stroke
			(width 0.07112)
			(type default)
		)
		(layer "In4.Cu")
	)
	(gr_line
		(start 385.64439 -393.787376)
		(end 385.644898 -393.786868)
		(stroke
			(width 0.07112)
			(type default)
		)
		(layer "In4.Cu")
	)
	(gr_line
		(start 385.691126 -394.385292)
		(end 385.785868 -394.031724)
		(stroke
			(width 0.07112)
			(type default)
		)
		(layer "In4.Cu")
	)
	(gr_line
		(start 385.74472 -373.013224)
		(end 385.748276 -372.995698)
		(stroke
			(width 0.07112)
			(type default)
		)
		(layer "In4.Cu")
	)
	(gr_line
		(start 385.748276 -372.995698)
		(end 385.753356 -372.978934)
		(stroke
			(width 0.07112)
			(type default)
		)
		(layer "In4.Cu")
	)
	(gr_line
		(start 385.755134 -322.423282)
		(end 385.755134 -322.423536)
		(stroke
			(width 0.07112)
			(type default)
		)
		(layer "In4.Cu")
	)
	(gr_line
		(start 385.761484 -388.406894)
		(end 386.029962 -387.758686)
		(stroke
			(width 0.07112)
			(type default)
		)
		(layer "In4.Cu")
	)
	(gr_line
		(start 385.770628 -372.922038)
		(end 385.770882 -372.92153)
		(stroke
			(width 0.07112)
			(type default)
		)
		(layer "In4.Cu")
	)
	(gr_line
		(start 385.858258 -387.077712)
		(end 386.02158 -386.68325)
		(stroke
			(width 0.07112)
			(type default)
		)
		(layer "In4.Cu")
	)
	(gr_line
		(start 385.907534 -393.961112)
		(end 385.960366 -393.930632)
		(stroke
			(width 0.07112)
			(type default)
		)
		(layer "In4.Cu")
	)
	(gr_line
		(start 385.931918 -387.255512)
		(end 385.858258 -387.077712)
		(stroke
			(width 0.07112)
			(type default)
		)
		(layer "In4.Cu")
	)
	(gr_line
		(start 385.960366 -393.930632)
		(end 386.048504 -393.842494)
		(stroke
			(width 0.07112)
			(type default)
		)
		(layer "In4.Cu")
	)
	(gr_line
		(start 385.963414 -410.630878)
		(end 385.31546 -410.899102)
		(stroke
			(width 0.07112)
			(type default)
		)
		(layer "In4.Cu")
	)
	(gr_line
		(start 385.996942 -411.070806)
		(end 385.60248 -411.234128)
		(stroke
			(width 0.07112)
			(type default)
		)
		(layer "In4.Cu")
	)
	(gr_line
		(start 386.02158 -386.68325)
		(end 386.19938 -386.609336)
		(stroke
			(width 0.07112)
			(type default)
		)
		(layer "In4.Cu")
	)
	(gr_arc
		(start 386.025898 -373.055642)
		(mid 386.023706 -373.064778)
		(end 386.02158 -373.07393)
		(stroke
			(width 0.07112)
			(type default)
		)
		(layer "In4.Cu")
	)
	(gr_line
		(start 386.040376 -390.979914)
		(end 386.04063 -390.980168)
		(stroke
			(width 0.07112)
			(type default)
		)
		(layer "In4.Cu")
	)
	(gr_line
		(start 386.048504 -393.842494)
		(end 386.048504 -393.716764)
		(stroke
			(width 0.07112)
			(type default)
		)
		(layer "In4.Cu")
	)
	(gr_line
		(start 386.070856 -410.893006)
		(end 385.996942 -411.070806)
		(stroke
			(width 0.07112)
			(type default)
		)
		(layer "In4.Cu")
	)
	(gr_line
		(start 386.1054 -389.30834)
		(end 386.268722 -388.913878)
		(stroke
			(width 0.07112)
			(type default)
		)
		(layer "In4.Cu")
	)
	(gr_line
		(start 386.17906 -389.48614)
		(end 386.1054 -389.30834)
		(stroke
			(width 0.07112)
			(type default)
		)
		(layer "In4.Cu")
	)
	(gr_line
		(start 386.193284 -387.364732)
		(end 386.461508 -386.716778)
		(stroke
			(width 0.07112)
			(type default)
		)
		(layer "In4.Cu")
	)
	(gr_line
		(start 386.261102 -325.863966)
		(end 386.261102 -325.863712)
		(stroke
			(width 0.07112)
			(type default)
		)
		(layer "In4.Cu")
	)
	(gr_line
		(start 386.268722 -388.913878)
		(end 386.446522 -388.840218)
		(stroke
			(width 0.07112)
			(type default)
		)
		(layer "In4.Cu")
	)
	(gr_line
		(start 386.440426 -389.59536)
		(end 386.70865 -388.947406)
		(stroke
			(width 0.07112)
			(type default)
		)
		(layer "In4.Cu")
	)
	(gr_line
		(start 386.491226 -393.69238)
		(end 386.84454 -393.787376)
		(stroke
			(width 0.07112)
			(type default)
		)
		(layer "In4.Cu")
	)
	(gr_line
		(start 386.501132 -412.55569)
		(end 386.210302 -412.84652)
		(stroke
			(width 0.07112)
			(type default)
		)
		(layer "In4.Cu")
	)
	(gr_line
		(start 386.536946 -388.266432)
		(end 386.700268 -387.87197)
		(stroke
			(width 0.07112)
			(type default)
		)
		(layer "In4.Cu")
	)
	(gr_line
		(start 386.610606 -388.444232)
		(end 386.536946 -388.266432)
		(stroke
			(width 0.07112)
			(type default)
		)
		(layer "In4.Cu")
	)
	(gr_line
		(start 386.644642 -410.802582)
		(end 386.466842 -410.728922)
		(stroke
			(width 0.07112)
			(type default)
		)
		(layer "In4.Cu")
	)
	(gr_line
		(start 386.700268 -387.87197)
		(end 386.878068 -387.79831)
		(stroke
			(width 0.07112)
			(type default)
		)
		(layer "In4.Cu")
	)
	(gr_line
		(start 386.783072 -412.55569)
		(end 387.073902 -412.84652)
		(stroke
			(width 0.07112)
			(type default)
		)
		(layer "In4.Cu")
	)
	(gr_line
		(start 386.84454 -393.787376)
		(end 386.845048 -393.786868)
		(stroke
			(width 0.07112)
			(type default)
		)
		(layer "In4.Cu")
	)
	(gr_line
		(start 386.871972 -388.553452)
		(end 387.14045 -387.905244)
		(stroke
			(width 0.07112)
			(type default)
		)
		(layer "In4.Cu")
	)
	(gr_line
		(start 386.879846 -387.797548)
		(end 386.888736 -387.776212)
		(stroke
			(width 0.07112)
			(type default)
		)
		(layer "In4.Cu")
	)
	(gr_line
		(start 386.887466 -325.682864)
		(end 386.887212 -325.682864)
		(stroke
			(width 0.07112)
			(type default)
		)
		(layer "In4.Cu")
	)
	(gr_line
		(start 386.891276 -394.385292)
		(end 386.986018 -394.031724)
		(stroke
			(width 0.07112)
			(type default)
		)
		(layer "In4.Cu")
	)
	(gr_line
		(start 386.968746 -387.22427)
		(end 387.132068 -386.829808)
		(stroke
			(width 0.07112)
			(type default)
		)
		(layer "In4.Cu")
	)
	(gr_line
		(start 387.005576 -410.199332)
		(end 386.357622 -410.467556)
		(stroke
			(width 0.07112)
			(type default)
		)
		(layer "In4.Cu")
	)
	(gr_line
		(start 387.039104 -410.63926)
		(end 386.644642 -410.802582)
		(stroke
			(width 0.07112)
			(type default)
		)
		(layer "In4.Cu")
	)
	(gr_line
		(start 387.042406 -387.401816)
		(end 386.968746 -387.22427)
		(stroke
			(width 0.07112)
			(type default)
		)
		(layer "In4.Cu")
	)
	(gr_line
		(start 387.107684 -393.961112)
		(end 387.160516 -393.930632)
		(stroke
			(width 0.07112)
			(type default)
		)
		(layer "In4.Cu")
	)
	(gr_line
		(start 387.113018 -410.461206)
		(end 387.039104 -410.63926)
		(stroke
			(width 0.07112)
			(type default)
		)
		(layer "In4.Cu")
	)
	(gr_line
		(start 387.132068 -386.829808)
		(end 387.309868 -386.756148)
		(stroke
			(width 0.07112)
			(type default)
		)
		(layer "In4.Cu")
	)
	(gr_line
		(start 387.14045 -387.905244)
		(end 387.149086 -387.884162)
		(stroke
			(width 0.07112)
			(type default)
		)
		(layer "In4.Cu")
	)
	(gr_line
		(start 387.153912 -325.590408)
		(end 387.153912 -325.590154)
		(stroke
			(width 0.07112)
			(type default)
		)
		(layer "In4.Cu")
	)
	(gr_line
		(start 387.15823 -392.58494)
		(end 387.193282 -392.549888)
		(stroke
			(width 0.07112)
			(type default)
		)
		(layer "In4.Cu")
	)
	(gr_line
		(start 387.160516 -393.930632)
		(end 387.248654 -393.842494)
		(stroke
			(width 0.07112)
			(type default)
		)
		(layer "In4.Cu")
	)
	(gr_arc
		(start 387.193282 -392.549888)
		(mid 387.228241 -392.497558)
		(end 387.240526 -392.435842)
		(stroke
			(width 0.07112)
			(type default)
		)
		(layer "In4.Cu")
	)
	(gr_line
		(start 387.240526 -392.435842)
		(end 387.240526 -392.385296)
		(stroke
			(width 0.07112)
			(type default)
		)
		(layer "In4.Cu")
	)
	(gr_line
		(start 387.240526 -391.054844)
		(end 387.240526 -391.054082)
		(stroke
			(width 0.07112)
			(type default)
		)
		(layer "In4.Cu")
	)
	(gr_line
		(start 387.248654 -393.842494)
		(end 387.248654 -393.716764)
		(stroke
			(width 0.07112)
			(type default)
		)
		(layer "In4.Cu")
	)
	(gr_line
		(start 387.303518 -387.51129)
		(end 387.571996 -386.863082)
		(stroke
			(width 0.07112)
			(type default)
		)
		(layer "In4.Cu")
	)
	(gr_line
		(start 387.31063 -389.785098)
		(end 387.311138 -389.784336)
		(stroke
			(width 0.07112)
			(type default)
		)
		(layer "In4.Cu")
	)
	(gr_line
		(start 387.311646 -386.755386)
		(end 387.311392 -386.755132)
		(stroke
			(width 0.07112)
			(type default)
		)
		(layer "In4.Cu")
	)
	(gr_line
		(start 387.46049 -331.112114)
		(end 387.46049 -331.112368)
		(stroke
			(width 0.07112)
			(type default)
		)
		(layer "In4.Cu")
	)
	(gr_line
		(start 387.509004 -321.77355)
		(end 387.50875 -321.77355)
		(stroke
			(width 0.07112)
			(type default)
		)
		(layer "In4.Cu")
	)
	(gr_line
		(start 387.544564 -389.94588)
		(end 387.544564 -389.946134)
		(stroke
			(width 0.07112)
			(type default)
		)
		(layer "In4.Cu")
	)
	(gr_line
		(start 387.558788 -389.919464)
		(end 387.558788 -389.91921)
		(stroke
			(width 0.07112)
			(type default)
		)
		(layer "In4.Cu")
	)
	(gr_line
		(start 387.578346 -411.726126)
		(end 387.400546 -411.652466)
		(stroke
			(width 0.07112)
			(type default)
		)
		(layer "In4.Cu")
	)
	(gr_arc
		(start 387.601968 2.908046)
		(mid 385.828585 2.173457)
		(end 385.093972 0.40005)
		(stroke
			(width 0.2)
			(type default)
		)
		(layer "In4.Cu")
	)
	(gr_line
		(start 387.601968 2.908046)
		(end 456.202034 2.908046)
		(stroke
			(width 0.2)
			(type default)
		)
		(layer "In4.Cu")
	)
	(gr_line
		(start 387.691376 -393.69238)
		(end 388.044436 -393.787376)
		(stroke
			(width 0.07112)
			(type default)
		)
		(layer "In4.Cu")
	)
	(gr_line
		(start 387.93928 -411.122876)
		(end 387.291326 -411.391354)
		(stroke
			(width 0.07112)
			(type default)
		)
		(layer "In4.Cu")
	)
	(gr_line
		(start 387.972808 -411.562804)
		(end 387.578346 -411.726126)
		(stroke
			(width 0.07112)
			(type default)
		)
		(layer "In4.Cu")
	)
	(gr_line
		(start 388.044436 -393.787376)
		(end 388.044944 -393.786868)
		(stroke
			(width 0.07112)
			(type default)
		)
		(layer "In4.Cu")
	)
	(gr_line
		(start 388.046722 -411.385004)
		(end 387.972808 -411.562804)
		(stroke
			(width 0.07112)
			(type default)
		)
		(layer "In4.Cu")
	)
	(gr_line
		(start 388.091172 -394.385292)
		(end 388.185914 -394.031724)
		(stroke
			(width 0.07112)
			(type default)
		)
		(layer "In4.Cu")
	)
	(gr_line
		(start 388.109968 -0.508)
		(end 388.109968 -9.780016)
		(stroke
			(width 0.2)
			(type default)
		)
		(layer "In4.Cu")
	)
	(gr_line
		(start 388.30758 -393.961112)
		(end 388.360412 -393.930632)
		(stroke
			(width 0.07112)
			(type default)
		)
		(layer "In4.Cu")
	)
	(gr_line
		(start 388.360412 -393.930632)
		(end 388.44855 -393.842494)
		(stroke
			(width 0.07112)
			(type default)
		)
		(layer "In4.Cu")
	)
	(gr_line
		(start 388.380224 -321.439032)
		(end 388.37997 -321.439032)
		(stroke
			(width 0.07112)
			(type default)
		)
		(layer "In4.Cu")
	)
	(gr_line
		(start 388.44855 -393.842494)
		(end 388.44855 -393.716764)
		(stroke
			(width 0.07112)
			(type default)
		)
		(layer "In4.Cu")
	)
	(gr_line
		(start 388.596632 -387.135116)
		(end 388.800594 -386.759958)
		(stroke
			(width 0.07112)
			(type default)
		)
		(layer "In4.Cu")
	)
	(gr_line
		(start 388.620508 -411.294326)
		(end 388.442962 -411.22092)
		(stroke
			(width 0.07112)
			(type default)
		)
		(layer "In4.Cu")
	)
	(gr_line
		(start 388.650988 -387.31952)
		(end 388.596632 -387.135116)
		(stroke
			(width 0.07112)
			(type default)
		)
		(layer "In4.Cu")
	)
	(gr_line
		(start 388.707122 -379.123448)
		(end 388.707376 -379.123956)
		(stroke
			(width 0.07112)
			(type default)
		)
		(layer "In4.Cu")
	)
	(gr_line
		(start 388.728712 -332.889098)
		(end 388.728966 -332.889098)
		(stroke
			(width 0.07112)
			(type default)
		)
		(layer "In4.Cu")
	)
	(gr_line
		(start 388.78764 -359.237534)
		(end 388.78764 -359.23855)
		(stroke
			(width 0.07112)
			(type default)
		)
		(layer "In4.Cu")
	)
	(gr_line
		(start 388.800594 -386.759958)
		(end 388.984998 -386.705602)
		(stroke
			(width 0.07112)
			(type default)
		)
		(layer "In4.Cu")
	)
	(gr_arc
		(start 388.811262 -379.597666)
		(mid 388.811262 -379.59792)
		(end 388.811262 -379.598174)
		(stroke
			(width 0.07112)
			(type default)
		)
		(layer "In4.Cu")
	)
	(gr_line
		(start 388.891272 -393.69238)
		(end 389.245094 -393.786868)
		(stroke
			(width 0.07112)
			(type default)
		)
		(layer "In4.Cu")
	)
	(gr_line
		(start 388.899146 -387.455918)
		(end 389.234426 -386.839714)
		(stroke
			(width 0.07112)
			(type default)
		)
		(layer "In4.Cu")
	)
	(gr_line
		(start 388.981696 -410.691076)
		(end 388.333488 -410.959554)
		(stroke
			(width 0.07112)
			(type default)
		)
		(layer "In4.Cu")
	)
	(gr_line
		(start 389.01497 -411.131004)
		(end 388.620508 -411.294326)
		(stroke
			(width 0.07112)
			(type default)
		)
		(layer "In4.Cu")
	)
	(gr_line
		(start 389.08863 -410.953204)
		(end 389.01497 -411.131004)
		(stroke
			(width 0.07112)
			(type default)
		)
		(layer "In4.Cu")
	)
	(gr_line
		(start 389.13562 -386.144262)
		(end 389.339582 -385.769358)
		(stroke
			(width 0.07112)
			(type default)
		)
		(layer "In4.Cu")
	)
	(gr_line
		(start 389.189976 -386.32892)
		(end 389.13562 -386.144262)
		(stroke
			(width 0.07112)
			(type default)
		)
		(layer "In4.Cu")
	)
	(gr_line
		(start 389.291322 -394.385292)
		(end 389.386318 -394.031216)
		(stroke
			(width 0.07112)
			(type default)
		)
		(layer "In4.Cu")
	)
	(gr_line
		(start 389.320532 -321.163188)
		(end 389.320532 -321.163442)
		(stroke
			(width 0.07112)
			(type default)
		)
		(layer "In4.Cu")
	)
	(gr_line
		(start 389.339582 -385.769358)
		(end 389.52424 -385.715002)
		(stroke
			(width 0.07112)
			(type default)
		)
		(layer "In4.Cu")
	)
	(gr_line
		(start 389.438388 -386.465318)
		(end 389.773668 -385.849114)
		(stroke
			(width 0.07112)
			(type default)
		)
		(layer "In4.Cu")
	)
	(gr_line
		(start 389.526018 -385.714494)
		(end 389.708898 -385.378198)
		(stroke
			(width 0.07112)
			(type default)
		)
		(layer "In4.Cu")
	)
	(gr_line
		(start 389.564372 -412.55569)
		(end 389.273542 -412.84652)
		(stroke
			(width 0.07112)
			(type default)
		)
		(layer "In4.Cu")
	)
	(gr_line
		(start 389.571484 -324.868286)
		(end 389.571484 -324.86854)
		(stroke
			(width 0.07112)
			(type default)
		)
		(layer "In4.Cu")
	)
	(gr_line
		(start 389.66267 -410.86278)
		(end 389.48487 -410.78912)
		(stroke
			(width 0.07112)
			(type default)
		)
		(layer "In4.Cu")
	)
	(gr_line
		(start 389.674862 -385.153662)
		(end 389.878824 -384.778758)
		(stroke
			(width 0.07112)
			(type default)
		)
		(layer "In4.Cu")
	)
	(gr_line
		(start 389.67537 -388.093204)
		(end 389.912606 -387.738112)
		(stroke
			(width 0.07112)
			(type default)
		)
		(layer "In4.Cu")
	)
	(gr_line
		(start 389.712962 -388.28218)
		(end 389.67537 -388.093204)
		(stroke
			(width 0.07112)
			(type default)
		)
		(layer "In4.Cu")
	)
	(gr_line
		(start 389.71982 -360.814874)
		(end 389.71982 -360.81589)
		(stroke
			(width 0.07112)
			(type default)
		)
		(layer "In4.Cu")
	)
	(gr_line
		(start 389.729218 -385.338066)
		(end 389.674862 -385.153662)
		(stroke
			(width 0.07112)
			(type default)
		)
		(layer "In4.Cu")
	)
	(gr_line
		(start 389.846312 -412.55569)
		(end 390.137142 -412.84652)
		(stroke
			(width 0.07112)
			(type default)
		)
		(layer "In4.Cu")
	)
	(gr_line
		(start 389.878824 -384.778758)
		(end 390.063228 -384.724148)
		(stroke
			(width 0.07112)
			(type default)
		)
		(layer "In4.Cu")
	)
	(gr_line
		(start 389.912606 -387.738112)
		(end 390.101582 -387.70052)
		(stroke
			(width 0.07112)
			(type default)
		)
		(layer "In4.Cu")
	)
	(gr_line
		(start 389.947912 -388.440168)
		(end 390.337548 -387.856984)
		(stroke
			(width 0.07112)
			(type default)
		)
		(layer "In4.Cu")
	)
	(gr_line
		(start 389.977376 -385.474464)
		(end 390.31291 -384.858006)
		(stroke
			(width 0.07112)
			(type default)
		)
		(layer "In4.Cu")
	)
	(gr_line
		(start 390.023604 -410.25953)
		(end 389.37565 -410.528008)
		(stroke
			(width 0.07112)
			(type default)
		)
		(layer "In4.Cu")
	)
	(gr_line
		(start 390.057132 -410.699458)
		(end 389.66267 -410.86278)
		(stroke
			(width 0.07112)
			(type default)
		)
		(layer "In4.Cu")
	)
	(gr_line
		(start 390.06526 -384.72364)
		(end 390.06526 -384.723132)
		(stroke
			(width 0.07112)
			(type default)
		)
		(layer "In4.Cu")
	)
	(gr_line
		(start 390.131046 -410.521658)
		(end 390.057132 -410.699458)
		(stroke
			(width 0.07112)
			(type default)
		)
		(layer "In4.Cu")
	)
	(gr_line
		(start 390.301988 -387.155436)
		(end 390.539224 -386.800344)
		(stroke
			(width 0.07112)
			(type default)
		)
		(layer "In4.Cu")
	)
	(gr_line
		(start 390.324594 -17.90319)
		(end 390.033764 -17.61236)
		(stroke
			(width 0.07112)
			(type default)
		)
		(layer "In4.Cu")
	)
	(gr_line
		(start 390.33958 -387.344158)
		(end 390.301988 -387.155436)
		(stroke
			(width 0.07112)
			(type default)
		)
		(layer "In4.Cu")
	)
	(gr_line
		(start 390.500362 -324.560692)
		(end 390.500616 -324.560692)
		(stroke
			(width 0.07112)
			(type default)
		)
		(layer "In4.Cu")
	)
	(gr_line
		(start 390.539224 -386.800344)
		(end 390.727946 -386.762752)
		(stroke
			(width 0.07112)
			(type default)
		)
		(layer "In4.Cu")
	)
	(gr_line
		(start 390.565132 -332.554072)
		(end 390.565386 -332.554072)
		(stroke
			(width 0.07112)
			(type default)
		)
		(layer "In4.Cu")
	)
	(gr_line
		(start 390.57453 -387.5024)
		(end 390.964166 -386.919216)
		(stroke
			(width 0.07112)
			(type default)
		)
		(layer "In4.Cu")
	)
	(gr_line
		(start 390.705594 -411.592268)
		(end 390.528048 -411.518608)
		(stroke
			(width 0.07112)
			(type default)
		)
		(layer "In4.Cu")
	)
	(gr_line
		(start 390.866884 -391.689336)
		(end 390.868408 -391.687812)
		(stroke
			(width 0.07112)
			(type default)
		)
		(layer "In4.Cu")
	)
	(gr_line
		(start 390.897364 -17.61236)
		(end 390.606534 -17.90319)
		(stroke
			(width 0.07112)
			(type default)
		)
		(layer "In4.Cu")
	)
	(gr_line
		(start 390.933686 -334.604868)
		(end 390.933686 -334.605122)
		(stroke
			(width 0.07112)
			(type default)
		)
		(layer "In4.Cu")
	)
	(gr_line
		(start 390.982962 -386.136388)
		(end 391.220198 -385.781296)
		(stroke
			(width 0.07112)
			(type default)
		)
		(layer "In4.Cu")
	)
	(gr_line
		(start 391.020554 -386.32511)
		(end 390.982962 -386.136388)
		(stroke
			(width 0.07112)
			(type default)
		)
		(layer "In4.Cu")
	)
	(gr_line
		(start 391.066528 -410.989018)
		(end 390.418574 -411.257496)
		(stroke
			(width 0.07112)
			(type default)
		)
		(layer "In4.Cu")
	)
	(gr_line
		(start 391.10031 -411.4292)
		(end 390.705594 -411.592268)
		(stroke
			(width 0.07112)
			(type default)
		)
		(layer "In4.Cu")
	)
	(gr_line
		(start 391.17397 -411.251146)
		(end 391.10031 -411.4292)
		(stroke
			(width 0.07112)
			(type default)
		)
		(layer "In4.Cu")
	)
	(gr_line
		(start 391.220198 -385.781296)
		(end 391.40892 -385.743704)
		(stroke
			(width 0.07112)
			(type default)
		)
		(layer "In4.Cu")
	)
	(gr_line
		(start 391.230866 6.008878)
		(end 390.940036 5.718048)
		(stroke
			(width 0.07112)
			(type default)
		)
		(layer "In4.Cu")
	)
	(gr_line
		(start 391.230866 6.290818)
		(end 390.940036 6.581648)
		(stroke
			(width 0.07112)
			(type default)
		)
		(layer "In4.Cu")
	)
	(gr_line
		(start 391.25525 -386.483352)
		(end 391.644886 -385.900168)
		(stroke
			(width 0.07112)
			(type default)
		)
		(layer "In4.Cu")
	)
	(gr_line
		(start 391.542524 -332.639924)
		(end 391.542778 -332.639924)
		(stroke
			(width 0.07112)
			(type default)
		)
		(layer "In4.Cu")
	)
	(gr_arc
		(start 391.58418 -371.389656)
		(mid 391.58418 -371.38991)
		(end 391.58418 -371.390164)
		(stroke
			(width 0.07112)
			(type default)
		)
		(layer "In4.Cu")
	)
	(gr_line
		(start 391.747756 -411.160722)
		(end 391.569702 -411.087062)
		(stroke
			(width 0.07112)
			(type default)
		)
		(layer "In4.Cu")
	)
	(gr_line
		(start 392.108944 -410.557218)
		(end 391.460736 -410.825696)
		(stroke
			(width 0.07112)
			(type default)
		)
		(layer "In4.Cu")
	)
	(gr_line
		(start 392.142218 -410.9974)
		(end 391.747756 -411.160722)
		(stroke
			(width 0.07112)
			(type default)
		)
		(layer "In4.Cu")
	)
	(gr_line
		(start 392.216132 -410.819092)
		(end 392.142218 -410.9974)
		(stroke
			(width 0.07112)
			(type default)
		)
		(layer "In4.Cu")
	)
	(gr_line
		(start 392.216894 -410.817822)
		(end 392.21664 -410.818076)
		(stroke
			(width 0.07112)
			(type default)
		)
		(layer "In4.Cu")
	)
	(gr_line
		(start 392.627612 -412.55569)
		(end 392.336782 -412.84652)
		(stroke
			(width 0.07112)
			(type default)
		)
		(layer "In4.Cu")
	)
	(gr_line
		(start 392.909552 -412.55569)
		(end 393.200382 -412.84652)
		(stroke
			(width 0.07112)
			(type default)
		)
		(layer "In4.Cu")
	)
	(gr_line
		(start 393.036298 -372.19763)
		(end 393.036552 -372.19763)
		(stroke
			(width 0.07112)
			(type default)
		)
		(layer "In4.Cu")
	)
	(gr_line
		(start 393.117578 -19.427952)
		(end 392.826748 -19.137122)
		(stroke
			(width 0.07112)
			(type default)
		)
		(layer "In4.Cu")
	)
	(gr_line
		(start 393.233148 -410.604462)
		(end 393.063222 -410.513784)
		(stroke
			(width 0.07112)
			(type default)
		)
		(layer "In4.Cu")
	)
	(gr_line
		(start 393.28852 -378.800868)
		(end 393.289028 -378.800106)
		(stroke
			(width 0.07112)
			(type default)
		)
		(layer "In4.Cu")
	)
	(gr_line
		(start 393.303252 -368.605054)
		(end 393.303252 -368.603784)
		(stroke
			(width 0.07112)
			(type default)
		)
		(layer "In4.Cu")
	)
	(gr_line
		(start 393.464034 -332.09865)
		(end 393.46378 -332.09865)
		(stroke
			(width 0.07112)
			(type default)
		)
		(layer "In4.Cu")
	)
	(gr_arc
		(start 393.585192 -368.604038)
		(mid 393.585192 -368.603784)
		(end 393.585192 -368.60353)
		(stroke
			(width 0.07112)
			(type default)
		)
		(layer "In4.Cu")
	)
	(gr_line
		(start 393.64158 -410.48051)
		(end 393.233148 -410.604462)
		(stroke
			(width 0.07112)
			(type default)
		)
		(layer "In4.Cu")
	)
	(gr_line
		(start 393.651232 -410.039312)
		(end 392.980164 -410.24302)
		(stroke
			(width 0.07112)
			(type default)
		)
		(layer "In4.Cu")
	)
	(gr_line
		(start 393.690348 -19.137122)
		(end 393.399518 -19.427952)
		(stroke
			(width 0.07112)
			(type default)
		)
		(layer "In4.Cu")
	)
	(gr_line
		(start 393.702794 -411.671008)
		(end 393.524994 -411.597348)
		(stroke
			(width 0.07112)
			(type default)
		)
		(layer "In4.Cu")
	)
	(gr_line
		(start 393.732258 -410.310584)
		(end 393.64158 -410.48051)
		(stroke
			(width 0.07112)
			(type default)
		)
		(layer "In4.Cu")
	)
	(gr_line
		(start 394.009626 -375.64441)
		(end 394.009626 -375.644918)
		(stroke
			(width 0.07112)
			(type default)
		)
		(layer "In4.Cu")
	)
	(gr_line
		(start 394.063982 -411.067758)
		(end 393.415774 -411.336236)
		(stroke
			(width 0.07112)
			(type default)
		)
		(layer "In4.Cu")
	)
	(gr_line
		(start 394.097256 -411.507686)
		(end 393.702794 -411.671008)
		(stroke
			(width 0.07112)
			(type default)
		)
		(layer "In4.Cu")
	)
	(gr_line
		(start 394.17117 -411.329886)
		(end 394.097256 -411.507686)
		(stroke
			(width 0.07112)
			(type default)
		)
		(layer "In4.Cu")
	)
	(gr_line
		(start 394.24737 -336.4992)
		(end 394.247624 -336.498946)
		(stroke
			(width 0.07112)
			(type default)
		)
		(layer "In4.Cu")
	)
	(gr_line
		(start 394.247624 -367.740184)
		(end 394.247624 -367.697766)
		(stroke
			(width 0.07112)
			(type default)
		)
		(layer "In4.Cu")
	)
	(gr_line
		(start 394.248132 -367.741454)
		(end 394.247624 -367.740184)
		(stroke
			(width 0.07112)
			(type default)
		)
		(layer "In4.Cu")
	)
	(gr_line
		(start 394.26007 -367.780824)
		(end 394.248132 -367.741454)
		(stroke
			(width 0.07112)
			(type default)
		)
		(layer "In4.Cu")
	)
	(gr_line
		(start 394.530072 -367.69929)
		(end 394.530072 -367.699036)
		(stroke
			(width 0.07112)
			(type default)
		)
		(layer "In4.Cu")
	)
	(gr_line
		(start 394.744956 -411.239462)
		(end 394.567156 -411.165802)
		(stroke
			(width 0.07112)
			(type default)
		)
		(layer "In4.Cu")
	)
	(gr_line
		(start 395.01826 -378.008642)
		(end 395.01826 -378.008134)
		(stroke
			(width 0.07112)
			(type default)
		)
		(layer "In4.Cu")
	)
	(gr_line
		(start 395.10589 -410.636212)
		(end 394.457936 -410.904436)
		(stroke
			(width 0.07112)
			(type default)
		)
		(layer "In4.Cu")
	)
	(gr_line
		(start 395.139418 -411.07614)
		(end 394.744956 -411.239462)
		(stroke
			(width 0.07112)
			(type default)
		)
		(layer "In4.Cu")
	)
	(gr_line
		(start 395.213332 -410.89834)
		(end 395.139418 -411.07614)
		(stroke
			(width 0.07112)
			(type default)
		)
		(layer "In4.Cu")
	)
	(gr_line
		(start 395.477492 -388.447534)
		(end 395.477492 -388.020814)
		(stroke
			(width 0.07112)
			(type default)
		)
		(layer "In4.Cu")
	)
	(gr_line
		(start 395.477492 -388.020814)
		(end 395.613382 -387.884924)
		(stroke
			(width 0.07112)
			(type default)
		)
		(layer "In4.Cu")
	)
	(gr_line
		(start 395.477492 -387.076442)
		(end 395.477492 -386.649722)
		(stroke
			(width 0.07112)
			(type default)
		)
		(layer "In4.Cu")
	)
	(gr_line
		(start 395.477492 -386.649722)
		(end 395.613382 -386.513832)
		(stroke
			(width 0.07112)
			(type default)
		)
		(layer "In4.Cu")
	)
	(gr_line
		(start 395.477492 -383.99085)
		(end 395.477492 -383.56413)
		(stroke
			(width 0.07112)
			(type default)
		)
		(layer "In4.Cu")
	)
	(gr_line
		(start 395.477492 -383.56413)
		(end 395.618462 -383.42316)
		(stroke
			(width 0.07112)
			(type default)
		)
		(layer "In4.Cu")
	)
	(gr_line
		(start 395.613382 -388.583424)
		(end 395.477492 -388.447534)
		(stroke
			(width 0.07112)
			(type default)
		)
		(layer "In4.Cu")
	)
	(gr_line
		(start 395.613382 -387.212332)
		(end 395.477492 -387.076442)
		(stroke
			(width 0.07112)
			(type default)
		)
		(layer "In4.Cu")
	)
	(gr_line
		(start 395.614652 -384.12801)
		(end 395.477492 -383.99085)
		(stroke
			(width 0.07112)
			(type default)
		)
		(layer "In4.Cu")
	)
	(gr_line
		(start 395.619478 -383.422144)
		(end 395.62024 -383.421382)
		(stroke
			(width 0.07112)
			(type default)
		)
		(layer "In4.Cu")
	)
	(gr_line
		(start 395.690852 -412.55569)
		(end 395.400022 -412.84652)
		(stroke
			(width 0.07112)
			(type default)
		)
		(layer "In4.Cu")
	)
	(gr_line
		(start 395.896592 -388.584694)
		(end 395.896592 -387.883654)
		(stroke
			(width 0.07112)
			(type default)
		)
		(layer "In4.Cu")
	)
	(gr_line
		(start 395.896592 -387.213602)
		(end 395.896592 -386.512562)
		(stroke
			(width 0.07112)
			(type default)
		)
		(layer "In4.Cu")
	)
	(gr_line
		(start 395.896592 -384.12801)
		(end 395.901672 -384.12293)
		(stroke
			(width 0.07112)
			(type default)
		)
		(layer "In4.Cu")
	)
	(gr_line
		(start 395.901672 -384.12293)
		(end 395.901672 -383.422144)
		(stroke
			(width 0.07112)
			(type default)
		)
		(layer "In4.Cu")
	)
	(gr_line
		(start 395.901672 -383.422144)
		(end 395.90218 -383.421636)
		(stroke
			(width 0.07112)
			(type default)
		)
		(layer "In4.Cu")
	)
	(gr_line
		(start 395.912594 -17.90319)
		(end 395.621764 -17.61236)
		(stroke
			(width 0.07112)
			(type default)
		)
		(layer "In4.Cu")
	)
	(gr_line
		(start 395.972792 -412.55569)
		(end 396.263622 -412.84652)
		(stroke
			(width 0.07112)
			(type default)
		)
		(layer "In4.Cu")
	)
	(gr_line
		(start 396.349474 -410.63418)
		(end 396.179548 -410.543248)
		(stroke
			(width 0.07112)
			(type default)
		)
		(layer "In4.Cu")
	)
	(gr_line
		(start 396.485364 -17.61236)
		(end 396.194534 -17.90319)
		(stroke
			(width 0.07112)
			(type default)
		)
		(layer "In4.Cu")
	)
	(gr_line
		(start 396.621508 -411.766766)
		(end 396.467584 -411.698694)
		(stroke
			(width 0.07112)
			(type default)
		)
		(layer "In4.Cu")
	)
	(gr_line
		(start 396.757906 -410.510228)
		(end 396.349474 -410.63418)
		(stroke
			(width 0.07112)
			(type default)
		)
		(layer "In4.Cu")
	)
	(gr_line
		(start 396.767558 -410.06903)
		(end 396.09649 -410.272738)
		(stroke
			(width 0.07112)
			(type default)
		)
		(layer "In4.Cu")
	)
	(gr_line
		(start 396.848584 -410.340302)
		(end 396.757906 -410.510228)
		(stroke
			(width 0.07112)
			(type default)
		)
		(layer "In4.Cu")
	)
	(gr_line
		(start 396.984982 -411.193234)
		(end 396.363952 -411.435042)
		(stroke
			(width 0.07112)
			(type default)
		)
		(layer "In4.Cu")
	)
	(gr_line
		(start 397.019526 -411.611826)
		(end 396.621508 -411.766766)
		(stroke
			(width 0.07112)
			(type default)
		)
		(layer "In4.Cu")
	)
	(gr_line
		(start 397.086582 -411.457648)
		(end 397.019526 -411.611826)
		(stroke
			(width 0.07112)
			(type default)
		)
		(layer "In4.Cu")
	)
	(gr_line
		(start 397.66113 -411.380178)
		(end 397.485108 -411.302708)
		(stroke
			(width 0.07112)
			(type default)
		)
		(layer "In4.Cu")
	)
	(gr_line
		(start 398.034764 -410.784802)
		(end 397.381222 -411.039056)
		(stroke
			(width 0.07112)
			(type default)
		)
		(layer "In4.Cu")
	)
	(gr_line
		(start 398.058894 -411.225492)
		(end 397.66113 -411.380178)
		(stroke
			(width 0.07112)
			(type default)
		)
		(layer "In4.Cu")
	)
	(gr_line
		(start 398.136364 -411.049216)
		(end 398.058894 -411.225492)
		(stroke
			(width 0.07112)
			(type default)
		)
		(layer "In4.Cu")
	)
	(gr_line
		(start 398.706594 -19.42719)
		(end 398.415764 -19.13636)
		(stroke
			(width 0.07112)
			(type default)
		)
		(layer "In4.Cu")
	)
	(gr_line
		(start 398.712182 -410.971238)
		(end 398.53616 -410.893768)
		(stroke
			(width 0.07112)
			(type default)
		)
		(layer "In4.Cu")
	)
	(gr_line
		(start 398.754092 -412.55569)
		(end 398.463262 -412.84652)
		(stroke
			(width 0.07112)
			(type default)
		)
		(layer "In4.Cu")
	)
	(gr_line
		(start 399.036032 -412.55569)
		(end 399.326862 -412.84652)
		(stroke
			(width 0.07112)
			(type default)
		)
		(layer "In4.Cu")
	)
	(gr_line
		(start 399.085816 -410.375862)
		(end 398.432274 -410.630116)
		(stroke
			(width 0.07112)
			(type default)
		)
		(layer "In4.Cu")
	)
	(gr_line
		(start 399.109946 -410.816552)
		(end 398.712182 -410.971238)
		(stroke
			(width 0.07112)
			(type default)
		)
		(layer "In4.Cu")
	)
	(gr_line
		(start 399.18767 -410.640276)
		(end 399.109946 -410.816552)
		(stroke
			(width 0.07112)
			(type default)
		)
		(layer "In4.Cu")
	)
	(gr_line
		(start 399.279364 -19.13636)
		(end 398.988534 -19.42719)
		(stroke
			(width 0.07112)
			(type default)
		)
		(layer "In4.Cu")
	)
	(gr_line
		(start 399.900394 -411.730952)
		(end 399.726404 -411.648402)
		(stroke
			(width 0.07112)
			(type default)
		)
		(layer "In4.Cu")
	)
	(gr_line
		(start 400.290284 -411.14599)
		(end 399.630138 -411.38221)
		(stroke
			(width 0.07112)
			(type default)
		)
		(layer "In4.Cu")
	)
	(gr_line
		(start 400.302476 -411.587188)
		(end 399.900394 -411.730952)
		(stroke
			(width 0.07112)
			(type default)
		)
		(layer "In4.Cu")
	)
	(gr_line
		(start 400.384518 -411.412944)
		(end 400.302476 -411.587188)
		(stroke
			(width 0.07112)
			(type default)
		)
		(layer "In4.Cu")
	)
	(gr_line
		(start 400.962368 -411.350968)
		(end 400.788124 -411.268672)
		(stroke
			(width 0.07112)
			(type default)
		)
		(layer "In4.Cu")
	)
	(gr_line
		(start 401.352258 -410.766006)
		(end 400.691858 -411.002226)
		(stroke
			(width 0.07112)
			(type default)
		)
		(layer "In4.Cu")
	)
	(gr_line
		(start 401.364196 -411.207204)
		(end 400.962368 -411.350968)
		(stroke
			(width 0.07112)
			(type default)
		)
		(layer "In4.Cu")
	)
	(gr_line
		(start 401.446492 -411.033214)
		(end 401.364196 -411.207204)
		(stroke
			(width 0.07112)
			(type default)
		)
		(layer "In4.Cu")
	)
	(gr_line
		(start 401.500594 -17.90319)
		(end 401.209764 -17.61236)
		(stroke
			(width 0.07112)
			(type default)
		)
		(layer "In4.Cu")
	)
	(gr_line
		(start 401.817332 -412.55569)
		(end 401.526502 -412.84652)
		(stroke
			(width 0.07112)
			(type default)
		)
		(layer "In4.Cu")
	)
	(gr_line
		(start 402.073364 -17.61236)
		(end 401.782534 -17.90319)
		(stroke
			(width 0.07112)
			(type default)
		)
		(layer "In4.Cu")
	)
	(gr_line
		(start 402.099272 -412.55569)
		(end 402.390102 -412.84652)
		(stroke
			(width 0.07112)
			(type default)
		)
		(layer "In4.Cu")
	)
	(gr_line
		(start 403.001988 -411.700726)
		(end 402.832062 -411.610048)
		(stroke
			(width 0.07112)
			(type default)
		)
		(layer "In4.Cu")
	)
	(gr_line
		(start 403.41042 -411.576774)
		(end 403.001988 -411.700726)
		(stroke
			(width 0.07112)
			(type default)
		)
		(layer "In4.Cu")
	)
	(gr_line
		(start 403.419056 -397.156432)
		(end 403.464522 -397.201898)
		(stroke
			(width 0.07112)
			(type default)
		)
		(layer "In4.Cu")
	)
	(gr_line
		(start 403.420072 -411.13583)
		(end 402.749004 -411.339284)
		(stroke
			(width 0.07112)
			(type default)
		)
		(layer "In4.Cu")
	)
	(gr_line
		(start 403.464522 -397.381984)
		(end 403.319234 -397.527272)
		(stroke
			(width 0.07112)
			(type default)
		)
		(layer "In4.Cu")
	)
	(gr_line
		(start 403.464522 -397.201898)
		(end 403.464522 -397.381984)
		(stroke
			(width 0.07112)
			(type default)
		)
		(layer "In4.Cu")
	)
	(gr_line
		(start 403.501098 -411.407102)
		(end 403.41042 -411.576774)
		(stroke
			(width 0.07112)
			(type default)
		)
		(layer "In4.Cu")
	)
	(gr_line
		(start 403.696424 -397.726662)
		(end 403.520402 -397.726662)
		(stroke
			(width 0.07112)
			(type default)
		)
		(layer "In4.Cu")
	)
	(gr_line
		(start 403.819106 -397.849344)
		(end 403.696424 -397.726662)
		(stroke
			(width 0.07112)
			(type default)
		)
		(layer "In4.Cu")
	)
	(gr_line
		(start 404.044658 -399.645378)
		(end 404.043896 -399.645632)
		(stroke
			(width 0.07112)
			(type default)
		)
		(layer "In4.Cu")
	)
	(gr_line
		(start 404.081234 -411.37332)
		(end 403.911562 -411.282642)
		(stroke
			(width 0.07112)
			(type default)
		)
		(layer "In4.Cu")
	)
	(gr_line
		(start 404.294594 -19.42719)
		(end 404.003764 -19.13636)
		(stroke
			(width 0.07112)
			(type default)
		)
		(layer "In4.Cu")
	)
	(gr_line
		(start 404.489666 -411.249622)
		(end 404.081234 -411.37332)
		(stroke
			(width 0.07112)
			(type default)
		)
		(layer "In4.Cu")
	)
	(gr_line
		(start 404.499318 -410.808424)
		(end 403.82825 -411.011878)
		(stroke
			(width 0.07112)
			(type default)
		)
		(layer "In4.Cu")
	)
	(gr_line
		(start 404.580344 -411.079696)
		(end 404.489666 -411.249622)
		(stroke
			(width 0.07112)
			(type default)
		)
		(layer "In4.Cu")
	)
	(gr_line
		(start 404.618952 -397.156432)
		(end 404.671276 -397.208756)
		(stroke
			(width 0.07112)
			(type default)
		)
		(layer "In4.Cu")
	)
	(gr_line
		(start 404.655274 -410.76118)
		(end 404.499318 -410.808424)
		(stroke
			(width 0.07112)
			(type default)
		)
		(layer "In4.Cu")
	)
	(gr_line
		(start 404.671276 -397.388588)
		(end 404.524718 -397.535146)
		(stroke
			(width 0.07112)
			(type default)
		)
		(layer "In4.Cu")
	)
	(gr_line
		(start 404.671276 -397.208756)
		(end 404.671276 -397.388588)
		(stroke
			(width 0.07112)
			(type default)
		)
		(layer "In4.Cu")
	)
	(gr_line
		(start 404.867364 -19.13636)
		(end 404.576534 -19.42719)
		(stroke
			(width 0.07112)
			(type default)
		)
		(layer "In4.Cu")
	)
	(gr_line
		(start 404.880572 -412.55569)
		(end 404.589742 -412.84652)
		(stroke
			(width 0.07112)
			(type default)
		)
		(layer "In4.Cu")
	)
	(gr_line
		(start 404.904194 -397.734536)
		(end 404.725886 -397.734536)
		(stroke
			(width 0.07112)
			(type default)
		)
		(layer "In4.Cu")
	)
	(gr_line
		(start 405.019002 -397.849344)
		(end 404.904194 -397.734536)
		(stroke
			(width 0.07112)
			(type default)
		)
		(layer "In4.Cu")
	)
	(gr_line
		(start 405.162512 -412.55569)
		(end 405.453342 -412.84652)
		(stroke
			(width 0.07112)
			(type default)
		)
		(layer "In4.Cu")
	)
	(gr_line
		(start 405.819102 -397.156432)
		(end 405.87041 -397.20774)
		(stroke
			(width 0.07112)
			(type default)
		)
		(layer "In4.Cu")
	)
	(gr_line
		(start 405.823166 -397.464788)
		(end 405.753824 -397.53413)
		(stroke
			(width 0.07112)
			(type default)
		)
		(layer "In4.Cu")
	)
	(gr_arc
		(start 405.823166 -397.464788)
		(mid 405.858126 -397.412464)
		(end 405.87041 -397.350742)
		(stroke
			(width 0.07112)
			(type default)
		)
		(layer "In4.Cu")
	)
	(gr_line
		(start 405.826468 -398.67713)
		(end 405.826214 -398.67713)
		(stroke
			(width 0.07112)
			(type default)
		)
		(layer "In4.Cu")
	)
	(gr_line
		(start 405.87041 -397.20774)
		(end 405.87041 -397.350742)
		(stroke
			(width 0.07112)
			(type default)
		)
		(layer "In4.Cu")
	)
	(gr_line
		(start 405.981916 -411.73908)
		(end 405.80437 -411.66542)
		(stroke
			(width 0.07112)
			(type default)
		)
		(layer "In4.Cu")
	)
	(gr_line
		(start 406.103074 -397.73352)
		(end 405.954992 -397.73352)
		(stroke
			(width 0.07112)
			(type default)
		)
		(layer "In4.Cu")
	)
	(gr_line
		(start 406.218898 -397.849344)
		(end 406.103074 -397.73352)
		(stroke
			(width 0.07112)
			(type default)
		)
		(layer "In4.Cu")
	)
	(gr_line
		(start 406.343104 -411.13583)
		(end 405.694896 -411.404054)
		(stroke
			(width 0.07112)
			(type default)
		)
		(layer "In4.Cu")
	)
	(gr_line
		(start 406.376378 -411.575758)
		(end 405.981916 -411.73908)
		(stroke
			(width 0.07112)
			(type default)
		)
		(layer "In4.Cu")
	)
	(gr_line
		(start 406.450038 -411.397958)
		(end 406.376378 -411.575758)
		(stroke
			(width 0.07112)
			(type default)
		)
		(layer "In4.Cu")
	)
	(gr_line
		(start 406.512268 -411.065726)
		(end 406.343104 -411.13583)
		(stroke
			(width 0.07112)
			(type default)
		)
		(layer "In4.Cu")
	)
	(gr_line
		(start 406.619964 -411.326076)
		(end 406.4508 -411.39618)
		(stroke
			(width 0.07112)
			(type default)
		)
		(layer "In4.Cu")
	)
	(gr_line
		(start 407.018998 -397.156432)
		(end 407.071322 -397.208756)
		(stroke
			(width 0.07112)
			(type default)
		)
		(layer "In4.Cu")
	)
	(gr_line
		(start 407.024078 -411.30728)
		(end 406.846532 -411.23362)
		(stroke
			(width 0.07112)
			(type default)
		)
		(layer "In4.Cu")
	)
	(gr_line
		(start 407.071322 -397.388588)
		(end 406.924764 -397.535146)
		(stroke
			(width 0.07112)
			(type default)
		)
		(layer "In4.Cu")
	)
	(gr_line
		(start 407.071322 -397.208756)
		(end 407.071322 -397.388588)
		(stroke
			(width 0.07112)
			(type default)
		)
		(layer "In4.Cu")
	)
	(gr_line
		(start 407.087578 -17.903952)
		(end 406.796748 -17.613122)
		(stroke
			(width 0.07112)
			(type default)
		)
		(layer "In4.Cu")
	)
	(gr_line
		(start 407.30424 -397.734536)
		(end 407.125932 -397.734536)
		(stroke
			(width 0.07112)
			(type default)
		)
		(layer "In4.Cu")
	)
	(gr_line
		(start 407.385012 -410.70403)
		(end 406.737312 -410.972508)
		(stroke
			(width 0.07112)
			(type default)
		)
		(layer "In4.Cu")
	)
	(gr_line
		(start 407.414984 -410.691838)
		(end 407.385012 -410.70403)
		(stroke
			(width 0.07112)
			(type default)
		)
		(layer "In4.Cu")
	)
	(gr_line
		(start 407.41854 -411.143958)
		(end 407.024078 -411.30728)
		(stroke
			(width 0.07112)
			(type default)
		)
		(layer "In4.Cu")
	)
	(gr_line
		(start 407.419048 -397.849344)
		(end 407.30424 -397.734536)
		(stroke
			(width 0.07112)
			(type default)
		)
		(layer "In4.Cu")
	)
	(gr_line
		(start 407.4922 -410.966412)
		(end 407.41854 -411.143958)
		(stroke
			(width 0.07112)
			(type default)
		)
		(layer "In4.Cu")
	)
	(gr_line
		(start 407.660348 -17.613122)
		(end 407.369518 -17.903952)
		(stroke
			(width 0.07112)
			(type default)
		)
		(layer "In4.Cu")
	)
	(gr_line
		(start 407.943812 -412.55569)
		(end 407.652982 -412.84652)
		(stroke
			(width 0.07112)
			(type default)
		)
		(layer "In4.Cu")
	)
	(gr_line
		(start 408.218894 -397.156432)
		(end 408.271218 -397.208756)
		(stroke
			(width 0.07112)
			(type default)
		)
		(layer "In4.Cu")
	)
	(gr_line
		(start 408.225752 -412.55569)
		(end 408.516582 -412.84652)
		(stroke
			(width 0.07112)
			(type default)
		)
		(layer "In4.Cu")
	)
	(gr_line
		(start 408.271218 -397.388588)
		(end 408.12466 -397.535146)
		(stroke
			(width 0.07112)
			(type default)
		)
		(layer "In4.Cu")
	)
	(gr_line
		(start 408.271218 -397.208756)
		(end 408.271218 -397.388588)
		(stroke
			(width 0.07112)
			(type default)
		)
		(layer "In4.Cu")
	)
	(gr_line
		(start 408.303476 -410.777436)
		(end 408.12593 -410.703776)
		(stroke
			(width 0.07112)
			(type default)
		)
		(layer "In4.Cu")
	)
	(gr_line
		(start 408.504136 -397.734536)
		(end 408.325828 -397.734536)
		(stroke
			(width 0.07112)
			(type default)
		)
		(layer "In4.Cu")
	)
	(gr_line
		(start 408.618944 -397.849344)
		(end 408.504136 -397.734536)
		(stroke
			(width 0.07112)
			(type default)
		)
		(layer "In4.Cu")
	)
	(gr_line
		(start 408.66441 -410.174186)
		(end 408.016456 -410.442664)
		(stroke
			(width 0.07112)
			(type default)
		)
		(layer "In4.Cu")
	)
	(gr_line
		(start 408.698192 -410.614114)
		(end 408.303476 -410.777436)
		(stroke
			(width 0.07112)
			(type default)
		)
		(layer "In4.Cu")
	)
	(gr_line
		(start 408.771598 -410.436314)
		(end 408.698192 -410.614114)
		(stroke
			(width 0.07112)
			(type default)
		)
		(layer "In4.Cu")
	)
	(gr_line
		(start 409.09113 -411.645862)
		(end 408.912568 -411.574488)
		(stroke
			(width 0.07112)
			(type default)
		)
		(layer "In4.Cu")
	)
	(gr_line
		(start 409.419044 -397.156432)
		(end 409.46959 -397.206978)
		(stroke
			(width 0.07112)
			(type default)
		)
		(layer "In4.Cu")
	)
	(gr_line
		(start 409.44419 -411.03804)
		(end 408.799792 -411.314646)
		(stroke
			(width 0.07112)
			(type default)
		)
		(layer "In4.Cu")
	)
	(gr_line
		(start 409.46959 -397.40713)
		(end 409.341574 -397.535146)
		(stroke
			(width 0.07112)
			(type default)
		)
		(layer "In4.Cu")
	)
	(gr_line
		(start 409.46959 -397.206978)
		(end 409.46959 -397.40713)
		(stroke
			(width 0.07112)
			(type default)
		)
		(layer "In4.Cu")
	)
	(gr_line
		(start 409.48356 -411.47746)
		(end 409.09113 -411.645862)
		(stroke
			(width 0.07112)
			(type default)
		)
		(layer "In4.Cu")
	)
	(gr_line
		(start 409.55468 -411.298644)
		(end 409.48356 -411.47746)
		(stroke
			(width 0.07112)
			(type default)
		)
		(layer "In4.Cu")
	)
	(gr_line
		(start 409.704286 -397.734536)
		(end 409.542742 -397.734536)
		(stroke
			(width 0.07112)
			(type default)
		)
		(layer "In4.Cu")
	)
	(gr_line
		(start 409.819094 -397.849344)
		(end 409.704286 -397.734536)
		(stroke
			(width 0.07112)
			(type default)
		)
		(layer "In4.Cu")
	)
	(gr_line
		(start 409.882594 -19.42719)
		(end 409.591764 -19.13636)
		(stroke
			(width 0.07112)
			(type default)
		)
		(layer "In4.Cu")
	)
	(gr_line
		(start 410.12745 -411.200854)
		(end 409.948888 -411.12948)
		(stroke
			(width 0.07112)
			(type default)
		)
		(layer "In4.Cu")
	)
	(gr_line
		(start 410.372814 -410.63926)
		(end 409.836112 -410.869638)
		(stroke
			(width 0.07112)
			(type default)
		)
		(layer "In4.Cu")
	)
	(gr_line
		(start 410.372814 -410.63926)
		(end 410.373068 -410.639006)
		(stroke
			(width 0.07112)
			(type default)
		)
		(layer "In4.Cu")
	)
	(gr_line
		(start 410.455364 -19.13636)
		(end 410.164534 -19.42719)
		(stroke
			(width 0.07112)
			(type default)
		)
		(layer "In4.Cu")
	)
	(gr_line
		(start 410.48051 -410.593032)
		(end 410.373068 -410.639006)
		(stroke
			(width 0.07112)
			(type default)
		)
		(layer "In4.Cu")
	)
	(gr_line
		(start 410.51988 -411.032452)
		(end 410.12745 -411.200854)
		(stroke
			(width 0.07112)
			(type default)
		)
		(layer "In4.Cu")
	)
	(gr_line
		(start 410.591254 -410.853636)
		(end 410.51988 -411.032452)
		(stroke
			(width 0.07112)
			(type default)
		)
		(layer "In4.Cu")
	)
	(gr_line
		(start 410.61894 -397.156432)
		(end 410.671264 -397.208756)
		(stroke
			(width 0.07112)
			(type default)
		)
		(layer "In4.Cu")
	)
	(gr_line
		(start 410.671264 -397.388588)
		(end 410.524706 -397.535146)
		(stroke
			(width 0.07112)
			(type default)
		)
		(layer "In4.Cu")
	)
	(gr_line
		(start 410.671264 -397.208756)
		(end 410.671264 -397.388588)
		(stroke
			(width 0.07112)
			(type default)
		)
		(layer "In4.Cu")
	)
	(gr_line
		(start 410.904182 -397.734536)
		(end 410.725874 -397.734536)
		(stroke
			(width 0.07112)
			(type default)
		)
		(layer "In4.Cu")
	)
	(gr_line
		(start 411.007052 -412.55569)
		(end 410.716222 -412.84652)
		(stroke
			(width 0.07112)
			(type default)
		)
		(layer "In4.Cu")
	)
	(gr_line
		(start 411.01899 -397.849344)
		(end 410.904182 -397.734536)
		(stroke
			(width 0.07112)
			(type default)
		)
		(layer "In4.Cu")
	)
	(gr_line
		(start 411.288992 -412.55569)
		(end 411.579822 -412.84652)
		(stroke
			(width 0.07112)
			(type default)
		)
		(layer "In4.Cu")
	)
	(gr_line
		(start 411.81909 -397.156432)
		(end 411.871414 -397.208756)
		(stroke
			(width 0.07112)
			(type default)
		)
		(layer "In4.Cu")
	)
	(gr_line
		(start 411.871414 -397.388588)
		(end 411.724856 -397.535146)
		(stroke
			(width 0.07112)
			(type default)
		)
		(layer "In4.Cu")
	)
	(gr_line
		(start 411.871414 -397.208756)
		(end 411.871414 -397.388588)
		(stroke
			(width 0.07112)
			(type default)
		)
		(layer "In4.Cu")
	)
	(gr_line
		(start 412.104078 -397.734536)
		(end 411.926024 -397.734536)
		(stroke
			(width 0.07112)
			(type default)
		)
		(layer "In4.Cu")
	)
	(gr_arc
		(start 412.195518 -398.557496)
		(mid 412.195518 -398.557877)
		(end 412.195518 -398.558258)
		(stroke
			(width 0.07112)
			(type default)
		)
		(layer "In4.Cu")
	)
	(gr_line
		(start 412.218886 -397.849344)
		(end 412.104078 -397.734536)
		(stroke
			(width 0.07112)
			(type default)
		)
		(layer "In4.Cu")
	)
	(gr_line
		(start 412.52775 -410.790136)
		(end 412.335726 -410.790136)
		(stroke
			(width 0.07112)
			(type default)
		)
		(layer "In4.Cu")
	)
	(gr_line
		(start 412.630366 -410.094938)
		(end 412.134558 -410.590746)
		(stroke
			(width 0.07112)
			(type default)
		)
		(layer "In4.Cu")
	)
	(gr_line
		(start 412.675578 -17.903952)
		(end 412.384748 -17.613122)
		(stroke
			(width 0.07112)
			(type default)
		)
		(layer "In4.Cu")
	)
	(gr_line
		(start 412.829756 -410.48813)
		(end 412.52775 -410.790136)
		(stroke
			(width 0.07112)
			(type default)
		)
		(layer "In4.Cu")
	)
	(gr_line
		(start 412.829756 -410.296106)
		(end 412.829756 -410.48813)
		(stroke
			(width 0.07112)
			(type default)
		)
		(layer "In4.Cu")
	)
	(gr_line
		(start 413.018986 -397.156432)
		(end 413.07131 -397.208756)
		(stroke
			(width 0.07112)
			(type default)
		)
		(layer "In4.Cu")
	)
	(gr_line
		(start 413.07131 -397.388588)
		(end 412.924752 -397.535146)
		(stroke
			(width 0.07112)
			(type default)
		)
		(layer "In4.Cu")
	)
	(gr_line
		(start 413.07131 -397.208756)
		(end 413.07131 -397.388588)
		(stroke
			(width 0.07112)
			(type default)
		)
		(layer "In4.Cu")
	)
	(gr_line
		(start 413.248348 -17.613122)
		(end 412.957518 -17.903952)
		(stroke
			(width 0.07112)
			(type default)
		)
		(layer "In4.Cu")
	)
	(gr_line
		(start 413.304228 -397.734536)
		(end 413.12592 -397.734536)
		(stroke
			(width 0.07112)
			(type default)
		)
		(layer "In4.Cu")
	)
	(gr_line
		(start 413.419036 -397.849344)
		(end 413.304228 -397.734536)
		(stroke
			(width 0.07112)
			(type default)
		)
		(layer "In4.Cu")
	)
	(gr_line
		(start 413.541718 -402.696426)
		(end 413.541718 -403.397466)
		(stroke
			(width 0.07112)
			(type default)
		)
		(layer "In4.Cu")
	)
	(gr_line
		(start 413.824928 -402.697696)
		(end 413.960818 -402.833586)
		(stroke
			(width 0.07112)
			(type default)
		)
		(layer "In4.Cu")
	)
	(gr_line
		(start 413.838898 -409.479242)
		(end 413.64662 -409.479242)
		(stroke
			(width 0.07112)
			(type default)
		)
		(layer "In4.Cu")
	)
	(gr_line
		(start 413.941514 -408.78379)
		(end 413.445452 -409.279852)
		(stroke
			(width 0.07112)
			(type default)
		)
		(layer "In4.Cu")
	)
	(gr_line
		(start 413.960818 -403.260306)
		(end 413.824928 -403.396196)
		(stroke
			(width 0.07112)
			(type default)
		)
		(layer "In4.Cu")
	)
	(gr_line
		(start 413.960818 -402.833586)
		(end 413.960818 -403.260306)
		(stroke
			(width 0.07112)
			(type default)
		)
		(layer "In4.Cu")
	)
	(gr_line
		(start 414.070292 -412.55569)
		(end 413.779462 -412.84652)
		(stroke
			(width 0.07112)
			(type default)
		)
		(layer "In4.Cu")
	)
	(gr_line
		(start 414.140904 -409.177236)
		(end 413.838898 -409.479242)
		(stroke
			(width 0.07112)
			(type default)
		)
		(layer "In4.Cu")
	)
	(gr_line
		(start 414.140904 -408.984958)
		(end 414.140904 -409.177236)
		(stroke
			(width 0.07112)
			(type default)
		)
		(layer "In4.Cu")
	)
	(gr_line
		(start 414.218882 -397.156432)
		(end 414.271206 -397.208756)
		(stroke
			(width 0.07112)
			(type default)
		)
		(layer "In4.Cu")
	)
	(gr_line
		(start 414.271206 -397.388588)
		(end 414.124648 -397.535146)
		(stroke
			(width 0.07112)
			(type default)
		)
		(layer "In4.Cu")
	)
	(gr_line
		(start 414.271206 -397.208756)
		(end 414.271206 -397.388588)
		(stroke
			(width 0.07112)
			(type default)
		)
		(layer "In4.Cu")
	)
	(gr_line
		(start 414.352232 -412.55569)
		(end 414.643062 -412.84652)
		(stroke
			(width 0.07112)
			(type default)
		)
		(layer "In4.Cu")
	)
	(gr_line
		(start 414.504124 -397.734536)
		(end 414.325816 -397.734536)
		(stroke
			(width 0.07112)
			(type default)
		)
		(layer "In4.Cu")
	)
	(gr_line
		(start 414.618932 -397.849344)
		(end 414.504124 -397.734536)
		(stroke
			(width 0.07112)
			(type default)
		)
		(layer "In4.Cu")
	)
	(gr_line
		(start 414.682432 -402.717)
		(end 414.682432 -403.41804)
		(stroke
			(width 0.07112)
			(type default)
		)
		(layer "In4.Cu")
	)
	(gr_line
		(start 414.951164 -408.366722)
		(end 414.75914 -408.366722)
		(stroke
			(width 0.07112)
			(type default)
		)
		(layer "In4.Cu")
	)
	(gr_line
		(start 414.965642 -402.71827)
		(end 415.101532 -402.85416)
		(stroke
			(width 0.07112)
			(type default)
		)
		(layer "In4.Cu")
	)
	(gr_line
		(start 415.05378 -407.671524)
		(end 414.557972 -408.167332)
		(stroke
			(width 0.07112)
			(type default)
		)
		(layer "In4.Cu")
	)
	(gr_line
		(start 415.101532 -403.28088)
		(end 414.965642 -403.41677)
		(stroke
			(width 0.07112)
			(type default)
		)
		(layer "In4.Cu")
	)
	(gr_line
		(start 415.101532 -402.85416)
		(end 415.101532 -403.28088)
		(stroke
			(width 0.07112)
			(type default)
		)
		(layer "In4.Cu")
	)
	(gr_line
		(start 415.25317 -408.064716)
		(end 414.951164 -408.366722)
		(stroke
			(width 0.07112)
			(type default)
		)
		(layer "In4.Cu")
	)
	(gr_line
		(start 415.25317 -407.872692)
		(end 415.25317 -408.064716)
		(stroke
			(width 0.07112)
			(type default)
		)
		(layer "In4.Cu")
	)
	(gr_line
		(start 415.419032 -397.156432)
		(end 415.471356 -397.208756)
		(stroke
			(width 0.07112)
			(type default)
		)
		(layer "In4.Cu")
	)
	(gr_line
		(start 415.471356 -397.388588)
		(end 415.324798 -397.535146)
		(stroke
			(width 0.07112)
			(type default)
		)
		(layer "In4.Cu")
	)
	(gr_line
		(start 415.471356 -397.208756)
		(end 415.471356 -397.388588)
		(stroke
			(width 0.07112)
			(type default)
		)
		(layer "In4.Cu")
	)
	(gr_line
		(start 415.704274 -397.734536)
		(end 415.525966 -397.734536)
		(stroke
			(width 0.07112)
			(type default)
		)
		(layer "In4.Cu")
	)
	(gr_line
		(start 415.77641 -19.42719)
		(end 415.48558 -19.13636)
		(stroke
			(width 0.07112)
			(type default)
		)
		(layer "In4.Cu")
	)
	(gr_line
		(start 415.819082 -397.849344)
		(end 415.704274 -397.734536)
		(stroke
			(width 0.07112)
			(type default)
		)
		(layer "In4.Cu")
	)
	(gr_line
		(start 416.211766 -409.29687)
		(end 416.02025 -409.315666)
		(stroke
			(width 0.07112)
			(type default)
		)
		(layer "In4.Cu")
	)
	(gr_line
		(start 416.245548 -408.594814)
		(end 415.800794 -409.13685)
		(stroke
			(width 0.07112)
			(type default)
		)
		(layer "In4.Cu")
	)
	(gr_line
		(start 416.34918 -19.13636)
		(end 416.05835 -19.42719)
		(stroke
			(width 0.07112)
			(type default)
		)
		(layer "In4.Cu")
	)
	(gr_line
		(start 416.463988 -408.775154)
		(end 416.48253 -408.966924)
		(stroke
			(width 0.07112)
			(type default)
		)
		(layer "In4.Cu")
	)
	(gr_line
		(start 416.48253 -408.966924)
		(end 416.211766 -409.29687)
		(stroke
			(width 0.07112)
			(type default)
		)
		(layer "In4.Cu")
	)
	(gr_line
		(start 416.618928 -397.156432)
		(end 416.671252 -397.208756)
		(stroke
			(width 0.07112)
			(type default)
		)
		(layer "In4.Cu")
	)
	(gr_line
		(start 416.671252 -397.388588)
		(end 416.524694 -397.535146)
		(stroke
			(width 0.07112)
			(type default)
		)
		(layer "In4.Cu")
	)
	(gr_line
		(start 416.671252 -397.208756)
		(end 416.671252 -397.388588)
		(stroke
			(width 0.07112)
			(type default)
		)
		(layer "In4.Cu")
	)
	(gr_line
		(start 416.90417 -397.734536)
		(end 416.725862 -397.734536)
		(stroke
			(width 0.07112)
			(type default)
		)
		(layer "In4.Cu")
	)
	(gr_line
		(start 417.018978 -397.849344)
		(end 416.90417 -397.734536)
		(stroke
			(width 0.07112)
			(type default)
		)
		(layer "In4.Cu")
	)
	(gr_line
		(start 417.133532 -412.55569)
		(end 416.842702 -412.84652)
		(stroke
			(width 0.07112)
			(type default)
		)
		(layer "In4.Cu")
	)
	(gr_line
		(start 417.148264 -402.917406)
		(end 417.148264 -403.618446)
		(stroke
			(width 0.07112)
			(type default)
		)
		(layer "In4.Cu")
	)
	(gr_line
		(start 417.31819 -407.948892)
		(end 417.12642 -407.967688)
		(stroke
			(width 0.07112)
			(type default)
		)
		(layer "In4.Cu")
	)
	(gr_line
		(start 417.351972 -407.246582)
		(end 416.906964 -407.788872)
		(stroke
			(width 0.07112)
			(type default)
		)
		(layer "In4.Cu")
	)
	(gr_line
		(start 417.415472 -412.55569)
		(end 417.706302 -412.84652)
		(stroke
			(width 0.07112)
			(type default)
		)
		(layer "In4.Cu")
	)
	(gr_line
		(start 417.431474 -402.918676)
		(end 417.567364 -403.054566)
		(stroke
			(width 0.07112)
			(type default)
		)
		(layer "In4.Cu")
	)
	(gr_line
		(start 417.567364 -403.481286)
		(end 417.431474 -403.617176)
		(stroke
			(width 0.07112)
			(type default)
		)
		(layer "In4.Cu")
	)
	(gr_line
		(start 417.567364 -403.054566)
		(end 417.567364 -403.481286)
		(stroke
			(width 0.07112)
			(type default)
		)
		(layer "In4.Cu")
	)
	(gr_line
		(start 417.570412 -407.426922)
		(end 417.589208 -407.618692)
		(stroke
			(width 0.07112)
			(type default)
		)
		(layer "In4.Cu")
	)
	(gr_line
		(start 417.589208 -407.618692)
		(end 417.31819 -407.948892)
		(stroke
			(width 0.07112)
			(type default)
		)
		(layer "In4.Cu")
	)
	(gr_line
		(start 417.819078 -397.156432)
		(end 417.871402 -397.208756)
		(stroke
			(width 0.07112)
			(type default)
		)
		(layer "In4.Cu")
	)
	(gr_line
		(start 417.871402 -397.388588)
		(end 417.724844 -397.535146)
		(stroke
			(width 0.07112)
			(type default)
		)
		(layer "In4.Cu")
	)
	(gr_line
		(start 417.871402 -397.208756)
		(end 417.871402 -397.388588)
		(stroke
			(width 0.07112)
			(type default)
		)
		(layer "In4.Cu")
	)
	(gr_line
		(start 418.104066 -397.734536)
		(end 417.926012 -397.734536)
		(stroke
			(width 0.07112)
			(type default)
		)
		(layer "In4.Cu")
	)
	(gr_line
		(start 418.194236 -409.888436)
		(end 417.863782 -410.506926)
		(stroke
			(width 0.07112)
			(type default)
		)
		(layer "In4.Cu")
	)
	(gr_line
		(start 418.218874 -397.849344)
		(end 418.104066 -397.734536)
		(stroke
			(width 0.07112)
			(type default)
		)
		(layer "In4.Cu")
	)
	(gr_line
		(start 418.298376 -410.583634)
		(end 418.113972 -410.63926)
		(stroke
			(width 0.07112)
			(type default)
		)
		(layer "In4.Cu")
	)
	(gr_line
		(start 418.417502 -406.609296)
		(end 418.225732 -406.628092)
		(stroke
			(width 0.07112)
			(type default)
		)
		(layer "In4.Cu")
	)
	(gr_line
		(start 418.443664 -410.022802)
		(end 418.499544 -410.206952)
		(stroke
			(width 0.07112)
			(type default)
		)
		(layer "In4.Cu")
	)
	(gr_line
		(start 418.45103 -405.90724)
		(end 418.006276 -406.449276)
		(stroke
			(width 0.07112)
			(type default)
		)
		(layer "In4.Cu")
	)
	(gr_line
		(start 418.499544 -410.206952)
		(end 418.298376 -410.583634)
		(stroke
			(width 0.07112)
			(type default)
		)
		(layer "In4.Cu")
	)
	(gr_line
		(start 418.57041 -17.90319)
		(end 418.27958 -17.61236)
		(stroke
			(width 0.07112)
			(type default)
		)
		(layer "In4.Cu")
	)
	(gr_line
		(start 418.64407 -409.645104)
		(end 418.623496 -409.683712)
		(stroke
			(width 0.07112)
			(type default)
		)
		(layer "In4.Cu")
	)
	(gr_line
		(start 418.66947 -406.087326)
		(end 418.688266 -406.27935)
		(stroke
			(width 0.07112)
			(type default)
		)
		(layer "In4.Cu")
	)
	(gr_line
		(start 418.688266 -406.27935)
		(end 418.417502 -406.609296)
		(stroke
			(width 0.07112)
			(type default)
		)
		(layer "In4.Cu")
	)
	(gr_line
		(start 418.726112 -408.893518)
		(end 418.395404 -409.512262)
		(stroke
			(width 0.07112)
			(type default)
		)
		(layer "In4.Cu")
	)
	(gr_line
		(start 418.829998 -409.588716)
		(end 418.645848 -409.644596)
		(stroke
			(width 0.07112)
			(type default)
		)
		(layer "In4.Cu")
	)
	(gr_line
		(start 418.97554 -409.027884)
		(end 419.031166 -409.212288)
		(stroke
			(width 0.07112)
			(type default)
		)
		(layer "In4.Cu")
	)
	(gr_line
		(start 419.018974 -397.156432)
		(end 419.071298 -397.208756)
		(stroke
			(width 0.07112)
			(type default)
		)
		(layer "In4.Cu")
	)
	(gr_line
		(start 419.031166 -409.212288)
		(end 418.829998 -409.588716)
		(stroke
			(width 0.07112)
			(type default)
		)
		(layer "In4.Cu")
	)
	(gr_line
		(start 419.071298 -397.388588)
		(end 418.92474 -397.535146)
		(stroke
			(width 0.07112)
			(type default)
		)
		(layer "In4.Cu")
	)
	(gr_line
		(start 419.071298 -397.208756)
		(end 419.071298 -397.388588)
		(stroke
			(width 0.07112)
			(type default)
		)
		(layer "In4.Cu")
	)
	(gr_line
		(start 419.14318 -17.61236)
		(end 418.85235 -17.90319)
		(stroke
			(width 0.07112)
			(type default)
		)
		(layer "In4.Cu")
	)
	(gr_line
		(start 419.304216 -397.734536)
		(end 419.125908 -397.734536)
		(stroke
			(width 0.07112)
			(type default)
		)
		(layer "In4.Cu")
	)
	(gr_line
		(start 419.306248 -407.80843)
		(end 418.97554 -408.42692)
		(stroke
			(width 0.07112)
			(type default)
		)
		(layer "In4.Cu")
	)
	(gr_line
		(start 419.410388 -408.503628)
		(end 419.225984 -408.559254)
		(stroke
			(width 0.07112)
			(type default)
		)
		(layer "In4.Cu")
	)
	(gr_line
		(start 419.419024 -397.849344)
		(end 419.304216 -397.734536)
		(stroke
			(width 0.07112)
			(type default)
		)
		(layer "In4.Cu")
	)
	(gr_line
		(start 419.555422 -407.942796)
		(end 419.611556 -408.126946)
		(stroke
			(width 0.07112)
			(type default)
		)
		(layer "In4.Cu")
	)
	(gr_line
		(start 419.611556 -408.126946)
		(end 419.410388 -408.503628)
		(stroke
			(width 0.07112)
			(type default)
		)
		(layer "In4.Cu")
	)
	(gr_line
		(start 420.219124 -397.156432)
		(end 420.271448 -397.208756)
		(stroke
			(width 0.07112)
			(type default)
		)
		(layer "In4.Cu")
	)
	(gr_line
		(start 420.271448 -397.388588)
		(end 420.12489 -397.535146)
		(stroke
			(width 0.07112)
			(type default)
		)
		(layer "In4.Cu")
	)
	(gr_line
		(start 420.271448 -397.208756)
		(end 420.271448 -397.388588)
		(stroke
			(width 0.07112)
			(type default)
		)
		(layer "In4.Cu")
	)
	(gr_line
		(start 420.504112 -397.734536)
		(end 420.326058 -397.734536)
		(stroke
			(width 0.07112)
			(type default)
		)
		(layer "In4.Cu")
	)
	(gr_line
		(start 420.61892 -397.849344)
		(end 420.504112 -397.734536)
		(stroke
			(width 0.07112)
			(type default)
		)
		(layer "In4.Cu")
	)
	(gr_line
		(start 421.363394 -19.427952)
		(end 421.072564 -19.137122)
		(stroke
			(width 0.07112)
			(type default)
		)
		(layer "In4.Cu")
	)
	(gr_line
		(start 421.41902 -397.156432)
		(end 421.471344 -397.208756)
		(stroke
			(width 0.07112)
			(type default)
		)
		(layer "In4.Cu")
	)
	(gr_line
		(start 421.471344 -397.388588)
		(end 421.324786 -397.535146)
		(stroke
			(width 0.07112)
			(type default)
		)
		(layer "In4.Cu")
	)
	(gr_line
		(start 421.471344 -397.208756)
		(end 421.471344 -397.388588)
		(stroke
			(width 0.07112)
			(type default)
		)
		(layer "In4.Cu")
	)
	(gr_line
		(start 421.704262 -397.734536)
		(end 421.525954 -397.734536)
		(stroke
			(width 0.07112)
			(type default)
		)
		(layer "In4.Cu")
	)
	(gr_line
		(start 421.81907 -397.849344)
		(end 421.704262 -397.734536)
		(stroke
			(width 0.07112)
			(type default)
		)
		(layer "In4.Cu")
	)
	(gr_line
		(start 421.936164 -19.137122)
		(end 421.645334 -19.427952)
		(stroke
			(width 0.07112)
			(type default)
		)
		(layer "In4.Cu")
	)
	(gr_line
		(start 424.15841 -17.90319)
		(end 423.86758 -17.61236)
		(stroke
			(width 0.07112)
			(type default)
		)
		(layer "In4.Cu")
	)
	(gr_line
		(start 424.73118 -17.61236)
		(end 424.44035 -17.90319)
		(stroke
			(width 0.07112)
			(type default)
		)
		(layer "In4.Cu")
	)
	(gr_line
		(start 426.986446 -19.42719)
		(end 426.695616 -19.13636)
		(stroke
			(width 0.07112)
			(type default)
		)
		(layer "In4.Cu")
	)
	(gr_line
		(start 427.559216 -19.13636)
		(end 427.268386 -19.42719)
		(stroke
			(width 0.07112)
			(type default)
		)
		(layer "In4.Cu")
	)
	(gr_line
		(start 429.77943 -17.903952)
		(end 429.4886 -17.613122)
		(stroke
			(width 0.07112)
			(type default)
		)
		(layer "In4.Cu")
	)
	(gr_line
		(start 430.3522 -17.613122)
		(end 430.06137 -17.903952)
		(stroke
			(width 0.07112)
			(type default)
		)
		(layer "In4.Cu")
	)
	(gr_line
		(start 432.574446 -19.42719)
		(end 432.283616 -19.13636)
		(stroke
			(width 0.07112)
			(type default)
		)
		(layer "In4.Cu")
	)
	(gr_line
		(start 433.147216 -19.13636)
		(end 432.856386 -19.42719)
		(stroke
			(width 0.07112)
			(type default)
		)
		(layer "In4.Cu")
	)
	(gr_line
		(start 439.307478 5.718048)
		(end 439.016648 6.008878)
		(stroke
			(width 0.07112)
			(type default)
		)
		(layer "In4.Cu")
	)
	(gr_line
		(start 439.307478 6.581648)
		(end 439.016648 6.290818)
		(stroke
			(width 0.07112)
			(type default)
		)
		(layer "In4.Cu")
	)
	(gr_line
		(start 455.694034 -9.780016)
		(end 455.694034 -0.508)
		(stroke
			(width 0.2)
			(type default)
		)
		(layer "In4.Cu")
	)
	(gr_arc
		(start 455.694034 -9.780016)
		(mid 456.428616 -11.553416)
		(end 458.20203 -12.288012)
		(stroke
			(width 0.2)
			(type default)
		)
		(layer "In4.Cu")
	)
	(gr_line
		(start 455.694034 -0.508)
		(end 388.109968 -0.508)
		(stroke
			(width 0.2)
			(type default)
		)
		(layer "In4.Cu")
	)
	(gr_arc
		(start 458.71003 -7.78002)
		(mid 459.147026 -8.83502)
		(end 460.202026 -9.272016)
		(stroke
			(width 0.2)
			(type default)
		)
		(layer "In4.Cu")
	)
	(gr_arc
		(start 458.71003 0.40005)
		(mid 457.975475 2.173515)
		(end 456.202034 2.908046)
		(stroke
			(width 0.2)
			(type default)
		)
		(layer "In4.Cu")
	)
	(gr_line
		(start 458.71003 0.40005)
		(end 458.71003 -7.78002)
		(stroke
			(width 0.2)
			(type default)
		)
		(layer "In4.Cu")
	)
	(gr_line
		(start 460.202026 -9.272016)
		(end 464.439 -9.272016)
		(stroke
			(width 0.2)
			(type default)
		)
		(layer "In4.Cu")
	)
	(gr_arc
		(start 463.300064 -441.481972)
		(mid 464.355064 -441.044976)
		(end 464.79206 -439.989976)
		(stroke
			(width 0.2)
			(type default)
		)
		(layer "In4.Cu")
	)
	(gr_line
		(start 464.439 -12.288012)
		(end 458.20203 -12.288012)
		(stroke
			(width 0.2)
			(type default)
		)
		(layer "In4.Cu")
	)
	(gr_line
		(start 464.439 -9.272016)
		(end 464.439 -12.288012)
		(stroke
			(width 0.2)
			(type default)
		)
		(layer "In4.Cu")
	)
	(gr_line
		(start 464.447636 -12.288012)
		(end 464.447636 -9.272016)
		(stroke
			(width 0.2)
			(type default)
		)
		(layer "In4.Cu")
	)
	(gr_line
		(start 464.447636 -9.272016)
		(end 469.799924 -9.272016)
		(stroke
			(width 0.2)
			(type default)
		)
		(layer "In4.Cu")
	)
	(gr_line
		(start 464.79206 -439.989976)
		(end 464.79206 -418.46881)
		(stroke
			(width 0.2)
			(type default)
		)
		(layer "In4.Cu")
	)
	(gr_line
		(start 464.79206 -418.46881)
		(end 467.808056 -418.46881)
		(stroke
			(width 0.2)
			(type default)
		)
		(layer "In4.Cu")
	)
	(gr_line
		(start 464.79206 -418.45738)
		(end 464.79206 -409.528264)
		(stroke
			(width 0.2)
			(type default)
		)
		(layer "In4.Cu")
	)
	(gr_arc
		(start 465.526628 -407.75509)
		(mid 464.983024 -408.568632)
		(end 464.79206 -409.528264)
		(stroke
			(width 0.2)
			(type default)
		)
		(layer "In4.Cu")
	)
	(gr_line
		(start 465.526628 -407.75509)
		(end 467.355174 -405.926544)
		(stroke
			(width 0.2)
			(type default)
		)
		(layer "In4.Cu")
	)
	(gr_arc
		(start 467.355174 -405.926544)
		(mid 467.678507 -405.442687)
		(end 467.792054 -404.871936)
		(stroke
			(width 0.2)
			(type default)
		)
		(layer "In4.Cu")
	)
	(gr_line
		(start 467.792054 -404.871936)
		(end 467.792054 -82.82813)
		(stroke
			(width 0.2)
			(type default)
		)
		(layer "In4.Cu")
	)
	(gr_arc
		(start 467.808056 -439.989976)
		(mid 468.245052 -441.044976)
		(end 469.300052 -441.481972)
		(stroke
			(width 0.2)
			(type default)
		)
		(layer "In4.Cu")
	)
	(gr_line
		(start 467.808056 -418.46881)
		(end 467.808056 -439.989976)
		(stroke
			(width 0.2)
			(type default)
		)
		(layer "In4.Cu")
	)
	(gr_line
		(start 467.808056 -418.45738)
		(end 464.79206 -418.45738)
		(stroke
			(width 0.2)
			(type default)
		)
		(layer "In4.Cu")
	)
	(gr_line
		(start 467.808056 -410.356812)
		(end 467.808056 -418.45738)
		(stroke
			(width 0.2)
			(type default)
		)
		(layer "In4.Cu")
	)
	(gr_arc
		(start 468.244936 -409.30195)
		(mid 467.921608 -409.785939)
		(end 467.808056 -410.356812)
		(stroke
			(width 0.2)
			(type default)
		)
		(layer "In4.Cu")
	)
	(gr_arc
		(start 468.526622 -81.054956)
		(mid 467.983009 -81.868496)
		(end 467.792054 -82.82813)
		(stroke
			(width 0.2)
			(type default)
		)
		(layer "In4.Cu")
	)
	(gr_line
		(start 468.526622 -81.054956)
		(end 470.85504 -78.726538)
		(stroke
			(width 0.2)
			(type default)
		)
		(layer "In4.Cu")
	)
	(gr_line
		(start 469.300052 -441.481972)
		(end 471.79992 -441.481972)
		(stroke
			(width 0.2)
			(type default)
		)
		(layer "In4.Cu")
	)
	(gr_line
		(start 469.487758 -408.059128)
		(end 468.244936 -409.30195)
		(stroke
			(width 0.2)
			(type default)
		)
		(layer "In4.Cu")
	)
	(gr_arc
		(start 469.487758 -408.059128)
		(mid 470.464844 -406.596826)
		(end 470.80805 -404.871936)
		(stroke
			(width 0.2)
			(type default)
		)
		(layer "In4.Cu")
	)
	(gr_line
		(start 469.799924 -12.288012)
		(end 464.447636 -12.288012)
		(stroke
			(width 0.2)
			(type default)
		)
		(layer "In4.Cu")
	)
	(gr_arc
		(start 469.799924 -9.272016)
		(mid 470.854924 -8.83502)
		(end 471.29192 -7.78002)
		(stroke
			(width 0.2)
			(type default)
		)
		(layer "In4.Cu")
	)
	(gr_line
		(start 469.799924 11.892026)
		(end 1.999996 11.892026)
		(stroke
			(width 0.2)
			(type default)
		)
		(layer "In4.Cu")
	)
	(gr_line
		(start 470.80805 -83.656678)
		(end 470.80805 -404.871936)
		(stroke
			(width 0.2)
			(type default)
		)
		(layer "In4.Cu")
	)
	(gr_arc
		(start 470.85504 -78.726538)
		(mid 471.178373 -78.242681)
		(end 471.29192 -77.67193)
		(stroke
			(width 0.2)
			(type default)
		)
		(layer "In4.Cu")
	)
	(gr_arc
		(start 471.245184 -82.601562)
		(mid 470.921671 -83.085639)
		(end 470.80805 -83.656678)
		(stroke
			(width 0.2)
			(type default)
		)
		(layer "In4.Cu")
	)
	(gr_line
		(start 471.29192 -77.67193)
		(end 471.29192 -13.780008)
		(stroke
			(width 0.2)
			(type default)
		)
		(layer "In4.Cu")
	)
	(gr_arc
		(start 471.29192 -13.780008)
		(mid 470.854924 -12.725008)
		(end 469.799924 -12.288012)
		(stroke
			(width 0.2)
			(type default)
		)
		(layer "In4.Cu")
	)
	(gr_line
		(start 471.29192 -7.78002)
		(end 471.29192 10.40003)
		(stroke
			(width 0.2)
			(type default)
		)
		(layer "In4.Cu")
	)
	(gr_arc
		(start 471.29192 10.40003)
		(mid 470.854924 11.45503)
		(end 469.799924 11.892026)
		(stroke
			(width 0.2)
			(type default)
		)
		(layer "In4.Cu")
	)
	(gr_line
		(start 472.987624 -80.859122)
		(end 471.245184 -82.601562)
		(stroke
			(width 0.2)
			(type default)
		)
		(layer "In4.Cu")
	)
	(gr_arc
		(start 472.987624 -80.859122)
		(mid 473.964715 -79.396821)
		(end 474.307916 -77.67193)
		(stroke
			(width 0.2)
			(type default)
		)
		(layer "In4.Cu")
	)
	(gr_arc
		(start 474.307916 -461.028288)
		(mid 474.744912 -462.083288)
		(end 475.799912 -462.520284)
		(stroke
			(width 0.2)
			(type default)
		)
		(layer "In4.Cu")
	)
	(gr_arc
		(start 474.307916 -443.989968)
		(mid 473.573331 -442.216561)
		(end 471.79992 -441.481972)
		(stroke
			(width 0.2)
			(type default)
		)
		(layer "In4.Cu")
	)
	(gr_line
		(start 474.307916 -443.989968)
		(end 474.307916 -461.028288)
		(stroke
			(width 0.2)
			(type default)
		)
		(layer "In4.Cu")
	)
	(gr_line
		(start 474.307916 10.40003)
		(end 474.307916 -77.67193)
		(stroke
			(width 0.2)
			(type default)
		)
		(layer "In4.Cu")
	)
	(gr_line
		(start 475.799912 -462.520284)
		(end 531.7998 -462.520284)
		(stroke
			(width 0.2)
			(type default)
		)
		(layer "In4.Cu")
	)
	(gr_arc
		(start 475.799912 11.892026)
		(mid 474.744912 11.45503)
		(end 474.307916 10.40003)
		(stroke
			(width 0.2)
			(type default)
		)
		(layer "In4.Cu")
	)
	(gr_line
		(start 513.5118 -451.028308)
		(end 513.5118 -312.408316)
		(stroke
			(width 0.2)
			(type default)
		)
		(layer "In4.Cu")
	)
	(gr_arc
		(start 513.5118 -451.028308)
		(mid 514.246378 -452.801725)
		(end 516.019796 -453.536304)
		(stroke
			(width 0.2)
			(type default)
		)
		(layer "In4.Cu")
	)
	(gr_arc
		(start 516.019796 -309.90032)
		(mid 514.246383 -310.634897)
		(end 513.5118 -312.408316)
		(stroke
			(width 0.2)
			(type default)
		)
		(layer "In4.Cu")
	)
	(gr_line
		(start 516.019796 -309.90032)
		(end 531.7998 -309.90032)
		(stroke
			(width 0.2)
			(type default)
		)
		(layer "In4.Cu")
	)
	(gr_arc
		(start 531.7998 -462.520284)
		(mid 532.8548 -462.083288)
		(end 533.291796 -461.028288)
		(stroke
			(width 0.2)
			(type default)
		)
		(layer "In4.Cu")
	)
	(gr_line
		(start 531.7998 -453.536304)
		(end 516.019796 -453.536304)
		(stroke
			(width 0.2)
			(type default)
		)
		(layer "In4.Cu")
	)
	(gr_arc
		(start 531.7998 -309.90032)
		(mid 532.8548 -309.463324)
		(end 533.291796 -308.408324)
		(stroke
			(width 0.2)
			(type default)
		)
		(layer "In4.Cu")
	)
	(gr_line
		(start 531.7998 11.892026)
		(end 475.799912 11.892026)
		(stroke
			(width 0.2)
			(type default)
		)
		(layer "In4.Cu")
	)
	(gr_line
		(start 533.291796 -461.028288)
		(end 533.291796 -455.0283)
		(stroke
			(width 0.2)
			(type default)
		)
		(layer "In4.Cu")
	)
	(gr_arc
		(start 533.291796 -455.0283)
		(mid 532.8548 -453.9733)
		(end 531.7998 -453.536304)
		(stroke
			(width 0.2)
			(type default)
		)
		(layer "In4.Cu")
	)
	(gr_line
		(start 533.291796 -308.408324)
		(end 533.291796 10.40003)
		(stroke
			(width 0.2)
			(type default)
		)
		(layer "In4.Cu")
	)
	(gr_arc
		(start 533.291796 10.40003)
		(mid 532.8548 11.45503)
		(end 531.7998 11.892026)
		(stroke
			(width 0.2)
			(type default)
		)
		(layer "In4.Cu")
	)
	(gr_line
		(start 0 -77.671676)
		(end 0 -13.780008)
		(stroke
			(width 1.016)
			(type default)
		)
		(layer "In5.Cu")
	)
	(gr_arc
		(start 0 -77.671676)
		(mid 0.152237 -78.436936)
		(end 0.585724 -79.085694)
		(stroke
			(width 1.016)
			(type default)
		)
		(layer "In5.Cu")
	)
	(gr_poly
		(pts
			(arc
				(start 228.921818 -436.47868)
				(mid 228.941341 -436.474779)
				(end 228.957886 -436.463694)
			)
			(arc
				(start 229.664514 -435.757066)
				(mid 229.675625 -435.740532)
				(end 229.6795 -435.720998)
			)
			(arc
				(start 229.6795 -422.180766)
				(mid 229.703653 -422.05925)
				(end 229.772464 -421.95623)
			)
			(arc
				(start 234.67314 -417.055554)
				(mid 234.776172 -416.986773)
				(end 234.897676 -416.96259)
			)
			(arc
				(start 272.037556 -416.96259)
				(mid 272.057079 -416.958689)
				(end 272.073624 -416.947604)
			)
			(arc
				(start 280.035254 -408.985974)
				(mid 280.046365 -408.96944)
				(end 280.05024 -408.949906)
			)
			(arc
				(start 280.05024 -398.569942)
				(mid 280.046339 -398.550419)
				(end 280.035254 -398.533874)
			)
			(arc
				(start 279.299416 -397.798036)
				(mid 279.282882 -397.786925)
				(end 279.263348 -397.78305)
			)
			(arc
				(start 239.542066 -397.78305)
				(mid 239.522543 -397.786951)
				(end 239.505998 -397.798036)
			)
			(arc
				(start 239.215168 -398.088866)
				(mid 239.204057 -398.1054)
				(end 239.200182 -398.124934)
			)
			(arc
				(start 239.200182 -406.145492)
				(mid 239.176029 -406.267008)
				(end 239.107218 -406.370028)
			)
			(arc
				(start 234.940094 -410.537152)
				(mid 234.837062 -410.605933)
				(end 234.715558 -410.630116)
			)
			(arc
				(start 229.698296 -410.630116)
				(mid 229.678773 -410.634017)
				(end 229.662228 -410.645102)
			)
			(arc
				(start 227.151946 -413.155384)
				(mid 227.048914 -413.224165)
				(end 226.92741 -413.248348)
			)
			(arc
				(start 195.944744 -413.248348)
				(mid 195.925221 -413.252249)
				(end 195.908676 -413.263334)
			)
			(arc
				(start 195.239386 -413.932624)
				(mid 195.228275 -413.949158)
				(end 195.2244 -413.968692)
			)
			(arc
				(start 195.2244 -420.7002)
				(mid 195.228301 -420.719723)
				(end 195.239386 -420.736268)
			)
			(xy 195.23964 -420.736522)
			(arc
				(start 205.961996 -431.458878)
				(mid 206.030777 -431.56191)
				(end 206.05496 -431.683414)
			)
			(arc
				(start 206.05496 -435.078378)
				(mid 206.058861 -435.097901)
				(end 206.069946 -435.114446)
			)
			(arc
				(start 207.419194 -436.463694)
				(mid 207.435728 -436.474805)
				(end 207.455262 -436.47868)
			)
		)
		(stroke
			(width 0)
			(type solid)
		)
		(fill yes)
		(layer "In5.Cu")
		(net "P12V_PSU")
	)
	(gr_poly
		(pts
			(xy 531.7998 -462.519268) (xy 531.855569 -462.518759) (xy 531.966796 -462.510424) (xy 532.077089 -462.4938)
			(xy 532.185831 -462.46898) (xy 532.292414 -462.436103) (xy 532.396243 -462.395354) (xy 532.496736 -462.346959)
			(xy 532.593331 -462.291189) (xy 532.685488 -462.228357) (xy 532.772692 -462.158813) (xy 532.854456 -462.082947)
			(xy 532.930321 -462.001183) (xy 532.999864 -461.913979) (xy 533.062695 -461.821821) (xy 533.118464 -461.725225)
			(xy 533.166858 -461.624732) (xy 533.207607 -461.520903) (xy 533.240483 -461.41432) (xy 533.265302 -461.305577)
			(xy 533.281925 -461.195284) (xy 533.29026 -461.084057) (xy 533.29078 -461.028288) (xy 533.29078 -455.0283)
			(xy 533.290259 -454.972531) (xy 533.281923 -454.861305) (xy 533.265299 -454.751013) (xy 533.24048 -454.642271)
			(xy 533.207603 -454.535688) (xy 533.166854 -454.43186) (xy 533.118459 -454.331368) (xy 533.06269 -454.234773)
			(xy 532.999859 -454.142616) (xy 532.930316 -454.055412) (xy 532.854451 -453.973649) (xy 532.772688 -453.897784)
			(xy 532.685484 -453.828241) (xy 532.593327 -453.76541) (xy 532.496732 -453.709641) (xy 532.39624 -453.661246)
			(xy 532.292412 -453.620497) (xy 532.185829 -453.58762) (xy 532.077087 -453.562801) (xy 531.966795 -453.546177)
			(xy 531.855569 -453.537841) (xy 531.7998 -453.53732) (xy 516.019796 -453.53732) (xy 515.949414 -453.536826)
			(xy 515.808871 -453.528933) (xy 515.668991 -453.513172) (xy 515.530216 -453.489593) (xy 515.392981 -453.45827)
			(xy 515.257718 -453.419302) (xy 515.124852 -453.37281) (xy 514.994803 -453.318942) (xy 514.867978 -453.257866)
			(xy 514.744778 -453.189776) (xy 514.625589 -453.114884) (xy 514.510787 -453.033428) (xy 514.400733 -452.945663)
			(xy 514.295773 -452.851865) (xy 514.196238 -452.75233) (xy 514.10244 -452.64737) (xy 514.014674 -452.537316)
			(xy 513.933218 -452.422514) (xy 513.858326 -452.303325) (xy 513.790236 -452.180125) (xy 513.72916 -452.053301)
			(xy 513.675292 -451.923251) (xy 513.6288 -451.790386) (xy 513.589831 -451.655123) (xy 513.558507 -451.517888)
			(xy 513.534928 -451.379113) (xy 513.519167 -451.239233) (xy 513.511274 -451.09869) (xy 513.510784 -451.028308)
			(xy 513.510784 -312.408316) (xy 513.511268 -312.337933) (xy 513.51916 -312.197389) (xy 513.53492 -312.057508)
			(xy 513.558498 -311.918731) (xy 513.589821 -311.781495) (xy 513.628789 -311.646231) (xy 513.67528 -311.513364)
			(xy 513.729148 -311.383313) (xy 513.790224 -311.256488) (xy 513.858314 -311.133286) (xy 513.933205 -311.014096)
			(xy 514.014662 -310.899292) (xy 514.102427 -310.789237) (xy 514.196225 -310.684276) (xy 514.295761 -310.584739)
			(xy 514.400722 -310.49094) (xy 514.510776 -310.403174) (xy 514.625579 -310.321716) (xy 514.744769 -310.246824)
			(xy 514.86797 -310.178733) (xy 514.994795 -310.117656) (xy 515.124845 -310.063787) (xy 515.257712 -310.017295)
			(xy 515.392976 -309.978326) (xy 515.530212 -309.947002) (xy 515.668989 -309.923423) (xy 515.808869 -309.907662)
			(xy 515.949413 -309.899769) (xy 516.019796 -309.899304) (xy 531.7998 -309.899304) (xy 531.855569 -309.898783)
			(xy 531.966796 -309.890447) (xy 532.077089 -309.873823) (xy 532.185831 -309.849004) (xy 532.292415 -309.816128)
			(xy 532.396243 -309.775378) (xy 532.496737 -309.726984) (xy 532.593332 -309.671215) (xy 532.68549 -309.608384)
			(xy 532.772695 -309.538841) (xy 532.854459 -309.462976) (xy 532.930326 -309.381213) (xy 532.99987 -309.294009)
			(xy 533.062703 -309.201852) (xy 533.118473 -309.105258) (xy 533.166869 -309.004765) (xy 533.20762 -308.900937)
			(xy 533.240498 -308.794355) (xy 533.265319 -308.685613) (xy 533.281945 -308.57532) (xy 533.290282 -308.464093)
			(xy 533.29078 -308.408324) (xy 533.29078 10.40003) (xy 533.290257 10.455798) (xy 533.28192 10.567023)
			(xy 533.265294 10.677313) (xy 533.240473 10.786053) (xy 533.207596 10.892634) (xy 533.166845 10.99646)
			(xy 533.11845 11.09695) (xy 533.06268 11.193543) (xy 532.999848 11.285698) (xy 532.930305 11.3729)
			(xy 532.85444 11.454661) (xy 532.772677 11.530525) (xy 532.685474 11.600066) (xy 532.593318 11.662896)
			(xy 532.496724 11.718664) (xy 532.396232 11.767057) (xy 532.292406 11.807806) (xy 532.185824 11.840681)
			(xy 532.077084 11.8655) (xy 531.966793 11.882123) (xy 531.855568 11.890459) (xy 531.7998 11.89101)
			(xy 475.799912 11.89101) (xy 475.744142 11.890489) (xy 475.632915 11.882155) (xy 475.522621 11.865531)
			(xy 475.413878 11.840713) (xy 475.307293 11.807837) (xy 475.203464 11.767088) (xy 475.10297 11.718694)
			(xy 475.006373 11.662926) (xy 474.914214 11.600094) (xy 474.827008 11.530552) (xy 474.745243 11.454687)
			(xy 474.669376 11.372924) (xy 474.599831 11.28572) (xy 474.536997 11.193563) (xy 474.481225 11.096967)
			(xy 474.432829 10.996475) (xy 474.392077 10.892646) (xy 474.359198 10.786063) (xy 474.334376 10.67732)
			(xy 474.31775 10.567027) (xy 474.309413 10.4558) (xy 474.308932 10.40003) (xy 474.308932 7.335466)
			(xy 526.704041 7.335466) (xy 526.704041 7.464606) (xy 526.711991 7.593501) (xy 526.727861 7.721661)
			(xy 526.75159 7.848602) (xy 526.783089 7.973841) (xy 526.822238 8.096904) (xy 526.868889 8.217323)
			(xy 526.922864 8.334642) (xy 526.983959 8.448416) (xy 527.051942 8.558213) (xy 527.126556 8.663616)
			(xy 527.207517 8.764226) (xy 527.294517 8.859661) (xy 527.387228 8.94956) (xy 527.485298 9.033581)
			(xy 527.588353 9.111405) (xy 527.696004 9.182737) (xy 527.807843 9.247307) (xy 527.923444 9.304869)
			(xy 528.042369 9.355206) (xy 528.164168 9.398126) (xy 528.288378 9.433467) (xy 528.414527 9.461094)
			(xy 528.542139 9.480903) (xy 528.670728 9.492819) (xy 528.799806 9.496796) (xy 528.928884 9.492819)
			(xy 529.057473 9.480903) (xy 529.185085 9.461094) (xy 529.311234 9.433467) (xy 529.435444 9.398126)
			(xy 529.557243 9.355206) (xy 529.676168 9.304869) (xy 529.791769 9.247307) (xy 529.903608 9.182737)
			(xy 530.011259 9.111405) (xy 530.114314 9.033581) (xy 530.212384 8.94956) (xy 530.305095 8.859661)
			(xy 530.392095 8.764226) (xy 530.473056 8.663616) (xy 530.54767 8.558213) (xy 530.615653 8.448416)
			(xy 530.676748 8.334642) (xy 530.730723 8.217323) (xy 530.777374 8.096904) (xy 530.816523 7.973841)
			(xy 530.848022 7.848602) (xy 530.871751 7.721661) (xy 530.887621 7.593501) (xy 530.895571 7.464606)
			(xy 530.896068 7.400036) (xy 530.895571 7.335466) (xy 530.887621 7.206571) (xy 530.871751 7.078411)
			(xy 530.848022 6.95147) (xy 530.816523 6.826231) (xy 530.777374 6.703168) (xy 530.730723 6.582749)
			(xy 530.676748 6.46543) (xy 530.615653 6.351656) (xy 530.54767 6.241859) (xy 530.473056 6.136456)
			(xy 530.392095 6.035846) (xy 530.305095 5.940411) (xy 530.212384 5.850512) (xy 530.114314 5.766491)
			(xy 530.011259 5.688667) (xy 529.903608 5.617335) (xy 529.791769 5.552765) (xy 529.676168 5.495203)
			(xy 529.557243 5.444866) (xy 529.435444 5.401946) (xy 529.311234 5.366605) (xy 529.185085 5.338978)
			(xy 529.057473 5.319169) (xy 528.928884 5.307253) (xy 528.799806 5.303277) (xy 528.670728 5.307253)
			(xy 528.542139 5.319169) (xy 528.414527 5.338978) (xy 528.288378 5.366605) (xy 528.164168 5.401946)
			(xy 528.042369 5.444866) (xy 527.923444 5.495203) (xy 527.807843 5.552765) (xy 527.696004 5.617335)
			(xy 527.588353 5.688667) (xy 527.485298 5.766491) (xy 527.387228 5.850512) (xy 527.294517 5.940411)
			(xy 527.207517 6.035846) (xy 527.126556 6.136456) (xy 527.051942 6.241859) (xy 526.983959 6.351656)
			(xy 526.922864 6.46543) (xy 526.868889 6.582749) (xy 526.822238 6.703168) (xy 526.783089 6.826231)
			(xy 526.75159 6.95147) (xy 526.727861 7.078411) (xy 526.711991 7.206571) (xy 526.704041 7.335466)
			(xy 474.308932 7.335466) (xy 474.308932 -12.515904) (xy 476.704141 -12.515904) (xy 476.704141 -12.386764)
			(xy 476.712091 -12.257869) (xy 476.727961 -12.129709) (xy 476.75169 -12.002768) (xy 476.783189 -11.877529)
			(xy 476.822338 -11.754466) (xy 476.868989 -11.634047) (xy 476.922964 -11.516728) (xy 476.984059 -11.402954)
			(xy 477.052042 -11.293157) (xy 477.126656 -11.187754) (xy 477.207617 -11.087144) (xy 477.294617 -10.991709)
			(xy 477.387328 -10.90181) (xy 477.485398 -10.817789) (xy 477.588453 -10.739965) (xy 477.696104 -10.668633)
			(xy 477.807943 -10.604063) (xy 477.923544 -10.546501) (xy 478.042469 -10.496164) (xy 478.164268 -10.453244)
			(xy 478.288478 -10.417903) (xy 478.414627 -10.390276) (xy 478.542239 -10.370467) (xy 478.670828 -10.358551)
			(xy 478.799906 -10.354575) (xy 478.928984 -10.358551) (xy 479.057573 -10.370467) (xy 479.185185 -10.390276)
			(xy 479.311334 -10.417903) (xy 479.435544 -10.453244) (xy 479.557343 -10.496164) (xy 479.676268 -10.546501)
			(xy 479.791869 -10.604063) (xy 479.903708 -10.668633) (xy 480.011359 -10.739965) (xy 480.114414 -10.817789)
			(xy 480.212484 -10.90181) (xy 480.305195 -10.991709) (xy 480.392195 -11.087144) (xy 480.473156 -11.187754)
			(xy 480.54777 -11.293157) (xy 480.615753 -11.402954) (xy 480.676848 -11.516728) (xy 480.730823 -11.634047)
			(xy 480.777474 -11.754466) (xy 480.816623 -11.877529) (xy 480.848122 -12.002768) (xy 480.871851 -12.129709)
			(xy 480.887721 -12.257869) (xy 480.895671 -12.386764) (xy 480.896168 -12.451334) (xy 480.895671 -12.515904)
			(xy 480.887721 -12.644799) (xy 480.871851 -12.772959) (xy 480.848122 -12.8999) (xy 480.816623 -13.025139)
			(xy 480.777474 -13.148202) (xy 480.730823 -13.268621) (xy 480.676848 -13.38594) (xy 480.615753 -13.499714)
			(xy 480.54777 -13.609511) (xy 480.473156 -13.714914) (xy 480.392195 -13.815524) (xy 480.305195 -13.910959)
			(xy 480.212484 -14.000858) (xy 480.114414 -14.084879) (xy 480.011359 -14.162703) (xy 479.903708 -14.234035)
			(xy 479.791869 -14.298605) (xy 479.676268 -14.356167) (xy 479.557343 -14.406504) (xy 479.435544 -14.449424)
			(xy 479.311334 -14.484765) (xy 479.185185 -14.512392) (xy 479.057573 -14.532201) (xy 478.928984 -14.544117)
			(xy 478.799906 -14.548094) (xy 478.670828 -14.544117) (xy 478.542239 -14.532201) (xy 478.414627 -14.512392)
			(xy 478.288478 -14.484765) (xy 478.164268 -14.449424) (xy 478.042469 -14.406504) (xy 477.923544 -14.356167)
			(xy 477.807943 -14.298605) (xy 477.696104 -14.234035) (xy 477.588453 -14.162703) (xy 477.485398 -14.084879)
			(xy 477.387328 -14.000858) (xy 477.294617 -13.910959) (xy 477.207617 -13.815524) (xy 477.126656 -13.714914)
			(xy 477.052042 -13.609511) (xy 476.984059 -13.499714) (xy 476.922964 -13.38594) (xy 476.868989 -13.268621)
			(xy 476.822338 -13.148202) (xy 476.783189 -13.025139) (xy 476.75169 -12.8999) (xy 476.727961 -12.772959)
			(xy 476.712091 -12.644799) (xy 476.704141 -12.515904) (xy 474.308932 -12.515904) (xy 474.308932 -77.67193)
			(xy 474.308458 -77.765117) (xy 474.300759 -77.951331) (xy 474.28537 -78.137067) (xy 474.262318 -78.32201)
			(xy 474.231642 -78.505841) (xy 474.193396 -78.688247) (xy 474.147643 -78.868917) (xy 474.094463 -79.047542)
			(xy 474.033945 -79.223817) (xy 473.966195 -79.397439) (xy 473.891327 -79.568113) (xy 473.809469 -79.735548)
			(xy 473.720761 -79.899456) (xy 473.625355 -80.059558) (xy 473.523414 -80.21558) (xy 473.415112 -80.367256)
			(xy 473.300633 -80.514327) (xy 473.180175 -80.65654) (xy 473.053942 -80.793654) (xy 472.988386 -80.859884)
			(xy 471.245946 -82.602324) (xy 471.208633 -82.640304) (xy 471.138899 -82.72077) (xy 471.07508 -82.806006)
			(xy 471.017504 -82.895576) (xy 470.966464 -82.989025) (xy 470.922218 -83.085876) (xy 470.884993 -83.185636)
			(xy 470.854978 -83.287798) (xy 470.832326 -83.391839) (xy 470.817153 -83.497232) (xy 470.809535 -83.603438)
			(xy 470.809066 -83.656678) (xy 470.809066 -328.137828) (xy 473.204275 -328.137828) (xy 473.204275 -328.008688)
			(xy 473.212225 -327.879793) (xy 473.228095 -327.751633) (xy 473.251824 -327.624692) (xy 473.283323 -327.499453)
			(xy 473.322472 -327.37639) (xy 473.369123 -327.255971) (xy 473.423098 -327.138652) (xy 473.484193 -327.024878)
			(xy 473.552176 -326.915081) (xy 473.62679 -326.809678) (xy 473.707751 -326.709068) (xy 473.794751 -326.613633)
			(xy 473.887462 -326.523734) (xy 473.985532 -326.439713) (xy 474.088587 -326.361889) (xy 474.196238 -326.290557)
			(xy 474.308077 -326.225987) (xy 474.423678 -326.168425) (xy 474.542603 -326.118088) (xy 474.664402 -326.075168)
			(xy 474.788612 -326.039827) (xy 474.914761 -326.0122) (xy 475.042373 -325.992391) (xy 475.170962 -325.980475)
			(xy 475.30004 -325.976499) (xy 475.429118 -325.980475) (xy 475.557707 -325.992391) (xy 475.685319 -326.0122)
			(xy 475.811468 -326.039827) (xy 475.935678 -326.075168) (xy 476.057477 -326.118088) (xy 476.176402 -326.168425)
			(xy 476.292003 -326.225987) (xy 476.403842 -326.290557) (xy 476.511493 -326.361889) (xy 476.614548 -326.439713)
			(xy 476.712618 -326.523734) (xy 476.805329 -326.613633) (xy 476.892329 -326.709068) (xy 476.97329 -326.809678)
			(xy 477.047904 -326.915081) (xy 477.115887 -327.024878) (xy 477.176982 -327.138652) (xy 477.230957 -327.255971)
			(xy 477.277608 -327.37639) (xy 477.316757 -327.499453) (xy 477.348256 -327.624692) (xy 477.371985 -327.751633)
			(xy 477.387855 -327.879793) (xy 477.395805 -328.008688) (xy 477.396302 -328.073258) (xy 477.395805 -328.137828)
			(xy 477.387855 -328.266723) (xy 477.371985 -328.394883) (xy 477.348256 -328.521824) (xy 477.316757 -328.647063)
			(xy 477.277608 -328.770126) (xy 477.230957 -328.890545) (xy 477.176982 -329.007864) (xy 477.115887 -329.121638)
			(xy 477.047904 -329.231435) (xy 476.97329 -329.336838) (xy 476.892329 -329.437448) (xy 476.805329 -329.532883)
			(xy 476.712618 -329.622782) (xy 476.614548 -329.706803) (xy 476.511493 -329.784627) (xy 476.403842 -329.855959)
			(xy 476.292003 -329.920529) (xy 476.176402 -329.978091) (xy 476.057477 -330.028428) (xy 475.935678 -330.071348)
			(xy 475.811468 -330.106689) (xy 475.685319 -330.134316) (xy 475.557707 -330.154125) (xy 475.429118 -330.166041)
			(xy 475.30004 -330.170018) (xy 475.170962 -330.166041) (xy 475.042373 -330.154125) (xy 474.914761 -330.134316)
			(xy 474.788612 -330.106689) (xy 474.664402 -330.071348) (xy 474.542603 -330.028428) (xy 474.423678 -329.978091)
			(xy 474.308077 -329.920529) (xy 474.196238 -329.855959) (xy 474.088587 -329.784627) (xy 473.985532 -329.706803)
			(xy 473.887462 -329.622782) (xy 473.794751 -329.532883) (xy 473.707751 -329.437448) (xy 473.62679 -329.336838)
			(xy 473.552176 -329.231435) (xy 473.484193 -329.121638) (xy 473.423098 -329.007864) (xy 473.369123 -328.890545)
			(xy 473.322472 -328.770126) (xy 473.283323 -328.647063) (xy 473.251824 -328.521824) (xy 473.228095 -328.394883)
			(xy 473.212225 -328.266723) (xy 473.204275 -328.137828) (xy 470.809066 -328.137828) (xy 470.809066 -404.871936)
			(xy 470.808592 -404.965123) (xy 470.800892 -405.151337) (xy 470.785503 -405.337074) (xy 470.762451 -405.522016)
			(xy 470.731776 -405.705847) (xy 470.693529 -405.888254) (xy 470.647776 -406.068924) (xy 470.594596 -406.247549)
			(xy 470.534079 -406.423823) (xy 470.466329 -406.597446) (xy 470.391461 -406.76812) (xy 470.309603 -406.935555)
			(xy 470.220896 -407.099463) (xy 470.12549 -407.259566) (xy 470.02355 -407.415588) (xy 469.915248 -407.567265)
			(xy 469.80077 -407.714335) (xy 469.680312 -407.856549) (xy 469.554079 -407.993664) (xy 469.48852 -408.05989)
			(xy 468.245698 -409.302712) (xy 468.208406 -409.340689) (xy 468.138712 -409.421147) (xy 468.074932 -409.506369)
			(xy 468.017391 -409.595922) (xy 467.966382 -409.68935) (xy 467.922165 -409.786178) (xy 467.884964 -409.885911)
			(xy 467.85497 -409.988044) (xy 467.832334 -410.092055) (xy 467.817172 -410.197416) (xy 467.809562 -410.303589)
			(xy 467.809072 -410.356812) (xy 467.809072 -439.989976) (xy 467.809593 -440.045746) (xy 467.817926 -440.156975)
			(xy 467.834548 -440.26727) (xy 467.859367 -440.376014) (xy 467.892242 -440.4826) (xy 467.93299 -440.586431)
			(xy 467.981383 -440.686926) (xy 468.037152 -440.783525) (xy 468.099983 -440.875685) (xy 468.169525 -440.962893)
			(xy 468.24539 -441.044659) (xy 468.327153 -441.120528) (xy 468.414357 -441.190075) (xy 468.506514 -441.25291)
			(xy 468.60311 -441.308683) (xy 468.703603 -441.357081) (xy 468.807432 -441.397835) (xy 468.914016 -441.430715)
			(xy 469.022759 -441.455538) (xy 469.133053 -441.472166) (xy 469.244282 -441.480505) (xy 469.300052 -441.480956)
			(xy 471.79992 -441.480956) (xy 471.870302 -441.48145) (xy 472.010845 -441.489344) (xy 472.150724 -441.505105)
			(xy 472.2895 -441.528685) (xy 472.426735 -441.560009) (xy 472.561998 -441.598978) (xy 472.694863 -441.64547)
			(xy 472.824912 -441.699339) (xy 472.951736 -441.760414) (xy 473.074936 -441.828505) (xy 473.194125 -441.903396)
			(xy 473.308927 -441.984852) (xy 473.418981 -442.072617) (xy 473.523941 -442.166415) (xy 473.623477 -442.26595)
			(xy 473.717275 -442.37091) (xy 473.80504 -442.480964) (xy 473.886497 -442.595765) (xy 473.961389 -442.714953)
			(xy 474.02948 -442.838153) (xy 474.090556 -442.964977) (xy 474.144426 -443.095026) (xy 474.190918 -443.227891)
			(xy 474.229888 -443.363154) (xy 474.261212 -443.500389) (xy 474.284793 -443.639164) (xy 474.300555 -443.779043)
			(xy 474.308449 -443.919586) (xy 474.308932 -443.989968) (xy 474.308932 -458.092864) (xy 526.704041 -458.092864)
			(xy 526.704041 -457.963724) (xy 526.711991 -457.834829) (xy 526.727861 -457.706669) (xy 526.75159 -457.579728)
			(xy 526.783089 -457.454489) (xy 526.822238 -457.331426) (xy 526.868889 -457.211007) (xy 526.922864 -457.093688)
			(xy 526.983959 -456.979914) (xy 527.051942 -456.870117) (xy 527.126556 -456.764714) (xy 527.207517 -456.664104)
			(xy 527.294517 -456.568669) (xy 527.387228 -456.47877) (xy 527.485298 -456.394749) (xy 527.588353 -456.316925)
			(xy 527.696004 -456.245593) (xy 527.807843 -456.181023) (xy 527.923444 -456.123461) (xy 528.042369 -456.073124)
			(xy 528.164168 -456.030204) (xy 528.288378 -455.994863) (xy 528.414527 -455.967236) (xy 528.542139 -455.947427)
			(xy 528.670728 -455.935511) (xy 528.799806 -455.931535) (xy 528.928884 -455.935511) (xy 529.057473 -455.947427)
			(xy 529.185085 -455.967236) (xy 529.311234 -455.994863) (xy 529.435444 -456.030204) (xy 529.557243 -456.073124)
			(xy 529.676168 -456.123461) (xy 529.791769 -456.181023) (xy 529.903608 -456.245593) (xy 530.011259 -456.316925)
			(xy 530.114314 -456.394749) (xy 530.212384 -456.47877) (xy 530.305095 -456.568669) (xy 530.392095 -456.664104)
			(xy 530.473056 -456.764714) (xy 530.54767 -456.870117) (xy 530.615653 -456.979914) (xy 530.676748 -457.093688)
			(xy 530.730723 -457.211007) (xy 530.777374 -457.331426) (xy 530.816523 -457.454489) (xy 530.848022 -457.579728)
			(xy 530.871751 -457.706669) (xy 530.887621 -457.834829) (xy 530.895571 -457.963724) (xy 530.896068 -458.028294)
			(xy 530.895571 -458.092864) (xy 530.887621 -458.221759) (xy 530.871751 -458.349919) (xy 530.848022 -458.47686)
			(xy 530.816523 -458.602099) (xy 530.777374 -458.725162) (xy 530.730723 -458.845581) (xy 530.676748 -458.9629)
			(xy 530.615653 -459.076674) (xy 530.54767 -459.186471) (xy 530.473056 -459.291874) (xy 530.392095 -459.392484)
			(xy 530.305095 -459.487919) (xy 530.212384 -459.577818) (xy 530.114314 -459.661839) (xy 530.011259 -459.739663)
			(xy 529.903608 -459.810995) (xy 529.791769 -459.875565) (xy 529.676168 -459.933127) (xy 529.557243 -459.983464)
			(xy 529.435444 -460.026384) (xy 529.311234 -460.061725) (xy 529.185085 -460.089352) (xy 529.057473 -460.109161)
			(xy 528.928884 -460.121077) (xy 528.799806 -460.125054) (xy 528.670728 -460.121077) (xy 528.542139 -460.109161)
			(xy 528.414527 -460.089352) (xy 528.288378 -460.061725) (xy 528.164168 -460.026384) (xy 528.042369 -459.983464)
			(xy 527.923444 -459.933127) (xy 527.807843 -459.875565) (xy 527.696004 -459.810995) (xy 527.588353 -459.739663)
			(xy 527.485298 -459.661839) (xy 527.387228 -459.577818) (xy 527.294517 -459.487919) (xy 527.207517 -459.392484)
			(xy 527.126556 -459.291874) (xy 527.051942 -459.186471) (xy 526.983959 -459.076674) (xy 526.922864 -458.9629)
			(xy 526.868889 -458.845581) (xy 526.822238 -458.725162) (xy 526.783089 -458.602099) (xy 526.75159 -458.47686)
			(xy 526.727861 -458.349919) (xy 526.711991 -458.221759) (xy 526.704041 -458.092864) (xy 474.308932 -458.092864)
			(xy 474.308932 -461.028288) (xy 474.30944 -461.084058) (xy 474.317775 -461.195285) (xy 474.334398 -461.305579)
			(xy 474.359217 -461.414322) (xy 474.392093 -461.520906) (xy 474.432843 -461.624735) (xy 474.481238 -461.725228)
			(xy 474.537007 -461.821824) (xy 474.599839 -461.913982) (xy 474.669383 -462.001187) (xy 474.745248 -462.082952)
			(xy 474.827013 -462.158817) (xy 474.914218 -462.228361) (xy 475.006376 -462.291193) (xy 475.102972 -462.346962)
			(xy 475.203465 -462.395357) (xy 475.307294 -462.436107) (xy 475.413878 -462.468983) (xy 475.522621 -462.493802)
			(xy 475.632915 -462.510425) (xy 475.744142 -462.51876) (xy 475.799912 -462.519268)
		)
		(stroke
			(width 0)
			(type solid)
		)
		(fill yes)
		(layer "In5.Cu")
		(net "T1_GND")
	)
	(gr_poly
		(pts
			(xy 255.800098 -33.611058) (xy 255.832245 -33.610555) (xy 255.89599 -33.602163) (xy 255.958093 -33.585522)
			(xy 256.017493 -33.560917) (xy 256.073173 -33.528769) (xy 256.124181 -33.489628) (xy 256.169643 -33.444164)
			(xy 256.208781 -33.393155) (xy 256.240927 -33.337473) (xy 256.265529 -33.278072) (xy 256.282167 -33.215968)
			(xy 256.290557 -33.152223) (xy 256.29108 -33.120076) (xy 256.29108 -11.780012) (xy 256.291564 -11.709629)
			(xy 256.299456 -11.569085) (xy 256.315217 -11.429205) (xy 256.338795 -11.290428) (xy 256.370118 -11.153191)
			(xy 256.409086 -11.017927) (xy 256.455577 -10.885061) (xy 256.509445 -10.75501) (xy 256.570521 -10.628184)
			(xy 256.638611 -10.504983) (xy 256.713502 -10.385793) (xy 256.794959 -10.27099) (xy 256.882724 -10.160934)
			(xy 256.976523 -10.055973) (xy 257.076059 -9.956436) (xy 257.181019 -9.862637) (xy 257.291074 -9.774871)
			(xy 257.405876 -9.693414) (xy 257.525065 -9.618521) (xy 257.648266 -9.55043) (xy 257.775092 -9.489354)
			(xy 257.905142 -9.435484) (xy 258.038008 -9.388992) (xy 258.173272 -9.350023) (xy 258.310508 -9.318699)
			(xy 258.449285 -9.295119) (xy 258.589165 -9.279358) (xy 258.729709 -9.271465) (xy 258.800092 -9.271)
			(xy 383.601976 -9.271) (xy 383.657746 -9.270492) (xy 383.768975 -9.262159) (xy 383.87927 -9.245536)
			(xy 383.988015 -9.220718) (xy 384.094601 -9.187842) (xy 384.198432 -9.147093) (xy 384.298927 -9.098699)
			(xy 384.395525 -9.04293) (xy 384.487685 -8.980099) (xy 384.574892 -8.910555) (xy 384.656659 -8.83469)
			(xy 384.732527 -8.752926) (xy 384.802073 -8.665721) (xy 384.864907 -8.573562) (xy 384.920679 -8.476966)
			(xy 384.969076 -8.376472) (xy 385.009828 -8.272642) (xy 385.042706 -8.166058) (xy 385.067528 -8.057314)
			(xy 385.084154 -7.947019) (xy 385.092491 -7.83579) (xy 385.092956 -7.78002) (xy 385.092956 0.40005)
			(xy 385.093451 0.470432) (xy 385.101346 0.610973) (xy 385.117109 0.750851) (xy 385.14069 0.889625)
			(xy 385.172015 1.026859) (xy 385.210985 1.16212) (xy 385.257478 1.294984) (xy 385.311348 1.425032)
			(xy 385.372424 1.551855) (xy 385.440515 1.675053) (xy 385.515407 1.79424) (xy 385.596863 1.909041)
			(xy 385.684628 2.019094) (xy 385.778426 2.124052) (xy 385.877961 2.223587) (xy 385.98292 2.317383)
			(xy 386.092974 2.405148) (xy 386.207775 2.486603) (xy 386.326962 2.561494) (xy 386.450161 2.629584)
			(xy 386.576985 2.69066) (xy 386.707033 2.744528) (xy 386.839897 2.79102) (xy 386.975158 2.829989)
			(xy 387.112392 2.861313) (xy 387.251166 2.884893) (xy 387.391045 2.900655) (xy 387.531586 2.908549)
			(xy 387.601968 2.909062) (xy 456.202034 2.909062) (xy 456.272416 2.908567) (xy 456.412959 2.900673)
			(xy 456.552838 2.884911) (xy 456.691613 2.861331) (xy 456.828848 2.830006) (xy 456.96411 2.791037)
			(xy 457.096975 2.744544) (xy 457.227024 2.690676) (xy 457.353848 2.6296) (xy 457.477048 2.561509)
			(xy 457.596236 2.486618) (xy 457.711038 2.405161) (xy 457.821092 2.317396) (xy 457.926052 2.223599)
			(xy 458.025588 2.124064) (xy 458.119386 2.019104) (xy 458.207152 1.909051) (xy 458.288609 1.79425)
			(xy 458.363501 1.675062) (xy 458.431592 1.551862) (xy 458.492669 1.425039) (xy 458.546539 1.29499)
			(xy 458.593032 1.162126) (xy 458.632002 1.026863) (xy 458.663327 0.889629) (xy 458.686909 0.750854)
			(xy 458.702672 0.610975) (xy 458.710567 0.470432) (xy 458.711046 0.40005) (xy 458.711046 -4.844596)
			(xy 464.704165 -4.844596) (xy 464.704165 -4.715456) (xy 464.712115 -4.586561) (xy 464.727985 -4.458401)
			(xy 464.751714 -4.33146) (xy 464.783213 -4.206221) (xy 464.822362 -4.083158) (xy 464.869013 -3.962739)
			(xy 464.922988 -3.84542) (xy 464.984083 -3.731646) (xy 465.052066 -3.621849) (xy 465.12668 -3.516446)
			(xy 465.207641 -3.415836) (xy 465.294641 -3.320401) (xy 465.387352 -3.230502) (xy 465.485422 -3.146481)
			(xy 465.588477 -3.068657) (xy 465.696128 -2.997325) (xy 465.807967 -2.932755) (xy 465.923568 -2.875193)
			(xy 466.042493 -2.824856) (xy 466.164292 -2.781936) (xy 466.288502 -2.746595) (xy 466.414651 -2.718968)
			(xy 466.542263 -2.699159) (xy 466.670852 -2.687243) (xy 466.79993 -2.683267) (xy 466.929008 -2.687243)
			(xy 467.057597 -2.699159) (xy 467.185209 -2.718968) (xy 467.311358 -2.746595) (xy 467.435568 -2.781936)
			(xy 467.557367 -2.824856) (xy 467.676292 -2.875193) (xy 467.791893 -2.932755) (xy 467.903732 -2.997325)
			(xy 468.011383 -3.068657) (xy 468.114438 -3.146481) (xy 468.212508 -3.230502) (xy 468.305219 -3.320401)
			(xy 468.392219 -3.415836) (xy 468.47318 -3.516446) (xy 468.547794 -3.621849) (xy 468.615777 -3.731646)
			(xy 468.676872 -3.84542) (xy 468.730847 -3.962739) (xy 468.777498 -4.083158) (xy 468.816647 -4.206221)
			(xy 468.848146 -4.33146) (xy 468.871875 -4.458401) (xy 468.887745 -4.586561) (xy 468.895695 -4.715456)
			(xy 468.896192 -4.780026) (xy 468.895695 -4.844596) (xy 468.887745 -4.973491) (xy 468.871875 -5.101651)
			(xy 468.848146 -5.228592) (xy 468.816647 -5.353831) (xy 468.777498 -5.476894) (xy 468.730847 -5.597313)
			(xy 468.676872 -5.714632) (xy 468.615777 -5.828406) (xy 468.547794 -5.938203) (xy 468.47318 -6.043606)
			(xy 468.392219 -6.144216) (xy 468.305219 -6.239651) (xy 468.212508 -6.32955) (xy 468.114438 -6.413571)
			(xy 468.011383 -6.491395) (xy 467.903732 -6.562727) (xy 467.791893 -6.627297) (xy 467.676292 -6.684859)
			(xy 467.557367 -6.735196) (xy 467.435568 -6.778116) (xy 467.311358 -6.813457) (xy 467.185209 -6.841084)
			(xy 467.057597 -6.860893) (xy 466.929008 -6.872809) (xy 466.79993 -6.876786) (xy 466.670852 -6.872809)
			(xy 466.542263 -6.860893) (xy 466.414651 -6.841084) (xy 466.288502 -6.813457) (xy 466.164292 -6.778116)
			(xy 466.042493 -6.735196) (xy 465.923568 -6.684859) (xy 465.807967 -6.627297) (xy 465.696128 -6.562727)
			(xy 465.588477 -6.491395) (xy 465.485422 -6.413571) (xy 465.387352 -6.32955) (xy 465.294641 -6.239651)
			(xy 465.207641 -6.144216) (xy 465.12668 -6.043606) (xy 465.052066 -5.938203) (xy 464.984083 -5.828406)
			(xy 464.922988 -5.714632) (xy 464.869013 -5.597313) (xy 464.822362 -5.476894) (xy 464.783213 -5.353831)
			(xy 464.751714 -5.228592) (xy 464.727985 -5.101651) (xy 464.712115 -4.973491) (xy 464.704165 -4.844596)
			(xy 458.711046 -4.844596) (xy 458.711046 -7.78002) (xy 458.711555 -7.835789) (xy 458.719892 -7.947014)
			(xy 458.736517 -8.057305) (xy 458.761338 -8.166046) (xy 458.794216 -8.272628) (xy 458.834967 -8.376454)
			(xy 458.883362 -8.476945) (xy 458.939132 -8.573538) (xy 459.001965 -8.665694) (xy 459.071509 -8.752896)
			(xy 459.147375 -8.834658) (xy 459.229138 -8.910521) (xy 459.316343 -8.980062) (xy 459.4085 -9.042892)
			(xy 459.505096 -9.098659) (xy 459.605588 -9.147052) (xy 459.709416 -9.187799) (xy 459.815999 -9.220674)
			(xy 459.92474 -9.245491) (xy 460.035032 -9.262113) (xy 460.146257 -9.270446) (xy 460.202026 -9.271)
			(xy 469.799924 -9.271) (xy 469.855693 -9.270478) (xy 469.966918 -9.262141) (xy 470.07721 -9.245516)
			(xy 470.18595 -9.220695) (xy 470.292532 -9.187817) (xy 470.396359 -9.147067) (xy 470.49685 -9.098672)
			(xy 470.593444 -9.042903) (xy 470.685601 -8.980071) (xy 470.772804 -8.910528) (xy 470.854566 -8.834664)
			(xy 470.930431 -8.752901) (xy 470.999974 -8.665697) (xy 471.062805 -8.573541) (xy 471.118574 -8.476947)
			(xy 471.166969 -8.376455) (xy 471.207719 -8.272628) (xy 471.240596 -8.166046) (xy 471.265416 -8.057306)
			(xy 471.282041 -7.947014) (xy 471.290378 -7.835789) (xy 471.290904 -7.78002) (xy 471.290904 10.40003)
			(xy 471.290381 10.455799) (xy 471.282044 10.567024) (xy 471.265419 10.677315) (xy 471.240598 10.786055)
			(xy 471.20772 10.892637) (xy 471.16697 10.996464) (xy 471.118574 11.096955) (xy 471.062805 11.193548)
			(xy 470.999973 11.285705) (xy 470.930431 11.372908) (xy 470.854566 11.45467) (xy 470.772803 11.530534)
			(xy 470.6856 11.600077) (xy 470.593443 11.662908) (xy 470.49685 11.718677) (xy 470.396358 11.767072)
			(xy 470.292531 11.807822) (xy 470.18595 11.840699) (xy 470.077209 11.86552) (xy 469.966918 11.882145)
			(xy 469.855693 11.890482) (xy 469.799924 11.89101) (xy 1.999996 11.89101) (xy 1.944227 11.890488)
			(xy 1.833001 11.882153) (xy 1.722709 11.865529) (xy 1.613968 11.840709) (xy 1.507385 11.807832) (xy 1.403558 11.767083)
			(xy 1.303066 11.718688) (xy 1.206471 11.662919) (xy 1.114314 11.600087) (xy 1.027111 11.530545) (xy 0.945348 11.454679)
			(xy 0.869483 11.372916) (xy 0.79994 11.285712) (xy 0.737109 11.193555) (xy 0.68134 11.096961) (xy 0.632946 10.996469)
			(xy 0.592196 10.892641) (xy 0.55932 10.786058) (xy 0.534501 10.677317) (xy 0.517877 10.567025) (xy 0.509541 10.455799)
			(xy 0.509016 10.40003) (xy 0.509016 9.916973) (xy 385.651997 9.916973) (xy 385.651997 10.002723)
			(xy 385.659909 10.088106) (xy 385.675665 10.172396) (xy 385.699132 10.254872) (xy 385.730108 10.334831)
			(xy 385.76833 10.411591) (xy 385.813471 10.484497) (xy 385.865147 10.552926) (xy 385.922916 10.616296)
			(xy 385.986286 10.674065) (xy 386.054715 10.725741) (xy 386.127621 10.770882) (xy 386.204381 10.809104)
			(xy 386.28434 10.84008) (xy 386.366816 10.863547) (xy 386.451106 10.879303) (xy 386.536489 10.887215)
			(xy 386.622239 10.887215) (xy 386.707622 10.879303) (xy 386.791912 10.863547) (xy 386.874388 10.84008)
			(xy 386.954347 10.809104) (xy 387.031107 10.770882) (xy 387.104013 10.725741) (xy 387.172442 10.674065)
			(xy 387.235812 10.616296) (xy 387.293581 10.552926) (xy 387.345257 10.484497) (xy 387.390398 10.411591)
			(xy 387.42862 10.334831) (xy 387.459596 10.254872) (xy 387.483063 10.172396) (xy 387.498819 10.088106)
			(xy 387.506731 10.002723) (xy 387.507226 9.959848) (xy 387.506731 9.916973) (xy 392.001997 9.916973)
			(xy 392.001997 10.002723) (xy 392.009909 10.088106) (xy 392.025665 10.172396) (xy 392.049132 10.254872)
			(xy 392.080108 10.334831) (xy 392.11833 10.411591) (xy 392.163471 10.484497) (xy 392.215147 10.552926)
			(xy 392.272916 10.616296) (xy 392.336286 10.674065) (xy 392.404715 10.725741) (xy 392.477621 10.770882)
			(xy 392.554381 10.809104) (xy 392.63434 10.84008) (xy 392.716816 10.863547) (xy 392.801106 10.879303)
			(xy 392.886489 10.887215) (xy 392.972239 10.887215) (xy 393.057622 10.879303) (xy 393.141912 10.863547)
			(xy 393.224388 10.84008) (xy 393.304347 10.809104) (xy 393.381107 10.770882) (xy 393.454013 10.725741)
			(xy 393.522442 10.674065) (xy 393.585812 10.616296) (xy 393.643581 10.552926) (xy 393.695257 10.484497)
			(xy 393.740398 10.411591) (xy 393.77862 10.334831) (xy 393.809596 10.254872) (xy 393.833063 10.172396)
			(xy 393.848819 10.088106) (xy 393.856731 10.002723) (xy 393.857226 9.959848) (xy 393.856731 9.916973)
			(xy 436.390783 9.916973) (xy 436.390783 10.002723) (xy 436.398695 10.088106) (xy 436.414451 10.172396)
			(xy 436.437918 10.254872) (xy 436.468894 10.334831) (xy 436.507116 10.411591) (xy 436.552257 10.484497)
			(xy 436.603933 10.552926) (xy 436.661702 10.616296) (xy 436.725072 10.674065) (xy 436.793501 10.725741)
			(xy 436.866407 10.770882) (xy 436.943167 10.809104) (xy 437.023126 10.84008) (xy 437.105602 10.863547)
			(xy 437.189892 10.879303) (xy 437.275275 10.887215) (xy 437.361025 10.887215) (xy 437.446408 10.879303)
			(xy 437.530698 10.863547) (xy 437.613174 10.84008) (xy 437.693133 10.809104) (xy 437.769893 10.770882)
			(xy 437.842799 10.725741) (xy 437.911228 10.674065) (xy 437.974598 10.616296) (xy 438.032367 10.552926)
			(xy 438.084043 10.484497) (xy 438.129184 10.411591) (xy 438.167406 10.334831) (xy 438.198382 10.254872)
			(xy 438.221849 10.172396) (xy 438.237605 10.088106) (xy 438.245517 10.002723) (xy 438.246012 9.959848)
			(xy 438.245517 9.916973) (xy 442.740783 9.916973) (xy 442.740783 10.002723) (xy 442.748695 10.088106)
			(xy 442.764451 10.172396) (xy 442.787918 10.254872) (xy 442.818894 10.334831) (xy 442.857116 10.411591)
			(xy 442.902257 10.484497) (xy 442.953933 10.552926) (xy 443.011702 10.616296) (xy 443.075072 10.674065)
			(xy 443.143501 10.725741) (xy 443.216407 10.770882) (xy 443.293167 10.809104) (xy 443.373126 10.84008)
			(xy 443.455602 10.863547) (xy 443.539892 10.879303) (xy 443.625275 10.887215) (xy 443.711025 10.887215)
			(xy 443.796408 10.879303) (xy 443.880698 10.863547) (xy 443.963174 10.84008) (xy 444.043133 10.809104)
			(xy 444.119893 10.770882) (xy 444.192799 10.725741) (xy 444.261228 10.674065) (xy 444.324598 10.616296)
			(xy 444.382367 10.552926) (xy 444.434043 10.484497) (xy 444.479184 10.411591) (xy 444.517406 10.334831)
			(xy 444.548382 10.254872) (xy 444.571849 10.172396) (xy 444.587605 10.088106) (xy 444.595517 10.002723)
			(xy 444.596012 9.959848) (xy 444.595517 9.916973) (xy 444.587605 9.83159) (xy 444.571849 9.7473)
			(xy 444.548382 9.664824) (xy 444.517406 9.584865) (xy 444.479184 9.508105) (xy 444.434043 9.435199)
			(xy 444.382367 9.36677) (xy 444.324598 9.3034) (xy 444.261228 9.245631) (xy 444.192799 9.193955)
			(xy 444.119893 9.148814) (xy 444.043133 9.110592) (xy 443.963174 9.079616) (xy 443.880698 9.056149)
			(xy 443.796408 9.040393) (xy 443.711025 9.032481) (xy 443.625275 9.032481) (xy 443.539892 9.040393)
			(xy 443.455602 9.056149) (xy 443.373126 9.079616) (xy 443.293167 9.110592) (xy 443.216407 9.148814)
			(xy 443.143501 9.193955) (xy 443.075072 9.245631) (xy 443.011702 9.3034) (xy 442.953933 9.36677)
			(xy 442.902257 9.435199) (xy 442.857116 9.508105) (xy 442.818894 9.584865) (xy 442.787918 9.664824)
			(xy 442.764451 9.7473) (xy 442.748695 9.83159) (xy 442.740783 9.916973) (xy 438.245517 9.916973)
			(xy 438.237605 9.83159) (xy 438.221849 9.7473) (xy 438.198382 9.664824) (xy 438.167406 9.584865)
			(xy 438.129184 9.508105) (xy 438.084043 9.435199) (xy 438.032367 9.36677) (xy 437.974598 9.3034)
			(xy 437.911228 9.245631) (xy 437.842799 9.193955) (xy 437.769893 9.148814) (xy 437.693133 9.110592)
			(xy 437.613174 9.079616) (xy 437.530698 9.056149) (xy 437.446408 9.040393) (xy 437.361025 9.032481)
			(xy 437.275275 9.032481) (xy 437.189892 9.040393) (xy 437.105602 9.056149) (xy 437.023126 9.079616)
			(xy 436.943167 9.110592) (xy 436.866407 9.148814) (xy 436.793501 9.193955) (xy 436.725072 9.245631)
			(xy 436.661702 9.3034) (xy 436.603933 9.36677) (xy 436.552257 9.435199) (xy 436.507116 9.508105)
			(xy 436.468894 9.584865) (xy 436.437918 9.664824) (xy 436.414451 9.7473) (xy 436.398695 9.83159)
			(xy 436.390783 9.916973) (xy 393.856731 9.916973) (xy 393.848819 9.83159) (xy 393.833063 9.7473)
			(xy 393.809596 9.664824) (xy 393.77862 9.584865) (xy 393.740398 9.508105) (xy 393.695257 9.435199)
			(xy 393.643581 9.36677) (xy 393.585812 9.3034) (xy 393.522442 9.245631) (xy 393.454013 9.193955)
			(xy 393.381107 9.148814) (xy 393.304347 9.110592) (xy 393.224388 9.079616) (xy 393.141912 9.056149)
			(xy 393.057622 9.040393) (xy 392.972239 9.032481) (xy 392.886489 9.032481) (xy 392.801106 9.040393)
			(xy 392.716816 9.056149) (xy 392.63434 9.079616) (xy 392.554381 9.110592) (xy 392.477621 9.148814)
			(xy 392.404715 9.193955) (xy 392.336286 9.245631) (xy 392.272916 9.3034) (xy 392.215147 9.36677)
			(xy 392.163471 9.435199) (xy 392.11833 9.508105) (xy 392.080108 9.584865) (xy 392.049132 9.664824)
			(xy 392.025665 9.7473) (xy 392.009909 9.83159) (xy 392.001997 9.916973) (xy 387.506731 9.916973)
			(xy 387.498819 9.83159) (xy 387.483063 9.7473) (xy 387.459596 9.664824) (xy 387.42862 9.584865) (xy 387.390398 9.508105)
			(xy 387.345257 9.435199) (xy 387.293581 9.36677) (xy 387.235812 9.3034) (xy 387.172442 9.245631)
			(xy 387.104013 9.193955) (xy 387.031107 9.148814) (xy 386.954347 9.110592) (xy 386.874388 9.079616)
			(xy 386.791912 9.056149) (xy 386.707622 9.040393) (xy 386.622239 9.032481) (xy 386.536489 9.032481)
			(xy 386.451106 9.040393) (xy 386.366816 9.056149) (xy 386.28434 9.079616) (xy 386.204381 9.110592)
			(xy 386.127621 9.148814) (xy 386.054715 9.193955) (xy 385.986286 9.245631) (xy 385.922916 9.3034)
			(xy 385.865147 9.36677) (xy 385.813471 9.435199) (xy 385.76833 9.508105) (xy 385.730108 9.584865)
			(xy 385.699132 9.664824) (xy 385.675665 9.7473) (xy 385.659909 9.83159) (xy 385.651997 9.916973)
			(xy 0.509016 9.916973) (xy 0.509016 7.335466) (xy 2.904225 7.335466) (xy 2.904225 7.464606) (xy 2.912175 7.593501)
			(xy 2.928045 7.721661) (xy 2.951774 7.848602) (xy 2.983273 7.973841) (xy 3.022422 8.096904) (xy 3.069073 8.217323)
			(xy 3.123048 8.334642) (xy 3.184143 8.448416) (xy 3.252126 8.558213) (xy 3.32674 8.663616) (xy 3.407701 8.764226)
			(xy 3.494701 8.859661) (xy 3.587412 8.94956) (xy 3.685482 9.033581) (xy 3.788537 9.111405) (xy 3.896188 9.182737)
			(xy 4.008027 9.247307) (xy 4.123628 9.304869) (xy 4.242553 9.355206) (xy 4.364352 9.398126) (xy 4.488562 9.433467)
			(xy 4.614711 9.461094) (xy 4.742323 9.480903) (xy 4.870912 9.492819) (xy 4.99999 9.496796) (xy 5.129068 9.492819)
			(xy 5.257657 9.480903) (xy 5.385269 9.461094) (xy 5.511418 9.433467) (xy 5.635628 9.398126) (xy 5.757427 9.355206)
			(xy 5.876352 9.304869) (xy 5.991953 9.247307) (xy 6.103792 9.182737) (xy 6.211443 9.111405) (xy 6.314498 9.033581)
			(xy 6.412568 8.94956) (xy 6.505279 8.859661) (xy 6.51416 8.849919) (xy 208.661241 8.849919) (xy 208.661241 8.935669)
			(xy 208.669153 9.021052) (xy 208.684909 9.105342) (xy 208.708376 9.187818) (xy 208.739352 9.267777)
			(xy 208.777574 9.344537) (xy 208.822715 9.417443) (xy 208.874391 9.485872) (xy 208.93216 9.549242)
			(xy 208.99553 9.607011) (xy 209.063959 9.658687) (xy 209.136865 9.703828) (xy 209.213625 9.74205)
			(xy 209.293584 9.773026) (xy 209.37606 9.796493) (xy 209.46035 9.812249) (xy 209.545733 9.820161)
			(xy 209.631483 9.820161) (xy 209.716866 9.812249) (xy 209.801156 9.796493) (xy 209.883632 9.773026)
			(xy 209.963591 9.74205) (xy 210.040351 9.703828) (xy 210.113257 9.658687) (xy 210.181686 9.607011)
			(xy 210.245056 9.549242) (xy 210.302825 9.485872) (xy 210.354501 9.417443) (xy 210.399642 9.344537)
			(xy 210.437864 9.267777) (xy 210.46884 9.187818) (xy 210.492307 9.105342) (xy 210.508063 9.021052)
			(xy 210.515975 8.935669) (xy 210.51647 8.892794) (xy 210.515975 8.849919) (xy 215.011241 8.849919)
			(xy 215.011241 8.935669) (xy 215.019153 9.021052) (xy 215.034909 9.105342) (xy 215.058376 9.187818)
			(xy 215.089352 9.267777) (xy 215.127574 9.344537) (xy 215.172715 9.417443) (xy 215.224391 9.485872)
			(xy 215.28216 9.549242) (xy 215.34553 9.607011) (xy 215.413959 9.658687) (xy 215.486865 9.703828)
			(xy 215.563625 9.74205) (xy 215.643584 9.773026) (xy 215.72606 9.796493) (xy 215.81035 9.812249)
			(xy 215.895733 9.820161) (xy 215.981483 9.820161) (xy 216.066866 9.812249) (xy 216.151156 9.796493)
			(xy 216.233632 9.773026) (xy 216.313591 9.74205) (xy 216.390351 9.703828) (xy 216.463257 9.658687)
			(xy 216.531686 9.607011) (xy 216.595056 9.549242) (xy 216.652825 9.485872) (xy 216.704501 9.417443)
			(xy 216.749642 9.344537) (xy 216.787864 9.267777) (xy 216.81884 9.187818) (xy 216.842307 9.105342)
			(xy 216.858063 9.021052) (xy 216.865975 8.935669) (xy 216.86647 8.892794) (xy 216.865975 8.849919)
			(xy 296.143921 8.849919) (xy 296.143921 8.935669) (xy 296.151833 9.021052) (xy 296.167589 9.105342)
			(xy 296.191056 9.187818) (xy 296.222032 9.267777) (xy 296.260254 9.344537) (xy 296.305395 9.417443)
			(xy 296.357071 9.485872) (xy 296.41484 9.549242) (xy 296.47821 9.607011) (xy 296.546639 9.658687)
			(xy 296.619545 9.703828) (xy 296.696305 9.74205) (xy 296.776264 9.773026) (xy 296.85874 9.796493)
			(xy 296.94303 9.812249) (xy 297.028413 9.820161) (xy 297.114163 9.820161) (xy 297.199546 9.812249)
			(xy 297.283836 9.796493) (xy 297.366312 9.773026) (xy 297.446271 9.74205) (xy 297.523031 9.703828)
			(xy 297.595937 9.658687) (xy 297.664366 9.607011) (xy 297.727736 9.549242) (xy 297.785505 9.485872)
			(xy 297.837181 9.417443) (xy 297.882322 9.344537) (xy 297.920544 9.267777) (xy 297.95152 9.187818)
			(xy 297.974987 9.105342) (xy 297.990743 9.021052) (xy 297.998655 8.935669) (xy 297.99915 8.892794)
			(xy 297.998655 8.849919) (xy 302.493921 8.849919) (xy 302.493921 8.935669) (xy 302.501833 9.021052)
			(xy 302.517589 9.105342) (xy 302.541056 9.187818) (xy 302.572032 9.267777) (xy 302.610254 9.344537)
			(xy 302.655395 9.417443) (xy 302.707071 9.485872) (xy 302.76484 9.549242) (xy 302.82821 9.607011)
			(xy 302.896639 9.658687) (xy 302.969545 9.703828) (xy 303.046305 9.74205) (xy 303.126264 9.773026)
			(xy 303.20874 9.796493) (xy 303.29303 9.812249) (xy 303.378413 9.820161) (xy 303.464163 9.820161)
			(xy 303.549546 9.812249) (xy 303.633836 9.796493) (xy 303.716312 9.773026) (xy 303.796271 9.74205)
			(xy 303.873031 9.703828) (xy 303.945937 9.658687) (xy 304.014366 9.607011) (xy 304.077736 9.549242)
			(xy 304.135505 9.485872) (xy 304.187181 9.417443) (xy 304.232322 9.344537) (xy 304.270544 9.267777)
			(xy 304.30152 9.187818) (xy 304.324987 9.105342) (xy 304.340743 9.021052) (xy 304.348655 8.935669)
			(xy 304.34915 8.892794) (xy 304.348655 8.849919) (xy 311.155321 8.849919) (xy 311.155321 8.935669)
			(xy 311.163233 9.021052) (xy 311.178989 9.105342) (xy 311.202456 9.187818) (xy 311.233432 9.267777)
			(xy 311.271654 9.344537) (xy 311.316795 9.417443) (xy 311.368471 9.485872) (xy 311.42624 9.549242)
			(xy 311.48961 9.607011) (xy 311.558039 9.658687) (xy 311.630945 9.703828) (xy 311.707705 9.74205)
			(xy 311.787664 9.773026) (xy 311.87014 9.796493) (xy 311.95443 9.812249) (xy 312.039813 9.820161)
			(xy 312.125563 9.820161) (xy 312.210946 9.812249) (xy 312.295236 9.796493) (xy 312.377712 9.773026)
			(xy 312.457671 9.74205) (xy 312.534431 9.703828) (xy 312.607337 9.658687) (xy 312.675766 9.607011)
			(xy 312.739136 9.549242) (xy 312.796905 9.485872) (xy 312.848581 9.417443) (xy 312.893722 9.344537)
			(xy 312.931944 9.267777) (xy 312.96292 9.187818) (xy 312.986387 9.105342) (xy 313.002143 9.021052)
			(xy 313.010055 8.935669) (xy 313.01055 8.892794) (xy 313.010055 8.849919) (xy 317.505321 8.849919)
			(xy 317.505321 8.935669) (xy 317.513233 9.021052) (xy 317.528989 9.105342) (xy 317.552456 9.187818)
			(xy 317.583432 9.267777) (xy 317.621654 9.344537) (xy 317.666795 9.417443) (xy 317.718471 9.485872)
			(xy 317.77624 9.549242) (xy 317.83961 9.607011) (xy 317.908039 9.658687) (xy 317.980945 9.703828)
			(xy 318.057705 9.74205) (xy 318.137664 9.773026) (xy 318.22014 9.796493) (xy 318.30443 9.812249)
			(xy 318.389813 9.820161) (xy 318.475563 9.820161) (xy 318.560946 9.812249) (xy 318.645236 9.796493)
			(xy 318.727712 9.773026) (xy 318.807671 9.74205) (xy 318.884431 9.703828) (xy 318.957337 9.658687)
			(xy 319.025766 9.607011) (xy 319.089136 9.549242) (xy 319.146905 9.485872) (xy 319.198581 9.417443)
			(xy 319.243722 9.344537) (xy 319.281944 9.267777) (xy 319.31292 9.187818) (xy 319.336387 9.105342)
			(xy 319.352143 9.021052) (xy 319.360055 8.935669) (xy 319.36055 8.892794) (xy 319.360055 8.849919)
			(xy 361.894107 8.849919) (xy 361.894107 8.935669) (xy 361.902019 9.021052) (xy 361.917775 9.105342)
			(xy 361.941242 9.187818) (xy 361.972218 9.267777) (xy 362.01044 9.344537) (xy 362.055581 9.417443)
			(xy 362.107257 9.485872) (xy 362.165026 9.549242) (xy 362.228396 9.607011) (xy 362.296825 9.658687)
			(xy 362.369731 9.703828) (xy 362.446491 9.74205) (xy 362.52645 9.773026) (xy 362.608926 9.796493)
			(xy 362.693216 9.812249) (xy 362.778599 9.820161) (xy 362.864349 9.820161) (xy 362.949732 9.812249)
			(xy 363.034022 9.796493) (xy 363.116498 9.773026) (xy 363.196457 9.74205) (xy 363.273217 9.703828)
			(xy 363.346123 9.658687) (xy 363.414552 9.607011) (xy 363.477922 9.549242) (xy 363.535691 9.485872)
			(xy 363.587367 9.417443) (xy 363.632508 9.344537) (xy 363.67073 9.267777) (xy 363.701706 9.187818)
			(xy 363.725173 9.105342) (xy 363.740929 9.021052) (xy 363.748841 8.935669) (xy 363.749336 8.892794)
			(xy 363.748841 8.849919) (xy 368.244107 8.849919) (xy 368.244107 8.935669) (xy 368.252019 9.021052)
			(xy 368.267775 9.105342) (xy 368.291242 9.187818) (xy 368.322218 9.267777) (xy 368.36044 9.344537)
			(xy 368.405581 9.417443) (xy 368.457257 9.485872) (xy 368.515026 9.549242) (xy 368.578396 9.607011)
			(xy 368.646825 9.658687) (xy 368.719731 9.703828) (xy 368.796491 9.74205) (xy 368.87645 9.773026)
			(xy 368.958926 9.796493) (xy 369.043216 9.812249) (xy 369.128599 9.820161) (xy 369.214349 9.820161)
			(xy 369.299732 9.812249) (xy 369.384022 9.796493) (xy 369.466498 9.773026) (xy 369.546457 9.74205)
			(xy 369.623217 9.703828) (xy 369.696123 9.658687) (xy 369.764552 9.607011) (xy 369.827922 9.549242)
			(xy 369.885691 9.485872) (xy 369.937367 9.417443) (xy 369.982508 9.344537) (xy 370.02073 9.267777)
			(xy 370.051706 9.187818) (xy 370.075173 9.105342) (xy 370.090929 9.021052) (xy 370.098841 8.935669)
			(xy 370.099336 8.892794) (xy 370.098841 8.849919) (xy 370.090929 8.764536) (xy 370.075173 8.680246)
			(xy 370.051706 8.59777) (xy 370.02073 8.517811) (xy 369.982508 8.441051) (xy 369.937367 8.368145)
			(xy 369.885691 8.299716) (xy 369.827922 8.236346) (xy 369.764552 8.178577) (xy 369.696123 8.126901)
			(xy 369.623217 8.08176) (xy 369.546457 8.043538) (xy 369.466498 8.012562) (xy 369.384022 7.989095)
			(xy 369.299732 7.973339) (xy 369.214349 7.965427) (xy 369.128599 7.965427) (xy 369.043216 7.973339)
			(xy 368.958926 7.989095) (xy 368.87645 8.012562) (xy 368.796491 8.043538) (xy 368.719731 8.08176)
			(xy 368.646825 8.126901) (xy 368.578396 8.178577) (xy 368.515026 8.236346) (xy 368.457257 8.299716)
			(xy 368.405581 8.368145) (xy 368.36044 8.441051) (xy 368.322218 8.517811) (xy 368.291242 8.59777)
			(xy 368.267775 8.680246) (xy 368.252019 8.764536) (xy 368.244107 8.849919) (xy 363.748841 8.849919)
			(xy 363.740929 8.764536) (xy 363.725173 8.680246) (xy 363.701706 8.59777) (xy 363.67073 8.517811)
			(xy 363.632508 8.441051) (xy 363.587367 8.368145) (xy 363.535691 8.299716) (xy 363.477922 8.236346)
			(xy 363.414552 8.178577) (xy 363.346123 8.126901) (xy 363.273217 8.08176) (xy 363.196457 8.043538)
			(xy 363.116498 8.012562) (xy 363.034022 7.989095) (xy 362.949732 7.973339) (xy 362.864349 7.965427)
			(xy 362.778599 7.965427) (xy 362.693216 7.973339) (xy 362.608926 7.989095) (xy 362.52645 8.012562)
			(xy 362.446491 8.043538) (xy 362.369731 8.08176) (xy 362.296825 8.126901) (xy 362.228396 8.178577)
			(xy 362.165026 8.236346) (xy 362.107257 8.299716) (xy 362.055581 8.368145) (xy 362.01044 8.441051)
			(xy 361.972218 8.517811) (xy 361.941242 8.59777) (xy 361.917775 8.680246) (xy 361.902019 8.764536)
			(xy 361.894107 8.849919) (xy 319.360055 8.849919) (xy 319.352143 8.764536) (xy 319.336387 8.680246)
			(xy 319.31292 8.59777) (xy 319.281944 8.517811) (xy 319.243722 8.441051) (xy 319.198581 8.368145)
			(xy 319.146905 8.299716) (xy 319.089136 8.236346) (xy 319.025766 8.178577) (xy 318.957337 8.126901)
			(xy 318.884431 8.08176) (xy 318.807671 8.043538) (xy 318.727712 8.012562) (xy 318.645236 7.989095)
			(xy 318.560946 7.973339) (xy 318.475563 7.965427) (xy 318.389813 7.965427) (xy 318.30443 7.973339)
			(xy 318.22014 7.989095) (xy 318.137664 8.012562) (xy 318.057705 8.043538) (xy 317.980945 8.08176)
			(xy 317.908039 8.126901) (xy 317.83961 8.178577) (xy 317.77624 8.236346) (xy 317.718471 8.299716)
			(xy 317.666795 8.368145) (xy 317.621654 8.441051) (xy 317.583432 8.517811) (xy 317.552456 8.59777)
			(xy 317.528989 8.680246) (xy 317.513233 8.764536) (xy 317.505321 8.849919) (xy 313.010055 8.849919)
			(xy 313.002143 8.764536) (xy 312.986387 8.680246) (xy 312.96292 8.59777) (xy 312.931944 8.517811)
			(xy 312.893722 8.441051) (xy 312.848581 8.368145) (xy 312.796905 8.299716) (xy 312.739136 8.236346)
			(xy 312.675766 8.178577) (xy 312.607337 8.126901) (xy 312.534431 8.08176) (xy 312.457671 8.043538)
			(xy 312.377712 8.012562) (xy 312.295236 7.989095) (xy 312.210946 7.973339) (xy 312.125563 7.965427)
			(xy 312.039813 7.965427) (xy 311.95443 7.973339) (xy 311.87014 7.989095) (xy 311.787664 8.012562)
			(xy 311.707705 8.043538) (xy 311.630945 8.08176) (xy 311.558039 8.126901) (xy 311.48961 8.178577)
			(xy 311.42624 8.236346) (xy 311.368471 8.299716) (xy 311.316795 8.368145) (xy 311.271654 8.441051)
			(xy 311.233432 8.517811) (xy 311.202456 8.59777) (xy 311.178989 8.680246) (xy 311.163233 8.764536)
			(xy 311.155321 8.849919) (xy 304.348655 8.849919) (xy 304.340743 8.764536) (xy 304.324987 8.680246)
			(xy 304.30152 8.59777) (xy 304.270544 8.517811) (xy 304.232322 8.441051) (xy 304.187181 8.368145)
			(xy 304.135505 8.299716) (xy 304.077736 8.236346) (xy 304.014366 8.178577) (xy 303.945937 8.126901)
			(xy 303.873031 8.08176) (xy 303.796271 8.043538) (xy 303.716312 8.012562) (xy 303.633836 7.989095)
			(xy 303.549546 7.973339) (xy 303.464163 7.965427) (xy 303.378413 7.965427) (xy 303.29303 7.973339)
			(xy 303.20874 7.989095) (xy 303.126264 8.012562) (xy 303.046305 8.043538) (xy 302.969545 8.08176)
			(xy 302.896639 8.126901) (xy 302.82821 8.178577) (xy 302.76484 8.236346) (xy 302.707071 8.299716)
			(xy 302.655395 8.368145) (xy 302.610254 8.441051) (xy 302.572032 8.517811) (xy 302.541056 8.59777)
			(xy 302.517589 8.680246) (xy 302.501833 8.764536) (xy 302.493921 8.849919) (xy 297.998655 8.849919)
			(xy 297.990743 8.764536) (xy 297.974987 8.680246) (xy 297.95152 8.59777) (xy 297.920544 8.517811)
			(xy 297.882322 8.441051) (xy 297.837181 8.368145) (xy 297.785505 8.299716) (xy 297.727736 8.236346)
			(xy 297.664366 8.178577) (xy 297.595937 8.126901) (xy 297.523031 8.08176) (xy 297.446271 8.043538)
			(xy 297.366312 8.012562) (xy 297.283836 7.989095) (xy 297.199546 7.973339) (xy 297.114163 7.965427)
			(xy 297.028413 7.965427) (xy 296.94303 7.973339) (xy 296.85874 7.989095) (xy 296.776264 8.012562)
			(xy 296.696305 8.043538) (xy 296.619545 8.08176) (xy 296.546639 8.126901) (xy 296.47821 8.178577)
			(xy 296.41484 8.236346) (xy 296.357071 8.299716) (xy 296.305395 8.368145) (xy 296.260254 8.441051)
			(xy 296.222032 8.517811) (xy 296.191056 8.59777) (xy 296.167589 8.680246) (xy 296.151833 8.764536)
			(xy 296.143921 8.849919) (xy 216.865975 8.849919) (xy 216.858063 8.764536) (xy 216.842307 8.680246)
			(xy 216.81884 8.59777) (xy 216.787864 8.517811) (xy 216.749642 8.441051) (xy 216.704501 8.368145)
			(xy 216.652825 8.299716) (xy 216.595056 8.236346) (xy 216.531686 8.178577) (xy 216.463257 8.126901)
			(xy 216.390351 8.08176) (xy 216.313591 8.043538) (xy 216.233632 8.012562) (xy 216.151156 7.989095)
			(xy 216.066866 7.973339) (xy 215.981483 7.965427) (xy 215.895733 7.965427) (xy 215.81035 7.973339)
			(xy 215.72606 7.989095) (xy 215.643584 8.012562) (xy 215.563625 8.043538) (xy 215.486865 8.08176)
			(xy 215.413959 8.126901) (xy 215.34553 8.178577) (xy 215.28216 8.236346) (xy 215.224391 8.299716)
			(xy 215.172715 8.368145) (xy 215.127574 8.441051) (xy 215.089352 8.517811) (xy 215.058376 8.59777)
			(xy 215.034909 8.680246) (xy 215.019153 8.764536) (xy 215.011241 8.849919) (xy 210.515975 8.849919)
			(xy 210.508063 8.764536) (xy 210.492307 8.680246) (xy 210.46884 8.59777) (xy 210.437864 8.517811)
			(xy 210.399642 8.441051) (xy 210.354501 8.368145) (xy 210.302825 8.299716) (xy 210.245056 8.236346)
			(xy 210.181686 8.178577) (xy 210.113257 8.126901) (xy 210.040351 8.08176) (xy 209.963591 8.043538)
			(xy 209.883632 8.012562) (xy 209.801156 7.989095) (xy 209.716866 7.973339) (xy 209.631483 7.965427)
			(xy 209.545733 7.965427) (xy 209.46035 7.973339) (xy 209.37606 7.989095) (xy 209.293584 8.012562)
			(xy 209.213625 8.043538) (xy 209.136865 8.08176) (xy 209.063959 8.126901) (xy 208.99553 8.178577)
			(xy 208.93216 8.236346) (xy 208.874391 8.299716) (xy 208.822715 8.368145) (xy 208.777574 8.441051)
			(xy 208.739352 8.517811) (xy 208.708376 8.59777) (xy 208.684909 8.680246) (xy 208.669153 8.764536)
			(xy 208.661241 8.849919) (xy 6.51416 8.849919) (xy 6.592279 8.764226) (xy 6.67324 8.663616) (xy 6.747854 8.558213)
			(xy 6.815837 8.448416) (xy 6.876932 8.334642) (xy 6.930907 8.217323) (xy 6.977558 8.096904) (xy 7.016707 7.973841)
			(xy 7.048206 7.848602) (xy 7.071935 7.721661) (xy 7.087805 7.593501) (xy 7.095755 7.464606) (xy 7.096252 7.400036)
			(xy 7.095755 7.335466) (xy 7.092973 7.290359) (xy 93.985575 7.290359) (xy 93.985575 7.376109) (xy 93.993487 7.461492)
			(xy 94.009243 7.545782) (xy 94.03271 7.628258) (xy 94.063686 7.708217) (xy 94.101908 7.784977) (xy 94.147049 7.857883)
			(xy 94.198725 7.926312) (xy 94.256494 7.989682) (xy 94.319864 8.047451) (xy 94.388293 8.099127) (xy 94.461199 8.144268)
			(xy 94.537959 8.18249) (xy 94.617918 8.213466) (xy 94.700394 8.236933) (xy 94.784684 8.252689) (xy 94.870067 8.260601)
			(xy 94.955817 8.260601) (xy 95.0412 8.252689) (xy 95.12549 8.236933) (xy 95.207966 8.213466) (xy 95.287925 8.18249)
			(xy 95.364685 8.144268) (xy 95.437591 8.099127) (xy 95.50602 8.047451) (xy 95.56939 7.989682) (xy 95.627159 7.926312)
			(xy 95.678835 7.857883) (xy 95.723976 7.784977) (xy 95.762198 7.708217) (xy 95.793174 7.628258) (xy 95.816641 7.545782)
			(xy 95.832397 7.461492) (xy 95.840309 7.376109) (xy 95.840804 7.333234) (xy 95.840309 7.290359) (xy 100.335575 7.290359)
			(xy 100.335575 7.376109) (xy 100.343487 7.461492) (xy 100.359243 7.545782) (xy 100.38271 7.628258)
			(xy 100.413686 7.708217) (xy 100.451908 7.784977) (xy 100.497049 7.857883) (xy 100.548725 7.926312)
			(xy 100.606494 7.989682) (xy 100.669864 8.047451) (xy 100.738293 8.099127) (xy 100.811199 8.144268)
			(xy 100.887959 8.18249) (xy 100.967918 8.213466) (xy 101.050394 8.236933) (xy 101.134684 8.252689)
			(xy 101.220067 8.260601) (xy 101.305817 8.260601) (xy 101.3912 8.252689) (xy 101.47549 8.236933)
			(xy 101.557966 8.213466) (xy 101.637925 8.18249) (xy 101.714685 8.144268) (xy 101.787591 8.099127)
			(xy 101.85602 8.047451) (xy 101.91939 7.989682) (xy 101.977159 7.926312) (xy 102.028835 7.857883)
			(xy 102.073976 7.784977) (xy 102.112198 7.708217) (xy 102.143174 7.628258) (xy 102.166641 7.545782)
			(xy 102.182397 7.461492) (xy 102.190309 7.376109) (xy 102.190804 7.333234) (xy 102.190309 7.290359)
			(xy 181.468255 7.290359) (xy 181.468255 7.376109) (xy 181.476167 7.461492) (xy 181.491923 7.545782)
			(xy 181.51539 7.628258) (xy 181.546366 7.708217) (xy 181.584588 7.784977) (xy 181.629729 7.857883)
			(xy 181.681405 7.926312) (xy 181.739174 7.989682) (xy 181.802544 8.047451) (xy 181.870973 8.099127)
			(xy 181.943879 8.144268) (xy 182.020639 8.18249) (xy 182.100598 8.213466) (xy 182.183074 8.236933)
			(xy 182.267364 8.252689) (xy 182.352747 8.260601) (xy 182.438497 8.260601) (xy 182.52388 8.252689)
			(xy 182.60817 8.236933) (xy 182.690646 8.213466) (xy 182.770605 8.18249) (xy 182.847365 8.144268)
			(xy 182.920271 8.099127) (xy 182.9887 8.047451) (xy 183.05207 7.989682) (xy 183.109839 7.926312)
			(xy 183.161515 7.857883) (xy 183.206656 7.784977) (xy 183.244878 7.708217) (xy 183.275854 7.628258)
			(xy 183.299321 7.545782) (xy 183.315077 7.461492) (xy 183.322989 7.376109) (xy 183.323484 7.333234)
			(xy 183.322989 7.290359) (xy 187.818255 7.290359) (xy 187.818255 7.376109) (xy 187.826167 7.461492)
			(xy 187.841923 7.545782) (xy 187.86539 7.628258) (xy 187.896366 7.708217) (xy 187.934588 7.784977)
			(xy 187.979729 7.857883) (xy 188.031405 7.926312) (xy 188.089174 7.989682) (xy 188.152544 8.047451)
			(xy 188.220973 8.099127) (xy 188.293879 8.144268) (xy 188.370639 8.18249) (xy 188.450598 8.213466)
			(xy 188.533074 8.236933) (xy 188.617364 8.252689) (xy 188.702747 8.260601) (xy 188.788497 8.260601)
			(xy 188.87388 8.252689) (xy 188.95817 8.236933) (xy 189.040646 8.213466) (xy 189.120605 8.18249)
			(xy 189.197365 8.144268) (xy 189.270271 8.099127) (xy 189.3387 8.047451) (xy 189.40207 7.989682)
			(xy 189.459839 7.926312) (xy 189.511515 7.857883) (xy 189.556656 7.784977) (xy 189.594878 7.708217)
			(xy 189.625854 7.628258) (xy 189.649321 7.545782) (xy 189.665077 7.461492) (xy 189.672989 7.376109)
			(xy 189.673484 7.333234) (xy 189.672989 7.290359) (xy 189.665077 7.204976) (xy 189.649321 7.120686)
			(xy 189.625854 7.03821) (xy 189.594878 6.958251) (xy 189.556656 6.881491) (xy 189.511515 6.808585)
			(xy 189.459839 6.740156) (xy 189.40207 6.676786) (xy 189.3387 6.619017) (xy 189.270271 6.567341)
			(xy 189.197365 6.5222) (xy 189.120605 6.483978) (xy 189.040646 6.453002) (xy 188.95817 6.429535)
			(xy 188.87388 6.413779) (xy 188.788497 6.405867) (xy 188.702747 6.405867) (xy 188.617364 6.413779)
			(xy 188.533074 6.429535) (xy 188.450598 6.453002) (xy 188.370639 6.483978) (xy 188.293879 6.5222)
			(xy 188.220973 6.567341) (xy 188.152544 6.619017) (xy 188.089174 6.676786) (xy 188.031405 6.740156)
			(xy 187.979729 6.808585) (xy 187.934588 6.881491) (xy 187.896366 6.958251) (xy 187.86539 7.03821)
			(xy 187.841923 7.120686) (xy 187.826167 7.204976) (xy 187.818255 7.290359) (xy 183.322989 7.290359)
			(xy 183.315077 7.204976) (xy 183.299321 7.120686) (xy 183.275854 7.03821) (xy 183.244878 6.958251)
			(xy 183.206656 6.881491) (xy 183.161515 6.808585) (xy 183.109839 6.740156) (xy 183.05207 6.676786)
			(xy 182.9887 6.619017) (xy 182.920271 6.567341) (xy 182.847365 6.5222) (xy 182.770605 6.483978) (xy 182.690646 6.453002)
			(xy 182.60817 6.429535) (xy 182.52388 6.413779) (xy 182.438497 6.405867) (xy 182.352747 6.405867)
			(xy 182.267364 6.413779) (xy 182.183074 6.429535) (xy 182.100598 6.453002) (xy 182.020639 6.483978)
			(xy 181.943879 6.5222) (xy 181.870973 6.567341) (xy 181.802544 6.619017) (xy 181.739174 6.676786)
			(xy 181.681405 6.740156) (xy 181.629729 6.808585) (xy 181.584588 6.881491) (xy 181.546366 6.958251)
			(xy 181.51539 7.03821) (xy 181.491923 7.120686) (xy 181.476167 7.204976) (xy 181.468255 7.290359)
			(xy 102.190309 7.290359) (xy 102.182397 7.204976) (xy 102.166641 7.120686) (xy 102.143174 7.03821)
			(xy 102.112198 6.958251) (xy 102.073976 6.881491) (xy 102.028835 6.808585) (xy 101.977159 6.740156)
			(xy 101.91939 6.676786) (xy 101.85602 6.619017) (xy 101.787591 6.567341) (xy 101.714685 6.5222) (xy 101.637925 6.483978)
			(xy 101.557966 6.453002) (xy 101.47549 6.429535) (xy 101.3912 6.413779) (xy 101.305817 6.405867)
			(xy 101.220067 6.405867) (xy 101.134684 6.413779) (xy 101.050394 6.429535) (xy 100.967918 6.453002)
			(xy 100.887959 6.483978) (xy 100.811199 6.5222) (xy 100.738293 6.567341) (xy 100.669864 6.619017)
			(xy 100.606494 6.676786) (xy 100.548725 6.740156) (xy 100.497049 6.808585) (xy 100.451908 6.881491)
			(xy 100.413686 6.958251) (xy 100.38271 7.03821) (xy 100.359243 7.120686) (xy 100.343487 7.204976)
			(xy 100.335575 7.290359) (xy 95.840309 7.290359) (xy 95.832397 7.204976) (xy 95.816641 7.120686)
			(xy 95.793174 7.03821) (xy 95.762198 6.958251) (xy 95.723976 6.881491) (xy 95.678835 6.808585) (xy 95.627159 6.740156)
			(xy 95.56939 6.676786) (xy 95.50602 6.619017) (xy 95.437591 6.567341) (xy 95.364685 6.5222) (xy 95.287925 6.483978)
			(xy 95.207966 6.453002) (xy 95.12549 6.429535) (xy 95.0412 6.413779) (xy 94.955817 6.405867) (xy 94.870067 6.405867)
			(xy 94.784684 6.413779) (xy 94.700394 6.429535) (xy 94.617918 6.453002) (xy 94.537959 6.483978) (xy 94.461199 6.5222)
			(xy 94.388293 6.567341) (xy 94.319864 6.619017) (xy 94.256494 6.676786) (xy 94.198725 6.740156) (xy 94.147049 6.808585)
			(xy 94.101908 6.881491) (xy 94.063686 6.958251) (xy 94.03271 7.03821) (xy 94.009243 7.120686) (xy 93.993487 7.204976)
			(xy 93.985575 7.290359) (xy 7.092973 7.290359) (xy 7.087805 7.206571) (xy 7.071935 7.078411) (xy 7.048206 6.95147)
			(xy 7.016707 6.826231) (xy 6.977558 6.703168) (xy 6.930907 6.582749) (xy 6.876932 6.46543) (xy 6.815837 6.351656)
			(xy 6.747854 6.241859) (xy 6.67324 6.136456) (xy 6.592279 6.035846) (xy 6.505279 5.940411) (xy 6.412568 5.850512)
			(xy 6.314498 5.766491) (xy 6.211443 5.688667) (xy 6.103792 5.617335) (xy 5.991953 5.552765) (xy 5.876352 5.495203)
			(xy 5.757427 5.444866) (xy 5.635628 5.401946) (xy 5.511418 5.366605) (xy 5.385269 5.338978) (xy 5.257657 5.319169)
			(xy 5.129068 5.307253) (xy 4.99999 5.303277) (xy 4.870912 5.307253) (xy 4.742323 5.319169) (xy 4.614711 5.338978)
			(xy 4.488562 5.366605) (xy 4.364352 5.401946) (xy 4.242553 5.444866) (xy 4.123628 5.495203) (xy 4.008027 5.552765)
			(xy 3.896188 5.617335) (xy 3.788537 5.688667) (xy 3.685482 5.766491) (xy 3.587412 5.850512) (xy 3.494701 5.940411)
			(xy 3.407701 6.035846) (xy 3.32674 6.136456) (xy 3.252126 6.241859) (xy 3.184143 6.351656) (xy 3.123048 6.46543)
			(xy 3.069073 6.582749) (xy 3.022422 6.703168) (xy 2.983273 6.826231) (xy 2.951774 6.95147) (xy 2.928045 7.078411)
			(xy 2.912175 7.206571) (xy 2.904225 7.335466) (xy 0.509016 7.335466) (xy 0.509016 4.750359) (xy 93.985575 4.750359)
			(xy 93.985575 4.836109) (xy 93.993487 4.921492) (xy 94.009243 5.005782) (xy 94.03271 5.088258) (xy 94.063686 5.168217)
			(xy 94.101908 5.244977) (xy 94.147049 5.317883) (xy 94.198725 5.386312) (xy 94.256494 5.449682) (xy 94.319864 5.507451)
			(xy 94.388293 5.559127) (xy 94.461199 5.604268) (xy 94.537959 5.64249) (xy 94.617918 5.673466) (xy 94.700394 5.696933)
			(xy 94.784684 5.712689) (xy 94.870067 5.720601) (xy 94.955817 5.720601) (xy 95.0412 5.712689) (xy 95.12549 5.696933)
			(xy 95.207966 5.673466) (xy 95.287925 5.64249) (xy 95.308598 5.632196) (xy 98.842576 5.632196) (xy 98.842576 6.495796)
			(xy 98.84308 6.525332) (xy 98.851124 6.583854) (xy 98.867061 6.640736) (xy 98.890596 6.694918) (xy 98.921289 6.745391)
			(xy 98.958569 6.791214) (xy 99.001741 6.831534) (xy 99.050001 6.8656) (xy 99.102451 6.892777) (xy 99.158112 6.912559)
			(xy 99.215949 6.924578) (xy 99.274884 6.928609) (xy 99.333819 6.924578) (xy 99.391656 6.912559) (xy 99.447317 6.892777)
			(xy 99.499767 6.8656) (xy 99.548027 6.831534) (xy 99.591199 6.791214) (xy 99.628479 6.745391) (xy 99.659172 6.694918)
			(xy 99.682707 6.640736) (xy 99.698644 6.583854) (xy 99.706688 6.525332) (xy 99.707192 6.495796) (xy 99.707192 5.632196)
			(xy 99.706688 5.60266) (xy 99.698644 5.544138) (xy 99.682707 5.487256) (xy 99.659172 5.433074) (xy 99.628479 5.382601)
			(xy 99.591199 5.336778) (xy 99.548027 5.296458) (xy 99.499767 5.262392) (xy 99.447317 5.235215) (xy 99.391656 5.215433)
			(xy 99.333819 5.203414) (xy 99.274884 5.199383) (xy 99.215949 5.203414) (xy 99.158112 5.215433) (xy 99.102451 5.235215)
			(xy 99.050001 5.262392) (xy 99.001741 5.296458) (xy 98.958569 5.336778) (xy 98.921289 5.382601) (xy 98.890596 5.433074)
			(xy 98.867061 5.487256) (xy 98.851124 5.544138) (xy 98.84308 5.60266) (xy 98.842576 5.632196) (xy 95.308598 5.632196)
			(xy 95.364685 5.604268) (xy 95.437591 5.559127) (xy 95.50602 5.507451) (xy 95.56939 5.449682) (xy 95.627159 5.386312)
			(xy 95.678835 5.317883) (xy 95.723976 5.244977) (xy 95.762198 5.168217) (xy 95.793174 5.088258) (xy 95.816641 5.005782)
			(xy 95.832397 4.921492) (xy 95.840309 4.836109) (xy 95.840804 4.793234) (xy 95.840309 4.750359) (xy 100.335575 4.750359)
			(xy 100.335575 4.836109) (xy 100.343487 4.921492) (xy 100.359243 5.005782) (xy 100.38271 5.088258)
			(xy 100.413686 5.168217) (xy 100.451908 5.244977) (xy 100.497049 5.317883) (xy 100.548725 5.386312)
			(xy 100.606494 5.449682) (xy 100.669864 5.507451) (xy 100.738293 5.559127) (xy 100.811199 5.604268)
			(xy 100.887959 5.64249) (xy 100.967918 5.673466) (xy 101.050394 5.696933) (xy 101.134684 5.712689)
			(xy 101.220067 5.720601) (xy 101.305817 5.720601) (xy 101.3912 5.712689) (xy 101.47549 5.696933)
			(xy 101.557966 5.673466) (xy 101.637925 5.64249) (xy 101.714685 5.604268) (xy 101.787591 5.559127)
			(xy 101.85602 5.507451) (xy 101.91939 5.449682) (xy 101.977159 5.386312) (xy 102.028835 5.317883)
			(xy 102.073976 5.244977) (xy 102.112198 5.168217) (xy 102.143174 5.088258) (xy 102.166641 5.005782)
			(xy 102.182397 4.921492) (xy 102.190309 4.836109) (xy 102.190804 4.793234) (xy 102.190309 4.750359)
			(xy 181.468255 4.750359) (xy 181.468255 4.836109) (xy 181.476167 4.921492) (xy 181.491923 5.005782)
			(xy 181.51539 5.088258) (xy 181.546366 5.168217) (xy 181.584588 5.244977) (xy 181.629729 5.317883)
			(xy 181.681405 5.386312) (xy 181.739174 5.449682) (xy 181.802544 5.507451) (xy 181.870973 5.559127)
			(xy 181.943879 5.604268) (xy 182.020639 5.64249) (xy 182.100598 5.673466) (xy 182.183074 5.696933)
			(xy 182.267364 5.712689) (xy 182.352747 5.720601) (xy 182.438497 5.720601) (xy 182.52388 5.712689)
			(xy 182.60817 5.696933) (xy 182.690646 5.673466) (xy 182.770605 5.64249) (xy 182.791278 5.632196)
			(xy 183.953912 5.632196) (xy 183.953912 6.495796) (xy 183.954416 6.525332) (xy 183.96246 6.583854)
			(xy 183.978397 6.640736) (xy 184.001932 6.694918) (xy 184.032625 6.745391) (xy 184.069905 6.791214)
			(xy 184.113077 6.831534) (xy 184.161337 6.8656) (xy 184.213787 6.892777) (xy 184.269448 6.912559)
			(xy 184.327285 6.924578) (xy 184.38622 6.928609) (xy 184.445155 6.924578) (xy 184.502992 6.912559)
			(xy 184.558653 6.892777) (xy 184.611103 6.8656) (xy 184.659363 6.831534) (xy 184.702535 6.791214)
			(xy 184.739815 6.745391) (xy 184.770508 6.694918) (xy 184.794043 6.640736) (xy 184.80998 6.583854)
			(xy 184.818024 6.525332) (xy 184.818528 6.495796) (xy 184.818528 6.309919) (xy 208.661241 6.309919)
			(xy 208.661241 6.395669) (xy 208.669153 6.481052) (xy 208.684909 6.565342) (xy 208.708376 6.647818)
			(xy 208.739352 6.727777) (xy 208.777574 6.804537) (xy 208.822715 6.877443) (xy 208.874391 6.945872)
			(xy 208.93216 7.009242) (xy 208.99553 7.067011) (xy 209.063959 7.118687) (xy 209.136865 7.163828)
			(xy 209.213625 7.20205) (xy 209.293584 7.233026) (xy 209.37606 7.256493) (xy 209.46035 7.272249)
			(xy 209.545733 7.280161) (xy 209.631483 7.280161) (xy 209.716866 7.272249) (xy 209.801156 7.256493)
			(xy 209.883632 7.233026) (xy 209.963591 7.20205) (xy 210.040351 7.163828) (xy 210.113257 7.118687)
			(xy 210.181686 7.067011) (xy 210.245056 7.009242) (xy 210.302825 6.945872) (xy 210.354501 6.877443)
			(xy 210.399642 6.804537) (xy 210.437864 6.727777) (xy 210.46884 6.647818) (xy 210.492307 6.565342)
			(xy 210.508063 6.481052) (xy 210.515975 6.395669) (xy 210.51647 6.352794) (xy 210.515975 6.309919)
			(xy 215.011241 6.309919) (xy 215.011241 6.395669) (xy 215.019153 6.481052) (xy 215.034909 6.565342)
			(xy 215.058376 6.647818) (xy 215.089352 6.727777) (xy 215.127574 6.804537) (xy 215.172715 6.877443)
			(xy 215.224391 6.945872) (xy 215.28216 7.009242) (xy 215.34553 7.067011) (xy 215.413959 7.118687)
			(xy 215.486865 7.163828) (xy 215.563625 7.20205) (xy 215.643584 7.233026) (xy 215.72606 7.256493)
			(xy 215.81035 7.272249) (xy 215.895733 7.280161) (xy 215.981483 7.280161) (xy 216.066866 7.272249)
			(xy 216.151156 7.256493) (xy 216.233632 7.233026) (xy 216.313591 7.20205) (xy 216.390351 7.163828)
			(xy 216.463257 7.118687) (xy 216.531686 7.067011) (xy 216.595056 7.009242) (xy 216.652825 6.945872)
			(xy 216.704501 6.877443) (xy 216.749642 6.804537) (xy 216.787864 6.727777) (xy 216.81884 6.647818)
			(xy 216.842307 6.565342) (xy 216.858063 6.481052) (xy 216.865975 6.395669) (xy 216.86647 6.352794)
			(xy 216.865975 6.309919) (xy 296.143921 6.309919) (xy 296.143921 6.395669) (xy 296.151833 6.481052)
			(xy 296.167589 6.565342) (xy 296.191056 6.647818) (xy 296.222032 6.727777) (xy 296.260254 6.804537)
			(xy 296.305395 6.877443) (xy 296.357071 6.945872) (xy 296.41484 7.009242) (xy 296.47821 7.067011)
			(xy 296.546639 7.118687) (xy 296.619545 7.163828) (xy 296.696305 7.20205) (xy 296.776264 7.233026)
			(xy 296.85874 7.256493) (xy 296.94303 7.272249) (xy 297.028413 7.280161) (xy 297.114163 7.280161)
			(xy 297.199546 7.272249) (xy 297.283836 7.256493) (xy 297.366312 7.233026) (xy 297.446271 7.20205)
			(xy 297.523031 7.163828) (xy 297.595937 7.118687) (xy 297.664366 7.067011) (xy 297.727736 7.009242)
			(xy 297.785505 6.945872) (xy 297.837181 6.877443) (xy 297.882322 6.804537) (xy 297.920544 6.727777)
			(xy 297.95152 6.647818) (xy 297.974987 6.565342) (xy 297.990743 6.481052) (xy 297.998655 6.395669)
			(xy 297.99915 6.352794) (xy 297.998655 6.309919) (xy 302.493921 6.309919) (xy 302.493921 6.395669)
			(xy 302.501833 6.481052) (xy 302.517589 6.565342) (xy 302.541056 6.647818) (xy 302.572032 6.727777)
			(xy 302.610254 6.804537) (xy 302.655395 6.877443) (xy 302.707071 6.945872) (xy 302.76484 7.009242)
			(xy 302.82821 7.067011) (xy 302.896639 7.118687) (xy 302.969545 7.163828) (xy 303.046305 7.20205)
			(xy 303.126264 7.233026) (xy 303.20874 7.256493) (xy 303.29303 7.272249) (xy 303.378413 7.280161)
			(xy 303.464163 7.280161) (xy 303.549546 7.272249) (xy 303.633836 7.256493) (xy 303.716312 7.233026)
			(xy 303.796271 7.20205) (xy 303.873031 7.163828) (xy 303.945937 7.118687) (xy 304.014366 7.067011)
			(xy 304.077736 7.009242) (xy 304.135505 6.945872) (xy 304.187181 6.877443) (xy 304.232322 6.804537)
			(xy 304.270544 6.727777) (xy 304.30152 6.647818) (xy 304.324987 6.565342) (xy 304.340743 6.481052)
			(xy 304.348655 6.395669) (xy 304.34915 6.352794) (xy 304.348655 6.309919) (xy 311.155321 6.309919)
			(xy 311.155321 6.395669) (xy 311.163233 6.481052) (xy 311.178989 6.565342) (xy 311.202456 6.647818)
			(xy 311.233432 6.727777) (xy 311.271654 6.804537) (xy 311.316795 6.877443) (xy 311.368471 6.945872)
			(xy 311.42624 7.009242) (xy 311.48961 7.067011) (xy 311.558039 7.118687) (xy 311.630945 7.163828)
			(xy 311.707705 7.20205) (xy 311.787664 7.233026) (xy 311.87014 7.256493) (xy 311.95443 7.272249)
			(xy 312.039813 7.280161) (xy 312.125563 7.280161) (xy 312.210946 7.272249) (xy 312.295236 7.256493)
			(xy 312.377712 7.233026) (xy 312.457671 7.20205) (xy 312.478344 7.191756) (xy 316.012068 7.191756)
			(xy 316.012068 8.055356) (xy 316.012572 8.08491) (xy 316.020621 8.143466) (xy 316.036567 8.200381)
			(xy 316.060116 8.254595) (xy 316.090827 8.305098) (xy 316.128129 8.350948) (xy 316.171326 8.391291)
			(xy 316.219615 8.425377) (xy 316.272095 8.45257) (xy 316.32779 8.472364) (xy 316.385661 8.48439)
			(xy 316.44463 8.488424) (xy 316.503599 8.48439) (xy 316.56147 8.472364) (xy 316.617165 8.45257) (xy 316.669645 8.425377)
			(xy 316.717934 8.391291) (xy 316.761131 8.350948) (xy 316.798433 8.305098) (xy 316.829144 8.254595)
			(xy 316.852693 8.200381) (xy 316.868639 8.143466) (xy 316.876688 8.08491) (xy 316.877192 8.055356)
			(xy 316.877192 7.191756) (xy 316.876688 7.162202) (xy 316.868639 7.103646) (xy 316.852693 7.046731)
			(xy 316.829144 6.992517) (xy 316.798433 6.942014) (xy 316.761131 6.896164) (xy 316.717934 6.855821)
			(xy 316.669645 6.821735) (xy 316.617165 6.794542) (xy 316.56147 6.774748) (xy 316.503599 6.762722)
			(xy 316.44463 6.758689) (xy 316.385661 6.762722) (xy 316.32779 6.774748) (xy 316.272095 6.794542)
			(xy 316.219615 6.821735) (xy 316.171326 6.855821) (xy 316.128129 6.896164) (xy 316.090827 6.942014)
			(xy 316.060116 6.992517) (xy 316.036567 7.046731) (xy 316.020621 7.103646) (xy 316.012572 7.162202)
			(xy 316.012068 7.191756) (xy 312.478344 7.191756) (xy 312.534431 7.163828) (xy 312.607337 7.118687)
			(xy 312.675766 7.067011) (xy 312.739136 7.009242) (xy 312.796905 6.945872) (xy 312.848581 6.877443)
			(xy 312.893722 6.804537) (xy 312.931944 6.727777) (xy 312.96292 6.647818) (xy 312.986387 6.565342)
			(xy 313.002143 6.481052) (xy 313.010055 6.395669) (xy 313.01055 6.352794) (xy 313.010055 6.309919)
			(xy 317.505321 6.309919) (xy 317.505321 6.395669) (xy 317.513233 6.481052) (xy 317.528989 6.565342)
			(xy 317.552456 6.647818) (xy 317.583432 6.727777) (xy 317.621654 6.804537) (xy 317.666795 6.877443)
			(xy 317.718471 6.945872) (xy 317.77624 7.009242) (xy 317.83961 7.067011) (xy 317.908039 7.118687)
			(xy 317.980945 7.163828) (xy 318.057705 7.20205) (xy 318.137664 7.233026) (xy 318.22014 7.256493)
			(xy 318.30443 7.272249) (xy 318.389813 7.280161) (xy 318.475563 7.280161) (xy 318.560946 7.272249)
			(xy 318.645236 7.256493) (xy 318.727712 7.233026) (xy 318.807671 7.20205) (xy 318.884431 7.163828)
			(xy 318.957337 7.118687) (xy 319.025766 7.067011) (xy 319.089136 7.009242) (xy 319.146905 6.945872)
			(xy 319.198581 6.877443) (xy 319.243722 6.804537) (xy 319.281944 6.727777) (xy 319.31292 6.647818)
			(xy 319.336387 6.565342) (xy 319.352143 6.481052) (xy 319.360055 6.395669) (xy 319.36055 6.352794)
			(xy 319.360055 6.309919) (xy 361.894107 6.309919) (xy 361.894107 6.395669) (xy 361.902019 6.481052)
			(xy 361.917775 6.565342) (xy 361.941242 6.647818) (xy 361.972218 6.727777) (xy 362.01044 6.804537)
			(xy 362.055581 6.877443) (xy 362.107257 6.945872) (xy 362.165026 7.009242) (xy 362.228396 7.067011)
			(xy 362.296825 7.118687) (xy 362.369731 7.163828) (xy 362.446491 7.20205) (xy 362.52645 7.233026)
			(xy 362.608926 7.256493) (xy 362.693216 7.272249) (xy 362.778599 7.280161) (xy 362.864349 7.280161)
			(xy 362.949732 7.272249) (xy 363.034022 7.256493) (xy 363.116498 7.233026) (xy 363.196457 7.20205)
			(xy 363.21713 7.191756) (xy 364.379764 7.191756) (xy 364.379764 8.055356) (xy 364.380268 8.084892)
			(xy 364.388312 8.143414) (xy 364.404249 8.200296) (xy 364.427784 8.254478) (xy 364.458477 8.304951)
			(xy 364.495757 8.350774) (xy 364.538929 8.391094) (xy 364.587189 8.42516) (xy 364.639639 8.452337)
			(xy 364.6953 8.472119) (xy 364.753137 8.484138) (xy 364.812072 8.488169) (xy 364.871007 8.484138)
			(xy 364.928844 8.472119) (xy 364.984505 8.452337) (xy 365.036955 8.42516) (xy 365.085215 8.391094)
			(xy 365.128387 8.350774) (xy 365.165667 8.304951) (xy 365.19636 8.254478) (xy 365.219895 8.200296)
			(xy 365.235832 8.143414) (xy 365.243876 8.084892) (xy 365.24438 8.055356) (xy 365.24438 7.376973)
			(xy 385.651997 7.376973) (xy 385.651997 7.462723) (xy 385.659909 7.548106) (xy 385.675665 7.632396)
			(xy 385.699132 7.714872) (xy 385.730108 7.794831) (xy 385.76833 7.871591) (xy 385.813471 7.944497)
			(xy 385.865147 8.012926) (xy 385.922916 8.076296) (xy 385.986286 8.134065) (xy 386.054715 8.185741)
			(xy 386.127621 8.230882) (xy 386.204381 8.269104) (xy 386.28434 8.30008) (xy 386.366816 8.323547)
			(xy 386.451106 8.339303) (xy 386.536489 8.347215) (xy 386.622239 8.347215) (xy 386.707622 8.339303)
			(xy 386.791912 8.323547) (xy 386.874388 8.30008) (xy 386.954347 8.269104) (xy 386.97502 8.25881)
			(xy 390.508744 8.25881) (xy 390.508744 9.12241) (xy 390.509248 9.151964) (xy 390.517297 9.21052)
			(xy 390.533243 9.267435) (xy 390.556792 9.321649) (xy 390.587503 9.372152) (xy 390.624805 9.418002)
			(xy 390.668002 9.458345) (xy 390.716291 9.492431) (xy 390.768771 9.519624) (xy 390.824466 9.539418)
			(xy 390.882337 9.551444) (xy 390.941306 9.555478) (xy 391.000275 9.551444) (xy 391.058146 9.539418)
			(xy 391.113841 9.519624) (xy 391.166321 9.492431) (xy 391.21461 9.458345) (xy 391.257807 9.418002)
			(xy 391.295109 9.372152) (xy 391.32582 9.321649) (xy 391.349369 9.267435) (xy 391.365315 9.21052)
			(xy 391.373364 9.151964) (xy 391.373868 9.12241) (xy 391.373868 8.25881) (xy 391.373364 8.229256)
			(xy 391.365315 8.1707) (xy 391.349369 8.113785) (xy 391.32582 8.059571) (xy 391.295109 8.009068)
			(xy 391.257807 7.963218) (xy 391.21461 7.922875) (xy 391.166321 7.888789) (xy 391.113841 7.861596)
			(xy 391.058146 7.841802) (xy 391.000275 7.829776) (xy 390.941306 7.825743) (xy 390.882337 7.829776)
			(xy 390.824466 7.841802) (xy 390.768771 7.861596) (xy 390.716291 7.888789) (xy 390.668002 7.922875)
			(xy 390.624805 7.963218) (xy 390.587503 8.009068) (xy 390.556792 8.059571) (xy 390.533243 8.113785)
			(xy 390.517297 8.1707) (xy 390.509248 8.229256) (xy 390.508744 8.25881) (xy 386.97502 8.25881) (xy 387.031107 8.230882)
			(xy 387.104013 8.185741) (xy 387.172442 8.134065) (xy 387.235812 8.076296) (xy 387.293581 8.012926)
			(xy 387.345257 7.944497) (xy 387.390398 7.871591) (xy 387.42862 7.794831) (xy 387.459596 7.714872)
			(xy 387.483063 7.632396) (xy 387.498819 7.548106) (xy 387.506731 7.462723) (xy 387.507226 7.419848)
			(xy 387.506731 7.376973) (xy 392.001997 7.376973) (xy 392.001997 7.462723) (xy 392.009909 7.548106)
			(xy 392.025665 7.632396) (xy 392.049132 7.714872) (xy 392.080108 7.794831) (xy 392.11833 7.871591)
			(xy 392.163471 7.944497) (xy 392.215147 8.012926) (xy 392.272916 8.076296) (xy 392.336286 8.134065)
			(xy 392.404715 8.185741) (xy 392.477621 8.230882) (xy 392.554381 8.269104) (xy 392.63434 8.30008)
			(xy 392.716816 8.323547) (xy 392.801106 8.339303) (xy 392.886489 8.347215) (xy 392.972239 8.347215)
			(xy 393.057622 8.339303) (xy 393.141912 8.323547) (xy 393.224388 8.30008) (xy 393.304347 8.269104)
			(xy 393.381107 8.230882) (xy 393.454013 8.185741) (xy 393.522442 8.134065) (xy 393.585812 8.076296)
			(xy 393.643581 8.012926) (xy 393.695257 7.944497) (xy 393.740398 7.871591) (xy 393.77862 7.794831)
			(xy 393.809596 7.714872) (xy 393.833063 7.632396) (xy 393.848819 7.548106) (xy 393.856731 7.462723)
			(xy 393.857226 7.419848) (xy 393.856731 7.376973) (xy 436.390783 7.376973) (xy 436.390783 7.462723)
			(xy 436.398695 7.548106) (xy 436.414451 7.632396) (xy 436.437918 7.714872) (xy 436.468894 7.794831)
			(xy 436.507116 7.871591) (xy 436.552257 7.944497) (xy 436.603933 8.012926) (xy 436.661702 8.076296)
			(xy 436.725072 8.134065) (xy 436.793501 8.185741) (xy 436.866407 8.230882) (xy 436.943167 8.269104)
			(xy 437.023126 8.30008) (xy 437.105602 8.323547) (xy 437.189892 8.339303) (xy 437.275275 8.347215)
			(xy 437.361025 8.347215) (xy 437.446408 8.339303) (xy 437.530698 8.323547) (xy 437.613174 8.30008)
			(xy 437.693133 8.269104) (xy 437.713806 8.25881) (xy 438.87644 8.25881) (xy 438.87644 9.12241) (xy 438.876944 9.151946)
			(xy 438.884988 9.210468) (xy 438.900925 9.26735) (xy 438.92446 9.321532) (xy 438.955153 9.372005)
			(xy 438.992433 9.417828) (xy 439.035605 9.458148) (xy 439.083865 9.492214) (xy 439.136315 9.519391)
			(xy 439.191976 9.539173) (xy 439.249813 9.551192) (xy 439.308748 9.555223) (xy 439.367683 9.551192)
			(xy 439.42552 9.539173) (xy 439.481181 9.519391) (xy 439.533631 9.492214) (xy 439.581891 9.458148)
			(xy 439.625063 9.417828) (xy 439.662343 9.372005) (xy 439.693036 9.321532) (xy 439.716571 9.26735)
			(xy 439.732508 9.210468) (xy 439.740552 9.151946) (xy 439.741056 9.12241) (xy 439.741056 8.25881)
			(xy 439.740552 8.229274) (xy 439.732508 8.170752) (xy 439.716571 8.11387) (xy 439.693036 8.059688)
			(xy 439.662343 8.009215) (xy 439.625063 7.963392) (xy 439.581891 7.923072) (xy 439.533631 7.889006)
			(xy 439.481181 7.861829) (xy 439.42552 7.842047) (xy 439.367683 7.830028) (xy 439.308748 7.825997)
			(xy 439.249813 7.830028) (xy 439.191976 7.842047) (xy 439.136315 7.861829) (xy 439.083865 7.889006)
			(xy 439.035605 7.923072) (xy 438.992433 7.963392) (xy 438.955153 8.009215) (xy 438.92446 8.059688)
			(xy 438.900925 8.11387) (xy 438.884988 8.170752) (xy 438.876944 8.229274) (xy 438.87644 8.25881)
			(xy 437.713806 8.25881) (xy 437.769893 8.230882) (xy 437.842799 8.185741) (xy 437.911228 8.134065)
			(xy 437.974598 8.076296) (xy 438.032367 8.012926) (xy 438.084043 7.944497) (xy 438.129184 7.871591)
			(xy 438.167406 7.794831) (xy 438.198382 7.714872) (xy 438.221849 7.632396) (xy 438.237605 7.548106)
			(xy 438.245517 7.462723) (xy 438.246012 7.419848) (xy 438.245517 7.376973) (xy 442.740783 7.376973)
			(xy 442.740783 7.462723) (xy 442.748695 7.548106) (xy 442.764451 7.632396) (xy 442.787918 7.714872)
			(xy 442.818894 7.794831) (xy 442.857116 7.871591) (xy 442.902257 7.944497) (xy 442.953933 8.012926)
			(xy 443.011702 8.076296) (xy 443.075072 8.134065) (xy 443.143501 8.185741) (xy 443.216407 8.230882)
			(xy 443.293167 8.269104) (xy 443.373126 8.30008) (xy 443.455602 8.323547) (xy 443.539892 8.339303)
			(xy 443.625275 8.347215) (xy 443.711025 8.347215) (xy 443.796408 8.339303) (xy 443.880698 8.323547)
			(xy 443.963174 8.30008) (xy 444.043133 8.269104) (xy 444.119893 8.230882) (xy 444.192799 8.185741)
			(xy 444.261228 8.134065) (xy 444.324598 8.076296) (xy 444.382367 8.012926) (xy 444.434043 7.944497)
			(xy 444.479184 7.871591) (xy 444.517406 7.794831) (xy 444.548382 7.714872) (xy 444.571849 7.632396)
			(xy 444.587605 7.548106) (xy 444.595517 7.462723) (xy 444.596012 7.419848) (xy 444.595517 7.376973)
			(xy 444.587605 7.29159) (xy 444.571849 7.2073) (xy 444.548382 7.124824) (xy 444.517406 7.044865)
			(xy 444.479184 6.968105) (xy 444.434043 6.895199) (xy 444.382367 6.82677) (xy 444.324598 6.7634)
			(xy 444.261228 6.705631) (xy 444.192799 6.653955) (xy 444.119893 6.608814) (xy 444.043133 6.570592)
			(xy 443.963174 6.539616) (xy 443.880698 6.516149) (xy 443.796408 6.500393) (xy 443.711025 6.492481)
			(xy 443.625275 6.492481) (xy 443.539892 6.500393) (xy 443.455602 6.516149) (xy 443.373126 6.539616)
			(xy 443.293167 6.570592) (xy 443.216407 6.608814) (xy 443.143501 6.653955) (xy 443.075072 6.705631)
			(xy 443.011702 6.7634) (xy 442.953933 6.82677) (xy 442.902257 6.895199) (xy 442.857116 6.968105)
			(xy 442.818894 7.044865) (xy 442.787918 7.124824) (xy 442.764451 7.2073) (xy 442.748695 7.29159)
			(xy 442.740783 7.376973) (xy 438.245517 7.376973) (xy 438.237605 7.29159) (xy 438.221849 7.2073)
			(xy 438.198382 7.124824) (xy 438.167406 7.044865) (xy 438.129184 6.968105) (xy 438.084043 6.895199)
			(xy 438.032367 6.82677) (xy 437.974598 6.7634) (xy 437.911228 6.705631) (xy 437.842799 6.653955)
			(xy 437.769893 6.608814) (xy 437.693133 6.570592) (xy 437.613174 6.539616) (xy 437.530698 6.516149)
			(xy 437.446408 6.500393) (xy 437.361025 6.492481) (xy 437.275275 6.492481) (xy 437.189892 6.500393)
			(xy 437.105602 6.516149) (xy 437.023126 6.539616) (xy 436.943167 6.570592) (xy 436.866407 6.608814)
			(xy 436.793501 6.653955) (xy 436.725072 6.705631) (xy 436.661702 6.7634) (xy 436.603933 6.82677)
			(xy 436.552257 6.895199) (xy 436.507116 6.968105) (xy 436.468894 7.044865) (xy 436.437918 7.124824)
			(xy 436.414451 7.2073) (xy 436.398695 7.29159) (xy 436.390783 7.376973) (xy 393.856731 7.376973)
			(xy 393.848819 7.29159) (xy 393.833063 7.2073) (xy 393.809596 7.124824) (xy 393.77862 7.044865) (xy 393.740398 6.968105)
			(xy 393.695257 6.895199) (xy 393.643581 6.82677) (xy 393.585812 6.7634) (xy 393.522442 6.705631)
			(xy 393.454013 6.653955) (xy 393.381107 6.608814) (xy 393.304347 6.570592) (xy 393.224388 6.539616)
			(xy 393.141912 6.516149) (xy 393.057622 6.500393) (xy 392.972239 6.492481) (xy 392.886489 6.492481)
			(xy 392.801106 6.500393) (xy 392.716816 6.516149) (xy 392.63434 6.539616) (xy 392.554381 6.570592)
			(xy 392.477621 6.608814) (xy 392.404715 6.653955) (xy 392.336286 6.705631) (xy 392.272916 6.7634)
			(xy 392.215147 6.82677) (xy 392.163471 6.895199) (xy 392.11833 6.968105) (xy 392.080108 7.044865)
			(xy 392.049132 7.124824) (xy 392.025665 7.2073) (xy 392.009909 7.29159) (xy 392.001997 7.376973)
			(xy 387.506731 7.376973) (xy 387.498819 7.29159) (xy 387.483063 7.2073) (xy 387.459596 7.124824)
			(xy 387.42862 7.044865) (xy 387.390398 6.968105) (xy 387.345257 6.895199) (xy 387.293581 6.82677)
			(xy 387.235812 6.7634) (xy 387.172442 6.705631) (xy 387.104013 6.653955) (xy 387.031107 6.608814)
			(xy 386.954347 6.570592) (xy 386.874388 6.539616) (xy 386.791912 6.516149) (xy 386.707622 6.500393)
			(xy 386.622239 6.492481) (xy 386.536489 6.492481) (xy 386.451106 6.500393) (xy 386.366816 6.516149)
			(xy 386.28434 6.539616) (xy 386.204381 6.570592) (xy 386.127621 6.608814) (xy 386.054715 6.653955)
			(xy 385.986286 6.705631) (xy 385.922916 6.7634) (xy 385.865147 6.82677) (xy 385.813471 6.895199)
			(xy 385.76833 6.968105) (xy 385.730108 7.044865) (xy 385.699132 7.124824) (xy 385.675665 7.2073)
			(xy 385.659909 7.29159) (xy 385.651997 7.376973) (xy 365.24438 7.376973) (xy 365.24438 7.191756)
			(xy 365.243876 7.16222) (xy 365.235832 7.103698) (xy 365.219895 7.046816) (xy 365.19636 6.992634)
			(xy 365.165667 6.942161) (xy 365.128387 6.896338) (xy 365.085215 6.856018) (xy 365.036955 6.821952)
			(xy 364.984505 6.794775) (xy 364.928844 6.774993) (xy 364.871007 6.762974) (xy 364.812072 6.758943)
			(xy 364.753137 6.762974) (xy 364.6953 6.774993) (xy 364.639639 6.794775) (xy 364.587189 6.821952)
			(xy 364.538929 6.856018) (xy 364.495757 6.896338) (xy 364.458477 6.942161) (xy 364.427784 6.992634)
			(xy 364.404249 7.046816) (xy 364.388312 7.103698) (xy 364.380268 7.16222) (xy 364.379764 7.191756)
			(xy 363.21713 7.191756) (xy 363.273217 7.163828) (xy 363.346123 7.118687) (xy 363.414552 7.067011)
			(xy 363.477922 7.009242) (xy 363.535691 6.945872) (xy 363.587367 6.877443) (xy 363.632508 6.804537)
			(xy 363.67073 6.727777) (xy 363.701706 6.647818) (xy 363.725173 6.565342) (xy 363.740929 6.481052)
			(xy 363.748841 6.395669) (xy 363.749336 6.352794) (xy 363.748841 6.309919) (xy 368.244107 6.309919)
			(xy 368.244107 6.395669) (xy 368.252019 6.481052) (xy 368.267775 6.565342) (xy 368.291242 6.647818)
			(xy 368.322218 6.727777) (xy 368.36044 6.804537) (xy 368.405581 6.877443) (xy 368.457257 6.945872)
			(xy 368.515026 7.009242) (xy 368.578396 7.067011) (xy 368.646825 7.118687) (xy 368.719731 7.163828)
			(xy 368.796491 7.20205) (xy 368.87645 7.233026) (xy 368.958926 7.256493) (xy 369.043216 7.272249)
			(xy 369.128599 7.280161) (xy 369.214349 7.280161) (xy 369.299732 7.272249) (xy 369.384022 7.256493)
			(xy 369.466498 7.233026) (xy 369.546457 7.20205) (xy 369.623217 7.163828) (xy 369.696123 7.118687)
			(xy 369.764552 7.067011) (xy 369.827922 7.009242) (xy 369.885691 6.945872) (xy 369.937367 6.877443)
			(xy 369.982508 6.804537) (xy 370.02073 6.727777) (xy 370.051706 6.647818) (xy 370.075173 6.565342)
			(xy 370.090929 6.481052) (xy 370.098841 6.395669) (xy 370.099336 6.352794) (xy 370.098841 6.309919)
			(xy 370.090929 6.224536) (xy 370.075173 6.140246) (xy 370.051706 6.05777) (xy 370.02073 5.977811)
			(xy 369.982508 5.901051) (xy 369.937367 5.828145) (xy 369.885691 5.759716) (xy 369.827922 5.696346)
			(xy 369.764552 5.638577) (xy 369.696123 5.586901) (xy 369.623217 5.54176) (xy 369.546457 5.503538)
			(xy 369.466498 5.472562) (xy 369.384022 5.449095) (xy 369.299732 5.433339) (xy 369.214349 5.425427)
			(xy 369.128599 5.425427) (xy 369.043216 5.433339) (xy 368.958926 5.449095) (xy 368.87645 5.472562)
			(xy 368.796491 5.503538) (xy 368.719731 5.54176) (xy 368.646825 5.586901) (xy 368.578396 5.638577)
			(xy 368.515026 5.696346) (xy 368.457257 5.759716) (xy 368.405581 5.828145) (xy 368.36044 5.901051)
			(xy 368.322218 5.977811) (xy 368.291242 6.05777) (xy 368.267775 6.140246) (xy 368.252019 6.224536)
			(xy 368.244107 6.309919) (xy 363.748841 6.309919) (xy 363.740929 6.224536) (xy 363.725173 6.140246)
			(xy 363.701706 6.05777) (xy 363.67073 5.977811) (xy 363.632508 5.901051) (xy 363.587367 5.828145)
			(xy 363.535691 5.759716) (xy 363.477922 5.696346) (xy 363.414552 5.638577) (xy 363.346123 5.586901)
			(xy 363.273217 5.54176) (xy 363.196457 5.503538) (xy 363.116498 5.472562) (xy 363.034022 5.449095)
			(xy 362.949732 5.433339) (xy 362.864349 5.425427) (xy 362.778599 5.425427) (xy 362.693216 5.433339)
			(xy 362.608926 5.449095) (xy 362.52645 5.472562) (xy 362.446491 5.503538) (xy 362.369731 5.54176)
			(xy 362.296825 5.586901) (xy 362.228396 5.638577) (xy 362.165026 5.696346) (xy 362.107257 5.759716)
			(xy 362.055581 5.828145) (xy 362.01044 5.901051) (xy 361.972218 5.977811) (xy 361.941242 6.05777)
			(xy 361.917775 6.140246) (xy 361.902019 6.224536) (xy 361.894107 6.309919) (xy 319.360055 6.309919)
			(xy 319.352143 6.224536) (xy 319.336387 6.140246) (xy 319.31292 6.05777) (xy 319.281944 5.977811)
			(xy 319.243722 5.901051) (xy 319.198581 5.828145) (xy 319.146905 5.759716) (xy 319.089136 5.696346)
			(xy 319.025766 5.638577) (xy 318.957337 5.586901) (xy 318.884431 5.54176) (xy 318.807671 5.503538)
			(xy 318.727712 5.472562) (xy 318.645236 5.449095) (xy 318.560946 5.433339) (xy 318.475563 5.425427)
			(xy 318.389813 5.425427) (xy 318.30443 5.433339) (xy 318.22014 5.449095) (xy 318.137664 5.472562)
			(xy 318.057705 5.503538) (xy 317.980945 5.54176) (xy 317.908039 5.586901) (xy 317.83961 5.638577)
			(xy 317.77624 5.696346) (xy 317.718471 5.759716) (xy 317.666795 5.828145) (xy 317.621654 5.901051)
			(xy 317.583432 5.977811) (xy 317.552456 6.05777) (xy 317.528989 6.140246) (xy 317.513233 6.224536)
			(xy 317.505321 6.309919) (xy 313.010055 6.309919) (xy 313.002143 6.224536) (xy 312.986387 6.140246)
			(xy 312.96292 6.05777) (xy 312.931944 5.977811) (xy 312.893722 5.901051) (xy 312.848581 5.828145)
			(xy 312.796905 5.759716) (xy 312.739136 5.696346) (xy 312.675766 5.638577) (xy 312.607337 5.586901)
			(xy 312.534431 5.54176) (xy 312.457671 5.503538) (xy 312.377712 5.472562) (xy 312.295236 5.449095)
			(xy 312.210946 5.433339) (xy 312.125563 5.425427) (xy 312.039813 5.425427) (xy 311.95443 5.433339)
			(xy 311.87014 5.449095) (xy 311.787664 5.472562) (xy 311.707705 5.503538) (xy 311.630945 5.54176)
			(xy 311.558039 5.586901) (xy 311.48961 5.638577) (xy 311.42624 5.696346) (xy 311.368471 5.759716)
			(xy 311.316795 5.828145) (xy 311.271654 5.901051) (xy 311.233432 5.977811) (xy 311.202456 6.05777)
			(xy 311.178989 6.140246) (xy 311.163233 6.224536) (xy 311.155321 6.309919) (xy 304.348655 6.309919)
			(xy 304.340743 6.224536) (xy 304.324987 6.140246) (xy 304.30152 6.05777) (xy 304.270544 5.977811)
			(xy 304.232322 5.901051) (xy 304.187181 5.828145) (xy 304.135505 5.759716) (xy 304.077736 5.696346)
			(xy 304.014366 5.638577) (xy 303.945937 5.586901) (xy 303.873031 5.54176) (xy 303.796271 5.503538)
			(xy 303.716312 5.472562) (xy 303.633836 5.449095) (xy 303.549546 5.433339) (xy 303.464163 5.425427)
			(xy 303.378413 5.425427) (xy 303.29303 5.433339) (xy 303.20874 5.449095) (xy 303.126264 5.472562)
			(xy 303.046305 5.503538) (xy 302.969545 5.54176) (xy 302.896639 5.586901) (xy 302.82821 5.638577)
			(xy 302.76484 5.696346) (xy 302.707071 5.759716) (xy 302.655395 5.828145) (xy 302.610254 5.901051)
			(xy 302.572032 5.977811) (xy 302.541056 6.05777) (xy 302.517589 6.140246) (xy 302.501833 6.224536)
			(xy 302.493921 6.309919) (xy 297.998655 6.309919) (xy 297.990743 6.224536) (xy 297.974987 6.140246)
			(xy 297.95152 6.05777) (xy 297.920544 5.977811) (xy 297.882322 5.901051) (xy 297.837181 5.828145)
			(xy 297.785505 5.759716) (xy 297.727736 5.696346) (xy 297.664366 5.638577) (xy 297.595937 5.586901)
			(xy 297.523031 5.54176) (xy 297.446271 5.503538) (xy 297.366312 5.472562) (xy 297.283836 5.449095)
			(xy 297.199546 5.433339) (xy 297.114163 5.425427) (xy 297.028413 5.425427) (xy 296.94303 5.433339)
			(xy 296.85874 5.449095) (xy 296.776264 5.472562) (xy 296.696305 5.503538) (xy 296.619545 5.54176)
			(xy 296.546639 5.586901) (xy 296.47821 5.638577) (xy 296.41484 5.696346) (xy 296.357071 5.759716)
			(xy 296.305395 5.828145) (xy 296.260254 5.901051) (xy 296.222032 5.977811) (xy 296.191056 6.05777)
			(xy 296.167589 6.140246) (xy 296.151833 6.224536) (xy 296.143921 6.309919) (xy 216.865975 6.309919)
			(xy 216.858063 6.224536) (xy 216.842307 6.140246) (xy 216.81884 6.05777) (xy 216.787864 5.977811)
			(xy 216.749642 5.901051) (xy 216.704501 5.828145) (xy 216.652825 5.759716) (xy 216.595056 5.696346)
			(xy 216.531686 5.638577) (xy 216.463257 5.586901) (xy 216.390351 5.54176) (xy 216.313591 5.503538)
			(xy 216.233632 5.472562) (xy 216.151156 5.449095) (xy 216.066866 5.433339) (xy 215.981483 5.425427)
			(xy 215.895733 5.425427) (xy 215.81035 5.433339) (xy 215.72606 5.449095) (xy 215.643584 5.472562)
			(xy 215.563625 5.503538) (xy 215.486865 5.54176) (xy 215.413959 5.586901) (xy 215.34553 5.638577)
			(xy 215.28216 5.696346) (xy 215.224391 5.759716) (xy 215.172715 5.828145) (xy 215.127574 5.901051)
			(xy 215.089352 5.977811) (xy 215.058376 6.05777) (xy 215.034909 6.140246) (xy 215.019153 6.224536)
			(xy 215.011241 6.309919) (xy 210.515975 6.309919) (xy 210.508063 6.224536) (xy 210.492307 6.140246)
			(xy 210.46884 6.05777) (xy 210.437864 5.977811) (xy 210.399642 5.901051) (xy 210.354501 5.828145)
			(xy 210.302825 5.759716) (xy 210.245056 5.696346) (xy 210.181686 5.638577) (xy 210.113257 5.586901)
			(xy 210.040351 5.54176) (xy 209.963591 5.503538) (xy 209.883632 5.472562) (xy 209.801156 5.449095)
			(xy 209.716866 5.433339) (xy 209.631483 5.425427) (xy 209.545733 5.425427) (xy 209.46035 5.433339)
			(xy 209.37606 5.449095) (xy 209.293584 5.472562) (xy 209.213625 5.503538) (xy 209.136865 5.54176)
			(xy 209.063959 5.586901) (xy 208.99553 5.638577) (xy 208.93216 5.696346) (xy 208.874391 5.759716)
			(xy 208.822715 5.828145) (xy 208.777574 5.901051) (xy 208.739352 5.977811) (xy 208.708376 6.05777)
			(xy 208.684909 6.140246) (xy 208.669153 6.224536) (xy 208.661241 6.309919) (xy 184.818528 6.309919)
			(xy 184.818528 5.632196) (xy 184.818024 5.60266) (xy 184.80998 5.544138) (xy 184.794043 5.487256)
			(xy 184.770508 5.433074) (xy 184.739815 5.382601) (xy 184.702535 5.336778) (xy 184.659363 5.296458)
			(xy 184.611103 5.262392) (xy 184.558653 5.235215) (xy 184.502992 5.215433) (xy 184.445155 5.203414)
			(xy 184.38622 5.199383) (xy 184.327285 5.203414) (xy 184.269448 5.215433) (xy 184.213787 5.235215)
			(xy 184.161337 5.262392) (xy 184.113077 5.296458) (xy 184.069905 5.336778) (xy 184.032625 5.382601)
			(xy 184.001932 5.433074) (xy 183.978397 5.487256) (xy 183.96246 5.544138) (xy 183.954416 5.60266)
			(xy 183.953912 5.632196) (xy 182.791278 5.632196) (xy 182.847365 5.604268) (xy 182.920271 5.559127)
			(xy 182.9887 5.507451) (xy 183.05207 5.449682) (xy 183.109839 5.386312) (xy 183.161515 5.317883)
			(xy 183.206656 5.244977) (xy 183.244878 5.168217) (xy 183.275854 5.088258) (xy 183.299321 5.005782)
			(xy 183.315077 4.921492) (xy 183.322989 4.836109) (xy 183.323484 4.793234) (xy 183.322989 4.750359)
			(xy 187.818255 4.750359) (xy 187.818255 4.836109) (xy 187.826167 4.921492) (xy 187.841923 5.005782)
			(xy 187.86539 5.088258) (xy 187.896366 5.168217) (xy 187.934588 5.244977) (xy 187.979729 5.317883)
			(xy 188.031405 5.386312) (xy 188.089174 5.449682) (xy 188.152544 5.507451) (xy 188.220973 5.559127)
			(xy 188.293879 5.604268) (xy 188.370639 5.64249) (xy 188.450598 5.673466) (xy 188.533074 5.696933)
			(xy 188.617364 5.712689) (xy 188.702747 5.720601) (xy 188.788497 5.720601) (xy 188.87388 5.712689)
			(xy 188.95817 5.696933) (xy 189.040646 5.673466) (xy 189.120605 5.64249) (xy 189.197365 5.604268)
			(xy 189.270271 5.559127) (xy 189.3387 5.507451) (xy 189.40207 5.449682) (xy 189.459839 5.386312)
			(xy 189.511515 5.317883) (xy 189.556656 5.244977) (xy 189.594878 5.168217) (xy 189.625854 5.088258)
			(xy 189.649321 5.005782) (xy 189.665077 4.921492) (xy 189.672989 4.836109) (xy 189.673484 4.793234)
			(xy 189.672989 4.750359) (xy 189.665077 4.664976) (xy 189.649321 4.580686) (xy 189.625854 4.49821)
			(xy 189.594878 4.418251) (xy 189.556656 4.341491) (xy 189.511515 4.268585) (xy 189.459839 4.200156)
			(xy 189.40207 4.136786) (xy 189.3387 4.079017) (xy 189.270271 4.027341) (xy 189.197365 3.9822) (xy 189.120605 3.943978)
			(xy 189.040646 3.913002) (xy 188.95817 3.889535) (xy 188.87388 3.873779) (xy 188.788497 3.865867)
			(xy 188.702747 3.865867) (xy 188.617364 3.873779) (xy 188.533074 3.889535) (xy 188.450598 3.913002)
			(xy 188.370639 3.943978) (xy 188.293879 3.9822) (xy 188.220973 4.027341) (xy 188.152544 4.079017)
			(xy 188.089174 4.136786) (xy 188.031405 4.200156) (xy 187.979729 4.268585) (xy 187.934588 4.341491)
			(xy 187.896366 4.418251) (xy 187.86539 4.49821) (xy 187.841923 4.580686) (xy 187.826167 4.664976)
			(xy 187.818255 4.750359) (xy 183.322989 4.750359) (xy 183.315077 4.664976) (xy 183.299321 4.580686)
			(xy 183.275854 4.49821) (xy 183.244878 4.418251) (xy 183.206656 4.341491) (xy 183.161515 4.268585)
			(xy 183.109839 4.200156) (xy 183.05207 4.136786) (xy 182.9887 4.079017) (xy 182.920271 4.027341)
			(xy 182.847365 3.9822) (xy 182.770605 3.943978) (xy 182.690646 3.913002) (xy 182.60817 3.889535)
			(xy 182.52388 3.873779) (xy 182.438497 3.865867) (xy 182.352747 3.865867) (xy 182.267364 3.873779)
			(xy 182.183074 3.889535) (xy 182.100598 3.913002) (xy 182.020639 3.943978) (xy 181.943879 3.9822)
			(xy 181.870973 4.027341) (xy 181.802544 4.079017) (xy 181.739174 4.136786) (xy 181.681405 4.200156)
			(xy 181.629729 4.268585) (xy 181.584588 4.341491) (xy 181.546366 4.418251) (xy 181.51539 4.49821)
			(xy 181.491923 4.580686) (xy 181.476167 4.664976) (xy 181.468255 4.750359) (xy 102.190309 4.750359)
			(xy 102.182397 4.664976) (xy 102.166641 4.580686) (xy 102.143174 4.49821) (xy 102.112198 4.418251)
			(xy 102.073976 4.341491) (xy 102.028835 4.268585) (xy 101.977159 4.200156) (xy 101.91939 4.136786)
			(xy 101.85602 4.079017) (xy 101.787591 4.027341) (xy 101.714685 3.9822) (xy 101.637925 3.943978)
			(xy 101.557966 3.913002) (xy 101.47549 3.889535) (xy 101.3912 3.873779) (xy 101.305817 3.865867)
			(xy 101.220067 3.865867) (xy 101.134684 3.873779) (xy 101.050394 3.889535) (xy 100.967918 3.913002)
			(xy 100.887959 3.943978) (xy 100.811199 3.9822) (xy 100.738293 4.027341) (xy 100.669864 4.079017)
			(xy 100.606494 4.136786) (xy 100.548725 4.200156) (xy 100.497049 4.268585) (xy 100.451908 4.341491)
			(xy 100.413686 4.418251) (xy 100.38271 4.49821) (xy 100.359243 4.580686) (xy 100.343487 4.664976)
			(xy 100.335575 4.750359) (xy 95.840309 4.750359) (xy 95.832397 4.664976) (xy 95.816641 4.580686)
			(xy 95.793174 4.49821) (xy 95.762198 4.418251) (xy 95.723976 4.341491) (xy 95.678835 4.268585) (xy 95.627159 4.200156)
			(xy 95.56939 4.136786) (xy 95.50602 4.079017) (xy 95.437591 4.027341) (xy 95.364685 3.9822) (xy 95.287925 3.943978)
			(xy 95.207966 3.913002) (xy 95.12549 3.889535) (xy 95.0412 3.873779) (xy 94.955817 3.865867) (xy 94.870067 3.865867)
			(xy 94.784684 3.873779) (xy 94.700394 3.889535) (xy 94.617918 3.913002) (xy 94.537959 3.943978) (xy 94.461199 3.9822)
			(xy 94.388293 4.027341) (xy 94.319864 4.079017) (xy 94.256494 4.136786) (xy 94.198725 4.200156) (xy 94.147049 4.268585)
			(xy 94.101908 4.341491) (xy 94.063686 4.418251) (xy 94.03271 4.49821) (xy 94.009243 4.580686) (xy 93.993487 4.664976)
			(xy 93.985575 4.750359) (xy 0.509016 4.750359) (xy 0.509016 -7.78002) (xy 0.509537 -7.835789) (xy 0.517873 -7.947015)
			(xy 0.534497 -8.057308) (xy 0.559316 -8.166049) (xy 0.592193 -8.272632) (xy 0.632942 -8.37646) (xy 0.681336 -8.476953)
			(xy 0.737105 -8.573548) (xy 0.799937 -8.665705) (xy 0.86948 -8.752909) (xy 0.945345 -8.834672) (xy 1.027108 -8.910538)
			(xy 1.114312 -8.980081) (xy 1.206469 -9.042912) (xy 1.303064 -9.098682) (xy 1.403556 -9.147076) (xy 1.507384 -9.187826)
			(xy 1.613967 -9.220703) (xy 1.722708 -9.245523) (xy 1.833001 -9.262147) (xy 1.944227 -9.270482) (xy 1.999996 -9.271)
			(xy 9.10209 -9.271) (xy 9.15786 -9.270479) (xy 9.269087 -9.262144) (xy 9.37938 -9.245521) (xy 9.488123 -9.220702)
			(xy 9.594707 -9.187826) (xy 9.698536 -9.147077) (xy 9.79903 -9.098683) (xy 9.895626 -9.042915) (xy 9.987784 -8.980083)
			(xy 10.07499 -8.910541) (xy 10.156754 -8.834676) (xy 10.232621 -8.752912) (xy 10.302165 -8.665708)
			(xy 10.364999 -8.573551) (xy 10.420769 -8.476956) (xy 10.469165 -8.376463) (xy 10.509916 -8.272635)
			(xy 10.542794 -8.166052) (xy 10.567616 -8.05731) (xy 10.584241 -7.947017) (xy 10.592578 -7.83579)
			(xy 10.59307 -7.78002) (xy 10.59307 0.40005) (xy 10.593555 0.470432) (xy 10.601447 0.610976) (xy 10.617208 0.750856)
			(xy 10.640787 0.889632) (xy 10.67211 1.026868) (xy 10.711079 1.162131) (xy 10.757571 1.294997) (xy 10.811439 1.425046)
			(xy 10.872515 1.551871) (xy 10.940606 1.675072) (xy 11.015497 1.794261) (xy 11.096954 1.909063) (xy 11.184719 2.019118)
			(xy 11.278518 2.124078) (xy 11.378053 2.223614) (xy 11.483014 2.317412) (xy 11.593068 2.405178) (xy 11.707871 2.486634)
			(xy 11.82706 2.561525) (xy 11.950261 2.629616) (xy 12.077085 2.690692) (xy 12.207135 2.74456) (xy 12.340001 2.791052)
			(xy 12.475264 2.83002) (xy 12.6125 2.861343) (xy 12.751276 2.884922) (xy 12.891156 2.900683) (xy 13.0317 2.908575)
			(xy 13.102082 2.909062) (xy 81.701894 2.909062) (xy 81.772277 2.908568) (xy 81.912821 2.900676) (xy 82.052702 2.884916)
			(xy 82.191479 2.861337) (xy 82.328715 2.830015) (xy 82.46398 2.791046) (xy 82.596846 2.744555) (xy 82.726897 2.690688)
			(xy 82.853723 2.629613) (xy 82.976925 2.561522) (xy 83.096116 2.486632) (xy 83.210919 2.405176) (xy 83.320975 2.317411)
			(xy 83.425937 2.223613) (xy 83.439191 2.210359) (xy 93.985575 2.210359) (xy 93.985575 2.296109) (xy 93.993487 2.381492)
			(xy 94.009243 2.465782) (xy 94.03271 2.548258) (xy 94.063686 2.628217) (xy 94.101908 2.704977) (xy 94.147049 2.777883)
			(xy 94.198725 2.846312) (xy 94.256494 2.909682) (xy 94.319864 2.967451) (xy 94.388293 3.019127) (xy 94.461199 3.064268)
			(xy 94.537959 3.10249) (xy 94.617918 3.133466) (xy 94.700394 3.156933) (xy 94.784684 3.172689) (xy 94.870067 3.180601)
			(xy 94.955817 3.180601) (xy 95.0412 3.172689) (xy 95.12549 3.156933) (xy 95.207966 3.133466) (xy 95.287925 3.10249)
			(xy 95.308598 3.092196) (xy 98.842576 3.092196) (xy 98.842576 3.955796) (xy 98.84308 3.985332) (xy 98.851124 4.043854)
			(xy 98.867061 4.100736) (xy 98.890596 4.154918) (xy 98.921289 4.205391) (xy 98.958569 4.251214) (xy 99.001741 4.291534)
			(xy 99.050001 4.3256) (xy 99.102451 4.352777) (xy 99.158112 4.372559) (xy 99.215949 4.384578) (xy 99.274884 4.388609)
			(xy 99.333819 4.384578) (xy 99.391656 4.372559) (xy 99.447317 4.352777) (xy 99.499767 4.3256) (xy 99.548027 4.291534)
			(xy 99.591199 4.251214) (xy 99.628479 4.205391) (xy 99.659172 4.154918) (xy 99.682707 4.100736) (xy 99.698644 4.043854)
			(xy 99.706688 3.985332) (xy 99.707192 3.955796) (xy 99.707192 3.092196) (xy 99.706688 3.06266) (xy 99.698644 3.004138)
			(xy 99.682707 2.947256) (xy 99.659172 2.893074) (xy 99.628479 2.842601) (xy 99.591199 2.796778) (xy 99.548027 2.756458)
			(xy 99.499767 2.722392) (xy 99.447317 2.695215) (xy 99.391656 2.675433) (xy 99.333819 2.663414) (xy 99.274884 2.659383)
			(xy 99.215949 2.663414) (xy 99.158112 2.675433) (xy 99.102451 2.695215) (xy 99.050001 2.722392) (xy 99.001741 2.756458)
			(xy 98.958569 2.796778) (xy 98.921289 2.842601) (xy 98.890596 2.893074) (xy 98.867061 2.947256) (xy 98.851124 3.004138)
			(xy 98.84308 3.06266) (xy 98.842576 3.092196) (xy 95.308598 3.092196) (xy 95.364685 3.064268) (xy 95.437591 3.019127)
			(xy 95.50602 2.967451) (xy 95.56939 2.909682) (xy 95.627159 2.846312) (xy 95.678835 2.777883) (xy 95.723976 2.704977)
			(xy 95.762198 2.628217) (xy 95.793174 2.548258) (xy 95.816641 2.465782) (xy 95.832397 2.381492) (xy 95.840309 2.296109)
			(xy 95.840804 2.253234) (xy 95.840309 2.210359) (xy 100.335575 2.210359) (xy 100.335575 2.296109)
			(xy 100.343487 2.381492) (xy 100.359243 2.465782) (xy 100.38271 2.548258) (xy 100.413686 2.628217)
			(xy 100.451908 2.704977) (xy 100.497049 2.777883) (xy 100.548725 2.846312) (xy 100.606494 2.909682)
			(xy 100.669864 2.967451) (xy 100.738293 3.019127) (xy 100.811199 3.064268) (xy 100.887959 3.10249)
			(xy 100.967918 3.133466) (xy 101.050394 3.156933) (xy 101.134684 3.172689) (xy 101.220067 3.180601)
			(xy 101.305817 3.180601) (xy 101.3912 3.172689) (xy 101.47549 3.156933) (xy 101.557966 3.133466)
			(xy 101.637925 3.10249) (xy 101.714685 3.064268) (xy 101.787591 3.019127) (xy 101.85602 2.967451)
			(xy 101.91939 2.909682) (xy 101.977159 2.846312) (xy 102.028835 2.777883) (xy 102.073976 2.704977)
			(xy 102.112198 2.628217) (xy 102.143174 2.548258) (xy 102.166641 2.465782) (xy 102.182397 2.381492)
			(xy 102.190309 2.296109) (xy 102.190804 2.253234) (xy 102.190309 2.210359) (xy 181.468255 2.210359)
			(xy 181.468255 2.296109) (xy 181.476167 2.381492) (xy 181.491923 2.465782) (xy 181.51539 2.548258)
			(xy 181.546366 2.628217) (xy 181.584588 2.704977) (xy 181.629729 2.777883) (xy 181.681405 2.846312)
			(xy 181.739174 2.909682) (xy 181.802544 2.967451) (xy 181.870973 3.019127) (xy 181.943879 3.064268)
			(xy 182.020639 3.10249) (xy 182.100598 3.133466) (xy 182.183074 3.156933) (xy 182.267364 3.172689)
			(xy 182.352747 3.180601) (xy 182.438497 3.180601) (xy 182.52388 3.172689) (xy 182.60817 3.156933)
			(xy 182.690646 3.133466) (xy 182.770605 3.10249) (xy 182.791278 3.092196) (xy 183.953912 3.092196)
			(xy 183.953912 3.955796) (xy 183.954416 3.985332) (xy 183.96246 4.043854) (xy 183.978397 4.100736)
			(xy 184.001932 4.154918) (xy 184.032625 4.205391) (xy 184.069905 4.251214) (xy 184.113077 4.291534)
			(xy 184.161337 4.3256) (xy 184.213787 4.352777) (xy 184.269448 4.372559) (xy 184.327285 4.384578)
			(xy 184.38622 4.388609) (xy 184.445155 4.384578) (xy 184.502992 4.372559) (xy 184.558653 4.352777)
			(xy 184.611103 4.3256) (xy 184.659363 4.291534) (xy 184.702535 4.251214) (xy 184.739815 4.205391)
			(xy 184.770508 4.154918) (xy 184.794043 4.100736) (xy 184.80998 4.043854) (xy 184.818024 3.985332)
			(xy 184.818528 3.955796) (xy 184.818528 3.769919) (xy 208.661241 3.769919) (xy 208.661241 3.855669)
			(xy 208.669153 3.941052) (xy 208.684909 4.025342) (xy 208.708376 4.107818) (xy 208.739352 4.187777)
			(xy 208.777574 4.264537) (xy 208.822715 4.337443) (xy 208.874391 4.405872) (xy 208.93216 4.469242)
			(xy 208.99553 4.527011) (xy 209.063959 4.578687) (xy 209.136865 4.623828) (xy 209.213625 4.66205)
			(xy 209.293584 4.693026) (xy 209.37606 4.716493) (xy 209.46035 4.732249) (xy 209.545733 4.740161)
			(xy 209.631483 4.740161) (xy 209.716866 4.732249) (xy 209.801156 4.716493) (xy 209.883632 4.693026)
			(xy 209.963591 4.66205) (xy 209.984264 4.651756) (xy 213.517988 4.651756) (xy 213.517988 5.515356)
			(xy 213.518492 5.54491) (xy 213.526541 5.603466) (xy 213.542487 5.660381) (xy 213.566036 5.714595)
			(xy 213.596747 5.765098) (xy 213.634049 5.810948) (xy 213.677246 5.851291) (xy 213.725535 5.885377)
			(xy 213.778015 5.91257) (xy 213.83371 5.932364) (xy 213.891581 5.94439) (xy 213.95055 5.948424) (xy 214.009519 5.94439)
			(xy 214.06739 5.932364) (xy 214.123085 5.91257) (xy 214.175565 5.885377) (xy 214.223854 5.851291)
			(xy 214.267051 5.810948) (xy 214.304353 5.765098) (xy 214.335064 5.714595) (xy 214.358613 5.660381)
			(xy 214.374559 5.603466) (xy 214.382608 5.54491) (xy 214.383112 5.515356) (xy 214.383112 4.651756)
			(xy 214.382608 4.622202) (xy 214.374559 4.563646) (xy 214.358613 4.506731) (xy 214.335064 4.452517)
			(xy 214.304353 4.402014) (xy 214.267051 4.356164) (xy 214.223854 4.315821) (xy 214.175565 4.281735)
			(xy 214.123085 4.254542) (xy 214.06739 4.234748) (xy 214.009519 4.222722) (xy 213.95055 4.218689)
			(xy 213.891581 4.222722) (xy 213.83371 4.234748) (xy 213.778015 4.254542) (xy 213.725535 4.281735)
			(xy 213.677246 4.315821) (xy 213.634049 4.356164) (xy 213.596747 4.402014) (xy 213.566036 4.452517)
			(xy 213.542487 4.506731) (xy 213.526541 4.563646) (xy 213.518492 4.622202) (xy 213.517988 4.651756)
			(xy 209.984264 4.651756) (xy 210.040351 4.623828) (xy 210.113257 4.578687) (xy 210.181686 4.527011)
			(xy 210.245056 4.469242) (xy 210.302825 4.405872) (xy 210.354501 4.337443) (xy 210.399642 4.264537)
			(xy 210.437864 4.187777) (xy 210.46884 4.107818) (xy 210.492307 4.025342) (xy 210.508063 3.941052)
			(xy 210.515975 3.855669) (xy 210.51647 3.812794) (xy 210.515975 3.769919) (xy 215.011241 3.769919)
			(xy 215.011241 3.855669) (xy 215.019153 3.941052) (xy 215.034909 4.025342) (xy 215.058376 4.107818)
			(xy 215.089352 4.187777) (xy 215.127574 4.264537) (xy 215.172715 4.337443) (xy 215.224391 4.405872)
			(xy 215.28216 4.469242) (xy 215.34553 4.527011) (xy 215.413959 4.578687) (xy 215.486865 4.623828)
			(xy 215.563625 4.66205) (xy 215.643584 4.693026) (xy 215.72606 4.716493) (xy 215.81035 4.732249)
			(xy 215.895733 4.740161) (xy 215.981483 4.740161) (xy 216.066866 4.732249) (xy 216.151156 4.716493)
			(xy 216.233632 4.693026) (xy 216.313591 4.66205) (xy 216.390351 4.623828) (xy 216.463257 4.578687)
			(xy 216.531686 4.527011) (xy 216.595056 4.469242) (xy 216.652825 4.405872) (xy 216.704501 4.337443)
			(xy 216.749642 4.264537) (xy 216.787864 4.187777) (xy 216.81884 4.107818) (xy 216.842307 4.025342)
			(xy 216.858063 3.941052) (xy 216.865975 3.855669) (xy 216.86647 3.812794) (xy 216.865975 3.769919)
			(xy 296.143921 3.769919) (xy 296.143921 3.855669) (xy 296.151833 3.941052) (xy 296.167589 4.025342)
			(xy 296.191056 4.107818) (xy 296.222032 4.187777) (xy 296.260254 4.264537) (xy 296.305395 4.337443)
			(xy 296.357071 4.405872) (xy 296.41484 4.469242) (xy 296.47821 4.527011) (xy 296.546639 4.578687)
			(xy 296.619545 4.623828) (xy 296.696305 4.66205) (xy 296.776264 4.693026) (xy 296.85874 4.716493)
			(xy 296.94303 4.732249) (xy 297.028413 4.740161) (xy 297.114163 4.740161) (xy 297.199546 4.732249)
			(xy 297.283836 4.716493) (xy 297.366312 4.693026) (xy 297.446271 4.66205) (xy 297.466944 4.651756)
			(xy 298.629324 4.651756) (xy 298.629324 5.515356) (xy 298.629828 5.54491) (xy 298.637877 5.603466)
			(xy 298.653823 5.660381) (xy 298.677372 5.714595) (xy 298.708083 5.765098) (xy 298.745385 5.810948)
			(xy 298.788582 5.851291) (xy 298.836871 5.885377) (xy 298.889351 5.91257) (xy 298.945046 5.932364)
			(xy 299.002917 5.94439) (xy 299.061886 5.948424) (xy 299.120855 5.94439) (xy 299.178726 5.932364)
			(xy 299.234421 5.91257) (xy 299.286901 5.885377) (xy 299.33519 5.851291) (xy 299.378387 5.810948)
			(xy 299.415689 5.765098) (xy 299.4464 5.714595) (xy 299.469949 5.660381) (xy 299.485895 5.603466)
			(xy 299.493944 5.54491) (xy 299.494448 5.515356) (xy 299.494448 4.651756) (xy 299.493944 4.622202)
			(xy 299.485895 4.563646) (xy 299.469949 4.506731) (xy 299.4464 4.452517) (xy 299.415689 4.402014)
			(xy 299.378387 4.356164) (xy 299.33519 4.315821) (xy 299.286901 4.281735) (xy 299.234421 4.254542)
			(xy 299.178726 4.234748) (xy 299.120855 4.222722) (xy 299.061886 4.218689) (xy 299.002917 4.222722)
			(xy 298.945046 4.234748) (xy 298.889351 4.254542) (xy 298.836871 4.281735) (xy 298.788582 4.315821)
			(xy 298.745385 4.356164) (xy 298.708083 4.402014) (xy 298.677372 4.452517) (xy 298.653823 4.506731)
			(xy 298.637877 4.563646) (xy 298.629828 4.622202) (xy 298.629324 4.651756) (xy 297.466944 4.651756)
			(xy 297.523031 4.623828) (xy 297.595937 4.578687) (xy 297.664366 4.527011) (xy 297.727736 4.469242)
			(xy 297.785505 4.405872) (xy 297.837181 4.337443) (xy 297.882322 4.264537) (xy 297.920544 4.187777)
			(xy 297.95152 4.107818) (xy 297.974987 4.025342) (xy 297.990743 3.941052) (xy 297.998655 3.855669)
			(xy 297.99915 3.812794) (xy 297.998655 3.769919) (xy 302.493921 3.769919) (xy 302.493921 3.855669)
			(xy 302.501833 3.941052) (xy 302.517589 4.025342) (xy 302.541056 4.107818) (xy 302.572032 4.187777)
			(xy 302.610254 4.264537) (xy 302.655395 4.337443) (xy 302.707071 4.405872) (xy 302.76484 4.469242)
			(xy 302.82821 4.527011) (xy 302.896639 4.578687) (xy 302.969545 4.623828) (xy 303.046305 4.66205)
			(xy 303.126264 4.693026) (xy 303.20874 4.716493) (xy 303.29303 4.732249) (xy 303.378413 4.740161)
			(xy 303.464163 4.740161) (xy 303.549546 4.732249) (xy 303.633836 4.716493) (xy 303.716312 4.693026)
			(xy 303.796271 4.66205) (xy 303.873031 4.623828) (xy 303.945937 4.578687) (xy 304.014366 4.527011)
			(xy 304.077736 4.469242) (xy 304.135505 4.405872) (xy 304.187181 4.337443) (xy 304.232322 4.264537)
			(xy 304.270544 4.187777) (xy 304.30152 4.107818) (xy 304.324987 4.025342) (xy 304.340743 3.941052)
			(xy 304.348655 3.855669) (xy 304.34915 3.812794) (xy 304.348655 3.769919) (xy 311.155321 3.769919)
			(xy 311.155321 3.855669) (xy 311.163233 3.941052) (xy 311.178989 4.025342) (xy 311.202456 4.107818)
			(xy 311.233432 4.187777) (xy 311.271654 4.264537) (xy 311.316795 4.337443) (xy 311.368471 4.405872)
			(xy 311.42624 4.469242) (xy 311.48961 4.527011) (xy 311.558039 4.578687) (xy 311.630945 4.623828)
			(xy 311.707705 4.66205) (xy 311.787664 4.693026) (xy 311.87014 4.716493) (xy 311.95443 4.732249)
			(xy 312.039813 4.740161) (xy 312.125563 4.740161) (xy 312.210946 4.732249) (xy 312.295236 4.716493)
			(xy 312.377712 4.693026) (xy 312.457671 4.66205) (xy 312.478344 4.651756) (xy 316.012068 4.651756)
			(xy 316.012068 5.515356) (xy 316.012572 5.54491) (xy 316.020621 5.603466) (xy 316.036567 5.660381)
			(xy 316.060116 5.714595) (xy 316.090827 5.765098) (xy 316.128129 5.810948) (xy 316.171326 5.851291)
			(xy 316.219615 5.885377) (xy 316.272095 5.91257) (xy 316.32779 5.932364) (xy 316.385661 5.94439)
			(xy 316.44463 5.948424) (xy 316.503599 5.94439) (xy 316.56147 5.932364) (xy 316.617165 5.91257) (xy 316.669645 5.885377)
			(xy 316.717934 5.851291) (xy 316.761131 5.810948) (xy 316.798433 5.765098) (xy 316.829144 5.714595)
			(xy 316.852693 5.660381) (xy 316.868639 5.603466) (xy 316.876688 5.54491) (xy 316.877192 5.515356)
			(xy 316.877192 4.651756) (xy 316.876688 4.622202) (xy 316.868639 4.563646) (xy 316.852693 4.506731)
			(xy 316.829144 4.452517) (xy 316.798433 4.402014) (xy 316.761131 4.356164) (xy 316.717934 4.315821)
			(xy 316.669645 4.281735) (xy 316.617165 4.254542) (xy 316.56147 4.234748) (xy 316.503599 4.222722)
			(xy 316.44463 4.218689) (xy 316.385661 4.222722) (xy 316.32779 4.234748) (xy 316.272095 4.254542)
			(xy 316.219615 4.281735) (xy 316.171326 4.315821) (xy 316.128129 4.356164) (xy 316.090827 4.402014)
			(xy 316.060116 4.452517) (xy 316.036567 4.506731) (xy 316.020621 4.563646) (xy 316.012572 4.622202)
			(xy 316.012068 4.651756) (xy 312.478344 4.651756) (xy 312.534431 4.623828) (xy 312.607337 4.578687)
			(xy 312.675766 4.527011) (xy 312.739136 4.469242) (xy 312.796905 4.405872) (xy 312.848581 4.337443)
			(xy 312.893722 4.264537) (xy 312.931944 4.187777) (xy 312.96292 4.107818) (xy 312.986387 4.025342)
			(xy 313.002143 3.941052) (xy 313.010055 3.855669) (xy 313.01055 3.812794) (xy 313.010055 3.769919)
			(xy 317.505321 3.769919) (xy 317.505321 3.855669) (xy 317.513233 3.941052) (xy 317.528989 4.025342)
			(xy 317.552456 4.107818) (xy 317.583432 4.187777) (xy 317.621654 4.264537) (xy 317.666795 4.337443)
			(xy 317.718471 4.405872) (xy 317.77624 4.469242) (xy 317.83961 4.527011) (xy 317.908039 4.578687)
			(xy 317.980945 4.623828) (xy 318.057705 4.66205) (xy 318.137664 4.693026) (xy 318.22014 4.716493)
			(xy 318.30443 4.732249) (xy 318.389813 4.740161) (xy 318.475563 4.740161) (xy 318.560946 4.732249)
			(xy 318.645236 4.716493) (xy 318.727712 4.693026) (xy 318.807671 4.66205) (xy 318.884431 4.623828)
			(xy 318.957337 4.578687) (xy 319.025766 4.527011) (xy 319.089136 4.469242) (xy 319.146905 4.405872)
			(xy 319.198581 4.337443) (xy 319.243722 4.264537) (xy 319.281944 4.187777) (xy 319.31292 4.107818)
			(xy 319.336387 4.025342) (xy 319.352143 3.941052) (xy 319.360055 3.855669) (xy 319.36055 3.812794)
			(xy 319.360055 3.769919) (xy 361.894107 3.769919) (xy 361.894107 3.855669) (xy 361.902019 3.941052)
			(xy 361.917775 4.025342) (xy 361.941242 4.107818) (xy 361.972218 4.187777) (xy 362.01044 4.264537)
			(xy 362.055581 4.337443) (xy 362.107257 4.405872) (xy 362.165026 4.469242) (xy 362.228396 4.527011)
			(xy 362.296825 4.578687) (xy 362.369731 4.623828) (xy 362.446491 4.66205) (xy 362.52645 4.693026)
			(xy 362.608926 4.716493) (xy 362.693216 4.732249) (xy 362.778599 4.740161) (xy 362.864349 4.740161)
			(xy 362.949732 4.732249) (xy 363.034022 4.716493) (xy 363.116498 4.693026) (xy 363.196457 4.66205)
			(xy 363.21713 4.651756) (xy 364.379764 4.651756) (xy 364.379764 5.515356) (xy 364.380268 5.544892)
			(xy 364.388312 5.603414) (xy 364.404249 5.660296) (xy 364.427784 5.714478) (xy 364.458477 5.764951)
			(xy 364.495757 5.810774) (xy 364.538929 5.851094) (xy 364.587189 5.88516) (xy 364.639639 5.912337)
			(xy 364.6953 5.932119) (xy 364.753137 5.944138) (xy 364.812072 5.948169) (xy 364.871007 5.944138)
			(xy 364.928844 5.932119) (xy 364.984505 5.912337) (xy 365.036955 5.88516) (xy 365.085215 5.851094)
			(xy 365.128387 5.810774) (xy 365.165667 5.764951) (xy 365.19636 5.714478) (xy 365.219895 5.660296)
			(xy 365.235832 5.603414) (xy 365.243876 5.544892) (xy 365.24438 5.515356) (xy 365.24438 4.836973)
			(xy 385.651997 4.836973) (xy 385.651997 4.922723) (xy 385.659909 5.008106) (xy 385.675665 5.092396)
			(xy 385.699132 5.174872) (xy 385.730108 5.254831) (xy 385.76833 5.331591) (xy 385.813471 5.404497)
			(xy 385.865147 5.472926) (xy 385.922916 5.536296) (xy 385.986286 5.594065) (xy 386.054715 5.645741)
			(xy 386.127621 5.690882) (xy 386.204381 5.729104) (xy 386.28434 5.76008) (xy 386.366816 5.783547)
			(xy 386.451106 5.799303) (xy 386.536489 5.807215) (xy 386.622239 5.807215) (xy 386.707622 5.799303)
			(xy 386.791912 5.783547) (xy 386.874388 5.76008) (xy 386.954347 5.729104) (xy 386.97502 5.71881)
			(xy 390.508744 5.71881) (xy 390.508744 6.58241) (xy 390.509248 6.611964) (xy 390.517297 6.67052)
			(xy 390.533243 6.727435) (xy 390.556792 6.781649) (xy 390.587503 6.832152) (xy 390.624805 6.878002)
			(xy 390.668002 6.918345) (xy 390.716291 6.952431) (xy 390.768771 6.979624) (xy 390.824466 6.999418)
			(xy 390.882337 7.011444) (xy 390.941306 7.015478) (xy 391.000275 7.011444) (xy 391.058146 6.999418)
			(xy 391.113841 6.979624) (xy 391.166321 6.952431) (xy 391.21461 6.918345) (xy 391.257807 6.878002)
			(xy 391.295109 6.832152) (xy 391.32582 6.781649) (xy 391.349369 6.727435) (xy 391.365315 6.67052)
			(xy 391.373364 6.611964) (xy 391.373868 6.58241) (xy 391.373868 5.71881) (xy 391.373364 5.689256)
			(xy 391.365315 5.6307) (xy 391.349369 5.573785) (xy 391.32582 5.519571) (xy 391.295109 5.469068)
			(xy 391.257807 5.423218) (xy 391.21461 5.382875) (xy 391.166321 5.348789) (xy 391.113841 5.321596)
			(xy 391.058146 5.301802) (xy 391.000275 5.289776) (xy 390.941306 5.285743) (xy 390.882337 5.289776)
			(xy 390.824466 5.301802) (xy 390.768771 5.321596) (xy 390.716291 5.348789) (xy 390.668002 5.382875)
			(xy 390.624805 5.423218) (xy 390.587503 5.469068) (xy 390.556792 5.519571) (xy 390.533243 5.573785)
			(xy 390.517297 5.6307) (xy 390.509248 5.689256) (xy 390.508744 5.71881) (xy 386.97502 5.71881) (xy 387.031107 5.690882)
			(xy 387.104013 5.645741) (xy 387.172442 5.594065) (xy 387.235812 5.536296) (xy 387.293581 5.472926)
			(xy 387.345257 5.404497) (xy 387.390398 5.331591) (xy 387.42862 5.254831) (xy 387.459596 5.174872)
			(xy 387.483063 5.092396) (xy 387.498819 5.008106) (xy 387.506731 4.922723) (xy 387.507226 4.879848)
			(xy 387.506731 4.836973) (xy 392.001997 4.836973) (xy 392.001997 4.922723) (xy 392.009909 5.008106)
			(xy 392.025665 5.092396) (xy 392.049132 5.174872) (xy 392.080108 5.254831) (xy 392.11833 5.331591)
			(xy 392.163471 5.404497) (xy 392.215147 5.472926) (xy 392.272916 5.536296) (xy 392.336286 5.594065)
			(xy 392.404715 5.645741) (xy 392.477621 5.690882) (xy 392.554381 5.729104) (xy 392.63434 5.76008)
			(xy 392.716816 5.783547) (xy 392.801106 5.799303) (xy 392.886489 5.807215) (xy 392.972239 5.807215)
			(xy 393.057622 5.799303) (xy 393.141912 5.783547) (xy 393.224388 5.76008) (xy 393.304347 5.729104)
			(xy 393.381107 5.690882) (xy 393.454013 5.645741) (xy 393.522442 5.594065) (xy 393.585812 5.536296)
			(xy 393.643581 5.472926) (xy 393.695257 5.404497) (xy 393.740398 5.331591) (xy 393.77862 5.254831)
			(xy 393.809596 5.174872) (xy 393.833063 5.092396) (xy 393.848819 5.008106) (xy 393.856731 4.922723)
			(xy 393.857226 4.879848) (xy 393.856731 4.836973) (xy 436.390783 4.836973) (xy 436.390783 4.922723)
			(xy 436.398695 5.008106) (xy 436.414451 5.092396) (xy 436.437918 5.174872) (xy 436.468894 5.254831)
			(xy 436.507116 5.331591) (xy 436.552257 5.404497) (xy 436.603933 5.472926) (xy 436.661702 5.536296)
			(xy 436.725072 5.594065) (xy 436.793501 5.645741) (xy 436.866407 5.690882) (xy 436.943167 5.729104)
			(xy 437.023126 5.76008) (xy 437.105602 5.783547) (xy 437.189892 5.799303) (xy 437.275275 5.807215)
			(xy 437.361025 5.807215) (xy 437.446408 5.799303) (xy 437.530698 5.783547) (xy 437.613174 5.76008)
			(xy 437.693133 5.729104) (xy 437.713806 5.71881) (xy 438.87644 5.71881) (xy 438.87644 6.58241) (xy 438.876944 6.611946)
			(xy 438.884988 6.670468) (xy 438.900925 6.72735) (xy 438.92446 6.781532) (xy 438.955153 6.832005)
			(xy 438.992433 6.877828) (xy 439.035605 6.918148) (xy 439.083865 6.952214) (xy 439.136315 6.979391)
			(xy 439.191976 6.999173) (xy 439.249813 7.011192) (xy 439.308748 7.015223) (xy 439.367683 7.011192)
			(xy 439.42552 6.999173) (xy 439.481181 6.979391) (xy 439.533631 6.952214) (xy 439.581891 6.918148)
			(xy 439.625063 6.877828) (xy 439.662343 6.832005) (xy 439.693036 6.781532) (xy 439.716571 6.72735)
			(xy 439.732508 6.670468) (xy 439.740552 6.611946) (xy 439.741056 6.58241) (xy 439.741056 5.71881)
			(xy 439.740552 5.689274) (xy 439.732508 5.630752) (xy 439.716571 5.57387) (xy 439.693036 5.519688)
			(xy 439.662343 5.469215) (xy 439.625063 5.423392) (xy 439.581891 5.383072) (xy 439.533631 5.349006)
			(xy 439.481181 5.321829) (xy 439.42552 5.302047) (xy 439.367683 5.290028) (xy 439.308748 5.285997)
			(xy 439.249813 5.290028) (xy 439.191976 5.302047) (xy 439.136315 5.321829) (xy 439.083865 5.349006)
			(xy 439.035605 5.383072) (xy 438.992433 5.423392) (xy 438.955153 5.469215) (xy 438.92446 5.519688)
			(xy 438.900925 5.57387) (xy 438.884988 5.630752) (xy 438.876944 5.689274) (xy 438.87644 5.71881)
			(xy 437.713806 5.71881) (xy 437.769893 5.690882) (xy 437.842799 5.645741) (xy 437.911228 5.594065)
			(xy 437.974598 5.536296) (xy 438.032367 5.472926) (xy 438.084043 5.404497) (xy 438.129184 5.331591)
			(xy 438.167406 5.254831) (xy 438.198382 5.174872) (xy 438.221849 5.092396) (xy 438.237605 5.008106)
			(xy 438.245517 4.922723) (xy 438.246012 4.879848) (xy 438.245517 4.836973) (xy 442.740783 4.836973)
			(xy 442.740783 4.922723) (xy 442.748695 5.008106) (xy 442.764451 5.092396) (xy 442.787918 5.174872)
			(xy 442.818894 5.254831) (xy 442.857116 5.331591) (xy 442.902257 5.404497) (xy 442.953933 5.472926)
			(xy 443.011702 5.536296) (xy 443.075072 5.594065) (xy 443.143501 5.645741) (xy 443.216407 5.690882)
			(xy 443.293167 5.729104) (xy 443.373126 5.76008) (xy 443.455602 5.783547) (xy 443.539892 5.799303)
			(xy 443.625275 5.807215) (xy 443.711025 5.807215) (xy 443.796408 5.799303) (xy 443.880698 5.783547)
			(xy 443.963174 5.76008) (xy 444.043133 5.729104) (xy 444.119893 5.690882) (xy 444.192799 5.645741)
			(xy 444.261228 5.594065) (xy 444.324598 5.536296) (xy 444.382367 5.472926) (xy 444.434043 5.404497)
			(xy 444.479184 5.331591) (xy 444.517406 5.254831) (xy 444.548382 5.174872) (xy 444.571849 5.092396)
			(xy 444.587605 5.008106) (xy 444.595517 4.922723) (xy 444.596012 4.879848) (xy 444.595517 4.836973)
			(xy 444.587605 4.75159) (xy 444.571849 4.6673) (xy 444.548382 4.584824) (xy 444.517406 4.504865)
			(xy 444.479184 4.428105) (xy 444.434043 4.355199) (xy 444.382367 4.28677) (xy 444.324598 4.2234)
			(xy 444.261228 4.165631) (xy 444.192799 4.113955) (xy 444.119893 4.068814) (xy 444.043133 4.030592)
			(xy 443.963174 3.999616) (xy 443.880698 3.976149) (xy 443.796408 3.960393) (xy 443.711025 3.952481)
			(xy 443.625275 3.952481) (xy 443.539892 3.960393) (xy 443.455602 3.976149) (xy 443.373126 3.999616)
			(xy 443.293167 4.030592) (xy 443.216407 4.068814) (xy 443.143501 4.113955) (xy 443.075072 4.165631)
			(xy 443.011702 4.2234) (xy 442.953933 4.28677) (xy 442.902257 4.355199) (xy 442.857116 4.428105)
			(xy 442.818894 4.504865) (xy 442.787918 4.584824) (xy 442.764451 4.6673) (xy 442.748695 4.75159)
			(xy 442.740783 4.836973) (xy 438.245517 4.836973) (xy 438.237605 4.75159) (xy 438.221849 4.6673)
			(xy 438.198382 4.584824) (xy 438.167406 4.504865) (xy 438.129184 4.428105) (xy 438.084043 4.355199)
			(xy 438.032367 4.28677) (xy 437.974598 4.2234) (xy 437.911228 4.165631) (xy 437.842799 4.113955)
			(xy 437.769893 4.068814) (xy 437.693133 4.030592) (xy 437.613174 3.999616) (xy 437.530698 3.976149)
			(xy 437.446408 3.960393) (xy 437.361025 3.952481) (xy 437.275275 3.952481) (xy 437.189892 3.960393)
			(xy 437.105602 3.976149) (xy 437.023126 3.999616) (xy 436.943167 4.030592) (xy 436.866407 4.068814)
			(xy 436.793501 4.113955) (xy 436.725072 4.165631) (xy 436.661702 4.2234) (xy 436.603933 4.28677)
			(xy 436.552257 4.355199) (xy 436.507116 4.428105) (xy 436.468894 4.504865) (xy 436.437918 4.584824)
			(xy 436.414451 4.6673) (xy 436.398695 4.75159) (xy 436.390783 4.836973) (xy 393.856731 4.836973)
			(xy 393.848819 4.75159) (xy 393.833063 4.6673) (xy 393.809596 4.584824) (xy 393.77862 4.504865) (xy 393.740398 4.428105)
			(xy 393.695257 4.355199) (xy 393.643581 4.28677) (xy 393.585812 4.2234) (xy 393.522442 4.165631)
			(xy 393.454013 4.113955) (xy 393.381107 4.068814) (xy 393.304347 4.030592) (xy 393.224388 3.999616)
			(xy 393.141912 3.976149) (xy 393.057622 3.960393) (xy 392.972239 3.952481) (xy 392.886489 3.952481)
			(xy 392.801106 3.960393) (xy 392.716816 3.976149) (xy 392.63434 3.999616) (xy 392.554381 4.030592)
			(xy 392.477621 4.068814) (xy 392.404715 4.113955) (xy 392.336286 4.165631) (xy 392.272916 4.2234)
			(xy 392.215147 4.28677) (xy 392.163471 4.355199) (xy 392.11833 4.428105) (xy 392.080108 4.504865)
			(xy 392.049132 4.584824) (xy 392.025665 4.6673) (xy 392.009909 4.75159) (xy 392.001997 4.836973)
			(xy 387.506731 4.836973) (xy 387.498819 4.75159) (xy 387.483063 4.6673) (xy 387.459596 4.584824)
			(xy 387.42862 4.504865) (xy 387.390398 4.428105) (xy 387.345257 4.355199) (xy 387.293581 4.28677)
			(xy 387.235812 4.2234) (xy 387.172442 4.165631) (xy 387.104013 4.113955) (xy 387.031107 4.068814)
			(xy 386.954347 4.030592) (xy 386.874388 3.999616) (xy 386.791912 3.976149) (xy 386.707622 3.960393)
			(xy 386.622239 3.952481) (xy 386.536489 3.952481) (xy 386.451106 3.960393) (xy 386.366816 3.976149)
			(xy 386.28434 3.999616) (xy 386.204381 4.030592) (xy 386.127621 4.068814) (xy 386.054715 4.113955)
			(xy 385.986286 4.165631) (xy 385.922916 4.2234) (xy 385.865147 4.28677) (xy 385.813471 4.355199)
			(xy 385.76833 4.428105) (xy 385.730108 4.504865) (xy 385.699132 4.584824) (xy 385.675665 4.6673)
			(xy 385.659909 4.75159) (xy 385.651997 4.836973) (xy 365.24438 4.836973) (xy 365.24438 4.651756)
			(xy 365.243876 4.62222) (xy 365.235832 4.563698) (xy 365.219895 4.506816) (xy 365.19636 4.452634)
			(xy 365.165667 4.402161) (xy 365.128387 4.356338) (xy 365.085215 4.316018) (xy 365.036955 4.281952)
			(xy 364.984505 4.254775) (xy 364.928844 4.234993) (xy 364.871007 4.222974) (xy 364.812072 4.218943)
			(xy 364.753137 4.222974) (xy 364.6953 4.234993) (xy 364.639639 4.254775) (xy 364.587189 4.281952)
			(xy 364.538929 4.316018) (xy 364.495757 4.356338) (xy 364.458477 4.402161) (xy 364.427784 4.452634)
			(xy 364.404249 4.506816) (xy 364.388312 4.563698) (xy 364.380268 4.62222) (xy 364.379764 4.651756)
			(xy 363.21713 4.651756) (xy 363.273217 4.623828) (xy 363.346123 4.578687) (xy 363.414552 4.527011)
			(xy 363.477922 4.469242) (xy 363.535691 4.405872) (xy 363.587367 4.337443) (xy 363.632508 4.264537)
			(xy 363.67073 4.187777) (xy 363.701706 4.107818) (xy 363.725173 4.025342) (xy 363.740929 3.941052)
			(xy 363.748841 3.855669) (xy 363.749336 3.812794) (xy 363.748841 3.769919) (xy 368.244107 3.769919)
			(xy 368.244107 3.855669) (xy 368.252019 3.941052) (xy 368.267775 4.025342) (xy 368.291242 4.107818)
			(xy 368.322218 4.187777) (xy 368.36044 4.264537) (xy 368.405581 4.337443) (xy 368.457257 4.405872)
			(xy 368.515026 4.469242) (xy 368.578396 4.527011) (xy 368.646825 4.578687) (xy 368.719731 4.623828)
			(xy 368.796491 4.66205) (xy 368.87645 4.693026) (xy 368.958926 4.716493) (xy 369.043216 4.732249)
			(xy 369.128599 4.740161) (xy 369.214349 4.740161) (xy 369.299732 4.732249) (xy 369.384022 4.716493)
			(xy 369.466498 4.693026) (xy 369.546457 4.66205) (xy 369.623217 4.623828) (xy 369.696123 4.578687)
			(xy 369.764552 4.527011) (xy 369.827922 4.469242) (xy 369.885691 4.405872) (xy 369.937367 4.337443)
			(xy 369.982508 4.264537) (xy 370.02073 4.187777) (xy 370.051706 4.107818) (xy 370.075173 4.025342)
			(xy 370.090929 3.941052) (xy 370.098841 3.855669) (xy 370.099336 3.812794) (xy 370.098841 3.769919)
			(xy 370.090929 3.684536) (xy 370.075173 3.600246) (xy 370.051706 3.51777) (xy 370.02073 3.437811)
			(xy 369.982508 3.361051) (xy 369.937367 3.288145) (xy 369.885691 3.219716) (xy 369.827922 3.156346)
			(xy 369.764552 3.098577) (xy 369.696123 3.046901) (xy 369.623217 3.00176) (xy 369.546457 2.963538)
			(xy 369.466498 2.932562) (xy 369.384022 2.909095) (xy 369.299732 2.893339) (xy 369.214349 2.885427)
			(xy 369.128599 2.885427) (xy 369.043216 2.893339) (xy 368.958926 2.909095) (xy 368.87645 2.932562)
			(xy 368.796491 2.963538) (xy 368.719731 3.00176) (xy 368.646825 3.046901) (xy 368.578396 3.098577)
			(xy 368.515026 3.156346) (xy 368.457257 3.219716) (xy 368.405581 3.288145) (xy 368.36044 3.361051)
			(xy 368.322218 3.437811) (xy 368.291242 3.51777) (xy 368.267775 3.600246) (xy 368.252019 3.684536)
			(xy 368.244107 3.769919) (xy 363.748841 3.769919) (xy 363.740929 3.684536) (xy 363.725173 3.600246)
			(xy 363.701706 3.51777) (xy 363.67073 3.437811) (xy 363.632508 3.361051) (xy 363.587367 3.288145)
			(xy 363.535691 3.219716) (xy 363.477922 3.156346) (xy 363.414552 3.098577) (xy 363.346123 3.046901)
			(xy 363.273217 3.00176) (xy 363.196457 2.963538) (xy 363.116498 2.932562) (xy 363.034022 2.909095)
			(xy 362.949732 2.893339) (xy 362.864349 2.885427) (xy 362.778599 2.885427) (xy 362.693216 2.893339)
			(xy 362.608926 2.909095) (xy 362.52645 2.932562) (xy 362.446491 2.963538) (xy 362.369731 3.00176)
			(xy 362.296825 3.046901) (xy 362.228396 3.098577) (xy 362.165026 3.156346) (xy 362.107257 3.219716)
			(xy 362.055581 3.288145) (xy 362.01044 3.361051) (xy 361.972218 3.437811) (xy 361.941242 3.51777)
			(xy 361.917775 3.600246) (xy 361.902019 3.684536) (xy 361.894107 3.769919) (xy 319.360055 3.769919)
			(xy 319.352143 3.684536) (xy 319.336387 3.600246) (xy 319.31292 3.51777) (xy 319.281944 3.437811)
			(xy 319.243722 3.361051) (xy 319.198581 3.288145) (xy 319.146905 3.219716) (xy 319.089136 3.156346)
			(xy 319.025766 3.098577) (xy 318.957337 3.046901) (xy 318.884431 3.00176) (xy 318.807671 2.963538)
			(xy 318.727712 2.932562) (xy 318.645236 2.909095) (xy 318.560946 2.893339) (xy 318.475563 2.885427)
			(xy 318.389813 2.885427) (xy 318.30443 2.893339) (xy 318.22014 2.909095) (xy 318.137664 2.932562)
			(xy 318.057705 2.963538) (xy 317.980945 3.00176) (xy 317.908039 3.046901) (xy 317.83961 3.098577)
			(xy 317.77624 3.156346) (xy 317.718471 3.219716) (xy 317.666795 3.288145) (xy 317.621654 3.361051)
			(xy 317.583432 3.437811) (xy 317.552456 3.51777) (xy 317.528989 3.600246) (xy 317.513233 3.684536)
			(xy 317.505321 3.769919) (xy 313.010055 3.769919) (xy 313.002143 3.684536) (xy 312.986387 3.600246)
			(xy 312.96292 3.51777) (xy 312.931944 3.437811) (xy 312.893722 3.361051) (xy 312.848581 3.288145)
			(xy 312.796905 3.219716) (xy 312.739136 3.156346) (xy 312.675766 3.098577) (xy 312.607337 3.046901)
			(xy 312.534431 3.00176) (xy 312.457671 2.963538) (xy 312.377712 2.932562) (xy 312.295236 2.909095)
			(xy 312.210946 2.893339) (xy 312.125563 2.885427) (xy 312.039813 2.885427) (xy 311.95443 2.893339)
			(xy 311.87014 2.909095) (xy 311.787664 2.932562) (xy 311.707705 2.963538) (xy 311.630945 3.00176)
			(xy 311.558039 3.046901) (xy 311.48961 3.098577) (xy 311.42624 3.156346) (xy 311.368471 3.219716)
			(xy 311.316795 3.288145) (xy 311.271654 3.361051) (xy 311.233432 3.437811) (xy 311.202456 3.51777)
			(xy 311.178989 3.600246) (xy 311.163233 3.684536) (xy 311.155321 3.769919) (xy 304.348655 3.769919)
			(xy 304.340743 3.684536) (xy 304.324987 3.600246) (xy 304.30152 3.51777) (xy 304.270544 3.437811)
			(xy 304.232322 3.361051) (xy 304.187181 3.288145) (xy 304.135505 3.219716) (xy 304.077736 3.156346)
			(xy 304.014366 3.098577) (xy 303.945937 3.046901) (xy 303.873031 3.00176) (xy 303.796271 2.963538)
			(xy 303.716312 2.932562) (xy 303.633836 2.909095) (xy 303.549546 2.893339) (xy 303.464163 2.885427)
			(xy 303.378413 2.885427) (xy 303.29303 2.893339) (xy 303.20874 2.909095) (xy 303.126264 2.932562)
			(xy 303.046305 2.963538) (xy 302.969545 3.00176) (xy 302.896639 3.046901) (xy 302.82821 3.098577)
			(xy 302.76484 3.156346) (xy 302.707071 3.219716) (xy 302.655395 3.288145) (xy 302.610254 3.361051)
			(xy 302.572032 3.437811) (xy 302.541056 3.51777) (xy 302.517589 3.600246) (xy 302.501833 3.684536)
			(xy 302.493921 3.769919) (xy 297.998655 3.769919) (xy 297.990743 3.684536) (xy 297.974987 3.600246)
			(xy 297.95152 3.51777) (xy 297.920544 3.437811) (xy 297.882322 3.361051) (xy 297.837181 3.288145)
			(xy 297.785505 3.219716) (xy 297.727736 3.156346) (xy 297.664366 3.098577) (xy 297.595937 3.046901)
			(xy 297.523031 3.00176) (xy 297.446271 2.963538) (xy 297.366312 2.932562) (xy 297.283836 2.909095)
			(xy 297.199546 2.893339) (xy 297.114163 2.885427) (xy 297.028413 2.885427) (xy 296.94303 2.893339)
			(xy 296.85874 2.909095) (xy 296.776264 2.932562) (xy 296.696305 2.963538) (xy 296.619545 3.00176)
			(xy 296.546639 3.046901) (xy 296.47821 3.098577) (xy 296.41484 3.156346) (xy 296.357071 3.219716)
			(xy 296.305395 3.288145) (xy 296.260254 3.361051) (xy 296.222032 3.437811) (xy 296.191056 3.51777)
			(xy 296.167589 3.600246) (xy 296.151833 3.684536) (xy 296.143921 3.769919) (xy 216.865975 3.769919)
			(xy 216.858063 3.684536) (xy 216.842307 3.600246) (xy 216.81884 3.51777) (xy 216.787864 3.437811)
			(xy 216.749642 3.361051) (xy 216.704501 3.288145) (xy 216.652825 3.219716) (xy 216.595056 3.156346)
			(xy 216.531686 3.098577) (xy 216.463257 3.046901) (xy 216.390351 3.00176) (xy 216.313591 2.963538)
			(xy 216.233632 2.932562) (xy 216.151156 2.909095) (xy 216.066866 2.893339) (xy 215.981483 2.885427)
			(xy 215.895733 2.885427) (xy 215.81035 2.893339) (xy 215.72606 2.909095) (xy 215.643584 2.932562)
			(xy 215.563625 2.963538) (xy 215.486865 3.00176) (xy 215.413959 3.046901) (xy 215.34553 3.098577)
			(xy 215.28216 3.156346) (xy 215.224391 3.219716) (xy 215.172715 3.288145) (xy 215.127574 3.361051)
			(xy 215.089352 3.437811) (xy 215.058376 3.51777) (xy 215.034909 3.600246) (xy 215.019153 3.684536)
			(xy 215.011241 3.769919) (xy 210.515975 3.769919) (xy 210.508063 3.684536) (xy 210.492307 3.600246)
			(xy 210.46884 3.51777) (xy 210.437864 3.437811) (xy 210.399642 3.361051) (xy 210.354501 3.288145)
			(xy 210.302825 3.219716) (xy 210.245056 3.156346) (xy 210.181686 3.098577) (xy 210.113257 3.046901)
			(xy 210.040351 3.00176) (xy 209.963591 2.963538) (xy 209.883632 2.932562) (xy 209.801156 2.909095)
			(xy 209.716866 2.893339) (xy 209.631483 2.885427) (xy 209.545733 2.885427) (xy 209.46035 2.893339)
			(xy 209.37606 2.909095) (xy 209.293584 2.932562) (xy 209.213625 2.963538) (xy 209.136865 3.00176)
			(xy 209.063959 3.046901) (xy 208.99553 3.098577) (xy 208.93216 3.156346) (xy 208.874391 3.219716)
			(xy 208.822715 3.288145) (xy 208.777574 3.361051) (xy 208.739352 3.437811) (xy 208.708376 3.51777)
			(xy 208.684909 3.600246) (xy 208.669153 3.684536) (xy 208.661241 3.769919) (xy 184.818528 3.769919)
			(xy 184.818528 3.092196) (xy 184.818024 3.06266) (xy 184.80998 3.004138) (xy 184.794043 2.947256)
			(xy 184.770508 2.893074) (xy 184.739815 2.842601) (xy 184.702535 2.796778) (xy 184.659363 2.756458)
			(xy 184.611103 2.722392) (xy 184.558653 2.695215) (xy 184.502992 2.675433) (xy 184.445155 2.663414)
			(xy 184.38622 2.659383) (xy 184.327285 2.663414) (xy 184.269448 2.675433) (xy 184.213787 2.695215)
			(xy 184.161337 2.722392) (xy 184.113077 2.756458) (xy 184.069905 2.796778) (xy 184.032625 2.842601)
			(xy 184.001932 2.893074) (xy 183.978397 2.947256) (xy 183.96246 3.004138) (xy 183.954416 3.06266)
			(xy 183.953912 3.092196) (xy 182.791278 3.092196) (xy 182.847365 3.064268) (xy 182.920271 3.019127)
			(xy 182.9887 2.967451) (xy 183.05207 2.909682) (xy 183.109839 2.846312) (xy 183.161515 2.777883)
			(xy 183.206656 2.704977) (xy 183.244878 2.628217) (xy 183.275854 2.548258) (xy 183.299321 2.465782)
			(xy 183.315077 2.381492) (xy 183.322989 2.296109) (xy 183.323484 2.253234) (xy 183.322989 2.210359)
			(xy 187.818255 2.210359) (xy 187.818255 2.296109) (xy 187.826167 2.381492) (xy 187.841923 2.465782)
			(xy 187.86539 2.548258) (xy 187.896366 2.628217) (xy 187.934588 2.704977) (xy 187.979729 2.777883)
			(xy 188.031405 2.846312) (xy 188.089174 2.909682) (xy 188.152544 2.967451) (xy 188.220973 3.019127)
			(xy 188.293879 3.064268) (xy 188.370639 3.10249) (xy 188.450598 3.133466) (xy 188.533074 3.156933)
			(xy 188.617364 3.172689) (xy 188.702747 3.180601) (xy 188.788497 3.180601) (xy 188.87388 3.172689)
			(xy 188.95817 3.156933) (xy 189.040646 3.133466) (xy 189.120605 3.10249) (xy 189.197365 3.064268)
			(xy 189.270271 3.019127) (xy 189.3387 2.967451) (xy 189.40207 2.909682) (xy 189.459839 2.846312)
			(xy 189.511515 2.777883) (xy 189.556656 2.704977) (xy 189.594878 2.628217) (xy 189.625854 2.548258)
			(xy 189.649321 2.465782) (xy 189.665077 2.381492) (xy 189.672989 2.296109) (xy 189.673484 2.253234)
			(xy 189.672989 2.210359) (xy 189.665077 2.124976) (xy 189.649321 2.040686) (xy 189.625854 1.95821)
			(xy 189.594878 1.878251) (xy 189.556656 1.801491) (xy 189.511515 1.728585) (xy 189.459839 1.660156)
			(xy 189.40207 1.596786) (xy 189.3387 1.539017) (xy 189.270271 1.487341) (xy 189.197365 1.4422) (xy 189.120605 1.403978)
			(xy 189.040646 1.373002) (xy 188.95817 1.349535) (xy 188.87388 1.333779) (xy 188.788497 1.325867)
			(xy 188.702747 1.325867) (xy 188.617364 1.333779) (xy 188.533074 1.349535) (xy 188.450598 1.373002)
			(xy 188.370639 1.403978) (xy 188.293879 1.4422) (xy 188.220973 1.487341) (xy 188.152544 1.539017)
			(xy 188.089174 1.596786) (xy 188.031405 1.660156) (xy 187.979729 1.728585) (xy 187.934588 1.801491)
			(xy 187.896366 1.878251) (xy 187.86539 1.95821) (xy 187.841923 2.040686) (xy 187.826167 2.124976)
			(xy 187.818255 2.210359) (xy 183.322989 2.210359) (xy 183.315077 2.124976) (xy 183.299321 2.040686)
			(xy 183.275854 1.95821) (xy 183.244878 1.878251) (xy 183.206656 1.801491) (xy 183.161515 1.728585)
			(xy 183.109839 1.660156) (xy 183.05207 1.596786) (xy 182.9887 1.539017) (xy 182.920271 1.487341)
			(xy 182.847365 1.4422) (xy 182.770605 1.403978) (xy 182.690646 1.373002) (xy 182.60817 1.349535)
			(xy 182.52388 1.333779) (xy 182.438497 1.325867) (xy 182.352747 1.325867) (xy 182.267364 1.333779)
			(xy 182.183074 1.349535) (xy 182.100598 1.373002) (xy 182.020639 1.403978) (xy 181.943879 1.4422)
			(xy 181.870973 1.487341) (xy 181.802544 1.539017) (xy 181.739174 1.596786) (xy 181.681405 1.660156)
			(xy 181.629729 1.728585) (xy 181.584588 1.801491) (xy 181.546366 1.878251) (xy 181.51539 1.95821)
			(xy 181.491923 2.040686) (xy 181.476167 2.124976) (xy 181.468255 2.210359) (xy 102.190309 2.210359)
			(xy 102.182397 2.124976) (xy 102.166641 2.040686) (xy 102.143174 1.95821) (xy 102.112198 1.878251)
			(xy 102.073976 1.801491) (xy 102.028835 1.728585) (xy 101.977159 1.660156) (xy 101.91939 1.596786)
			(xy 101.85602 1.539017) (xy 101.787591 1.487341) (xy 101.714685 1.4422) (xy 101.637925 1.403978)
			(xy 101.557966 1.373002) (xy 101.47549 1.349535) (xy 101.3912 1.333779) (xy 101.305817 1.325867)
			(xy 101.220067 1.325867) (xy 101.134684 1.333779) (xy 101.050394 1.349535) (xy 100.967918 1.373002)
			(xy 100.887959 1.403978) (xy 100.811199 1.4422) (xy 100.738293 1.487341) (xy 100.669864 1.539017)
			(xy 100.606494 1.596786) (xy 100.548725 1.660156) (xy 100.497049 1.728585) (xy 100.451908 1.801491)
			(xy 100.413686 1.878251) (xy 100.38271 1.95821) (xy 100.359243 2.040686) (xy 100.343487 2.124976)
			(xy 100.335575 2.210359) (xy 95.840309 2.210359) (xy 95.832397 2.124976) (xy 95.816641 2.040686)
			(xy 95.793174 1.95821) (xy 95.762198 1.878251) (xy 95.723976 1.801491) (xy 95.678835 1.728585) (xy 95.627159 1.660156)
			(xy 95.56939 1.596786) (xy 95.50602 1.539017) (xy 95.437591 1.487341) (xy 95.364685 1.4422) (xy 95.287925 1.403978)
			(xy 95.207966 1.373002) (xy 95.12549 1.349535) (xy 95.0412 1.333779) (xy 94.955817 1.325867) (xy 94.870067 1.325867)
			(xy 94.784684 1.333779) (xy 94.700394 1.349535) (xy 94.617918 1.373002) (xy 94.537959 1.403978) (xy 94.461199 1.4422)
			(xy 94.388293 1.487341) (xy 94.319864 1.539017) (xy 94.256494 1.596786) (xy 94.198725 1.660156) (xy 94.147049 1.728585)
			(xy 94.101908 1.801491) (xy 94.063686 1.878251) (xy 94.03271 1.95821) (xy 94.009243 2.040686) (xy 93.993487 2.124976)
			(xy 93.985575 2.210359) (xy 83.439191 2.210359) (xy 83.525475 2.124078) (xy 83.619275 2.019118) (xy 83.707042 1.909064)
			(xy 83.788501 1.794262) (xy 83.863394 1.675073) (xy 83.931487 1.551873) (xy 83.992565 1.425048) (xy 84.046435 1.294999)
			(xy 84.069209 1.229919) (xy 208.661241 1.229919) (xy 208.661241 1.315669) (xy 208.669153 1.401052)
			(xy 208.684909 1.485342) (xy 208.708376 1.567818) (xy 208.739352 1.647777) (xy 208.777574 1.724537)
			(xy 208.822715 1.797443) (xy 208.874391 1.865872) (xy 208.93216 1.929242) (xy 208.99553 1.987011)
			(xy 209.063959 2.038687) (xy 209.136865 2.083828) (xy 209.213625 2.12205) (xy 209.293584 2.153026)
			(xy 209.37606 2.176493) (xy 209.46035 2.192249) (xy 209.545733 2.200161) (xy 209.631483 2.200161)
			(xy 209.716866 2.192249) (xy 209.801156 2.176493) (xy 209.883632 2.153026) (xy 209.963591 2.12205)
			(xy 209.984264 2.111756) (xy 213.517988 2.111756) (xy 213.517988 2.975356) (xy 213.518492 3.00491)
			(xy 213.526541 3.063466) (xy 213.542487 3.120381) (xy 213.566036 3.174595) (xy 213.596747 3.225098)
			(xy 213.634049 3.270948) (xy 213.677246 3.311291) (xy 213.725535 3.345377) (xy 213.778015 3.37257)
			(xy 213.83371 3.392364) (xy 213.891581 3.40439) (xy 213.95055 3.408424) (xy 214.009519 3.40439) (xy 214.06739 3.392364)
			(xy 214.123085 3.37257) (xy 214.175565 3.345377) (xy 214.223854 3.311291) (xy 214.267051 3.270948)
			(xy 214.304353 3.225098) (xy 214.335064 3.174595) (xy 214.358613 3.120381) (xy 214.374559 3.063466)
			(xy 214.382608 3.00491) (xy 214.383112 2.975356) (xy 214.383112 2.111756) (xy 214.382608 2.082202)
			(xy 214.374559 2.023646) (xy 214.358613 1.966731) (xy 214.335064 1.912517) (xy 214.304353 1.862014)
			(xy 214.267051 1.816164) (xy 214.223854 1.775821) (xy 214.175565 1.741735) (xy 214.123085 1.714542)
			(xy 214.06739 1.694748) (xy 214.009519 1.682722) (xy 213.95055 1.678689) (xy 213.891581 1.682722)
			(xy 213.83371 1.694748) (xy 213.778015 1.714542) (xy 213.725535 1.741735) (xy 213.677246 1.775821)
			(xy 213.634049 1.816164) (xy 213.596747 1.862014) (xy 213.566036 1.912517) (xy 213.542487 1.966731)
			(xy 213.526541 2.023646) (xy 213.518492 2.082202) (xy 213.517988 2.111756) (xy 209.984264 2.111756)
			(xy 210.040351 2.083828) (xy 210.113257 2.038687) (xy 210.181686 1.987011) (xy 210.245056 1.929242)
			(xy 210.302825 1.865872) (xy 210.354501 1.797443) (xy 210.399642 1.724537) (xy 210.437864 1.647777)
			(xy 210.46884 1.567818) (xy 210.492307 1.485342) (xy 210.508063 1.401052) (xy 210.515975 1.315669)
			(xy 210.51647 1.272794) (xy 210.515975 1.229919) (xy 215.011241 1.229919) (xy 215.011241 1.315669)
			(xy 215.019153 1.401052) (xy 215.034909 1.485342) (xy 215.058376 1.567818) (xy 215.089352 1.647777)
			(xy 215.127574 1.724537) (xy 215.172715 1.797443) (xy 215.224391 1.865872) (xy 215.28216 1.929242)
			(xy 215.34553 1.987011) (xy 215.413959 2.038687) (xy 215.486865 2.083828) (xy 215.563625 2.12205)
			(xy 215.643584 2.153026) (xy 215.72606 2.176493) (xy 215.81035 2.192249) (xy 215.895733 2.200161)
			(xy 215.981483 2.200161) (xy 216.066866 2.192249) (xy 216.151156 2.176493) (xy 216.233632 2.153026)
			(xy 216.313591 2.12205) (xy 216.390351 2.083828) (xy 216.463257 2.038687) (xy 216.531686 1.987011)
			(xy 216.595056 1.929242) (xy 216.652825 1.865872) (xy 216.704501 1.797443) (xy 216.749642 1.724537)
			(xy 216.787864 1.647777) (xy 216.81884 1.567818) (xy 216.842307 1.485342) (xy 216.858063 1.401052)
			(xy 216.865975 1.315669) (xy 216.86647 1.272794) (xy 216.865975 1.229919) (xy 296.143921 1.229919)
			(xy 296.143921 1.315669) (xy 296.151833 1.401052) (xy 296.167589 1.485342) (xy 296.191056 1.567818)
			(xy 296.222032 1.647777) (xy 296.260254 1.724537) (xy 296.305395 1.797443) (xy 296.357071 1.865872)
			(xy 296.41484 1.929242) (xy 296.47821 1.987011) (xy 296.546639 2.038687) (xy 296.619545 2.083828)
			(xy 296.696305 2.12205) (xy 296.776264 2.153026) (xy 296.85874 2.176493) (xy 296.94303 2.192249)
			(xy 297.028413 2.200161) (xy 297.114163 2.200161) (xy 297.199546 2.192249) (xy 297.283836 2.176493)
			(xy 297.366312 2.153026) (xy 297.446271 2.12205) (xy 297.466944 2.111756) (xy 298.629324 2.111756)
			(xy 298.629324 2.975356) (xy 298.629828 3.00491) (xy 298.637877 3.063466) (xy 298.653823 3.120381)
			(xy 298.677372 3.174595) (xy 298.708083 3.225098) (xy 298.745385 3.270948) (xy 298.788582 3.311291)
			(xy 298.836871 3.345377) (xy 298.889351 3.37257) (xy 298.945046 3.392364) (xy 299.002917 3.40439)
			(xy 299.061886 3.408424) (xy 299.120855 3.40439) (xy 299.178726 3.392364) (xy 299.234421 3.37257)
			(xy 299.286901 3.345377) (xy 299.33519 3.311291) (xy 299.378387 3.270948) (xy 299.415689 3.225098)
			(xy 299.4464 3.174595) (xy 299.469949 3.120381) (xy 299.485895 3.063466) (xy 299.493944 3.00491)
			(xy 299.494448 2.975356) (xy 299.494448 2.111756) (xy 299.493944 2.082202) (xy 299.485895 2.023646)
			(xy 299.469949 1.966731) (xy 299.4464 1.912517) (xy 299.415689 1.862014) (xy 299.378387 1.816164)
			(xy 299.33519 1.775821) (xy 299.286901 1.741735) (xy 299.234421 1.714542) (xy 299.178726 1.694748)
			(xy 299.120855 1.682722) (xy 299.061886 1.678689) (xy 299.002917 1.682722) (xy 298.945046 1.694748)
			(xy 298.889351 1.714542) (xy 298.836871 1.741735) (xy 298.788582 1.775821) (xy 298.745385 1.816164)
			(xy 298.708083 1.862014) (xy 298.677372 1.912517) (xy 298.653823 1.966731) (xy 298.637877 2.023646)
			(xy 298.629828 2.082202) (xy 298.629324 2.111756) (xy 297.466944 2.111756) (xy 297.523031 2.083828)
			(xy 297.595937 2.038687) (xy 297.664366 1.987011) (xy 297.727736 1.929242) (xy 297.785505 1.865872)
			(xy 297.837181 1.797443) (xy 297.882322 1.724537) (xy 297.920544 1.647777) (xy 297.95152 1.567818)
			(xy 297.974987 1.485342) (xy 297.990743 1.401052) (xy 297.998655 1.315669) (xy 297.99915 1.272794)
			(xy 297.998655 1.229919) (xy 302.493921 1.229919) (xy 302.493921 1.315669) (xy 302.501833 1.401052)
			(xy 302.517589 1.485342) (xy 302.541056 1.567818) (xy 302.572032 1.647777) (xy 302.610254 1.724537)
			(xy 302.655395 1.797443) (xy 302.707071 1.865872) (xy 302.76484 1.929242) (xy 302.82821 1.987011)
			(xy 302.896639 2.038687) (xy 302.969545 2.083828) (xy 303.046305 2.12205) (xy 303.126264 2.153026)
			(xy 303.20874 2.176493) (xy 303.29303 2.192249) (xy 303.378413 2.200161) (xy 303.464163 2.200161)
			(xy 303.549546 2.192249) (xy 303.633836 2.176493) (xy 303.716312 2.153026) (xy 303.796271 2.12205)
			(xy 303.873031 2.083828) (xy 303.945937 2.038687) (xy 304.014366 1.987011) (xy 304.077736 1.929242)
			(xy 304.135505 1.865872) (xy 304.187181 1.797443) (xy 304.232322 1.724537) (xy 304.270544 1.647777)
			(xy 304.30152 1.567818) (xy 304.324987 1.485342) (xy 304.340743 1.401052) (xy 304.348655 1.315669)
			(xy 304.34915 1.272794) (xy 304.348655 1.229919) (xy 311.155321 1.229919) (xy 311.155321 1.315669)
			(xy 311.163233 1.401052) (xy 311.178989 1.485342) (xy 311.202456 1.567818) (xy 311.233432 1.647777)
			(xy 311.271654 1.724537) (xy 311.316795 1.797443) (xy 311.368471 1.865872) (xy 311.42624 1.929242)
			(xy 311.48961 1.987011) (xy 311.558039 2.038687) (xy 311.630945 2.083828) (xy 311.707705 2.12205)
			(xy 311.787664 2.153026) (xy 311.87014 2.176493) (xy 311.95443 2.192249) (xy 312.039813 2.200161)
			(xy 312.125563 2.200161) (xy 312.210946 2.192249) (xy 312.295236 2.176493) (xy 312.377712 2.153026)
			(xy 312.457671 2.12205) (xy 312.534431 2.083828) (xy 312.607337 2.038687) (xy 312.675766 1.987011)
			(xy 312.739136 1.929242) (xy 312.796905 1.865872) (xy 312.848581 1.797443) (xy 312.893722 1.724537)
			(xy 312.931944 1.647777) (xy 312.96292 1.567818) (xy 312.986387 1.485342) (xy 313.002143 1.401052)
			(xy 313.010055 1.315669) (xy 313.01055 1.272794) (xy 313.010055 1.229919) (xy 317.505321 1.229919)
			(xy 317.505321 1.315669) (xy 317.513233 1.401052) (xy 317.528989 1.485342) (xy 317.552456 1.567818)
			(xy 317.583432 1.647777) (xy 317.621654 1.724537) (xy 317.666795 1.797443) (xy 317.718471 1.865872)
			(xy 317.77624 1.929242) (xy 317.83961 1.987011) (xy 317.908039 2.038687) (xy 317.980945 2.083828)
			(xy 318.057705 2.12205) (xy 318.137664 2.153026) (xy 318.22014 2.176493) (xy 318.30443 2.192249)
			(xy 318.389813 2.200161) (xy 318.475563 2.200161) (xy 318.560946 2.192249) (xy 318.645236 2.176493)
			(xy 318.727712 2.153026) (xy 318.807671 2.12205) (xy 318.884431 2.083828) (xy 318.957337 2.038687)
			(xy 319.025766 1.987011) (xy 319.089136 1.929242) (xy 319.146905 1.865872) (xy 319.198581 1.797443)
			(xy 319.243722 1.724537) (xy 319.281944 1.647777) (xy 319.31292 1.567818) (xy 319.336387 1.485342)
			(xy 319.352143 1.401052) (xy 319.360055 1.315669) (xy 319.36055 1.272794) (xy 319.360055 1.229919)
			(xy 361.894107 1.229919) (xy 361.894107 1.315669) (xy 361.902019 1.401052) (xy 361.917775 1.485342)
			(xy 361.941242 1.567818) (xy 361.972218 1.647777) (xy 362.01044 1.724537) (xy 362.055581 1.797443)
			(xy 362.107257 1.865872) (xy 362.165026 1.929242) (xy 362.228396 1.987011) (xy 362.296825 2.038687)
			(xy 362.369731 2.083828) (xy 362.446491 2.12205) (xy 362.52645 2.153026) (xy 362.608926 2.176493)
			(xy 362.693216 2.192249) (xy 362.778599 2.200161) (xy 362.864349 2.200161) (xy 362.949732 2.192249)
			(xy 363.034022 2.176493) (xy 363.116498 2.153026) (xy 363.196457 2.12205) (xy 363.273217 2.083828)
			(xy 363.346123 2.038687) (xy 363.414552 1.987011) (xy 363.477922 1.929242) (xy 363.535691 1.865872)
			(xy 363.587367 1.797443) (xy 363.632508 1.724537) (xy 363.67073 1.647777) (xy 363.701706 1.567818)
			(xy 363.725173 1.485342) (xy 363.740929 1.401052) (xy 363.748841 1.315669) (xy 363.749336 1.272794)
			(xy 363.748841 1.229919) (xy 368.244107 1.229919) (xy 368.244107 1.315669) (xy 368.252019 1.401052)
			(xy 368.267775 1.485342) (xy 368.291242 1.567818) (xy 368.322218 1.647777) (xy 368.36044 1.724537)
			(xy 368.405581 1.797443) (xy 368.457257 1.865872) (xy 368.515026 1.929242) (xy 368.578396 1.987011)
			(xy 368.646825 2.038687) (xy 368.719731 2.083828) (xy 368.796491 2.12205) (xy 368.87645 2.153026)
			(xy 368.958926 2.176493) (xy 369.043216 2.192249) (xy 369.128599 2.200161) (xy 369.214349 2.200161)
			(xy 369.299732 2.192249) (xy 369.384022 2.176493) (xy 369.466498 2.153026) (xy 369.546457 2.12205)
			(xy 369.623217 2.083828) (xy 369.696123 2.038687) (xy 369.764552 1.987011) (xy 369.827922 1.929242)
			(xy 369.885691 1.865872) (xy 369.937367 1.797443) (xy 369.982508 1.724537) (xy 370.02073 1.647777)
			(xy 370.051706 1.567818) (xy 370.075173 1.485342) (xy 370.090929 1.401052) (xy 370.098841 1.315669)
			(xy 370.099336 1.272794) (xy 370.098841 1.229919) (xy 370.090929 1.144536) (xy 370.075173 1.060246)
			(xy 370.051706 0.97777) (xy 370.02073 0.897811) (xy 369.982508 0.821051) (xy 369.937367 0.748145)
			(xy 369.885691 0.679716) (xy 369.827922 0.616346) (xy 369.764552 0.558577) (xy 369.696123 0.506901)
			(xy 369.623217 0.46176) (xy 369.546457 0.423538) (xy 369.466498 0.392562) (xy 369.384022 0.369095)
			(xy 369.299732 0.353339) (xy 369.214349 0.345427) (xy 369.128599 0.345427) (xy 369.043216 0.353339)
			(xy 368.958926 0.369095) (xy 368.87645 0.392562) (xy 368.796491 0.423538) (xy 368.719731 0.46176)
			(xy 368.646825 0.506901) (xy 368.578396 0.558577) (xy 368.515026 0.616346) (xy 368.457257 0.679716)
			(xy 368.405581 0.748145) (xy 368.36044 0.821051) (xy 368.322218 0.897811) (xy 368.291242 0.97777)
			(xy 368.267775 1.060246) (xy 368.252019 1.144536) (xy 368.244107 1.229919) (xy 363.748841 1.229919)
			(xy 363.740929 1.144536) (xy 363.725173 1.060246) (xy 363.701706 0.97777) (xy 363.67073 0.897811)
			(xy 363.632508 0.821051) (xy 363.587367 0.748145) (xy 363.535691 0.679716) (xy 363.477922 0.616346)
			(xy 363.414552 0.558577) (xy 363.346123 0.506901) (xy 363.273217 0.46176) (xy 363.196457 0.423538)
			(xy 363.116498 0.392562) (xy 363.034022 0.369095) (xy 362.949732 0.353339) (xy 362.864349 0.345427)
			(xy 362.778599 0.345427) (xy 362.693216 0.353339) (xy 362.608926 0.369095) (xy 362.52645 0.392562)
			(xy 362.446491 0.423538) (xy 362.369731 0.46176) (xy 362.296825 0.506901) (xy 362.228396 0.558577)
			(xy 362.165026 0.616346) (xy 362.107257 0.679716) (xy 362.055581 0.748145) (xy 362.01044 0.821051)
			(xy 361.972218 0.897811) (xy 361.941242 0.97777) (xy 361.917775 1.060246) (xy 361.902019 1.144536)
			(xy 361.894107 1.229919) (xy 319.360055 1.229919) (xy 319.352143 1.144536) (xy 319.336387 1.060246)
			(xy 319.31292 0.97777) (xy 319.281944 0.897811) (xy 319.243722 0.821051) (xy 319.198581 0.748145)
			(xy 319.146905 0.679716) (xy 319.089136 0.616346) (xy 319.025766 0.558577) (xy 318.957337 0.506901)
			(xy 318.884431 0.46176) (xy 318.807671 0.423538) (xy 318.727712 0.392562) (xy 318.645236 0.369095)
			(xy 318.560946 0.353339) (xy 318.475563 0.345427) (xy 318.389813 0.345427) (xy 318.30443 0.353339)
			(xy 318.22014 0.369095) (xy 318.137664 0.392562) (xy 318.057705 0.423538) (xy 317.980945 0.46176)
			(xy 317.908039 0.506901) (xy 317.83961 0.558577) (xy 317.77624 0.616346) (xy 317.718471 0.679716)
			(xy 317.666795 0.748145) (xy 317.621654 0.821051) (xy 317.583432 0.897811) (xy 317.552456 0.97777)
			(xy 317.528989 1.060246) (xy 317.513233 1.144536) (xy 317.505321 1.229919) (xy 313.010055 1.229919)
			(xy 313.002143 1.144536) (xy 312.986387 1.060246) (xy 312.96292 0.97777) (xy 312.931944 0.897811)
			(xy 312.893722 0.821051) (xy 312.848581 0.748145) (xy 312.796905 0.679716) (xy 312.739136 0.616346)
			(xy 312.675766 0.558577) (xy 312.607337 0.506901) (xy 312.534431 0.46176) (xy 312.457671 0.423538)
			(xy 312.377712 0.392562) (xy 312.295236 0.369095) (xy 312.210946 0.353339) (xy 312.125563 0.345427)
			(xy 312.039813 0.345427) (xy 311.95443 0.353339) (xy 311.87014 0.369095) (xy 311.787664 0.392562)
			(xy 311.707705 0.423538) (xy 311.630945 0.46176) (xy 311.558039 0.506901) (xy 311.48961 0.558577)
			(xy 311.42624 0.616346) (xy 311.368471 0.679716) (xy 311.316795 0.748145) (xy 311.271654 0.821051)
			(xy 311.233432 0.897811) (xy 311.202456 0.97777) (xy 311.178989 1.060246) (xy 311.163233 1.144536)
			(xy 311.155321 1.229919) (xy 304.348655 1.229919) (xy 304.340743 1.144536) (xy 304.324987 1.060246)
			(xy 304.30152 0.97777) (xy 304.270544 0.897811) (xy 304.232322 0.821051) (xy 304.187181 0.748145)
			(xy 304.135505 0.679716) (xy 304.077736 0.616346) (xy 304.014366 0.558577) (xy 303.945937 0.506901)
			(xy 303.873031 0.46176) (xy 303.796271 0.423538) (xy 303.716312 0.392562) (xy 303.633836 0.369095)
			(xy 303.549546 0.353339) (xy 303.464163 0.345427) (xy 303.378413 0.345427) (xy 303.29303 0.353339)
			(xy 303.20874 0.369095) (xy 303.126264 0.392562) (xy 303.046305 0.423538) (xy 302.969545 0.46176)
			(xy 302.896639 0.506901) (xy 302.82821 0.558577) (xy 302.76484 0.616346) (xy 302.707071 0.679716)
			(xy 302.655395 0.748145) (xy 302.610254 0.821051) (xy 302.572032 0.897811) (xy 302.541056 0.97777)
			(xy 302.517589 1.060246) (xy 302.501833 1.144536) (xy 302.493921 1.229919) (xy 297.998655 1.229919)
			(xy 297.990743 1.144536) (xy 297.974987 1.060246) (xy 297.95152 0.97777) (xy 297.920544 0.897811)
			(xy 297.882322 0.821051) (xy 297.837181 0.748145) (xy 297.785505 0.679716) (xy 297.727736 0.616346)
			(xy 297.664366 0.558577) (xy 297.595937 0.506901) (xy 297.523031 0.46176) (xy 297.446271 0.423538)
			(xy 297.366312 0.392562) (xy 297.283836 0.369095) (xy 297.199546 0.353339) (xy 297.114163 0.345427)
			(xy 297.028413 0.345427) (xy 296.94303 0.353339) (xy 296.85874 0.369095) (xy 296.776264 0.392562)
			(xy 296.696305 0.423538) (xy 296.619545 0.46176) (xy 296.546639 0.506901) (xy 296.47821 0.558577)
			(xy 296.41484 0.616346) (xy 296.357071 0.679716) (xy 296.305395 0.748145) (xy 296.260254 0.821051)
			(xy 296.222032 0.897811) (xy 296.191056 0.97777) (xy 296.167589 1.060246) (xy 296.151833 1.144536)
			(xy 296.143921 1.229919) (xy 216.865975 1.229919) (xy 216.858063 1.144536) (xy 216.842307 1.060246)
			(xy 216.81884 0.97777) (xy 216.787864 0.897811) (xy 216.749642 0.821051) (xy 216.704501 0.748145)
			(xy 216.652825 0.679716) (xy 216.595056 0.616346) (xy 216.531686 0.558577) (xy 216.463257 0.506901)
			(xy 216.390351 0.46176) (xy 216.313591 0.423538) (xy 216.233632 0.392562) (xy 216.151156 0.369095)
			(xy 216.066866 0.353339) (xy 215.981483 0.345427) (xy 215.895733 0.345427) (xy 215.81035 0.353339)
			(xy 215.72606 0.369095) (xy 215.643584 0.392562) (xy 215.563625 0.423538) (xy 215.486865 0.46176)
			(xy 215.413959 0.506901) (xy 215.34553 0.558577) (xy 215.28216 0.616346) (xy 215.224391 0.679716)
			(xy 215.172715 0.748145) (xy 215.127574 0.821051) (xy 215.089352 0.897811) (xy 215.058376 0.97777)
			(xy 215.034909 1.060246) (xy 215.019153 1.144536) (xy 215.011241 1.229919) (xy 210.515975 1.229919)
			(xy 210.508063 1.144536) (xy 210.492307 1.060246) (xy 210.46884 0.97777) (xy 210.437864 0.897811)
			(xy 210.399642 0.821051) (xy 210.354501 0.748145) (xy 210.302825 0.679716) (xy 210.245056 0.616346)
			(xy 210.181686 0.558577) (xy 210.113257 0.506901) (xy 210.040351 0.46176) (xy 209.963591 0.423538)
			(xy 209.883632 0.392562) (xy 209.801156 0.369095) (xy 209.716866 0.353339) (xy 209.631483 0.345427)
			(xy 209.545733 0.345427) (xy 209.46035 0.353339) (xy 209.37606 0.369095) (xy 209.293584 0.392562)
			(xy 209.213625 0.423538) (xy 209.136865 0.46176) (xy 209.063959 0.506901) (xy 208.99553 0.558577)
			(xy 208.93216 0.616346) (xy 208.874391 0.679716) (xy 208.822715 0.748145) (xy 208.777574 0.821051)
			(xy 208.739352 0.897811) (xy 208.708376 0.97777) (xy 208.684909 1.060246) (xy 208.669153 1.144536)
			(xy 208.661241 1.229919) (xy 84.069209 1.229919) (xy 84.092929 1.162133) (xy 84.131901 1.02687) (xy 84.163226 0.889634)
			(xy 84.186808 0.750857) (xy 84.202571 0.610977) (xy 84.210467 0.470433) (xy 84.210906 0.40005) (xy 84.210906 -1.310081)
			(xy 208.661241 -1.310081) (xy 208.661241 -1.224331) (xy 208.669153 -1.138948) (xy 208.684909 -1.054658)
			(xy 208.708376 -0.972182) (xy 208.739352 -0.892223) (xy 208.777574 -0.815463) (xy 208.822715 -0.742557)
			(xy 208.874391 -0.674128) (xy 208.93216 -0.610758) (xy 208.99553 -0.552989) (xy 209.063959 -0.501313)
			(xy 209.136865 -0.456172) (xy 209.213625 -0.41795) (xy 209.293584 -0.386974) (xy 209.37606 -0.363507)
			(xy 209.46035 -0.347751) (xy 209.545733 -0.339839) (xy 209.631483 -0.339839) (xy 209.716866 -0.347751)
			(xy 209.801156 -0.363507) (xy 209.883632 -0.386974) (xy 209.963591 -0.41795) (xy 210.040351 -0.456172)
			(xy 210.113257 -0.501313) (xy 210.181686 -0.552989) (xy 210.245056 -0.610758) (xy 210.302825 -0.674128)
			(xy 210.354501 -0.742557) (xy 210.399642 -0.815463) (xy 210.437864 -0.892223) (xy 210.46884 -0.972182)
			(xy 210.492307 -1.054658) (xy 210.508063 -1.138948) (xy 210.515975 -1.224331) (xy 210.51647 -1.267206)
			(xy 210.515975 -1.310081) (xy 215.011241 -1.310081) (xy 215.011241 -1.224331) (xy 215.019153 -1.138948)
			(xy 215.034909 -1.054658) (xy 215.058376 -0.972182) (xy 215.089352 -0.892223) (xy 215.127574 -0.815463)
			(xy 215.172715 -0.742557) (xy 215.224391 -0.674128) (xy 215.28216 -0.610758) (xy 215.34553 -0.552989)
			(xy 215.413959 -0.501313) (xy 215.486865 -0.456172) (xy 215.563625 -0.41795) (xy 215.643584 -0.386974)
			(xy 215.72606 -0.363507) (xy 215.81035 -0.347751) (xy 215.895733 -0.339839) (xy 215.981483 -0.339839)
			(xy 216.066866 -0.347751) (xy 216.151156 -0.363507) (xy 216.233632 -0.386974) (xy 216.313591 -0.41795)
			(xy 216.390351 -0.456172) (xy 216.463257 -0.501313) (xy 216.531686 -0.552989) (xy 216.595056 -0.610758)
			(xy 216.652825 -0.674128) (xy 216.704501 -0.742557) (xy 216.749642 -0.815463) (xy 216.787864 -0.892223)
			(xy 216.81884 -0.972182) (xy 216.842307 -1.054658) (xy 216.858063 -1.138948) (xy 216.865975 -1.224331)
			(xy 216.86647 -1.267206) (xy 216.865975 -1.310081) (xy 296.143921 -1.310081) (xy 296.143921 -1.224331)
			(xy 296.151833 -1.138948) (xy 296.167589 -1.054658) (xy 296.191056 -0.972182) (xy 296.222032 -0.892223)
			(xy 296.260254 -0.815463) (xy 296.305395 -0.742557) (xy 296.357071 -0.674128) (xy 296.41484 -0.610758)
			(xy 296.47821 -0.552989) (xy 296.546639 -0.501313) (xy 296.619545 -0.456172) (xy 296.696305 -0.41795)
			(xy 296.776264 -0.386974) (xy 296.85874 -0.363507) (xy 296.94303 -0.347751) (xy 297.028413 -0.339839)
			(xy 297.114163 -0.339839) (xy 297.199546 -0.347751) (xy 297.283836 -0.363507) (xy 297.366312 -0.386974)
			(xy 297.446271 -0.41795) (xy 297.523031 -0.456172) (xy 297.595937 -0.501313) (xy 297.664366 -0.552989)
			(xy 297.727736 -0.610758) (xy 297.785505 -0.674128) (xy 297.837181 -0.742557) (xy 297.882322 -0.815463)
			(xy 297.920544 -0.892223) (xy 297.95152 -0.972182) (xy 297.974987 -1.054658) (xy 297.990743 -1.138948)
			(xy 297.998655 -1.224331) (xy 297.99915 -1.267206) (xy 297.998655 -1.310081) (xy 302.493921 -1.310081)
			(xy 302.493921 -1.224331) (xy 302.501833 -1.138948) (xy 302.517589 -1.054658) (xy 302.541056 -0.972182)
			(xy 302.572032 -0.892223) (xy 302.610254 -0.815463) (xy 302.655395 -0.742557) (xy 302.707071 -0.674128)
			(xy 302.76484 -0.610758) (xy 302.82821 -0.552989) (xy 302.896639 -0.501313) (xy 302.969545 -0.456172)
			(xy 303.046305 -0.41795) (xy 303.126264 -0.386974) (xy 303.20874 -0.363507) (xy 303.29303 -0.347751)
			(xy 303.378413 -0.339839) (xy 303.464163 -0.339839) (xy 303.549546 -0.347751) (xy 303.633836 -0.363507)
			(xy 303.716312 -0.386974) (xy 303.796271 -0.41795) (xy 303.873031 -0.456172) (xy 303.945937 -0.501313)
			(xy 304.014366 -0.552989) (xy 304.077736 -0.610758) (xy 304.135505 -0.674128) (xy 304.187181 -0.742557)
			(xy 304.232322 -0.815463) (xy 304.270544 -0.892223) (xy 304.30152 -0.972182) (xy 304.324987 -1.054658)
			(xy 304.340743 -1.138948) (xy 304.348655 -1.224331) (xy 304.34915 -1.267206) (xy 304.348655 -1.310081)
			(xy 311.155321 -1.310081) (xy 311.155321 -1.224331) (xy 311.163233 -1.138948) (xy 311.178989 -1.054658)
			(xy 311.202456 -0.972182) (xy 311.233432 -0.892223) (xy 311.271654 -0.815463) (xy 311.316795 -0.742557)
			(xy 311.368471 -0.674128) (xy 311.42624 -0.610758) (xy 311.48961 -0.552989) (xy 311.558039 -0.501313)
			(xy 311.630945 -0.456172) (xy 311.707705 -0.41795) (xy 311.787664 -0.386974) (xy 311.87014 -0.363507)
			(xy 311.95443 -0.347751) (xy 312.039813 -0.339839) (xy 312.125563 -0.339839) (xy 312.210946 -0.347751)
			(xy 312.295236 -0.363507) (xy 312.377712 -0.386974) (xy 312.457671 -0.41795) (xy 312.478344 -0.428244)
			(xy 316.012068 -0.428244) (xy 316.012068 0.435356) (xy 316.012572 0.46491) (xy 316.020621 0.523466)
			(xy 316.036567 0.580381) (xy 316.060116 0.634595) (xy 316.090827 0.685098) (xy 316.128129 0.730948)
			(xy 316.171326 0.771291) (xy 316.219615 0.805377) (xy 316.272095 0.83257) (xy 316.32779 0.852364)
			(xy 316.385661 0.86439) (xy 316.44463 0.868424) (xy 316.503599 0.86439) (xy 316.56147 0.852364) (xy 316.617165 0.83257)
			(xy 316.669645 0.805377) (xy 316.717934 0.771291) (xy 316.761131 0.730948) (xy 316.798433 0.685098)
			(xy 316.829144 0.634595) (xy 316.852693 0.580381) (xy 316.868639 0.523466) (xy 316.876688 0.46491)
			(xy 316.877192 0.435356) (xy 316.877192 -0.428244) (xy 316.876688 -0.457798) (xy 316.868639 -0.516354)
			(xy 316.852693 -0.573269) (xy 316.829144 -0.627483) (xy 316.798433 -0.677986) (xy 316.761131 -0.723836)
			(xy 316.717934 -0.764179) (xy 316.669645 -0.798265) (xy 316.617165 -0.825458) (xy 316.56147 -0.845252)
			(xy 316.503599 -0.857278) (xy 316.44463 -0.861312) (xy 316.385661 -0.857278) (xy 316.32779 -0.845252)
			(xy 316.272095 -0.825458) (xy 316.219615 -0.798265) (xy 316.171326 -0.764179) (xy 316.128129 -0.723836)
			(xy 316.090827 -0.677986) (xy 316.060116 -0.627483) (xy 316.036567 -0.573269) (xy 316.020621 -0.516354)
			(xy 316.012572 -0.457798) (xy 316.012068 -0.428244) (xy 312.478344 -0.428244) (xy 312.534431 -0.456172)
			(xy 312.607337 -0.501313) (xy 312.675766 -0.552989) (xy 312.739136 -0.610758) (xy 312.796905 -0.674128)
			(xy 312.848581 -0.742557) (xy 312.893722 -0.815463) (xy 312.931944 -0.892223) (xy 312.96292 -0.972182)
			(xy 312.986387 -1.054658) (xy 313.002143 -1.138948) (xy 313.010055 -1.224331) (xy 313.01055 -1.267206)
			(xy 313.010055 -1.310081) (xy 317.505321 -1.310081) (xy 317.505321 -1.224331) (xy 317.513233 -1.138948)
			(xy 317.528989 -1.054658) (xy 317.552456 -0.972182) (xy 317.583432 -0.892223) (xy 317.621654 -0.815463)
			(xy 317.666795 -0.742557) (xy 317.718471 -0.674128) (xy 317.77624 -0.610758) (xy 317.83961 -0.552989)
			(xy 317.908039 -0.501313) (xy 317.980945 -0.456172) (xy 318.057705 -0.41795) (xy 318.137664 -0.386974)
			(xy 318.22014 -0.363507) (xy 318.30443 -0.347751) (xy 318.389813 -0.339839) (xy 318.475563 -0.339839)
			(xy 318.560946 -0.347751) (xy 318.645236 -0.363507) (xy 318.727712 -0.386974) (xy 318.807671 -0.41795)
			(xy 318.884431 -0.456172) (xy 318.957337 -0.501313) (xy 319.025766 -0.552989) (xy 319.089136 -0.610758)
			(xy 319.146905 -0.674128) (xy 319.198581 -0.742557) (xy 319.243722 -0.815463) (xy 319.281944 -0.892223)
			(xy 319.31292 -0.972182) (xy 319.336387 -1.054658) (xy 319.352143 -1.138948) (xy 319.360055 -1.224331)
			(xy 319.36055 -1.267206) (xy 319.360055 -1.310081) (xy 361.894107 -1.310081) (xy 361.894107 -1.224331)
			(xy 361.902019 -1.138948) (xy 361.917775 -1.054658) (xy 361.941242 -0.972182) (xy 361.972218 -0.892223)
			(xy 362.01044 -0.815463) (xy 362.055581 -0.742557) (xy 362.107257 -0.674128) (xy 362.165026 -0.610758)
			(xy 362.228396 -0.552989) (xy 362.296825 -0.501313) (xy 362.369731 -0.456172) (xy 362.446491 -0.41795)
			(xy 362.52645 -0.386974) (xy 362.608926 -0.363507) (xy 362.693216 -0.347751) (xy 362.778599 -0.339839)
			(xy 362.864349 -0.339839) (xy 362.949732 -0.347751) (xy 363.034022 -0.363507) (xy 363.116498 -0.386974)
			(xy 363.196457 -0.41795) (xy 363.21713 -0.428244) (xy 364.379764 -0.428244) (xy 364.379764 0.435356)
			(xy 364.380268 0.464892) (xy 364.388312 0.523414) (xy 364.404249 0.580296) (xy 364.427784 0.634478)
			(xy 364.458477 0.684951) (xy 364.495757 0.730774) (xy 364.538929 0.771094) (xy 364.587189 0.80516)
			(xy 364.639639 0.832337) (xy 364.6953 0.852119) (xy 364.753137 0.864138) (xy 364.812072 0.868169)
			(xy 364.871007 0.864138) (xy 364.928844 0.852119) (xy 364.984505 0.832337) (xy 365.036955 0.80516)
			(xy 365.085215 0.771094) (xy 365.128387 0.730774) (xy 365.165667 0.684951) (xy 365.19636 0.634478)
			(xy 365.219895 0.580296) (xy 365.235832 0.523414) (xy 365.243876 0.464892) (xy 365.24438 0.435356)
			(xy 365.24438 -0.428244) (xy 365.243876 -0.45778) (xy 365.235832 -0.516302) (xy 365.219895 -0.573184)
			(xy 365.19636 -0.627366) (xy 365.165667 -0.677839) (xy 365.128387 -0.723662) (xy 365.085215 -0.763982)
			(xy 365.036955 -0.798048) (xy 364.984505 -0.825225) (xy 364.928844 -0.845007) (xy 364.871007 -0.857026)
			(xy 364.812072 -0.861057) (xy 364.753137 -0.857026) (xy 364.6953 -0.845007) (xy 364.639639 -0.825225)
			(xy 364.587189 -0.798048) (xy 364.538929 -0.763982) (xy 364.495757 -0.723662) (xy 364.458477 -0.677839)
			(xy 364.427784 -0.627366) (xy 364.404249 -0.573184) (xy 364.388312 -0.516302) (xy 364.380268 -0.45778)
			(xy 364.379764 -0.428244) (xy 363.21713 -0.428244) (xy 363.273217 -0.456172) (xy 363.346123 -0.501313)
			(xy 363.414552 -0.552989) (xy 363.477922 -0.610758) (xy 363.535691 -0.674128) (xy 363.587367 -0.742557)
			(xy 363.632508 -0.815463) (xy 363.67073 -0.892223) (xy 363.701706 -0.972182) (xy 363.725173 -1.054658)
			(xy 363.740929 -1.138948) (xy 363.748841 -1.224331) (xy 363.749336 -1.267206) (xy 363.748841 -1.310081)
			(xy 368.244107 -1.310081) (xy 368.244107 -1.224331) (xy 368.252019 -1.138948) (xy 368.267775 -1.054658)
			(xy 368.291242 -0.972182) (xy 368.322218 -0.892223) (xy 368.36044 -0.815463) (xy 368.405581 -0.742557)
			(xy 368.457257 -0.674128) (xy 368.515026 -0.610758) (xy 368.578396 -0.552989) (xy 368.646825 -0.501313)
			(xy 368.719731 -0.456172) (xy 368.796491 -0.41795) (xy 368.87645 -0.386974) (xy 368.958926 -0.363507)
			(xy 369.043216 -0.347751) (xy 369.128599 -0.339839) (xy 369.214349 -0.339839) (xy 369.299732 -0.347751)
			(xy 369.384022 -0.363507) (xy 369.466498 -0.386974) (xy 369.546457 -0.41795) (xy 369.623217 -0.456172)
			(xy 369.696123 -0.501313) (xy 369.764552 -0.552989) (xy 369.827922 -0.610758) (xy 369.885691 -0.674128)
			(xy 369.937367 -0.742557) (xy 369.982508 -0.815463) (xy 370.02073 -0.892223) (xy 370.051706 -0.972182)
			(xy 370.075173 -1.054658) (xy 370.090929 -1.138948) (xy 370.098841 -1.224331) (xy 370.099336 -1.267206)
			(xy 370.098841 -1.310081) (xy 370.090929 -1.395464) (xy 370.075173 -1.479754) (xy 370.051706 -1.56223)
			(xy 370.02073 -1.642189) (xy 369.982508 -1.718949) (xy 369.937367 -1.791855) (xy 369.885691 -1.860284)
			(xy 369.827922 -1.923654) (xy 369.764552 -1.981423) (xy 369.696123 -2.033099) (xy 369.623217 -2.07824)
			(xy 369.546457 -2.116462) (xy 369.466498 -2.147438) (xy 369.384022 -2.170905) (xy 369.299732 -2.186661)
			(xy 369.214349 -2.194573) (xy 369.128599 -2.194573) (xy 369.043216 -2.186661) (xy 368.958926 -2.170905)
			(xy 368.87645 -2.147438) (xy 368.796491 -2.116462) (xy 368.719731 -2.07824) (xy 368.646825 -2.033099)
			(xy 368.578396 -1.981423) (xy 368.515026 -1.923654) (xy 368.457257 -1.860284) (xy 368.405581 -1.791855)
			(xy 368.36044 -1.718949) (xy 368.322218 -1.642189) (xy 368.291242 -1.56223) (xy 368.267775 -1.479754)
			(xy 368.252019 -1.395464) (xy 368.244107 -1.310081) (xy 363.748841 -1.310081) (xy 363.740929 -1.395464)
			(xy 363.725173 -1.479754) (xy 363.701706 -1.56223) (xy 363.67073 -1.642189) (xy 363.632508 -1.718949)
			(xy 363.587367 -1.791855) (xy 363.535691 -1.860284) (xy 363.477922 -1.923654) (xy 363.414552 -1.981423)
			(xy 363.346123 -2.033099) (xy 363.273217 -2.07824) (xy 363.196457 -2.116462) (xy 363.116498 -2.147438)
			(xy 363.034022 -2.170905) (xy 362.949732 -2.186661) (xy 362.864349 -2.194573) (xy 362.778599 -2.194573)
			(xy 362.693216 -2.186661) (xy 362.608926 -2.170905) (xy 362.52645 -2.147438) (xy 362.446491 -2.116462)
			(xy 362.369731 -2.07824) (xy 362.296825 -2.033099) (xy 362.228396 -1.981423) (xy 362.165026 -1.923654)
			(xy 362.107257 -1.860284) (xy 362.055581 -1.791855) (xy 362.01044 -1.718949) (xy 361.972218 -1.642189)
			(xy 361.941242 -1.56223) (xy 361.917775 -1.479754) (xy 361.902019 -1.395464) (xy 361.894107 -1.310081)
			(xy 319.360055 -1.310081) (xy 319.352143 -1.395464) (xy 319.336387 -1.479754) (xy 319.31292 -1.56223)
			(xy 319.281944 -1.642189) (xy 319.243722 -1.718949) (xy 319.198581 -1.791855) (xy 319.146905 -1.860284)
			(xy 319.089136 -1.923654) (xy 319.025766 -1.981423) (xy 318.957337 -2.033099) (xy 318.884431 -2.07824)
			(xy 318.807671 -2.116462) (xy 318.727712 -2.147438) (xy 318.645236 -2.170905) (xy 318.560946 -2.186661)
			(xy 318.475563 -2.194573) (xy 318.389813 -2.194573) (xy 318.30443 -2.186661) (xy 318.22014 -2.170905)
			(xy 318.137664 -2.147438) (xy 318.057705 -2.116462) (xy 317.980945 -2.07824) (xy 317.908039 -2.033099)
			(xy 317.83961 -1.981423) (xy 317.77624 -1.923654) (xy 317.718471 -1.860284) (xy 317.666795 -1.791855)
			(xy 317.621654 -1.718949) (xy 317.583432 -1.642189) (xy 317.552456 -1.56223) (xy 317.528989 -1.479754)
			(xy 317.513233 -1.395464) (xy 317.505321 -1.310081) (xy 313.010055 -1.310081) (xy 313.002143 -1.395464)
			(xy 312.986387 -1.479754) (xy 312.96292 -1.56223) (xy 312.931944 -1.642189) (xy 312.893722 -1.718949)
			(xy 312.848581 -1.791855) (xy 312.796905 -1.860284) (xy 312.739136 -1.923654) (xy 312.675766 -1.981423)
			(xy 312.607337 -2.033099) (xy 312.534431 -2.07824) (xy 312.457671 -2.116462) (xy 312.377712 -2.147438)
			(xy 312.295236 -2.170905) (xy 312.210946 -2.186661) (xy 312.125563 -2.194573) (xy 312.039813 -2.194573)
			(xy 311.95443 -2.186661) (xy 311.87014 -2.170905) (xy 311.787664 -2.147438) (xy 311.707705 -2.116462)
			(xy 311.630945 -2.07824) (xy 311.558039 -2.033099) (xy 311.48961 -1.981423) (xy 311.42624 -1.923654)
			(xy 311.368471 -1.860284) (xy 311.316795 -1.791855) (xy 311.271654 -1.718949) (xy 311.233432 -1.642189)
			(xy 311.202456 -1.56223) (xy 311.178989 -1.479754) (xy 311.163233 -1.395464) (xy 311.155321 -1.310081)
			(xy 304.348655 -1.310081) (xy 304.340743 -1.395464) (xy 304.324987 -1.479754) (xy 304.30152 -1.56223)
			(xy 304.270544 -1.642189) (xy 304.232322 -1.718949) (xy 304.187181 -1.791855) (xy 304.135505 -1.860284)
			(xy 304.077736 -1.923654) (xy 304.014366 -1.981423) (xy 303.945937 -2.033099) (xy 303.873031 -2.07824)
			(xy 303.796271 -2.116462) (xy 303.716312 -2.147438) (xy 303.633836 -2.170905) (xy 303.549546 -2.186661)
			(xy 303.464163 -2.194573) (xy 303.378413 -2.194573) (xy 303.29303 -2.186661) (xy 303.20874 -2.170905)
			(xy 303.126264 -2.147438) (xy 303.046305 -2.116462) (xy 302.969545 -2.07824) (xy 302.896639 -2.033099)
			(xy 302.82821 -1.981423) (xy 302.76484 -1.923654) (xy 302.707071 -1.860284) (xy 302.655395 -1.791855)
			(xy 302.610254 -1.718949) (xy 302.572032 -1.642189) (xy 302.541056 -1.56223) (xy 302.517589 -1.479754)
			(xy 302.501833 -1.395464) (xy 302.493921 -1.310081) (xy 297.998655 -1.310081) (xy 297.990743 -1.395464)
			(xy 297.974987 -1.479754) (xy 297.95152 -1.56223) (xy 297.920544 -1.642189) (xy 297.882322 -1.718949)
			(xy 297.837181 -1.791855) (xy 297.785505 -1.860284) (xy 297.727736 -1.923654) (xy 297.664366 -1.981423)
			(xy 297.595937 -2.033099) (xy 297.523031 -2.07824) (xy 297.446271 -2.116462) (xy 297.366312 -2.147438)
			(xy 297.283836 -2.170905) (xy 297.199546 -2.186661) (xy 297.114163 -2.194573) (xy 297.028413 -2.194573)
			(xy 296.94303 -2.186661) (xy 296.85874 -2.170905) (xy 296.776264 -2.147438) (xy 296.696305 -2.116462)
			(xy 296.619545 -2.07824) (xy 296.546639 -2.033099) (xy 296.47821 -1.981423) (xy 296.41484 -1.923654)
			(xy 296.357071 -1.860284) (xy 296.305395 -1.791855) (xy 296.260254 -1.718949) (xy 296.222032 -1.642189)
			(xy 296.191056 -1.56223) (xy 296.167589 -1.479754) (xy 296.151833 -1.395464) (xy 296.143921 -1.310081)
			(xy 216.865975 -1.310081) (xy 216.858063 -1.395464) (xy 216.842307 -1.479754) (xy 216.81884 -1.56223)
			(xy 216.787864 -1.642189) (xy 216.749642 -1.718949) (xy 216.704501 -1.791855) (xy 216.652825 -1.860284)
			(xy 216.595056 -1.923654) (xy 216.531686 -1.981423) (xy 216.463257 -2.033099) (xy 216.390351 -2.07824)
			(xy 216.313591 -2.116462) (xy 216.233632 -2.147438) (xy 216.151156 -2.170905) (xy 216.066866 -2.186661)
			(xy 215.981483 -2.194573) (xy 215.895733 -2.194573) (xy 215.81035 -2.186661) (xy 215.72606 -2.170905)
			(xy 215.643584 -2.147438) (xy 215.563625 -2.116462) (xy 215.486865 -2.07824) (xy 215.413959 -2.033099)
			(xy 215.34553 -1.981423) (xy 215.28216 -1.923654) (xy 215.224391 -1.860284) (xy 215.172715 -1.791855)
			(xy 215.127574 -1.718949) (xy 215.089352 -1.642189) (xy 215.058376 -1.56223) (xy 215.034909 -1.479754)
			(xy 215.019153 -1.395464) (xy 215.011241 -1.310081) (xy 210.515975 -1.310081) (xy 210.508063 -1.395464)
			(xy 210.492307 -1.479754) (xy 210.46884 -1.56223) (xy 210.437864 -1.642189) (xy 210.399642 -1.718949)
			(xy 210.354501 -1.791855) (xy 210.302825 -1.860284) (xy 210.245056 -1.923654) (xy 210.181686 -1.981423)
			(xy 210.113257 -2.033099) (xy 210.040351 -2.07824) (xy 209.963591 -2.116462) (xy 209.883632 -2.147438)
			(xy 209.801156 -2.170905) (xy 209.716866 -2.186661) (xy 209.631483 -2.194573) (xy 209.545733 -2.194573)
			(xy 209.46035 -2.186661) (xy 209.37606 -2.170905) (xy 209.293584 -2.147438) (xy 209.213625 -2.116462)
			(xy 209.136865 -2.07824) (xy 209.063959 -2.033099) (xy 208.99553 -1.981423) (xy 208.93216 -1.923654)
			(xy 208.874391 -1.860284) (xy 208.822715 -1.791855) (xy 208.777574 -1.718949) (xy 208.739352 -1.642189)
			(xy 208.708376 -1.56223) (xy 208.684909 -1.479754) (xy 208.669153 -1.395464) (xy 208.661241 -1.310081)
			(xy 84.210906 -1.310081) (xy 84.210906 -7.78002) (xy 84.211428 -7.835789) (xy 84.219765 -7.947014)
			(xy 84.23639 -8.057306) (xy 84.26121 -8.166046) (xy 84.294088 -8.272628) (xy 84.334838 -8.376455)
			(xy 84.383233 -8.476947) (xy 84.439002 -8.573541) (xy 84.501834 -8.665697) (xy 84.571376 -8.7529)
			(xy 84.647241 -8.834663) (xy 84.729004 -8.910527) (xy 84.816208 -8.98007) (xy 84.908364 -9.042901)
			(xy 85.004959 -9.09867) (xy 85.10545 -9.147065) (xy 85.209277 -9.187814) (xy 85.315859 -9.220691)
			(xy 85.4246 -9.245511) (xy 85.534892 -9.262136) (xy 85.646117 -9.270472) (xy 85.701886 -9.271) (xy 122.102118 -9.271)
			(xy 122.157887 -9.270478) (xy 122.269113 -9.262141) (xy 122.379404 -9.245517) (xy 122.488145 -9.220696)
			(xy 122.594728 -9.187819) (xy 122.698555 -9.147069) (xy 122.799047 -9.098674) (xy 122.895641 -9.042905)
			(xy 122.987798 -8.980073) (xy 123.075001 -8.910531) (xy 123.156764 -8.834666) (xy 123.232629 -8.752903)
			(xy 123.302172 -8.665699) (xy 123.365004 -8.573543) (xy 123.420773 -8.476948) (xy 123.469168 -8.376457)
			(xy 123.509918 -8.27263) (xy 123.542796 -8.166047) (xy 123.567616 -8.057306) (xy 123.584241 -7.947015)
			(xy 123.592578 -7.835789) (xy 123.593098 -7.78002) (xy 123.593098 -4.879848) (xy 123.593581 -4.809465)
			(xy 123.601472 -4.66892) (xy 123.61723 -4.529038) (xy 123.640807 -4.39026) (xy 123.672128 -4.253022)
			(xy 123.711095 -4.117757) (xy 123.757586 -3.984889) (xy 123.811453 -3.854837) (xy 123.872528 -3.72801)
			(xy 123.940618 -3.604807) (xy 124.015509 -3.485616) (xy 124.096965 -3.370811) (xy 124.184731 -3.260755)
			(xy 124.278529 -3.155793) (xy 124.378065 -3.056255) (xy 124.483026 -2.962455) (xy 124.593081 -2.874688)
			(xy 124.707884 -2.79323) (xy 124.827074 -2.718337) (xy 124.950276 -2.650245) (xy 125.077102 -2.589169)
			(xy 125.207153 -2.535299) (xy 125.340021 -2.488807) (xy 125.475285 -2.449838) (xy 125.612523 -2.418514)
			(xy 125.7513 -2.394935) (xy 125.891182 -2.379175) (xy 126.031727 -2.371282) (xy 126.10211 -2.370836)
			(xy 194.701922 -2.370836) (xy 194.772304 -2.371321) (xy 194.912845 -2.379215) (xy 195.052723 -2.394977)
			(xy 195.191497 -2.418557) (xy 195.328731 -2.449881) (xy 195.463992 -2.488851) (xy 195.596856 -2.535344)
			(xy 195.726904 -2.589213) (xy 195.853726 -2.650289) (xy 195.976925 -2.71838) (xy 196.096111 -2.793273)
			(xy 196.210911 -2.87473) (xy 196.320963 -2.962495) (xy 196.425921 -3.056294) (xy 196.525454 -3.15583)
			(xy 196.61925 -3.26079) (xy 196.707012 -3.370845) (xy 196.788466 -3.485647) (xy 196.863355 -3.604836)
			(xy 196.931443 -3.728036) (xy 196.990215 -3.850081) (xy 208.661241 -3.850081) (xy 208.661241 -3.764331)
			(xy 208.669153 -3.678948) (xy 208.684909 -3.594658) (xy 208.708376 -3.512182) (xy 208.739352 -3.432223)
			(xy 208.777574 -3.355463) (xy 208.822715 -3.282557) (xy 208.874391 -3.214128) (xy 208.93216 -3.150758)
			(xy 208.99553 -3.092989) (xy 209.063959 -3.041313) (xy 209.136865 -2.996172) (xy 209.213625 -2.95795)
			(xy 209.293584 -2.926974) (xy 209.37606 -2.903507) (xy 209.46035 -2.887751) (xy 209.545733 -2.879839)
			(xy 209.631483 -2.879839) (xy 209.716866 -2.887751) (xy 209.801156 -2.903507) (xy 209.883632 -2.926974)
			(xy 209.963591 -2.95795) (xy 209.984264 -2.968244) (xy 213.517988 -2.968244) (xy 213.517988 -2.104644)
			(xy 213.518492 -2.07509) (xy 213.526541 -2.016534) (xy 213.542487 -1.959619) (xy 213.566036 -1.905405)
			(xy 213.596747 -1.854902) (xy 213.634049 -1.809052) (xy 213.677246 -1.768709) (xy 213.725535 -1.734623)
			(xy 213.778015 -1.70743) (xy 213.83371 -1.687636) (xy 213.891581 -1.67561) (xy 213.95055 -1.671577)
			(xy 214.009519 -1.67561) (xy 214.06739 -1.687636) (xy 214.123085 -1.70743) (xy 214.175565 -1.734623)
			(xy 214.223854 -1.768709) (xy 214.267051 -1.809052) (xy 214.304353 -1.854902) (xy 214.335064 -1.905405)
			(xy 214.358613 -1.959619) (xy 214.374559 -2.016534) (xy 214.382608 -2.07509) (xy 214.383112 -2.104644)
			(xy 214.383112 -2.968244) (xy 214.382608 -2.997798) (xy 214.374559 -3.056354) (xy 214.358613 -3.113269)
			(xy 214.335064 -3.167483) (xy 214.304353 -3.217986) (xy 214.267051 -3.263836) (xy 214.223854 -3.304179)
			(xy 214.175565 -3.338265) (xy 214.123085 -3.365458) (xy 214.06739 -3.385252) (xy 214.009519 -3.397278)
			(xy 213.95055 -3.401312) (xy 213.891581 -3.397278) (xy 213.83371 -3.385252) (xy 213.778015 -3.365458)
			(xy 213.725535 -3.338265) (xy 213.677246 -3.304179) (xy 213.634049 -3.263836) (xy 213.596747 -3.217986)
			(xy 213.566036 -3.167483) (xy 213.542487 -3.113269) (xy 213.526541 -3.056354) (xy 213.518492 -2.997798)
			(xy 213.517988 -2.968244) (xy 209.984264 -2.968244) (xy 210.040351 -2.996172) (xy 210.113257 -3.041313)
			(xy 210.181686 -3.092989) (xy 210.245056 -3.150758) (xy 210.302825 -3.214128) (xy 210.354501 -3.282557)
			(xy 210.399642 -3.355463) (xy 210.437864 -3.432223) (xy 210.46884 -3.512182) (xy 210.492307 -3.594658)
			(xy 210.508063 -3.678948) (xy 210.515975 -3.764331) (xy 210.51647 -3.807206) (xy 210.515975 -3.850081)
			(xy 215.011241 -3.850081) (xy 215.011241 -3.764331) (xy 215.019153 -3.678948) (xy 215.034909 -3.594658)
			(xy 215.058376 -3.512182) (xy 215.089352 -3.432223) (xy 215.127574 -3.355463) (xy 215.172715 -3.282557)
			(xy 215.224391 -3.214128) (xy 215.28216 -3.150758) (xy 215.34553 -3.092989) (xy 215.413959 -3.041313)
			(xy 215.486865 -2.996172) (xy 215.563625 -2.95795) (xy 215.643584 -2.926974) (xy 215.72606 -2.903507)
			(xy 215.81035 -2.887751) (xy 215.895733 -2.879839) (xy 215.981483 -2.879839) (xy 216.066866 -2.887751)
			(xy 216.151156 -2.903507) (xy 216.233632 -2.926974) (xy 216.313591 -2.95795) (xy 216.390351 -2.996172)
			(xy 216.463257 -3.041313) (xy 216.531686 -3.092989) (xy 216.595056 -3.150758) (xy 216.652825 -3.214128)
			(xy 216.704501 -3.282557) (xy 216.749642 -3.355463) (xy 216.787864 -3.432223) (xy 216.81884 -3.512182)
			(xy 216.842307 -3.594658) (xy 216.858063 -3.678948) (xy 216.865975 -3.764331) (xy 216.86647 -3.807206)
			(xy 216.865975 -3.850081) (xy 296.143921 -3.850081) (xy 296.143921 -3.764331) (xy 296.151833 -3.678948)
			(xy 296.167589 -3.594658) (xy 296.191056 -3.512182) (xy 296.222032 -3.432223) (xy 296.260254 -3.355463)
			(xy 296.305395 -3.282557) (xy 296.357071 -3.214128) (xy 296.41484 -3.150758) (xy 296.47821 -3.092989)
			(xy 296.546639 -3.041313) (xy 296.619545 -2.996172) (xy 296.696305 -2.95795) (xy 296.776264 -2.926974)
			(xy 296.85874 -2.903507) (xy 296.94303 -2.887751) (xy 297.028413 -2.879839) (xy 297.114163 -2.879839)
			(xy 297.199546 -2.887751) (xy 297.283836 -2.903507) (xy 297.366312 -2.926974) (xy 297.446271 -2.95795)
			(xy 297.466944 -2.968244) (xy 298.629324 -2.968244) (xy 298.629324 -2.104644) (xy 298.629828 -2.07509)
			(xy 298.637877 -2.016534) (xy 298.653823 -1.959619) (xy 298.677372 -1.905405) (xy 298.708083 -1.854902)
			(xy 298.745385 -1.809052) (xy 298.788582 -1.768709) (xy 298.836871 -1.734623) (xy 298.889351 -1.70743)
			(xy 298.945046 -1.687636) (xy 299.002917 -1.67561) (xy 299.061886 -1.671577) (xy 299.120855 -1.67561)
			(xy 299.178726 -1.687636) (xy 299.234421 -1.70743) (xy 299.286901 -1.734623) (xy 299.33519 -1.768709)
			(xy 299.378387 -1.809052) (xy 299.415689 -1.854902) (xy 299.4464 -1.905405) (xy 299.469949 -1.959619)
			(xy 299.485895 -2.016534) (xy 299.493944 -2.07509) (xy 299.494448 -2.104644) (xy 299.494448 -2.968244)
			(xy 299.493944 -2.997798) (xy 299.485895 -3.056354) (xy 299.469949 -3.113269) (xy 299.4464 -3.167483)
			(xy 299.415689 -3.217986) (xy 299.378387 -3.263836) (xy 299.33519 -3.304179) (xy 299.286901 -3.338265)
			(xy 299.234421 -3.365458) (xy 299.178726 -3.385252) (xy 299.120855 -3.397278) (xy 299.061886 -3.401312)
			(xy 299.002917 -3.397278) (xy 298.945046 -3.385252) (xy 298.889351 -3.365458) (xy 298.836871 -3.338265)
			(xy 298.788582 -3.304179) (xy 298.745385 -3.263836) (xy 298.708083 -3.217986) (xy 298.677372 -3.167483)
			(xy 298.653823 -3.113269) (xy 298.637877 -3.056354) (xy 298.629828 -2.997798) (xy 298.629324 -2.968244)
			(xy 297.466944 -2.968244) (xy 297.523031 -2.996172) (xy 297.595937 -3.041313) (xy 297.664366 -3.092989)
			(xy 297.727736 -3.150758) (xy 297.785505 -3.214128) (xy 297.837181 -3.282557) (xy 297.882322 -3.355463)
			(xy 297.920544 -3.432223) (xy 297.95152 -3.512182) (xy 297.974987 -3.594658) (xy 297.990743 -3.678948)
			(xy 297.998655 -3.764331) (xy 297.99915 -3.807206) (xy 297.998655 -3.850081) (xy 302.493921 -3.850081)
			(xy 302.493921 -3.764331) (xy 302.501833 -3.678948) (xy 302.517589 -3.594658) (xy 302.541056 -3.512182)
			(xy 302.572032 -3.432223) (xy 302.610254 -3.355463) (xy 302.655395 -3.282557) (xy 302.707071 -3.214128)
			(xy 302.76484 -3.150758) (xy 302.82821 -3.092989) (xy 302.896639 -3.041313) (xy 302.969545 -2.996172)
			(xy 303.046305 -2.95795) (xy 303.126264 -2.926974) (xy 303.20874 -2.903507) (xy 303.29303 -2.887751)
			(xy 303.378413 -2.879839) (xy 303.464163 -2.879839) (xy 303.549546 -2.887751) (xy 303.633836 -2.903507)
			(xy 303.716312 -2.926974) (xy 303.796271 -2.95795) (xy 303.873031 -2.996172) (xy 303.945937 -3.041313)
			(xy 304.014366 -3.092989) (xy 304.077736 -3.150758) (xy 304.135505 -3.214128) (xy 304.187181 -3.282557)
			(xy 304.232322 -3.355463) (xy 304.270544 -3.432223) (xy 304.30152 -3.512182) (xy 304.324987 -3.594658)
			(xy 304.340743 -3.678948) (xy 304.348655 -3.764331) (xy 304.34915 -3.807206) (xy 304.348655 -3.850081)
			(xy 311.155321 -3.850081) (xy 311.155321 -3.764331) (xy 311.163233 -3.678948) (xy 311.178989 -3.594658)
			(xy 311.202456 -3.512182) (xy 311.233432 -3.432223) (xy 311.271654 -3.355463) (xy 311.316795 -3.282557)
			(xy 311.368471 -3.214128) (xy 311.42624 -3.150758) (xy 311.48961 -3.092989) (xy 311.558039 -3.041313)
			(xy 311.630945 -2.996172) (xy 311.707705 -2.95795) (xy 311.787664 -2.926974) (xy 311.87014 -2.903507)
			(xy 311.95443 -2.887751) (xy 312.039813 -2.879839) (xy 312.125563 -2.879839) (xy 312.210946 -2.887751)
			(xy 312.295236 -2.903507) (xy 312.377712 -2.926974) (xy 312.457671 -2.95795) (xy 312.478344 -2.968244)
			(xy 316.012068 -2.968244) (xy 316.012068 -2.104644) (xy 316.012572 -2.07509) (xy 316.020621 -2.016534)
			(xy 316.036567 -1.959619) (xy 316.060116 -1.905405) (xy 316.090827 -1.854902) (xy 316.128129 -1.809052)
			(xy 316.171326 -1.768709) (xy 316.219615 -1.734623) (xy 316.272095 -1.70743) (xy 316.32779 -1.687636)
			(xy 316.385661 -1.67561) (xy 316.44463 -1.671577) (xy 316.503599 -1.67561) (xy 316.56147 -1.687636)
			(xy 316.617165 -1.70743) (xy 316.669645 -1.734623) (xy 316.717934 -1.768709) (xy 316.761131 -1.809052)
			(xy 316.798433 -1.854902) (xy 316.829144 -1.905405) (xy 316.852693 -1.959619) (xy 316.868639 -2.016534)
			(xy 316.876688 -2.07509) (xy 316.877192 -2.104644) (xy 316.877192 -2.968244) (xy 316.876688 -2.997798)
			(xy 316.868639 -3.056354) (xy 316.852693 -3.113269) (xy 316.829144 -3.167483) (xy 316.798433 -3.217986)
			(xy 316.761131 -3.263836) (xy 316.717934 -3.304179) (xy 316.669645 -3.338265) (xy 316.617165 -3.365458)
			(xy 316.56147 -3.385252) (xy 316.503599 -3.397278) (xy 316.44463 -3.401312) (xy 316.385661 -3.397278)
			(xy 316.32779 -3.385252) (xy 316.272095 -3.365458) (xy 316.219615 -3.338265) (xy 316.171326 -3.304179)
			(xy 316.128129 -3.263836) (xy 316.090827 -3.217986) (xy 316.060116 -3.167483) (xy 316.036567 -3.113269)
			(xy 316.020621 -3.056354) (xy 316.012572 -2.997798) (xy 316.012068 -2.968244) (xy 312.478344 -2.968244)
			(xy 312.534431 -2.996172) (xy 312.607337 -3.041313) (xy 312.675766 -3.092989) (xy 312.739136 -3.150758)
			(xy 312.796905 -3.214128) (xy 312.848581 -3.282557) (xy 312.893722 -3.355463) (xy 312.931944 -3.432223)
			(xy 312.96292 -3.512182) (xy 312.986387 -3.594658) (xy 313.002143 -3.678948) (xy 313.010055 -3.764331)
			(xy 313.01055 -3.807206) (xy 313.010055 -3.850081) (xy 317.505321 -3.850081) (xy 317.505321 -3.764331)
			(xy 317.513233 -3.678948) (xy 317.528989 -3.594658) (xy 317.552456 -3.512182) (xy 317.583432 -3.432223)
			(xy 317.621654 -3.355463) (xy 317.666795 -3.282557) (xy 317.718471 -3.214128) (xy 317.77624 -3.150758)
			(xy 317.83961 -3.092989) (xy 317.908039 -3.041313) (xy 317.980945 -2.996172) (xy 318.057705 -2.95795)
			(xy 318.137664 -2.926974) (xy 318.22014 -2.903507) (xy 318.30443 -2.887751) (xy 318.389813 -2.879839)
			(xy 318.475563 -2.879839) (xy 318.560946 -2.887751) (xy 318.645236 -2.903507) (xy 318.727712 -2.926974)
			(xy 318.807671 -2.95795) (xy 318.884431 -2.996172) (xy 318.957337 -3.041313) (xy 319.025766 -3.092989)
			(xy 319.089136 -3.150758) (xy 319.146905 -3.214128) (xy 319.198581 -3.282557) (xy 319.243722 -3.355463)
			(xy 319.281944 -3.432223) (xy 319.31292 -3.512182) (xy 319.336387 -3.594658) (xy 319.352143 -3.678948)
			(xy 319.360055 -3.764331) (xy 319.36055 -3.807206) (xy 319.360055 -3.850081) (xy 361.894107 -3.850081)
			(xy 361.894107 -3.764331) (xy 361.902019 -3.678948) (xy 361.917775 -3.594658) (xy 361.941242 -3.512182)
			(xy 361.972218 -3.432223) (xy 362.01044 -3.355463) (xy 362.055581 -3.282557) (xy 362.107257 -3.214128)
			(xy 362.165026 -3.150758) (xy 362.228396 -3.092989) (xy 362.296825 -3.041313) (xy 362.369731 -2.996172)
			(xy 362.446491 -2.95795) (xy 362.52645 -2.926974) (xy 362.608926 -2.903507) (xy 362.693216 -2.887751)
			(xy 362.778599 -2.879839) (xy 362.864349 -2.879839) (xy 362.949732 -2.887751) (xy 363.034022 -2.903507)
			(xy 363.116498 -2.926974) (xy 363.196457 -2.95795) (xy 363.21713 -2.968244) (xy 364.379764 -2.968244)
			(xy 364.379764 -2.104644) (xy 364.380268 -2.075108) (xy 364.388312 -2.016586) (xy 364.404249 -1.959704)
			(xy 364.427784 -1.905522) (xy 364.458477 -1.855049) (xy 364.495757 -1.809226) (xy 364.538929 -1.768906)
			(xy 364.587189 -1.73484) (xy 364.639639 -1.707663) (xy 364.6953 -1.687881) (xy 364.753137 -1.675862)
			(xy 364.812072 -1.671831) (xy 364.871007 -1.675862) (xy 364.928844 -1.687881) (xy 364.984505 -1.707663)
			(xy 365.036955 -1.73484) (xy 365.085215 -1.768906) (xy 365.128387 -1.809226) (xy 365.165667 -1.855049)
			(xy 365.19636 -1.905522) (xy 365.219895 -1.959704) (xy 365.235832 -2.016586) (xy 365.243876 -2.075108)
			(xy 365.24438 -2.104644) (xy 365.24438 -2.968244) (xy 365.243876 -2.99778) (xy 365.235832 -3.056302)
			(xy 365.219895 -3.113184) (xy 365.19636 -3.167366) (xy 365.165667 -3.217839) (xy 365.128387 -3.263662)
			(xy 365.085215 -3.303982) (xy 365.036955 -3.338048) (xy 364.984505 -3.365225) (xy 364.928844 -3.385007)
			(xy 364.871007 -3.397026) (xy 364.812072 -3.401057) (xy 364.753137 -3.397026) (xy 364.6953 -3.385007)
			(xy 364.639639 -3.365225) (xy 364.587189 -3.338048) (xy 364.538929 -3.303982) (xy 364.495757 -3.263662)
			(xy 364.458477 -3.217839) (xy 364.427784 -3.167366) (xy 364.404249 -3.113184) (xy 364.388312 -3.056302)
			(xy 364.380268 -2.99778) (xy 364.379764 -2.968244) (xy 363.21713 -2.968244) (xy 363.273217 -2.996172)
			(xy 363.346123 -3.041313) (xy 363.414552 -3.092989) (xy 363.477922 -3.150758) (xy 363.535691 -3.214128)
			(xy 363.587367 -3.282557) (xy 363.632508 -3.355463) (xy 363.67073 -3.432223) (xy 363.701706 -3.512182)
			(xy 363.725173 -3.594658) (xy 363.740929 -3.678948) (xy 363.748841 -3.764331) (xy 363.749336 -3.807206)
			(xy 363.748841 -3.850081) (xy 368.244107 -3.850081) (xy 368.244107 -3.764331) (xy 368.252019 -3.678948)
			(xy 368.267775 -3.594658) (xy 368.291242 -3.512182) (xy 368.322218 -3.432223) (xy 368.36044 -3.355463)
			(xy 368.405581 -3.282557) (xy 368.457257 -3.214128) (xy 368.515026 -3.150758) (xy 368.578396 -3.092989)
			(xy 368.646825 -3.041313) (xy 368.719731 -2.996172) (xy 368.796491 -2.95795) (xy 368.87645 -2.926974)
			(xy 368.958926 -2.903507) (xy 369.043216 -2.887751) (xy 369.128599 -2.879839) (xy 369.214349 -2.879839)
			(xy 369.299732 -2.887751) (xy 369.384022 -2.903507) (xy 369.466498 -2.926974) (xy 369.546457 -2.95795)
			(xy 369.623217 -2.996172) (xy 369.696123 -3.041313) (xy 369.764552 -3.092989) (xy 369.827922 -3.150758)
			(xy 369.885691 -3.214128) (xy 369.937367 -3.282557) (xy 369.982508 -3.355463) (xy 370.02073 -3.432223)
			(xy 370.051706 -3.512182) (xy 370.075173 -3.594658) (xy 370.090929 -3.678948) (xy 370.098841 -3.764331)
			(xy 370.099336 -3.807206) (xy 370.098841 -3.850081) (xy 370.090929 -3.935464) (xy 370.075173 -4.019754)
			(xy 370.051706 -4.10223) (xy 370.02073 -4.182189) (xy 369.982508 -4.258949) (xy 369.937367 -4.331855)
			(xy 369.885691 -4.400284) (xy 369.827922 -4.463654) (xy 369.764552 -4.521423) (xy 369.696123 -4.573099)
			(xy 369.623217 -4.61824) (xy 369.546457 -4.656462) (xy 369.466498 -4.687438) (xy 369.384022 -4.710905)
			(xy 369.299732 -4.726661) (xy 369.214349 -4.734573) (xy 369.128599 -4.734573) (xy 369.043216 -4.726661)
			(xy 368.958926 -4.710905) (xy 368.87645 -4.687438) (xy 368.796491 -4.656462) (xy 368.719731 -4.61824)
			(xy 368.646825 -4.573099) (xy 368.578396 -4.521423) (xy 368.515026 -4.463654) (xy 368.457257 -4.400284)
			(xy 368.405581 -4.331855) (xy 368.36044 -4.258949) (xy 368.322218 -4.182189) (xy 368.291242 -4.10223)
			(xy 368.267775 -4.019754) (xy 368.252019 -3.935464) (xy 368.244107 -3.850081) (xy 363.748841 -3.850081)
			(xy 363.740929 -3.935464) (xy 363.725173 -4.019754) (xy 363.701706 -4.10223) (xy 363.67073 -4.182189)
			(xy 363.632508 -4.258949) (xy 363.587367 -4.331855) (xy 363.535691 -4.400284) (xy 363.477922 -4.463654)
			(xy 363.414552 -4.521423) (xy 363.346123 -4.573099) (xy 363.273217 -4.61824) (xy 363.196457 -4.656462)
			(xy 363.116498 -4.687438) (xy 363.034022 -4.710905) (xy 362.949732 -4.726661) (xy 362.864349 -4.734573)
			(xy 362.778599 -4.734573) (xy 362.693216 -4.726661) (xy 362.608926 -4.710905) (xy 362.52645 -4.687438)
			(xy 362.446491 -4.656462) (xy 362.369731 -4.61824) (xy 362.296825 -4.573099) (xy 362.228396 -4.521423)
			(xy 362.165026 -4.463654) (xy 362.107257 -4.400284) (xy 362.055581 -4.331855) (xy 362.01044 -4.258949)
			(xy 361.972218 -4.182189) (xy 361.941242 -4.10223) (xy 361.917775 -4.019754) (xy 361.902019 -3.935464)
			(xy 361.894107 -3.850081) (xy 319.360055 -3.850081) (xy 319.352143 -3.935464) (xy 319.336387 -4.019754)
			(xy 319.31292 -4.10223) (xy 319.281944 -4.182189) (xy 319.243722 -4.258949) (xy 319.198581 -4.331855)
			(xy 319.146905 -4.400284) (xy 319.089136 -4.463654) (xy 319.025766 -4.521423) (xy 318.957337 -4.573099)
			(xy 318.884431 -4.61824) (xy 318.807671 -4.656462) (xy 318.727712 -4.687438) (xy 318.645236 -4.710905)
			(xy 318.560946 -4.726661) (xy 318.475563 -4.734573) (xy 318.389813 -4.734573) (xy 318.30443 -4.726661)
			(xy 318.22014 -4.710905) (xy 318.137664 -4.687438) (xy 318.057705 -4.656462) (xy 317.980945 -4.61824)
			(xy 317.908039 -4.573099) (xy 317.83961 -4.521423) (xy 317.77624 -4.463654) (xy 317.718471 -4.400284)
			(xy 317.666795 -4.331855) (xy 317.621654 -4.258949) (xy 317.583432 -4.182189) (xy 317.552456 -4.10223)
			(xy 317.528989 -4.019754) (xy 317.513233 -3.935464) (xy 317.505321 -3.850081) (xy 313.010055 -3.850081)
			(xy 313.002143 -3.935464) (xy 312.986387 -4.019754) (xy 312.96292 -4.10223) (xy 312.931944 -4.182189)
			(xy 312.893722 -4.258949) (xy 312.848581 -4.331855) (xy 312.796905 -4.400284) (xy 312.739136 -4.463654)
			(xy 312.675766 -4.521423) (xy 312.607337 -4.573099) (xy 312.534431 -4.61824) (xy 312.457671 -4.656462)
			(xy 312.377712 -4.687438) (xy 312.295236 -4.710905) (xy 312.210946 -4.726661) (xy 312.125563 -4.734573)
			(xy 312.039813 -4.734573) (xy 311.95443 -4.726661) (xy 311.87014 -4.710905) (xy 311.787664 -4.687438)
			(xy 311.707705 -4.656462) (xy 311.630945 -4.61824) (xy 311.558039 -4.573099) (xy 311.48961 -4.521423)
			(xy 311.42624 -4.463654) (xy 311.368471 -4.400284) (xy 311.316795 -4.331855) (xy 311.271654 -4.258949)
			(xy 311.233432 -4.182189) (xy 311.202456 -4.10223) (xy 311.178989 -4.019754) (xy 311.163233 -3.935464)
			(xy 311.155321 -3.850081) (xy 304.348655 -3.850081) (xy 304.340743 -3.935464) (xy 304.324987 -4.019754)
			(xy 304.30152 -4.10223) (xy 304.270544 -4.182189) (xy 304.232322 -4.258949) (xy 304.187181 -4.331855)
			(xy 304.135505 -4.400284) (xy 304.077736 -4.463654) (xy 304.014366 -4.521423) (xy 303.945937 -4.573099)
			(xy 303.873031 -4.61824) (xy 303.796271 -4.656462) (xy 303.716312 -4.687438) (xy 303.633836 -4.710905)
			(xy 303.549546 -4.726661) (xy 303.464163 -4.734573) (xy 303.378413 -4.734573) (xy 303.29303 -4.726661)
			(xy 303.20874 -4.710905) (xy 303.126264 -4.687438) (xy 303.046305 -4.656462) (xy 302.969545 -4.61824)
			(xy 302.896639 -4.573099) (xy 302.82821 -4.521423) (xy 302.76484 -4.463654) (xy 302.707071 -4.400284)
			(xy 302.655395 -4.331855) (xy 302.610254 -4.258949) (xy 302.572032 -4.182189) (xy 302.541056 -4.10223)
			(xy 302.517589 -4.019754) (xy 302.501833 -3.935464) (xy 302.493921 -3.850081) (xy 297.998655 -3.850081)
			(xy 297.990743 -3.935464) (xy 297.974987 -4.019754) (xy 297.95152 -4.10223) (xy 297.920544 -4.182189)
			(xy 297.882322 -4.258949) (xy 297.837181 -4.331855) (xy 297.785505 -4.400284) (xy 297.727736 -4.463654)
			(xy 297.664366 -4.521423) (xy 297.595937 -4.573099) (xy 297.523031 -4.61824) (xy 297.446271 -4.656462)
			(xy 297.366312 -4.687438) (xy 297.283836 -4.710905) (xy 297.199546 -4.726661) (xy 297.114163 -4.734573)
			(xy 297.028413 -4.734573) (xy 296.94303 -4.726661) (xy 296.85874 -4.710905) (xy 296.776264 -4.687438)
			(xy 296.696305 -4.656462) (xy 296.619545 -4.61824) (xy 296.546639 -4.573099) (xy 296.47821 -4.521423)
			(xy 296.41484 -4.463654) (xy 296.357071 -4.400284) (xy 296.305395 -4.331855) (xy 296.260254 -4.258949)
			(xy 296.222032 -4.182189) (xy 296.191056 -4.10223) (xy 296.167589 -4.019754) (xy 296.151833 -3.935464)
			(xy 296.143921 -3.850081) (xy 216.865975 -3.850081) (xy 216.858063 -3.935464) (xy 216.842307 -4.019754)
			(xy 216.81884 -4.10223) (xy 216.787864 -4.182189) (xy 216.749642 -4.258949) (xy 216.704501 -4.331855)
			(xy 216.652825 -4.400284) (xy 216.595056 -4.463654) (xy 216.531686 -4.521423) (xy 216.463257 -4.573099)
			(xy 216.390351 -4.61824) (xy 216.313591 -4.656462) (xy 216.233632 -4.687438) (xy 216.151156 -4.710905)
			(xy 216.066866 -4.726661) (xy 215.981483 -4.734573) (xy 215.895733 -4.734573) (xy 215.81035 -4.726661)
			(xy 215.72606 -4.710905) (xy 215.643584 -4.687438) (xy 215.563625 -4.656462) (xy 215.486865 -4.61824)
			(xy 215.413959 -4.573099) (xy 215.34553 -4.521423) (xy 215.28216 -4.463654) (xy 215.224391 -4.400284)
			(xy 215.172715 -4.331855) (xy 215.127574 -4.258949) (xy 215.089352 -4.182189) (xy 215.058376 -4.10223)
			(xy 215.034909 -4.019754) (xy 215.019153 -3.935464) (xy 215.011241 -3.850081) (xy 210.515975 -3.850081)
			(xy 210.508063 -3.935464) (xy 210.492307 -4.019754) (xy 210.46884 -4.10223) (xy 210.437864 -4.182189)
			(xy 210.399642 -4.258949) (xy 210.354501 -4.331855) (xy 210.302825 -4.400284) (xy 210.245056 -4.463654)
			(xy 210.181686 -4.521423) (xy 210.113257 -4.573099) (xy 210.040351 -4.61824) (xy 209.963591 -4.656462)
			(xy 209.883632 -4.687438) (xy 209.801156 -4.710905) (xy 209.716866 -4.726661) (xy 209.631483 -4.734573)
			(xy 209.545733 -4.734573) (xy 209.46035 -4.726661) (xy 209.37606 -4.710905) (xy 209.293584 -4.687438)
			(xy 209.213625 -4.656462) (xy 209.136865 -4.61824) (xy 209.063959 -4.573099) (xy 208.99553 -4.521423)
			(xy 208.93216 -4.463654) (xy 208.874391 -4.400284) (xy 208.822715 -4.331855) (xy 208.777574 -4.258949)
			(xy 208.739352 -4.182189) (xy 208.708376 -4.10223) (xy 208.684909 -4.019754) (xy 208.669153 -3.935464)
			(xy 208.661241 -3.850081) (xy 196.990215 -3.850081) (xy 196.992516 -3.85486) (xy 197.046381 -3.984909)
			(xy 197.09287 -4.117774) (xy 197.131836 -4.253037) (xy 197.163157 -4.390271) (xy 197.186733 -4.529046)
			(xy 197.202491 -4.668924) (xy 197.210381 -4.809466) (xy 197.210934 -4.879848) (xy 197.210934 -6.390081)
			(xy 208.661241 -6.390081) (xy 208.661241 -6.304331) (xy 208.669153 -6.218948) (xy 208.684909 -6.134658)
			(xy 208.708376 -6.052182) (xy 208.739352 -5.972223) (xy 208.777574 -5.895463) (xy 208.822715 -5.822557)
			(xy 208.874391 -5.754128) (xy 208.93216 -5.690758) (xy 208.99553 -5.632989) (xy 209.063959 -5.581313)
			(xy 209.136865 -5.536172) (xy 209.213625 -5.49795) (xy 209.293584 -5.466974) (xy 209.37606 -5.443507)
			(xy 209.46035 -5.427751) (xy 209.545733 -5.419839) (xy 209.631483 -5.419839) (xy 209.716866 -5.427751)
			(xy 209.801156 -5.443507) (xy 209.883632 -5.466974) (xy 209.963591 -5.49795) (xy 209.984264 -5.508244)
			(xy 213.517988 -5.508244) (xy 213.517988 -4.644644) (xy 213.518492 -4.61509) (xy 213.526541 -4.556534)
			(xy 213.542487 -4.499619) (xy 213.566036 -4.445405) (xy 213.596747 -4.394902) (xy 213.634049 -4.349052)
			(xy 213.677246 -4.308709) (xy 213.725535 -4.274623) (xy 213.778015 -4.24743) (xy 213.83371 -4.227636)
			(xy 213.891581 -4.21561) (xy 213.95055 -4.211577) (xy 214.009519 -4.21561) (xy 214.06739 -4.227636)
			(xy 214.123085 -4.24743) (xy 214.175565 -4.274623) (xy 214.223854 -4.308709) (xy 214.267051 -4.349052)
			(xy 214.304353 -4.394902) (xy 214.335064 -4.445405) (xy 214.358613 -4.499619) (xy 214.374559 -4.556534)
			(xy 214.382608 -4.61509) (xy 214.383112 -4.644644) (xy 214.383112 -5.508244) (xy 214.382608 -5.537798)
			(xy 214.374559 -5.596354) (xy 214.358613 -5.653269) (xy 214.335064 -5.707483) (xy 214.304353 -5.757986)
			(xy 214.267051 -5.803836) (xy 214.223854 -5.844179) (xy 214.175565 -5.878265) (xy 214.123085 -5.905458)
			(xy 214.06739 -5.925252) (xy 214.009519 -5.937278) (xy 213.95055 -5.941312) (xy 213.891581 -5.937278)
			(xy 213.83371 -5.925252) (xy 213.778015 -5.905458) (xy 213.725535 -5.878265) (xy 213.677246 -5.844179)
			(xy 213.634049 -5.803836) (xy 213.596747 -5.757986) (xy 213.566036 -5.707483) (xy 213.542487 -5.653269)
			(xy 213.526541 -5.596354) (xy 213.518492 -5.537798) (xy 213.517988 -5.508244) (xy 209.984264 -5.508244)
			(xy 210.040351 -5.536172) (xy 210.113257 -5.581313) (xy 210.181686 -5.632989) (xy 210.245056 -5.690758)
			(xy 210.302825 -5.754128) (xy 210.354501 -5.822557) (xy 210.399642 -5.895463) (xy 210.437864 -5.972223)
			(xy 210.46884 -6.052182) (xy 210.492307 -6.134658) (xy 210.508063 -6.218948) (xy 210.515975 -6.304331)
			(xy 210.51647 -6.347206) (xy 210.515975 -6.390081) (xy 215.011241 -6.390081) (xy 215.011241 -6.304331)
			(xy 215.019153 -6.218948) (xy 215.034909 -6.134658) (xy 215.058376 -6.052182) (xy 215.089352 -5.972223)
			(xy 215.127574 -5.895463) (xy 215.172715 -5.822557) (xy 215.224391 -5.754128) (xy 215.28216 -5.690758)
			(xy 215.34553 -5.632989) (xy 215.413959 -5.581313) (xy 215.486865 -5.536172) (xy 215.563625 -5.49795)
			(xy 215.643584 -5.466974) (xy 215.72606 -5.443507) (xy 215.81035 -5.427751) (xy 215.895733 -5.419839)
			(xy 215.981483 -5.419839) (xy 216.066866 -5.427751) (xy 216.151156 -5.443507) (xy 216.233632 -5.466974)
			(xy 216.313591 -5.49795) (xy 216.390351 -5.536172) (xy 216.463257 -5.581313) (xy 216.531686 -5.632989)
			(xy 216.595056 -5.690758) (xy 216.652825 -5.754128) (xy 216.704501 -5.822557) (xy 216.749642 -5.895463)
			(xy 216.787864 -5.972223) (xy 216.81884 -6.052182) (xy 216.842307 -6.134658) (xy 216.858063 -6.218948)
			(xy 216.865975 -6.304331) (xy 216.86647 -6.347206) (xy 216.865975 -6.390081) (xy 296.143921 -6.390081)
			(xy 296.143921 -6.304331) (xy 296.151833 -6.218948) (xy 296.167589 -6.134658) (xy 296.191056 -6.052182)
			(xy 296.222032 -5.972223) (xy 296.260254 -5.895463) (xy 296.305395 -5.822557) (xy 296.357071 -5.754128)
			(xy 296.41484 -5.690758) (xy 296.47821 -5.632989) (xy 296.546639 -5.581313) (xy 296.619545 -5.536172)
			(xy 296.696305 -5.49795) (xy 296.776264 -5.466974) (xy 296.85874 -5.443507) (xy 296.94303 -5.427751)
			(xy 297.028413 -5.419839) (xy 297.114163 -5.419839) (xy 297.199546 -5.427751) (xy 297.283836 -5.443507)
			(xy 297.366312 -5.466974) (xy 297.446271 -5.49795) (xy 297.466944 -5.508244) (xy 298.629324 -5.508244)
			(xy 298.629324 -4.644644) (xy 298.629828 -4.61509) (xy 298.637877 -4.556534) (xy 298.653823 -4.499619)
			(xy 298.677372 -4.445405) (xy 298.708083 -4.394902) (xy 298.745385 -4.349052) (xy 298.788582 -4.308709)
			(xy 298.836871 -4.274623) (xy 298.889351 -4.24743) (xy 298.945046 -4.227636) (xy 299.002917 -4.21561)
			(xy 299.061886 -4.211577) (xy 299.120855 -4.21561) (xy 299.178726 -4.227636) (xy 299.234421 -4.24743)
			(xy 299.286901 -4.274623) (xy 299.33519 -4.308709) (xy 299.378387 -4.349052) (xy 299.415689 -4.394902)
			(xy 299.4464 -4.445405) (xy 299.469949 -4.499619) (xy 299.485895 -4.556534) (xy 299.493944 -4.61509)
			(xy 299.494448 -4.644644) (xy 299.494448 -5.508244) (xy 299.493944 -5.537798) (xy 299.485895 -5.596354)
			(xy 299.469949 -5.653269) (xy 299.4464 -5.707483) (xy 299.415689 -5.757986) (xy 299.378387 -5.803836)
			(xy 299.33519 -5.844179) (xy 299.286901 -5.878265) (xy 299.234421 -5.905458) (xy 299.178726 -5.925252)
			(xy 299.120855 -5.937278) (xy 299.061886 -5.941312) (xy 299.002917 -5.937278) (xy 298.945046 -5.925252)
			(xy 298.889351 -5.905458) (xy 298.836871 -5.878265) (xy 298.788582 -5.844179) (xy 298.745385 -5.803836)
			(xy 298.708083 -5.757986) (xy 298.677372 -5.707483) (xy 298.653823 -5.653269) (xy 298.637877 -5.596354)
			(xy 298.629828 -5.537798) (xy 298.629324 -5.508244) (xy 297.466944 -5.508244) (xy 297.523031 -5.536172)
			(xy 297.595937 -5.581313) (xy 297.664366 -5.632989) (xy 297.727736 -5.690758) (xy 297.785505 -5.754128)
			(xy 297.837181 -5.822557) (xy 297.882322 -5.895463) (xy 297.920544 -5.972223) (xy 297.95152 -6.052182)
			(xy 297.974987 -6.134658) (xy 297.990743 -6.218948) (xy 297.998655 -6.304331) (xy 297.99915 -6.347206)
			(xy 297.998655 -6.390081) (xy 302.493921 -6.390081) (xy 302.493921 -6.304331) (xy 302.501833 -6.218948)
			(xy 302.517589 -6.134658) (xy 302.541056 -6.052182) (xy 302.572032 -5.972223) (xy 302.610254 -5.895463)
			(xy 302.655395 -5.822557) (xy 302.707071 -5.754128) (xy 302.76484 -5.690758) (xy 302.82821 -5.632989)
			(xy 302.896639 -5.581313) (xy 302.969545 -5.536172) (xy 303.046305 -5.49795) (xy 303.126264 -5.466974)
			(xy 303.20874 -5.443507) (xy 303.29303 -5.427751) (xy 303.378413 -5.419839) (xy 303.464163 -5.419839)
			(xy 303.549546 -5.427751) (xy 303.633836 -5.443507) (xy 303.716312 -5.466974) (xy 303.796271 -5.49795)
			(xy 303.873031 -5.536172) (xy 303.945937 -5.581313) (xy 304.014366 -5.632989) (xy 304.077736 -5.690758)
			(xy 304.135505 -5.754128) (xy 304.187181 -5.822557) (xy 304.232322 -5.895463) (xy 304.270544 -5.972223)
			(xy 304.30152 -6.052182) (xy 304.324987 -6.134658) (xy 304.340743 -6.218948) (xy 304.348655 -6.304331)
			(xy 304.34915 -6.347206) (xy 304.348655 -6.390081) (xy 311.155321 -6.390081) (xy 311.155321 -6.304331)
			(xy 311.163233 -6.218948) (xy 311.178989 -6.134658) (xy 311.202456 -6.052182) (xy 311.233432 -5.972223)
			(xy 311.271654 -5.895463) (xy 311.316795 -5.822557) (xy 311.368471 -5.754128) (xy 311.42624 -5.690758)
			(xy 311.48961 -5.632989) (xy 311.558039 -5.581313) (xy 311.630945 -5.536172) (xy 311.707705 -5.49795)
			(xy 311.787664 -5.466974) (xy 311.87014 -5.443507) (xy 311.95443 -5.427751) (xy 312.039813 -5.419839)
			(xy 312.125563 -5.419839) (xy 312.210946 -5.427751) (xy 312.295236 -5.443507) (xy 312.377712 -5.466974)
			(xy 312.457671 -5.49795) (xy 312.534431 -5.536172) (xy 312.607337 -5.581313) (xy 312.675766 -5.632989)
			(xy 312.739136 -5.690758) (xy 312.796905 -5.754128) (xy 312.848581 -5.822557) (xy 312.893722 -5.895463)
			(xy 312.931944 -5.972223) (xy 312.96292 -6.052182) (xy 312.986387 -6.134658) (xy 313.002143 -6.218948)
			(xy 313.010055 -6.304331) (xy 313.01055 -6.347206) (xy 313.010055 -6.390081) (xy 317.505321 -6.390081)
			(xy 317.505321 -6.304331) (xy 317.513233 -6.218948) (xy 317.528989 -6.134658) (xy 317.552456 -6.052182)
			(xy 317.583432 -5.972223) (xy 317.621654 -5.895463) (xy 317.666795 -5.822557) (xy 317.718471 -5.754128)
			(xy 317.77624 -5.690758) (xy 317.83961 -5.632989) (xy 317.908039 -5.581313) (xy 317.980945 -5.536172)
			(xy 318.057705 -5.49795) (xy 318.137664 -5.466974) (xy 318.22014 -5.443507) (xy 318.30443 -5.427751)
			(xy 318.389813 -5.419839) (xy 318.475563 -5.419839) (xy 318.560946 -5.427751) (xy 318.645236 -5.443507)
			(xy 318.727712 -5.466974) (xy 318.807671 -5.49795) (xy 318.884431 -5.536172) (xy 318.957337 -5.581313)
			(xy 319.025766 -5.632989) (xy 319.089136 -5.690758) (xy 319.146905 -5.754128) (xy 319.198581 -5.822557)
			(xy 319.243722 -5.895463) (xy 319.281944 -5.972223) (xy 319.31292 -6.052182) (xy 319.336387 -6.134658)
			(xy 319.352143 -6.218948) (xy 319.360055 -6.304331) (xy 319.36055 -6.347206) (xy 319.360055 -6.390081)
			(xy 361.894107 -6.390081) (xy 361.894107 -6.304331) (xy 361.902019 -6.218948) (xy 361.917775 -6.134658)
			(xy 361.941242 -6.052182) (xy 361.972218 -5.972223) (xy 362.01044 -5.895463) (xy 362.055581 -5.822557)
			(xy 362.107257 -5.754128) (xy 362.165026 -5.690758) (xy 362.228396 -5.632989) (xy 362.296825 -5.581313)
			(xy 362.369731 -5.536172) (xy 362.446491 -5.49795) (xy 362.52645 -5.466974) (xy 362.608926 -5.443507)
			(xy 362.693216 -5.427751) (xy 362.778599 -5.419839) (xy 362.864349 -5.419839) (xy 362.949732 -5.427751)
			(xy 363.034022 -5.443507) (xy 363.116498 -5.466974) (xy 363.196457 -5.49795) (xy 363.273217 -5.536172)
			(xy 363.346123 -5.581313) (xy 363.414552 -5.632989) (xy 363.477922 -5.690758) (xy 363.535691 -5.754128)
			(xy 363.587367 -5.822557) (xy 363.632508 -5.895463) (xy 363.67073 -5.972223) (xy 363.701706 -6.052182)
			(xy 363.725173 -6.134658) (xy 363.740929 -6.218948) (xy 363.748841 -6.304331) (xy 363.749336 -6.347206)
			(xy 363.748841 -6.390081) (xy 368.244107 -6.390081) (xy 368.244107 -6.304331) (xy 368.252019 -6.218948)
			(xy 368.267775 -6.134658) (xy 368.291242 -6.052182) (xy 368.322218 -5.972223) (xy 368.36044 -5.895463)
			(xy 368.405581 -5.822557) (xy 368.457257 -5.754128) (xy 368.515026 -5.690758) (xy 368.578396 -5.632989)
			(xy 368.646825 -5.581313) (xy 368.719731 -5.536172) (xy 368.796491 -5.49795) (xy 368.87645 -5.466974)
			(xy 368.958926 -5.443507) (xy 369.043216 -5.427751) (xy 369.128599 -5.419839) (xy 369.214349 -5.419839)
			(xy 369.299732 -5.427751) (xy 369.384022 -5.443507) (xy 369.466498 -5.466974) (xy 369.546457 -5.49795)
			(xy 369.623217 -5.536172) (xy 369.696123 -5.581313) (xy 369.764552 -5.632989) (xy 369.827922 -5.690758)
			(xy 369.885691 -5.754128) (xy 369.937367 -5.822557) (xy 369.982508 -5.895463) (xy 370.02073 -5.972223)
			(xy 370.051706 -6.052182) (xy 370.075173 -6.134658) (xy 370.090929 -6.218948) (xy 370.098841 -6.304331)
			(xy 370.099336 -6.347206) (xy 370.098841 -6.390081) (xy 370.090929 -6.475464) (xy 370.075173 -6.559754)
			(xy 370.051706 -6.64223) (xy 370.02073 -6.722189) (xy 369.982508 -6.798949) (xy 369.937367 -6.871855)
			(xy 369.885691 -6.940284) (xy 369.827922 -7.003654) (xy 369.764552 -7.061423) (xy 369.696123 -7.113099)
			(xy 369.623217 -7.15824) (xy 369.546457 -7.196462) (xy 369.466498 -7.227438) (xy 369.384022 -7.250905)
			(xy 369.299732 -7.266661) (xy 369.214349 -7.274573) (xy 369.128599 -7.274573) (xy 369.043216 -7.266661)
			(xy 368.958926 -7.250905) (xy 368.87645 -7.227438) (xy 368.796491 -7.196462) (xy 368.719731 -7.15824)
			(xy 368.646825 -7.113099) (xy 368.578396 -7.061423) (xy 368.515026 -7.003654) (xy 368.457257 -6.940284)
			(xy 368.405581 -6.871855) (xy 368.36044 -6.798949) (xy 368.322218 -6.722189) (xy 368.291242 -6.64223)
			(xy 368.267775 -6.559754) (xy 368.252019 -6.475464) (xy 368.244107 -6.390081) (xy 363.748841 -6.390081)
			(xy 363.740929 -6.475464) (xy 363.725173 -6.559754) (xy 363.701706 -6.64223) (xy 363.67073 -6.722189)
			(xy 363.632508 -6.798949) (xy 363.587367 -6.871855) (xy 363.535691 -6.940284) (xy 363.477922 -7.003654)
			(xy 363.414552 -7.061423) (xy 363.346123 -7.113099) (xy 363.273217 -7.15824) (xy 363.196457 -7.196462)
			(xy 363.116498 -7.227438) (xy 363.034022 -7.250905) (xy 362.949732 -7.266661) (xy 362.864349 -7.274573)
			(xy 362.778599 -7.274573) (xy 362.693216 -7.266661) (xy 362.608926 -7.250905) (xy 362.52645 -7.227438)
			(xy 362.446491 -7.196462) (xy 362.369731 -7.15824) (xy 362.296825 -7.113099) (xy 362.228396 -7.061423)
			(xy 362.165026 -7.003654) (xy 362.107257 -6.940284) (xy 362.055581 -6.871855) (xy 362.01044 -6.798949)
			(xy 361.972218 -6.722189) (xy 361.941242 -6.64223) (xy 361.917775 -6.559754) (xy 361.902019 -6.475464)
			(xy 361.894107 -6.390081) (xy 319.360055 -6.390081) (xy 319.352143 -6.475464) (xy 319.336387 -6.559754)
			(xy 319.31292 -6.64223) (xy 319.281944 -6.722189) (xy 319.243722 -6.798949) (xy 319.198581 -6.871855)
			(xy 319.146905 -6.940284) (xy 319.089136 -7.003654) (xy 319.025766 -7.061423) (xy 318.957337 -7.113099)
			(xy 318.884431 -7.15824) (xy 318.807671 -7.196462) (xy 318.727712 -7.227438) (xy 318.645236 -7.250905)
			(xy 318.560946 -7.266661) (xy 318.475563 -7.274573) (xy 318.389813 -7.274573) (xy 318.30443 -7.266661)
			(xy 318.22014 -7.250905) (xy 318.137664 -7.227438) (xy 318.057705 -7.196462) (xy 317.980945 -7.15824)
			(xy 317.908039 -7.113099) (xy 317.83961 -7.061423) (xy 317.77624 -7.003654) (xy 317.718471 -6.940284)
			(xy 317.666795 -6.871855) (xy 317.621654 -6.798949) (xy 317.583432 -6.722189) (xy 317.552456 -6.64223)
			(xy 317.528989 -6.559754) (xy 317.513233 -6.475464) (xy 317.505321 -6.390081) (xy 313.010055 -6.390081)
			(xy 313.002143 -6.475464) (xy 312.986387 -6.559754) (xy 312.96292 -6.64223) (xy 312.931944 -6.722189)
			(xy 312.893722 -6.798949) (xy 312.848581 -6.871855) (xy 312.796905 -6.940284) (xy 312.739136 -7.003654)
			(xy 312.675766 -7.061423) (xy 312.607337 -7.113099) (xy 312.534431 -7.15824) (xy 312.457671 -7.196462)
			(xy 312.377712 -7.227438) (xy 312.295236 -7.250905) (xy 312.210946 -7.266661) (xy 312.125563 -7.274573)
			(xy 312.039813 -7.274573) (xy 311.95443 -7.266661) (xy 311.87014 -7.250905) (xy 311.787664 -7.227438)
			(xy 311.707705 -7.196462) (xy 311.630945 -7.15824) (xy 311.558039 -7.113099) (xy 311.48961 -7.061423)
			(xy 311.42624 -7.003654) (xy 311.368471 -6.940284) (xy 311.316795 -6.871855) (xy 311.271654 -6.798949)
			(xy 311.233432 -6.722189) (xy 311.202456 -6.64223) (xy 311.178989 -6.559754) (xy 311.163233 -6.475464)
			(xy 311.155321 -6.390081) (xy 304.348655 -6.390081) (xy 304.340743 -6.475464) (xy 304.324987 -6.559754)
			(xy 304.30152 -6.64223) (xy 304.270544 -6.722189) (xy 304.232322 -6.798949) (xy 304.187181 -6.871855)
			(xy 304.135505 -6.940284) (xy 304.077736 -7.003654) (xy 304.014366 -7.061423) (xy 303.945937 -7.113099)
			(xy 303.873031 -7.15824) (xy 303.796271 -7.196462) (xy 303.716312 -7.227438) (xy 303.633836 -7.250905)
			(xy 303.549546 -7.266661) (xy 303.464163 -7.274573) (xy 303.378413 -7.274573) (xy 303.29303 -7.266661)
			(xy 303.20874 -7.250905) (xy 303.126264 -7.227438) (xy 303.046305 -7.196462) (xy 302.969545 -7.15824)
			(xy 302.896639 -7.113099) (xy 302.82821 -7.061423) (xy 302.76484 -7.003654) (xy 302.707071 -6.940284)
			(xy 302.655395 -6.871855) (xy 302.610254 -6.798949) (xy 302.572032 -6.722189) (xy 302.541056 -6.64223)
			(xy 302.517589 -6.559754) (xy 302.501833 -6.475464) (xy 302.493921 -6.390081) (xy 297.998655 -6.390081)
			(xy 297.990743 -6.475464) (xy 297.974987 -6.559754) (xy 297.95152 -6.64223) (xy 297.920544 -6.722189)
			(xy 297.882322 -6.798949) (xy 297.837181 -6.871855) (xy 297.785505 -6.940284) (xy 297.727736 -7.003654)
			(xy 297.664366 -7.061423) (xy 297.595937 -7.113099) (xy 297.523031 -7.15824) (xy 297.446271 -7.196462)
			(xy 297.366312 -7.227438) (xy 297.283836 -7.250905) (xy 297.199546 -7.266661) (xy 297.114163 -7.274573)
			(xy 297.028413 -7.274573) (xy 296.94303 -7.266661) (xy 296.85874 -7.250905) (xy 296.776264 -7.227438)
			(xy 296.696305 -7.196462) (xy 296.619545 -7.15824) (xy 296.546639 -7.113099) (xy 296.47821 -7.061423)
			(xy 296.41484 -7.003654) (xy 296.357071 -6.940284) (xy 296.305395 -6.871855) (xy 296.260254 -6.798949)
			(xy 296.222032 -6.722189) (xy 296.191056 -6.64223) (xy 296.167589 -6.559754) (xy 296.151833 -6.475464)
			(xy 296.143921 -6.390081) (xy 216.865975 -6.390081) (xy 216.858063 -6.475464) (xy 216.842307 -6.559754)
			(xy 216.81884 -6.64223) (xy 216.787864 -6.722189) (xy 216.749642 -6.798949) (xy 216.704501 -6.871855)
			(xy 216.652825 -6.940284) (xy 216.595056 -7.003654) (xy 216.531686 -7.061423) (xy 216.463257 -7.113099)
			(xy 216.390351 -7.15824) (xy 216.313591 -7.196462) (xy 216.233632 -7.227438) (xy 216.151156 -7.250905)
			(xy 216.066866 -7.266661) (xy 215.981483 -7.274573) (xy 215.895733 -7.274573) (xy 215.81035 -7.266661)
			(xy 215.72606 -7.250905) (xy 215.643584 -7.227438) (xy 215.563625 -7.196462) (xy 215.486865 -7.15824)
			(xy 215.413959 -7.113099) (xy 215.34553 -7.061423) (xy 215.28216 -7.003654) (xy 215.224391 -6.940284)
			(xy 215.172715 -6.871855) (xy 215.127574 -6.798949) (xy 215.089352 -6.722189) (xy 215.058376 -6.64223)
			(xy 215.034909 -6.559754) (xy 215.019153 -6.475464) (xy 215.011241 -6.390081) (xy 210.515975 -6.390081)
			(xy 210.508063 -6.475464) (xy 210.492307 -6.559754) (xy 210.46884 -6.64223) (xy 210.437864 -6.722189)
			(xy 210.399642 -6.798949) (xy 210.354501 -6.871855) (xy 210.302825 -6.940284) (xy 210.245056 -7.003654)
			(xy 210.181686 -7.061423) (xy 210.113257 -7.113099) (xy 210.040351 -7.15824) (xy 209.963591 -7.196462)
			(xy 209.883632 -7.227438) (xy 209.801156 -7.250905) (xy 209.716866 -7.266661) (xy 209.631483 -7.274573)
			(xy 209.545733 -7.274573) (xy 209.46035 -7.266661) (xy 209.37606 -7.250905) (xy 209.293584 -7.227438)
			(xy 209.213625 -7.196462) (xy 209.136865 -7.15824) (xy 209.063959 -7.113099) (xy 208.99553 -7.061423)
			(xy 208.93216 -7.003654) (xy 208.874391 -6.940284) (xy 208.822715 -6.871855) (xy 208.777574 -6.798949)
			(xy 208.739352 -6.722189) (xy 208.708376 -6.64223) (xy 208.684909 -6.559754) (xy 208.669153 -6.475464)
			(xy 208.661241 -6.390081) (xy 197.210934 -6.390081) (xy 197.210934 -7.78002) (xy 197.211456 -7.835788)
			(xy 197.219793 -7.947013) (xy 197.236418 -8.057304) (xy 197.261239 -8.166044) (xy 197.294116 -8.272625)
			(xy 197.334866 -8.376451) (xy 197.383261 -8.476941) (xy 197.439031 -8.573534) (xy 197.501863 -8.66569)
			(xy 197.571406 -8.752892) (xy 197.647271 -8.834653) (xy 197.729034 -8.910516) (xy 197.816238 -8.980057)
			(xy 197.908394 -9.042887) (xy 198.004989 -9.098654) (xy 198.10548 -9.147047) (xy 198.209307 -9.187795)
			(xy 198.315889 -9.22067) (xy 198.42463 -9.245488) (xy 198.534921 -9.262111) (xy 198.646146 -9.270445)
			(xy 198.701914 -9.271) (xy 223.300036 -9.271) (xy 223.370417 -9.271495) (xy 223.510959 -9.279389)
			(xy 223.650836 -9.295152) (xy 223.78961 -9.318732) (xy 223.926844 -9.350057) (xy 224.062105 -9.389027)
			(xy 224.194968 -9.435519) (xy 224.325015 -9.489388) (xy 224.451838 -9.550465) (xy 224.575036 -9.618556)
			(xy 224.694222 -9.693447) (xy 224.809022 -9.774904) (xy 224.919074 -9.862669) (xy 225.024032 -9.956467)
			(xy 225.123566 -10.056003) (xy 225.217361 -10.160962) (xy 225.305125 -10.271016) (xy 225.386579 -10.385818)
			(xy 225.461469 -10.505006) (xy 225.529557 -10.628205) (xy 225.590631 -10.755029) (xy 225.644498 -10.885077)
			(xy 225.690988 -11.017941) (xy 225.729955 -11.153203) (xy 225.761277 -11.290437) (xy 225.784855 -11.429211)
			(xy 225.800615 -11.569089) (xy 225.808507 -11.709631) (xy 225.809048 -11.780012) (xy 225.809048 -33.120076)
			(xy 225.809549 -33.152224) (xy 225.817939 -33.21597) (xy 225.834578 -33.278076) (xy 225.859182 -33.337478)
			(xy 225.891329 -33.39316) (xy 225.93047 -33.44417) (xy 225.975934 -33.489634) (xy 226.026945 -33.528774)
			(xy 226.082627 -33.560921) (xy 226.14203 -33.585524) (xy 226.204136 -33.602162) (xy 226.267882 -33.610551)
			(xy 226.30003 -33.611058)
		)
		(stroke
			(width 0)
			(type solid)
		)
		(fill yes)
		(layer "In5.Cu")
		(net "DELTA_L_GND_1")
	)
	(gr_poly
		(pts
			(xy 194.445128 -441.480956) (xy 194.455142 -441.480531) (xy 194.473642 -441.472854) (xy 194.487795 -441.458682)
			(xy 194.495445 -441.440171) (xy 194.495928 -441.430156) (xy 194.495928 -441.17006) (xy 194.49641 -441.126022)
			(xy 194.50409 -441.03828) (xy 194.519387 -440.951542) (xy 194.542185 -440.866466) (xy 194.572311 -440.783702)
			(xy 194.609536 -440.703878) (xy 194.653576 -440.627602) (xy 194.704095 -440.555454) (xy 194.760711 -440.487984)
			(xy 194.822991 -440.425704) (xy 194.890462 -440.369089) (xy 194.96261 -440.31857) (xy 195.038887 -440.274531)
			(xy 195.118711 -440.237308) (xy 195.201476 -440.207182) (xy 195.286551 -440.184385) (xy 195.37329 -440.169088)
			(xy 195.461032 -440.16141) (xy 195.50507 -440.160918) (xy 276.314916 -440.160918) (xy 276.358955 -440.161399)
			(xy 276.446699 -440.169077) (xy 276.533439 -440.184372) (xy 276.618516 -440.207169) (xy 276.701283 -440.237294)
			(xy 276.781109 -440.274518) (xy 276.857388 -440.318557) (xy 276.929538 -440.369076) (xy 276.99701 -440.425692)
			(xy 277.059292 -440.487972) (xy 277.115909 -440.555443) (xy 277.16643 -440.627592) (xy 277.210471 -440.703869)
			(xy 277.247697 -440.783695) (xy 277.277823 -440.866461) (xy 277.300622 -440.951538) (xy 277.31592 -441.038278)
			(xy 277.3236 -441.126021) (xy 277.324058 -441.17006) (xy 277.324058 -441.430156) (xy 277.324469 -441.440186)
			(xy 277.33213 -441.458725) (xy 277.346302 -441.472922) (xy 277.364828 -441.480614) (xy 277.374858 -441.480956)
			(xy 463.300064 -441.480956) (xy 463.355834 -441.480449) (xy 463.467062 -441.472116) (xy 463.577357 -441.455494)
			(xy 463.686101 -441.430676) (xy 463.792686 -441.397801) (xy 463.896517 -441.357052) (xy 463.997011 -441.308658)
			(xy 464.093608 -441.252889) (xy 464.185768 -441.190057) (xy 464.272974 -441.120513) (xy 464.354739 -441.044647)
			(xy 464.430606 -440.962883) (xy 464.50015 -440.875677) (xy 464.562982 -440.783519) (xy 464.618752 -440.686922)
			(xy 464.667147 -440.586428) (xy 464.707897 -440.482598) (xy 464.740773 -440.376013) (xy 464.765592 -440.267269)
			(xy 464.782215 -440.156974) (xy 464.790548 -440.045746) (xy 464.791044 -439.989976) (xy 464.791044 -409.528264)
			(xy 464.791546 -409.457891) (xy 464.799454 -409.317366) (xy 464.815227 -409.177505) (xy 464.838815 -409.038749)
			(xy 464.870143 -408.901532) (xy 464.909113 -408.766288) (xy 464.955604 -408.633441) (xy 465.009467 -408.503408)
			(xy 465.070535 -408.376599) (xy 465.138615 -408.253413) (xy 465.213493 -408.134236) (xy 465.294933 -408.019444)
			(xy 465.38268 -407.909398) (xy 465.476458 -407.804443) (xy 465.525866 -407.754328) (xy 467.354412 -405.925782)
			(xy 467.391703 -405.887819) (xy 467.461396 -405.807388) (xy 467.525176 -405.722192) (xy 467.582717 -405.632663)
			(xy 467.633725 -405.539259) (xy 467.677942 -405.442454) (xy 467.715142 -405.342742) (xy 467.745135 -405.240631)
			(xy 467.767768 -405.136641) (xy 467.782928 -405.031301) (xy 467.790535 -404.925148) (xy 467.791038 -404.871936)
			(xy 467.791038 -82.82813) (xy 467.791541 -82.757757) (xy 467.799451 -82.617233) (xy 467.815226 -82.477373)
			(xy 467.838815 -82.338618) (xy 467.870145 -82.201402) (xy 467.909116 -82.066159) (xy 467.955608 -81.933313)
			(xy 468.009473 -81.803282) (xy 468.070541 -81.676474) (xy 468.138622 -81.553289) (xy 468.213501 -81.434114)
			(xy 468.294942 -81.319323) (xy 468.382689 -81.209278) (xy 468.476467 -81.104324) (xy 468.52586 -81.054194)
			(xy 470.854278 -78.725776) (xy 470.891569 -78.687813) (xy 470.961264 -78.607383) (xy 471.025045 -78.522187)
			(xy 471.082586 -78.432659) (xy 471.133596 -78.339255) (xy 471.177813 -78.24245) (xy 471.215013 -78.142738)
			(xy 471.245007 -78.040626) (xy 471.267641 -77.936636) (xy 471.2828 -77.831296) (xy 471.290407 -77.725143)
			(xy 471.290904 -77.67193) (xy 471.290904 -13.780008) (xy 471.290383 -13.724238) (xy 471.282048 -13.613011)
			(xy 471.265425 -13.502718) (xy 471.240606 -13.393975) (xy 471.20773 -13.287391) (xy 471.166981 -13.183562)
			(xy 471.118587 -13.083068) (xy 471.062818 -12.986472) (xy 470.999987 -12.894314) (xy 470.930444 -12.807108)
			(xy 470.854579 -12.725344) (xy 470.772816 -12.649477) (xy 470.685612 -12.579932) (xy 470.593455 -12.517099)
			(xy 470.49686 -12.461328) (xy 470.396367 -12.412932) (xy 470.292539 -12.372181) (xy 470.185956 -12.339303)
			(xy 470.077214 -12.314481) (xy 469.966921 -12.297855) (xy 469.855694 -12.289518) (xy 469.799924 -12.289028)
			(xy 458.20203 -12.289028) (xy 458.131647 -12.288544) (xy 457.991102 -12.280653) (xy 457.85122 -12.264894)
			(xy 457.712443 -12.241316) (xy 457.575205 -12.209994) (xy 457.43994 -12.171027) (xy 457.307072 -12.124536)
			(xy 457.177021 -12.070668) (xy 457.050194 -12.009593) (xy 456.926991 -11.941503) (xy 456.8078 -11.866612)
			(xy 456.692996 -11.785156) (xy 456.582939 -11.69739) (xy 456.477977 -11.603592) (xy 456.378439 -11.504056)
			(xy 456.284639 -11.399096) (xy 456.196872 -11.289041) (xy 456.115413 -11.174238) (xy 456.04052 -11.055048)
			(xy 455.972428 -10.931847) (xy 455.911351 -10.805021) (xy 455.857481 -10.674971) (xy 455.810987 -10.542104)
			(xy 455.772017 -10.406839) (xy 455.740693 -10.269603) (xy 455.717113 -10.130825) (xy 455.701351 -9.990944)
			(xy 455.693457 -9.850399) (xy 455.693018 -9.780016) (xy 455.693018 -0.559816) (xy 455.692533 -0.549805)
			(xy 455.684877 -0.531304) (xy 455.670724 -0.517142) (xy 455.652229 -0.509474) (xy 455.642218 -0.509016)
			(xy 388.161784 -0.509016) (xy 388.15178 -0.509507) (xy 388.133296 -0.51717) (xy 388.119152 -0.531323)
			(xy 388.111501 -0.549811) (xy 388.110984 -0.559816) (xy 388.110984 -5.169916) (xy 388.849877 -5.169916)
			(xy 388.853883 -5.081985) (xy 388.865869 -4.994782) (xy 388.885734 -4.90903) (xy 388.913316 -4.82544)
			(xy 388.948384 -4.744705) (xy 388.990649 -4.667493) (xy 389.03976 -4.594444) (xy 389.09531 -4.526164)
			(xy 389.156839 -4.463218) (xy 389.223837 -4.406129) (xy 389.295748 -4.355368) (xy 389.371978 -4.311356)
			(xy 389.451894 -4.274459) (xy 389.534835 -4.244982) (xy 389.620112 -4.22317) (xy 389.707019 -4.209202)
			(xy 389.794837 -4.203195) (xy 389.882836 -4.205199) (xy 389.970289 -4.215196) (xy 390.056471 -4.233105)
			(xy 390.140667 -4.258777) (xy 390.22218 -4.291998) (xy 390.300334 -4.332494) (xy 390.374481 -4.379929)
			(xy 390.444008 -4.433911) (xy 390.508339 -4.493991) (xy 390.566939 -4.559672) (xy 390.619323 -4.63041)
			(xy 390.665059 -4.705618) (xy 390.703765 -4.784674) (xy 390.735123 -4.866921) (xy 390.758871 -4.95168)
			(xy 390.766051 -4.990667) (xy 394.939038 -4.990667) (xy 394.939038 -4.936133) (xy 394.946799 -4.882155)
			(xy 394.962162 -4.82983) (xy 394.984815 -4.780224) (xy 395.014296 -4.734346) (xy 395.050007 -4.693131)
			(xy 395.091219 -4.657417) (xy 395.137094 -4.627931) (xy 395.186698 -4.605274) (xy 395.239021 -4.589906)
			(xy 395.292999 -4.582141) (xy 395.320266 -4.581652) (xy 396.183866 -4.581652) (xy 396.21114 -4.582085)
			(xy 396.265132 -4.589844) (xy 396.317471 -4.605208) (xy 396.36709 -4.627864) (xy 396.41298 -4.657352)
			(xy 396.454205 -4.693071) (xy 396.489928 -4.734293) (xy 396.51942 -4.78018) (xy 396.542081 -4.829797)
			(xy 396.557449 -4.882135) (xy 396.565212 -4.936126) (xy 396.565212 -4.99067) (xy 398.538915 -4.99067)
			(xy 398.538915 -4.93613) (xy 398.546678 -4.882144) (xy 398.562044 -4.829813) (xy 398.584701 -4.780201)
			(xy 398.614188 -4.734318) (xy 398.649905 -4.6931) (xy 398.691125 -4.657383) (xy 398.737008 -4.627897)
			(xy 398.78662 -4.605241) (xy 398.838952 -4.589876) (xy 398.892938 -4.582115) (xy 398.920208 -4.581652)
			(xy 399.783808 -4.581652) (xy 399.811078 -4.582111) (xy 399.865063 -4.589874) (xy 399.917393 -4.60524)
			(xy 399.967004 -4.627898) (xy 400.012886 -4.657385) (xy 400.054104 -4.693102) (xy 400.08982 -4.734321)
			(xy 400.119306 -4.780203) (xy 400.141962 -4.829814) (xy 400.157328 -4.882145) (xy 400.16509 -4.93613)
			(xy 400.16509 -4.990666) (xy 402.138938 -4.990666) (xy 402.138938 -4.936134) (xy 402.146698 -4.882157)
			(xy 402.162061 -4.829833) (xy 402.184712 -4.780228) (xy 402.214192 -4.734351) (xy 402.249901 -4.693136)
			(xy 402.291111 -4.657422) (xy 402.336984 -4.627936) (xy 402.386586 -4.605278) (xy 402.438908 -4.589909)
			(xy 402.492884 -4.582142) (xy 402.52015 -4.581652) (xy 403.38375 -4.581652) (xy 403.411024 -4.582084)
			(xy 403.465019 -4.589841) (xy 403.517359 -4.605203) (xy 403.56698 -4.627859) (xy 403.612872 -4.657346)
			(xy 403.6541 -4.693065) (xy 403.689824 -4.734288) (xy 403.719317 -4.780176) (xy 403.741979 -4.829794)
			(xy 403.757349 -4.882132) (xy 403.765112 -4.936126) (xy 403.765112 -4.990672) (xy 405.739016 -4.990672)
			(xy 405.739016 -4.936128) (xy 405.746779 -4.882139) (xy 405.762147 -4.829805) (xy 405.784807 -4.78019)
			(xy 405.814298 -4.734306) (xy 405.850019 -4.693086) (xy 405.891243 -4.65737) (xy 405.937131 -4.627885)
			(xy 405.986748 -4.605231) (xy 406.039084 -4.589869) (xy 406.093074 -4.582112) (xy 406.120346 -4.581652)
			(xy 406.983946 -4.581652) (xy 407.011214 -4.582114) (xy 407.065195 -4.589881) (xy 407.117521 -4.605251)
			(xy 407.167127 -4.62791) (xy 407.213004 -4.657399) (xy 407.254217 -4.693115) (xy 407.289929 -4.734333)
			(xy 407.319412 -4.780213) (xy 407.342065 -4.829822) (xy 407.357429 -4.88215) (xy 407.36519 -4.936132)
			(xy 407.36519 -4.990668) (xy 407.36519 -4.99067) (xy 414.849015 -4.99067) (xy 414.849015 -4.93613)
			(xy 414.856778 -4.882144) (xy 414.872144 -4.829812) (xy 414.894801 -4.7802) (xy 414.924289 -4.734318)
			(xy 414.960006 -4.693099) (xy 415.001226 -4.657383) (xy 415.047109 -4.627896) (xy 415.096722 -4.60524)
			(xy 415.149054 -4.589875) (xy 415.20304 -4.582115) (xy 415.23031 -4.581652) (xy 416.09391 -4.581652)
			(xy 416.12118 -4.582111) (xy 416.175164 -4.589874) (xy 416.227495 -4.605241) (xy 416.277105 -4.627899)
			(xy 416.322987 -4.657386) (xy 416.364205 -4.693102) (xy 416.39992 -4.734321) (xy 416.429406 -4.780203)
			(xy 416.452062 -4.829815) (xy 416.467428 -4.882145) (xy 416.47519 -4.93613) (xy 416.47519 -4.990666)
			(xy 418.449038 -4.990666) (xy 418.449038 -4.936134) (xy 418.456798 -4.882156) (xy 418.472161 -4.829833)
			(xy 418.494813 -4.780227) (xy 418.524293 -4.734351) (xy 418.560002 -4.693136) (xy 418.601212 -4.657422)
			(xy 418.647085 -4.627936) (xy 418.696688 -4.605278) (xy 418.749009 -4.589909) (xy 418.802986 -4.582142)
			(xy 418.830252 -4.581652) (xy 419.693852 -4.581652) (xy 419.721126 -4.582084) (xy 419.77512 -4.589841)
			(xy 419.827461 -4.605204) (xy 419.877082 -4.627859) (xy 419.922973 -4.657347) (xy 419.9642 -4.693066)
			(xy 419.999924 -4.734288) (xy 420.029418 -4.780176) (xy 420.052079 -4.829794) (xy 420.067449 -4.882133)
			(xy 420.075212 -4.936126) (xy 420.075212 -4.990672) (xy 426.059016 -4.990672) (xy 426.059016 -4.936128)
			(xy 426.066779 -4.882139) (xy 426.082147 -4.829805) (xy 426.104807 -4.78019) (xy 426.134298 -4.734306)
			(xy 426.170019 -4.693086) (xy 426.211243 -4.65737) (xy 426.257131 -4.627885) (xy 426.306748 -4.605231)
			(xy 426.359084 -4.589869) (xy 426.413074 -4.582112) (xy 426.440346 -4.581652) (xy 427.303946 -4.581652)
			(xy 427.331214 -4.582114) (xy 427.385195 -4.589881) (xy 427.437521 -4.605251) (xy 427.487127 -4.62791)
			(xy 427.533004 -4.657399) (xy 427.574217 -4.693115) (xy 427.609929 -4.734333) (xy 427.639412 -4.780213)
			(xy 427.662065 -4.829822) (xy 427.677429 -4.88215) (xy 427.68519 -4.936132) (xy 427.68519 -4.990668)
			(xy 429.659038 -4.990668) (xy 429.659038 -4.936132) (xy 429.666799 -4.882152) (xy 429.682164 -4.829825)
			(xy 429.704818 -4.780217) (xy 429.734302 -4.734339) (xy 429.770014 -4.693123) (xy 429.811229 -4.657409)
			(xy 429.857107 -4.627924) (xy 429.906714 -4.605268) (xy 429.95904 -4.589902) (xy 430.01302 -4.582139)
			(xy 430.040288 -4.581652) (xy 430.903888 -4.581652) (xy 430.931161 -4.582087) (xy 430.985151 -4.589848)
			(xy 431.037487 -4.605214) (xy 431.087103 -4.627871) (xy 431.13299 -4.65736) (xy 431.174213 -4.693078)
			(xy 431.209933 -4.7343) (xy 431.239423 -4.780186) (xy 431.262082 -4.829802) (xy 431.27745 -4.882138)
			(xy 431.285212 -4.936127) (xy 431.285212 -4.990673) (xy 431.27745 -5.044662) (xy 431.262082 -5.096998)
			(xy 431.239423 -5.146614) (xy 431.209933 -5.1925) (xy 431.174213 -5.233722) (xy 431.13299 -5.26944)
			(xy 431.087103 -5.298929) (xy 431.037487 -5.321586) (xy 430.985151 -5.336952) (xy 430.931161 -5.344713)
			(xy 430.903888 -5.345176) (xy 430.040288 -5.345176) (xy 430.01302 -5.344661) (xy 429.95904 -5.336898)
			(xy 429.906714 -5.321532) (xy 429.857107 -5.298876) (xy 429.811229 -5.269391) (xy 429.770014 -5.233677)
			(xy 429.734302 -5.192461) (xy 429.704818 -5.146583) (xy 429.682164 -5.096975) (xy 429.666799 -5.044648)
			(xy 429.659038 -4.990668) (xy 427.68519 -4.990668) (xy 427.677429 -5.04465) (xy 427.662065 -5.096978)
			(xy 427.639412 -5.146587) (xy 427.609929 -5.192467) (xy 427.574217 -5.233685) (xy 427.533004 -5.269401)
			(xy 427.487127 -5.29889) (xy 427.437521 -5.321549) (xy 427.385195 -5.336919) (xy 427.331214 -5.344686)
			(xy 427.303946 -5.345176) (xy 426.440346 -5.345176) (xy 426.413074 -5.344688) (xy 426.359084 -5.336931)
			(xy 426.306748 -5.321569) (xy 426.257131 -5.298915) (xy 426.211243 -5.26943) (xy 426.170019 -5.233714)
			(xy 426.134298 -5.192494) (xy 426.104807 -5.14661) (xy 426.082147 -5.096995) (xy 426.066779 -5.044661)
			(xy 426.059016 -4.990672) (xy 420.075212 -4.990672) (xy 420.075212 -4.990674) (xy 420.067449 -5.044667)
			(xy 420.052079 -5.097006) (xy 420.029418 -5.146624) (xy 419.999924 -5.192512) (xy 419.9642 -5.233734)
			(xy 419.922973 -5.269453) (xy 419.877082 -5.298941) (xy 419.827461 -5.321596) (xy 419.77512 -5.336959)
			(xy 419.721126 -5.344716) (xy 419.693852 -5.345176) (xy 418.830252 -5.345176) (xy 418.802986 -5.344658)
			(xy 418.749009 -5.336891) (xy 418.696688 -5.321522) (xy 418.647085 -5.298864) (xy 418.601212 -5.269378)
			(xy 418.560002 -5.233664) (xy 418.524293 -5.192449) (xy 418.494813 -5.146573) (xy 418.472161 -5.096967)
			(xy 418.456798 -5.044644) (xy 418.449038 -4.990666) (xy 416.47519 -4.990666) (xy 416.47519 -4.99067)
			(xy 416.467428 -5.044655) (xy 416.452062 -5.096985) (xy 416.429406 -5.146597) (xy 416.39992 -5.192479)
			(xy 416.364205 -5.233698) (xy 416.322987 -5.269414) (xy 416.277105 -5.298901) (xy 416.227495 -5.321559)
			(xy 416.175164 -5.336926) (xy 416.12118 -5.344689) (xy 416.09391 -5.345176) (xy 415.23031 -5.345176)
			(xy 415.20304 -5.344685) (xy 415.149054 -5.336925) (xy 415.096722 -5.32156) (xy 415.047109 -5.298904)
			(xy 415.001226 -5.269417) (xy 414.960006 -5.233701) (xy 414.924289 -5.192482) (xy 414.894801 -5.1466)
			(xy 414.872144 -5.096988) (xy 414.856778 -5.044656) (xy 414.849015 -4.99067) (xy 407.36519 -4.99067)
			(xy 407.357429 -5.04465) (xy 407.342065 -5.096978) (xy 407.319412 -5.146587) (xy 407.289929 -5.192467)
			(xy 407.254217 -5.233685) (xy 407.213004 -5.269401) (xy 407.167127 -5.29889) (xy 407.117521 -5.321549)
			(xy 407.065195 -5.336919) (xy 407.011214 -5.344686) (xy 406.983946 -5.345176) (xy 406.120346 -5.345176)
			(xy 406.093074 -5.344688) (xy 406.039084 -5.336931) (xy 405.986748 -5.321569) (xy 405.937131 -5.298915)
			(xy 405.891243 -5.26943) (xy 405.850019 -5.233714) (xy 405.814298 -5.192494) (xy 405.784807 -5.14661)
			(xy 405.762147 -5.096995) (xy 405.746779 -5.044661) (xy 405.739016 -4.990672) (xy 403.765112 -4.990672)
			(xy 403.765112 -4.990674) (xy 403.757349 -5.044668) (xy 403.741979 -5.097006) (xy 403.719317 -5.146624)
			(xy 403.689824 -5.192512) (xy 403.6541 -5.233735) (xy 403.612872 -5.269454) (xy 403.56698 -5.298941)
			(xy 403.517359 -5.321597) (xy 403.465019 -5.336959) (xy 403.411024 -5.344716) (xy 403.38375 -5.345176)
			(xy 402.52015 -5.345176) (xy 402.492884 -5.344658) (xy 402.438908 -5.336891) (xy 402.386586 -5.321522)
			(xy 402.336984 -5.298864) (xy 402.291111 -5.269378) (xy 402.249901 -5.233664) (xy 402.214192 -5.192449)
			(xy 402.184712 -5.146572) (xy 402.162061 -5.096967) (xy 402.146698 -5.044643) (xy 402.138938 -4.990666)
			(xy 400.16509 -4.990666) (xy 400.16509 -4.99067) (xy 400.157328 -5.044655) (xy 400.141962 -5.096986)
			(xy 400.119306 -5.146597) (xy 400.08982 -5.192479) (xy 400.054104 -5.233698) (xy 400.012886 -5.269415)
			(xy 399.967004 -5.298902) (xy 399.917393 -5.32156) (xy 399.865063 -5.336926) (xy 399.811078 -5.344689)
			(xy 399.783808 -5.345176) (xy 398.920208 -5.345176) (xy 398.892938 -5.344685) (xy 398.838952 -5.336924)
			(xy 398.78662 -5.321559) (xy 398.737008 -5.298903) (xy 398.691125 -5.269417) (xy 398.649905 -5.2337)
			(xy 398.614188 -5.192482) (xy 398.584701 -5.146599) (xy 398.562044 -5.096987) (xy 398.546678 -5.044656)
			(xy 398.538915 -4.99067) (xy 396.565212 -4.99067) (xy 396.565212 -4.990674) (xy 396.557449 -5.044665)
			(xy 396.542081 -5.097003) (xy 396.51942 -5.14662) (xy 396.489928 -5.192507) (xy 396.454205 -5.233729)
			(xy 396.41298 -5.269448) (xy 396.36709 -5.298936) (xy 396.317471 -5.321592) (xy 396.265132 -5.336956)
			(xy 396.21114 -5.344715) (xy 396.183866 -5.345176) (xy 395.320266 -5.345176) (xy 395.292999 -5.344659)
			(xy 395.239021 -5.336894) (xy 395.186698 -5.321526) (xy 395.137094 -5.298869) (xy 395.091219 -5.269383)
			(xy 395.050007 -5.233669) (xy 395.014296 -5.192454) (xy 394.984815 -5.146576) (xy 394.962162 -5.09697)
			(xy 394.946799 -5.044645) (xy 394.939038 -4.990667) (xy 390.766051 -4.990667) (xy 390.774813 -5.038247)
			(xy 390.782817 -5.125905) (xy 390.783318 -5.169916) (xy 390.782817 -5.213927) (xy 390.774813 -5.301585)
			(xy 390.758871 -5.388152) (xy 390.735123 -5.472911) (xy 390.703765 -5.555158) (xy 390.665059 -5.634214)
			(xy 390.619323 -5.709422) (xy 390.566939 -5.78016) (xy 390.508339 -5.845841) (xy 390.444008 -5.905921)
			(xy 390.374481 -5.959903) (xy 390.300334 -6.007338) (xy 390.22218 -6.047834) (xy 390.140667 -6.081055)
			(xy 390.056471 -6.106727) (xy 389.970289 -6.124636) (xy 389.882836 -6.134633) (xy 389.794837 -6.136637)
			(xy 389.707019 -6.13063) (xy 389.620112 -6.116662) (xy 389.534835 -6.09485) (xy 389.451894 -6.065373)
			(xy 389.371978 -6.028476) (xy 389.295748 -5.984464) (xy 389.223837 -5.933703) (xy 389.156839 -5.876614)
			(xy 389.09531 -5.813668) (xy 389.03976 -5.745388) (xy 388.990649 -5.672339) (xy 388.948384 -5.595127)
			(xy 388.913316 -5.514392) (xy 388.885734 -5.430802) (xy 388.865869 -5.34505) (xy 388.853883 -5.257847)
			(xy 388.849877 -5.169916) (xy 388.110984 -5.169916) (xy 388.110984 -6.169914) (xy 453.015103 -6.169914)
			(xy 453.019108 -6.082006) (xy 453.031091 -5.994826) (xy 453.050951 -5.909097) (xy 453.078526 -5.825529)
			(xy 453.113585 -5.744815) (xy 453.155838 -5.667623) (xy 453.204936 -5.594594) (xy 453.260472 -5.526332)
			(xy 453.321984 -5.463402) (xy 453.388965 -5.406328) (xy 453.460858 -5.35558) (xy 453.537067 -5.31158)
			(xy 453.616962 -5.274693) (xy 453.699881 -5.245224) (xy 453.785136 -5.223417) (xy 453.87202 -5.209453)
			(xy 453.959814 -5.203447) (xy 454.047791 -5.205451) (xy 454.135221 -5.215446) (xy 454.22138 -5.23335)
			(xy 454.305554 -5.259014) (xy 454.387045 -5.292227) (xy 454.465179 -5.332713) (xy 454.539307 -5.380135)
			(xy 454.608815 -5.434102) (xy 454.673129 -5.494167) (xy 454.731713 -5.559831) (xy 454.784084 -5.63055)
			(xy 454.829807 -5.705738) (xy 454.868504 -5.784773) (xy 454.899853 -5.866999) (xy 454.923595 -5.951735)
			(xy 454.939533 -6.038279) (xy 454.947535 -6.125914) (xy 454.948036 -6.169914) (xy 454.947535 -6.213914)
			(xy 454.939533 -6.301549) (xy 454.923595 -6.388093) (xy 454.899853 -6.472829) (xy 454.868504 -6.555055)
			(xy 454.829807 -6.63409) (xy 454.784084 -6.709278) (xy 454.731713 -6.779997) (xy 454.673129 -6.845661)
			(xy 454.608815 -6.905726) (xy 454.539307 -6.959693) (xy 454.465179 -7.007115) (xy 454.387045 -7.047601)
			(xy 454.305554 -7.080814) (xy 454.22138 -7.106478) (xy 454.135221 -7.124382) (xy 454.047791 -7.134377)
			(xy 453.959814 -7.136381) (xy 453.87202 -7.130375) (xy 453.785136 -7.116411) (xy 453.699881 -7.094604)
			(xy 453.616962 -7.065135) (xy 453.537067 -7.028248) (xy 453.460858 -6.984248) (xy 453.388965 -6.9335)
			(xy 453.321984 -6.876426) (xy 453.260472 -6.813496) (xy 453.204936 -6.745234) (xy 453.155838 -6.672205)
			(xy 453.113585 -6.595013) (xy 453.078526 -6.514299) (xy 453.050951 -6.430731) (xy 453.031091 -6.345002)
			(xy 453.019108 -6.257822) (xy 453.015103 -6.169914) (xy 388.110984 -6.169914) (xy 388.110984 -6.752472)
			(xy 393.134283 -6.752472) (xy 393.134283 -6.697928) (xy 393.142045 -6.643939) (xy 393.157412 -6.591604)
			(xy 393.18007 -6.541988) (xy 393.209559 -6.496103) (xy 393.245278 -6.454881) (xy 393.286499 -6.419161)
			(xy 393.332385 -6.389672) (xy 393.382 -6.367013) (xy 393.434335 -6.351646) (xy 393.488324 -6.343883)
			(xy 393.515596 -6.343396) (xy 394.379196 -6.343396) (xy 394.406464 -6.343943) (xy 394.460446 -6.351704)
			(xy 394.512773 -6.367068) (xy 394.562381 -6.389723) (xy 394.60826 -6.419207) (xy 394.649476 -6.454921)
			(xy 394.68519 -6.496136) (xy 394.714675 -6.542015) (xy 394.73733 -6.591623) (xy 394.752695 -6.643951)
			(xy 394.760457 -6.697932) (xy 394.760457 -6.752468) (xy 394.760456 -6.752476) (xy 396.73416 -6.752476)
			(xy 396.73416 -6.697924) (xy 396.741924 -6.643928) (xy 396.757294 -6.591587) (xy 396.779956 -6.541966)
			(xy 396.809451 -6.496075) (xy 396.845176 -6.454849) (xy 396.886405 -6.419128) (xy 396.932299 -6.389638)
			(xy 396.981922 -6.36698) (xy 397.034265 -6.351616) (xy 397.088262 -6.343857) (xy 397.115538 -6.343396)
			(xy 397.979138 -6.343396) (xy 398.006403 -6.343969) (xy 398.060376 -6.351734) (xy 398.112695 -6.367101)
			(xy 398.162295 -6.389757) (xy 398.208166 -6.419241) (xy 398.249375 -6.454952) (xy 398.285082 -6.496164)
			(xy 398.314561 -6.542038) (xy 398.337212 -6.59164) (xy 398.352574 -6.643961) (xy 398.360334 -6.697935)
			(xy 398.360334 -6.752465) (xy 398.360333 -6.752471) (xy 400.334182 -6.752471) (xy 400.334182 -6.697929)
			(xy 400.341944 -6.643941) (xy 400.35731 -6.591607) (xy 400.379968 -6.541993) (xy 400.409455 -6.496108)
			(xy 400.445172 -6.454886) (xy 400.486392 -6.419167) (xy 400.532275 -6.389677) (xy 400.581888 -6.367017)
			(xy 400.634221 -6.351649) (xy 400.688209 -6.343884) (xy 400.71548 -6.343396) (xy 401.57908 -6.343396)
			(xy 401.606349 -6.343942) (xy 401.660332 -6.351701) (xy 401.712661 -6.367064) (xy 401.762272 -6.389718)
			(xy 401.808153 -6.419202) (xy 401.849371 -6.454915) (xy 401.885086 -6.496131) (xy 401.914573 -6.542011)
			(xy 401.937229 -6.59162) (xy 401.952595 -6.643948) (xy 401.960357 -6.697931) (xy 401.960357 -6.752469)
			(xy 401.960357 -6.752471) (xy 403.934382 -6.752471) (xy 403.934382 -6.697929) (xy 403.942144 -6.643941)
			(xy 403.95751 -6.591608) (xy 403.980167 -6.541994) (xy 404.009654 -6.496109) (xy 404.045371 -6.454888)
			(xy 404.08659 -6.419168) (xy 404.132473 -6.389679) (xy 404.182085 -6.367019) (xy 404.234418 -6.351649)
			(xy 404.288405 -6.343884) (xy 404.315676 -6.343396) (xy 405.179276 -6.343396) (xy 405.206545 -6.343942)
			(xy 405.260529 -6.3517) (xy 405.312858 -6.367063) (xy 405.362469 -6.389716) (xy 405.408351 -6.4192)
			(xy 405.449569 -6.454914) (xy 405.485285 -6.49613) (xy 405.514772 -6.54201) (xy 405.537429 -6.591619)
			(xy 405.552795 -6.643948) (xy 405.560557 -6.697931) (xy 405.560557 -6.752469) (xy 405.560556 -6.752476)
			(xy 413.04426 -6.752476) (xy 413.04426 -6.697924) (xy 413.052024 -6.643928) (xy 413.067394 -6.591586)
			(xy 413.090057 -6.541965) (xy 413.119551 -6.496074) (xy 413.155277 -6.454849) (xy 413.196506 -6.419127)
			(xy 413.2424 -6.389638) (xy 413.292024 -6.36698) (xy 413.344367 -6.351615) (xy 413.398364 -6.343857)
			(xy 413.42564 -6.343396) (xy 414.28924 -6.343396) (xy 414.316504 -6.343969) (xy 414.370478 -6.351734)
			(xy 414.422797 -6.367102) (xy 414.472397 -6.389758) (xy 414.518267 -6.419241) (xy 414.559476 -6.454953)
			(xy 414.595183 -6.496165) (xy 414.624662 -6.542039) (xy 414.647312 -6.591641) (xy 414.662674 -6.643961)
			(xy 414.670434 -6.697935) (xy 414.670434 -6.752465) (xy 414.670433 -6.752472) (xy 416.644282 -6.752472)
			(xy 416.644282 -6.697928) (xy 416.652045 -6.64394) (xy 416.667411 -6.591607) (xy 416.690068 -6.541992)
			(xy 416.719555 -6.496107) (xy 416.755273 -6.454885) (xy 416.796493 -6.419166) (xy 416.842376 -6.389677)
			(xy 416.89199 -6.367017) (xy 416.944323 -6.351648) (xy 416.99831 -6.343884) (xy 417.025582 -6.343396)
			(xy 417.889182 -6.343396) (xy 417.916451 -6.343942) (xy 417.970434 -6.351701) (xy 418.022763 -6.367064)
			(xy 418.072373 -6.389718) (xy 418.118254 -6.419202) (xy 418.159471 -6.454916) (xy 418.195187 -6.496132)
			(xy 418.224673 -6.542011) (xy 418.247329 -6.59162) (xy 418.262695 -6.643949) (xy 418.270457 -6.697931)
			(xy 418.270457 -6.752469) (xy 418.270457 -6.752471) (xy 424.254382 -6.752471) (xy 424.254382 -6.697929)
			(xy 424.262144 -6.643941) (xy 424.27751 -6.591608) (xy 424.300167 -6.541994) (xy 424.329654 -6.496109)
			(xy 424.365371 -6.454888) (xy 424.40659 -6.419168) (xy 424.452473 -6.389679) (xy 424.502085 -6.367019)
			(xy 424.554418 -6.351649) (xy 424.608405 -6.343884) (xy 424.635676 -6.343396) (xy 425.499276 -6.343396)
			(xy 425.526545 -6.343942) (xy 425.580529 -6.3517) (xy 425.632858 -6.367063) (xy 425.682469 -6.389716)
			(xy 425.728351 -6.4192) (xy 425.769569 -6.454914) (xy 425.805285 -6.49613) (xy 425.834772 -6.54201)
			(xy 425.857429 -6.591619) (xy 425.872795 -6.643948) (xy 425.880557 -6.697931) (xy 425.880557 -6.752469)
			(xy 425.880556 -6.752475) (xy 427.85426 -6.752475) (xy 427.85426 -6.697925) (xy 427.862023 -6.643931)
			(xy 427.877392 -6.591591) (xy 427.900053 -6.541971) (xy 427.929546 -6.496082) (xy 427.965269 -6.454856)
			(xy 428.006496 -6.419135) (xy 428.052387 -6.389645) (xy 428.102008 -6.366986) (xy 428.154348 -6.351619)
			(xy 428.208343 -6.343858) (xy 428.235618 -6.343396) (xy 429.099218 -6.343396) (xy 429.126484 -6.343968)
			(xy 429.180459 -6.35173) (xy 429.232781 -6.367096) (xy 429.282383 -6.38975) (xy 429.328257 -6.419234)
			(xy 429.369468 -6.454945) (xy 429.405177 -6.496157) (xy 429.434658 -6.542032) (xy 429.457311 -6.591636)
			(xy 429.472673 -6.643958) (xy 429.480434 -6.697934) (xy 429.480434 -6.752466) (xy 429.479412 -6.759571)
			(xy 431.465194 -6.759571) (xy 431.465194 -6.705029) (xy 431.472956 -6.651043) (xy 431.488322 -6.598711)
			(xy 431.510979 -6.549098) (xy 431.540465 -6.503214) (xy 431.576181 -6.461994) (xy 431.6174 -6.426276)
			(xy 431.663282 -6.396787) (xy 431.712894 -6.374128) (xy 431.765225 -6.35876) (xy 431.819211 -6.350996)
			(xy 431.846482 -6.350508) (xy 432.710082 -6.350508) (xy 432.737352 -6.35103) (xy 432.791336 -6.35879)
			(xy 432.843667 -6.374153) (xy 432.893279 -6.396808) (xy 432.939161 -6.426293) (xy 432.98038 -6.462007)
			(xy 433.016096 -6.503225) (xy 433.045583 -6.549106) (xy 433.068241 -6.598716) (xy 433.083607 -6.651046)
			(xy 433.091369 -6.70503) (xy 433.091369 -6.75247) (xy 445.449182 -6.75247) (xy 445.449182 -6.69793)
			(xy 445.456944 -6.643944) (xy 445.472308 -6.591613) (xy 445.494963 -6.542001) (xy 445.524448 -6.496117)
			(xy 445.560162 -6.454896) (xy 445.601379 -6.419177) (xy 445.647258 -6.389686) (xy 445.696868 -6.367025)
			(xy 445.749198 -6.351654) (xy 445.803182 -6.343886) (xy 445.830452 -6.343396) (xy 446.694052 -6.343396)
			(xy 446.721322 -6.34394) (xy 446.775308 -6.351696) (xy 446.827641 -6.367056) (xy 446.877255 -6.389709)
			(xy 446.923139 -6.419192) (xy 446.964361 -6.454905) (xy 447.00008 -6.496122) (xy 447.029568 -6.542003)
			(xy 447.052227 -6.591614) (xy 447.067594 -6.643945) (xy 447.075356 -6.69793) (xy 447.075356 -6.75247)
			(xy 447.067594 -6.806455) (xy 447.052227 -6.858786) (xy 447.029568 -6.908397) (xy 447.000079 -6.954278)
			(xy 446.964361 -6.995495) (xy 446.923139 -7.031208) (xy 446.877255 -7.060691) (xy 446.827641 -7.083344)
			(xy 446.775308 -7.098704) (xy 446.721322 -7.10646) (xy 446.694052 -7.10692) (xy 445.830452 -7.10692)
			(xy 445.803182 -7.106514) (xy 445.749198 -7.098746) (xy 445.696868 -7.083375) (xy 445.647258 -7.060714)
			(xy 445.601378 -7.031223) (xy 445.560162 -6.995504) (xy 445.524448 -6.954283) (xy 445.494963 -6.908399)
			(xy 445.472308 -6.858787) (xy 445.456944 -6.806455) (xy 445.449182 -6.75247) (xy 433.091369 -6.75247)
			(xy 433.091369 -6.75957) (xy 433.083607 -6.813554) (xy 433.068241 -6.865884) (xy 433.045583 -6.915494)
			(xy 433.016096 -6.961375) (xy 432.98038 -7.002593) (xy 432.939161 -7.038307) (xy 432.893279 -7.067792)
			(xy 432.843667 -7.090447) (xy 432.791336 -7.10581) (xy 432.737352 -7.11357) (xy 432.710082 -7.114032)
			(xy 431.846482 -7.114032) (xy 431.819211 -7.113604) (xy 431.765225 -7.10584) (xy 431.712894 -7.090472)
			(xy 431.663282 -7.067813) (xy 431.6174 -7.038324) (xy 431.576181 -7.002606) (xy 431.540465 -6.961386)
			(xy 431.510979 -6.915502) (xy 431.488322 -6.865889) (xy 431.472956 -6.813557) (xy 431.465194 -6.759571)
			(xy 429.479412 -6.759571) (xy 429.472673 -6.806442) (xy 429.457311 -6.858764) (xy 429.434658 -6.908368)
			(xy 429.405177 -6.954243) (xy 429.369468 -6.995455) (xy 429.328257 -7.031166) (xy 429.282383 -7.06065)
			(xy 429.232781 -7.083304) (xy 429.180459 -7.09867) (xy 429.126484 -7.106432) (xy 429.099218 -7.10692)
			(xy 428.235618 -7.10692) (xy 428.208343 -7.106542) (xy 428.154348 -7.098781) (xy 428.102008 -7.083414)
			(xy 428.052387 -7.060755) (xy 428.006496 -7.031265) (xy 427.965269 -6.995544) (xy 427.929546 -6.954318)
			(xy 427.900053 -6.908429) (xy 427.877392 -6.858809) (xy 427.862023 -6.806469) (xy 427.85426 -6.752475)
			(xy 425.880556 -6.752475) (xy 425.872795 -6.806452) (xy 425.857429 -6.858781) (xy 425.834772 -6.90839)
			(xy 425.805285 -6.95427) (xy 425.769569 -6.995486) (xy 425.728351 -7.0312) (xy 425.682469 -7.060684)
			(xy 425.632858 -7.083337) (xy 425.580529 -7.0987) (xy 425.526545 -7.106458) (xy 425.499276 -7.10692)
			(xy 424.635676 -7.10692) (xy 424.608405 -7.106516) (xy 424.554418 -7.098751) (xy 424.502085 -7.083381)
			(xy 424.452473 -7.060721) (xy 424.40659 -7.031232) (xy 424.365371 -6.995512) (xy 424.329654 -6.954291)
			(xy 424.300167 -6.908406) (xy 424.27751 -6.858792) (xy 424.262144 -6.806459) (xy 424.254382 -6.752471)
			(xy 418.270457 -6.752471) (xy 418.262695 -6.806451) (xy 418.247329 -6.85878) (xy 418.224673 -6.908389)
			(xy 418.195187 -6.954268) (xy 418.159471 -6.995484) (xy 418.118254 -7.031198) (xy 418.072373 -7.060682)
			(xy 418.022763 -7.083336) (xy 417.970434 -7.098699) (xy 417.916451 -7.106458) (xy 417.889182 -7.10692)
			(xy 417.025582 -7.10692) (xy 416.99831 -7.106516) (xy 416.944323 -7.098752) (xy 416.89199 -7.083383)
			(xy 416.842376 -7.060723) (xy 416.796493 -7.031234) (xy 416.755273 -6.995515) (xy 416.719555 -6.954293)
			(xy 416.690068 -6.908408) (xy 416.667411 -6.858793) (xy 416.652045 -6.806459) (xy 416.644282 -6.752472)
			(xy 414.670433 -6.752472) (xy 414.662674 -6.806439) (xy 414.647312 -6.858759) (xy 414.624662 -6.908361)
			(xy 414.595183 -6.954235) (xy 414.559476 -6.995447) (xy 414.518267 -7.031159) (xy 414.472397 -7.060642)
			(xy 414.422797 -7.083298) (xy 414.370478 -7.098666) (xy 414.316505 -7.106431) (xy 414.28924 -7.10692)
			(xy 413.42564 -7.10692) (xy 413.398364 -7.106543) (xy 413.344367 -7.098785) (xy 413.292024 -7.08342)
			(xy 413.2424 -7.060762) (xy 413.196506 -7.031273) (xy 413.155277 -6.995551) (xy 413.119551 -6.954326)
			(xy 413.090057 -6.908435) (xy 413.067394 -6.858814) (xy 413.052024 -6.806472) (xy 413.04426 -6.752476)
			(xy 405.560556 -6.752476) (xy 405.552795 -6.806452) (xy 405.537429 -6.858781) (xy 405.514772 -6.90839)
			(xy 405.485285 -6.95427) (xy 405.449569 -6.995486) (xy 405.408351 -7.0312) (xy 405.362469 -7.060684)
			(xy 405.312858 -7.083337) (xy 405.260529 -7.0987) (xy 405.206545 -7.106458) (xy 405.179276 -7.10692)
			(xy 404.315676 -7.10692) (xy 404.288405 -7.106516) (xy 404.234418 -7.098751) (xy 404.182085 -7.083381)
			(xy 404.132473 -7.060721) (xy 404.08659 -7.031232) (xy 404.045371 -6.995512) (xy 404.009654 -6.954291)
			(xy 403.980167 -6.908406) (xy 403.95751 -6.858792) (xy 403.942144 -6.806459) (xy 403.934382 -6.752471)
			(xy 401.960357 -6.752471) (xy 401.952595 -6.806452) (xy 401.937229 -6.85878) (xy 401.914573 -6.908389)
			(xy 401.885086 -6.954269) (xy 401.849371 -6.995485) (xy 401.808153 -7.031198) (xy 401.762272 -7.060682)
			(xy 401.712661 -7.083336) (xy 401.660332 -7.098699) (xy 401.606349 -7.106458) (xy 401.57908 -7.10692)
			(xy 400.71548 -7.10692) (xy 400.688209 -7.106516) (xy 400.634221 -7.098751) (xy 400.581888 -7.083383)
			(xy 400.532275 -7.060723) (xy 400.486392 -7.031233) (xy 400.445172 -6.995514) (xy 400.409455 -6.954292)
			(xy 400.379968 -6.908407) (xy 400.35731 -6.858793) (xy 400.341944 -6.806459) (xy 400.334182 -6.752471)
			(xy 398.360333 -6.752471) (xy 398.352574 -6.806439) (xy 398.337212 -6.85876) (xy 398.314561 -6.908362)
			(xy 398.285082 -6.954236) (xy 398.249375 -6.995448) (xy 398.208166 -7.031159) (xy 398.162295 -7.060643)
			(xy 398.112695 -7.083299) (xy 398.060376 -7.098666) (xy 398.006403 -7.106431) (xy 397.979138 -7.10692)
			(xy 397.115538 -7.10692) (xy 397.088262 -7.106543) (xy 397.034265 -7.098784) (xy 396.981922 -7.08342)
			(xy 396.932299 -7.060762) (xy 396.886405 -7.031272) (xy 396.845176 -6.995551) (xy 396.809451 -6.954325)
			(xy 396.779956 -6.908434) (xy 396.757294 -6.858813) (xy 396.741924 -6.806472) (xy 396.73416 -6.752476)
			(xy 394.760456 -6.752476) (xy 394.752695 -6.806449) (xy 394.73733 -6.858777) (xy 394.714675 -6.908385)
			(xy 394.68519 -6.954264) (xy 394.649476 -6.995479) (xy 394.60826 -7.031193) (xy 394.562381 -7.060677)
			(xy 394.512773 -7.083332) (xy 394.460446 -7.098696) (xy 394.406464 -7.106457) (xy 394.379196 -7.10692)
			(xy 393.515596 -7.10692) (xy 393.488324 -7.106517) (xy 393.434335 -7.098754) (xy 393.382 -7.083387)
			(xy 393.332385 -7.060728) (xy 393.286499 -7.031239) (xy 393.245278 -6.995519) (xy 393.209559 -6.954297)
			(xy 393.18007 -6.908412) (xy 393.157412 -6.858796) (xy 393.142045 -6.806461) (xy 393.134283 -6.752472)
			(xy 388.110984 -6.752472) (xy 388.110984 -9.780016) (xy 388.110499 -9.850398) (xy 388.102605 -9.99094)
			(xy 388.086844 -10.130819) (xy 388.063264 -10.269594) (xy 388.03194 -10.406828) (xy 387.992971 -10.54209)
			(xy 387.946478 -10.674954) (xy 387.892609 -10.805003) (xy 387.831533 -10.931826) (xy 387.763442 -11.055026)
			(xy 387.68855 -11.174213) (xy 387.607093 -11.289014) (xy 387.519328 -11.399067) (xy 387.425529 -11.504025)
			(xy 387.325993 -11.60356) (xy 387.221033 -11.697356) (xy 387.110979 -11.78512) (xy 386.996176 -11.866575)
			(xy 386.876988 -11.941465) (xy 386.753787 -12.009554) (xy 386.626963 -12.070627) (xy 386.496913 -12.124494)
			(xy 386.364048 -12.170984) (xy 386.228785 -12.209951) (xy 386.091551 -12.241273) (xy 385.952775 -12.26485)
			(xy 385.812896 -12.280609) (xy 385.672354 -12.2885) (xy 385.601972 -12.289028) (xy 260.800088 -12.289028)
			(xy 260.744319 -12.28955) (xy 260.633094 -12.297886) (xy 260.522803 -12.314511) (xy 260.414062 -12.339331)
			(xy 260.30748 -12.372208) (xy 260.234662 -12.400788) (xy 436.813452 -12.400788) (xy 436.813941 -12.359678)
			(xy 436.821529 -12.27781) (xy 436.83664 -12.196991) (xy 436.859145 -12.117912) (xy 436.888851 -12.041247)
			(xy 436.925505 -11.96765) (xy 436.968795 -11.89775) (xy 437.01835 -11.832142) (xy 437.073748 -11.771388)
			(xy 437.134516 -11.716006) (xy 437.200136 -11.666467) (xy 437.270047 -11.623195) (xy 437.343653 -11.58656)
			(xy 437.420326 -11.556873) (xy 437.499411 -11.534389) (xy 437.580234 -11.519298) (xy 437.662104 -11.511731)
			(xy 437.703214 -11.51128) (xy 437.747029 -11.511772) (xy 437.83424 -11.520318) (xy 437.920187 -11.537406)
			(xy 438.004035 -11.562868) (xy 438.084971 -11.596458) (xy 438.123838 -11.61669) (xy 438.135191 -11.622017)
			(xy 438.160237 -11.622017) (xy 438.17159 -11.61669) (xy 438.210465 -11.596477) (xy 438.291405 -11.562905)
			(xy 438.375252 -11.537448) (xy 438.461195 -11.520353) (xy 438.548401 -11.511784) (xy 438.592214 -11.51128)
			(xy 438.636029 -11.511772) (xy 438.72324 -11.520318) (xy 438.809187 -11.537406) (xy 438.893035 -11.562868)
			(xy 438.973971 -11.596458) (xy 439.012838 -11.61669) (xy 439.024191 -11.622017) (xy 439.049237 -11.622017)
			(xy 439.06059 -11.61669) (xy 439.099465 -11.596477) (xy 439.180405 -11.562905) (xy 439.264252 -11.537448)
			(xy 439.350195 -11.520353) (xy 439.437401 -11.511784) (xy 439.481214 -11.51128) (xy 439.521951 -11.511719)
			(xy 439.603086 -11.519152) (xy 439.683202 -11.533973) (xy 439.761626 -11.556057) (xy 439.837703 -11.585219)
			(xy 439.910794 -11.621216) (xy 439.94578 -11.64209) (xy 439.954798 -11.647053) (xy 439.975154 -11.650004)
			(xy 439.995036 -11.644737) (xy 440.003438 -11.638788) (xy 440.091322 -11.570462) (xy 440.10072 -11.54049)
			(xy 440.095894 -11.52525) (xy 440.083229 -11.482506) (xy 440.065483 -11.395136) (xy 440.056563 -11.306429)
			(xy 440.056016 -11.261852) (xy 440.056016 -11.26109) (xy 440.056438 -11.22287) (xy 440.062998 -11.146712)
			(xy 440.076079 -11.071399) (xy 440.095582 -10.997489) (xy 440.108086 -10.96137) (xy 440.110695 -10.953059)
			(xy 440.110679 -10.935651) (xy 440.108086 -10.927334) (xy 440.095582 -10.891215) (xy 440.076095 -10.817302)
			(xy 440.063015 -10.74199) (xy 440.056437 -10.665834) (xy 440.056016 -10.627614) (xy 440.056016 -10.626852)
			(xy 440.05652 -10.584504) (xy 440.064571 -10.50019) (xy 440.0806 -10.417024) (xy 440.104461 -10.335757)
			(xy 440.13594 -10.257127) (xy 440.174751 -10.181846) (xy 440.220541 -10.110594) (xy 440.272897 -10.044018)
			(xy 440.331345 -9.98272) (xy 440.395355 -9.927255) (xy 440.464347 -9.878126) (xy 440.537697 -9.835777)
			(xy 440.61474 -9.800593) (xy 440.694779 -9.772891) (xy 440.777088 -9.752923) (xy 440.860923 -9.74087)
			(xy 440.945524 -9.73684) (xy 441.030125 -9.74087) (xy 441.11396 -9.752923) (xy 441.196269 -9.772891)
			(xy 441.276308 -9.800593) (xy 441.353351 -9.835777) (xy 441.426701 -9.878126) (xy 441.495693 -9.927255)
			(xy 441.559703 -9.98272) (xy 441.618151 -10.044018) (xy 441.670507 -10.110594) (xy 441.716297 -10.181846)
			(xy 441.755108 -10.257127) (xy 441.786587 -10.335757) (xy 441.810448 -10.417024) (xy 441.826477 -10.50019)
			(xy 441.834528 -10.584504) (xy 441.835032 -10.626852) (xy 441.835032 -10.627614) (xy 441.834614 -10.665834)
			(xy 441.828053 -10.741992) (xy 441.814972 -10.817305) (xy 441.795467 -10.891215) (xy 441.782962 -10.927334)
			(xy 441.780399 -10.935656) (xy 441.780383 -10.953054) (xy 441.782962 -10.96137) (xy 441.795465 -10.997489)
			(xy 441.814952 -11.071403) (xy 441.828033 -11.146715) (xy 441.834611 -11.22287) (xy 441.835032 -11.26109)
			(xy 441.835032 -11.261852) (xy 441.834502 -11.302954) (xy 441.826922 -11.384807) (xy 441.811821 -11.465611)
			(xy 441.789329 -11.544677) (xy 441.759637 -11.621331) (xy 441.722999 -11.694918) (xy 441.679728 -11.764811)
			(xy 441.630192 -11.830413) (xy 441.574815 -11.891164) (xy 441.514068 -11.946546) (xy 441.44847 -11.996087)
			(xy 441.378581 -12.039364) (xy 441.304997 -12.076008) (xy 441.228346 -12.105706) (xy 441.149281 -12.128204)
			(xy 441.068478 -12.143312) (xy 440.986626 -12.150899) (xy 440.945524 -12.15136) (xy 440.945016 -12.15136)
			(xy 440.904322 -12.150875) (xy 440.823276 -12.143416) (xy 440.74325 -12.128584) (xy 440.664913 -12.106505)
			(xy 440.58892 -12.077363) (xy 440.515907 -12.041401) (xy 440.480958 -12.02055) (xy 440.471926 -12.015614)
			(xy 440.451579 -12.012649) (xy 440.431701 -12.017907) (xy 440.4233 -12.023852) (xy 440.335416 -12.092178)
			(xy 440.326018 -12.12215) (xy 440.330844 -12.13739) (xy 440.343568 -12.180123) (xy 440.361398 -12.267491)
			(xy 440.370394 -12.356204) (xy 440.370976 -12.400788) (xy 440.370415 -12.444238) (xy 440.361895 -12.530719)
			(xy 440.344992 -12.615959) (xy 440.319868 -12.699148) (xy 440.286761 -12.779495) (xy 440.266836 -12.81811)
			(xy 440.262961 -12.82623) (xy 440.260628 -12.84406) (xy 440.262264 -12.852908) (xy 440.272023 -12.900055)
			(xy 440.282457 -12.995773) (xy 440.283092 -13.043916) (xy 440.282667 -13.085188) (xy 440.275027 -13.167377)
			(xy 440.259804 -13.248505) (xy 440.23713 -13.327874) (xy 440.2072 -13.4048) (xy 440.170271 -13.478622)
			(xy 440.126661 -13.548705) (xy 440.076745 -13.614446) (xy 440.020952 -13.675279) (xy 439.959763 -13.730681)
			(xy 439.893704 -13.780175) (xy 439.823344 -13.823336) (xy 439.786522 -13.841984) (xy 439.778885 -13.846179)
			(xy 439.766763 -13.858679) (xy 439.759479 -13.874495) (xy 439.758328 -13.883132) (xy 439.755251 -13.911241)
			(xy 439.741951 -13.966197) (xy 439.720685 -14.018587) (xy 439.69192 -14.067266) (xy 439.656285 -14.111165)
			(xy 439.643167 -14.123162) (xy 440.58586 -14.123162) (xy 440.586283 -14.084873) (xy 440.592885 -14.008579)
			(xy 440.60603 -13.933136) (xy 440.625619 -13.859105) (xy 440.638184 -13.822934) (xy 440.640853 -13.814502)
			(xy 440.64084 -13.796827) (xy 440.638184 -13.78839) (xy 440.625655 -13.752208) (xy 440.606078 -13.678176)
			(xy 440.592927 -13.602738) (xy 440.586298 -13.52645) (xy 440.58586 -13.488162) (xy 440.586364 -13.445801)
			(xy 440.594417 -13.361464) (xy 440.610451 -13.278274) (xy 440.634319 -13.196984) (xy 440.665807 -13.118332)
			(xy 440.704629 -13.043029) (xy 440.750432 -12.971757) (xy 440.802803 -12.905161) (xy 440.861268 -12.843846)
			(xy 440.925296 -12.788365) (xy 440.994308 -12.739222) (xy 441.067678 -12.696862) (xy 441.144743 -12.661667)
			(xy 441.224805 -12.633958) (xy 441.307138 -12.613984) (xy 441.390997 -12.601927) (xy 441.475622 -12.597896)
			(xy 441.560247 -12.601927) (xy 441.644106 -12.613984) (xy 441.726439 -12.633958) (xy 441.806501 -12.661667)
			(xy 441.883566 -12.696862) (xy 441.956936 -12.739222) (xy 442.025948 -12.788365) (xy 442.089976 -12.843846)
			(xy 442.135955 -12.892066) (xy 445.44847 -12.892066) (xy 445.44847 -12.837534) (xy 445.456231 -12.783558)
			(xy 445.471594 -12.731236) (xy 445.494246 -12.681632) (xy 445.523728 -12.635757) (xy 445.559438 -12.594545)
			(xy 445.600649 -12.558834) (xy 445.646523 -12.529351) (xy 445.696126 -12.506697) (xy 445.748448 -12.491333)
			(xy 445.802424 -12.483571) (xy 445.82969 -12.483084) (xy 446.69329 -12.483084) (xy 446.720565 -12.483455)
			(xy 446.774559 -12.491217) (xy 446.826899 -12.506584) (xy 446.87652 -12.529244) (xy 446.92241 -12.558735)
			(xy 446.963636 -12.594456) (xy 446.999359 -12.635682) (xy 447.028851 -12.681571) (xy 447.051512 -12.731191)
			(xy 447.066881 -12.783531) (xy 447.074644 -12.837525) (xy 447.074644 -12.892075) (xy 447.066881 -12.946069)
			(xy 447.051512 -12.998409) (xy 447.028851 -13.048029) (xy 446.999359 -13.093918) (xy 446.963636 -13.135144)
			(xy 446.92241 -13.170865) (xy 446.87652 -13.200356) (xy 446.826899 -13.223016) (xy 446.774559 -13.238383)
			(xy 446.720565 -13.246145) (xy 446.69329 -13.246608) (xy 445.82969 -13.246608) (xy 445.802424 -13.246029)
			(xy 445.748448 -13.238267) (xy 445.696126 -13.222903) (xy 445.646523 -13.200249) (xy 445.600649 -13.170766)
			(xy 445.559438 -13.135055) (xy 445.523728 -13.093843) (xy 445.494246 -13.047968) (xy 445.471594 -12.998364)
			(xy 445.456231 -12.946042) (xy 445.44847 -12.892066) (xy 442.135955 -12.892066) (xy 442.148441 -12.905161)
			(xy 442.200812 -12.971757) (xy 442.246615 -13.043029) (xy 442.285437 -13.118332) (xy 442.316925 -13.196984)
			(xy 442.340793 -13.278274) (xy 442.356827 -13.361464) (xy 442.36488 -13.445801) (xy 442.365384 -13.488162)
			(xy 442.364966 -13.526452) (xy 442.358362 -13.602745) (xy 442.345216 -13.678188) (xy 442.325626 -13.752219)
			(xy 442.31306 -13.78839) (xy 442.310428 -13.796831) (xy 442.310415 -13.814498) (xy 442.31306 -13.822934)
			(xy 442.325598 -13.859113) (xy 442.345172 -13.933146) (xy 442.358321 -14.008585) (xy 442.364947 -14.084874)
			(xy 442.365384 -14.123162) (xy 442.36488 -14.165523) (xy 442.356827 -14.24986) (xy 442.340793 -14.33305)
			(xy 442.316925 -14.41434) (xy 442.285437 -14.492992) (xy 442.268155 -14.526514) (xy 449.780152 -14.526514)
			(xy 449.780656 -14.484153) (xy 449.788709 -14.399816) (xy 449.804743 -14.316626) (xy 449.828611 -14.235336)
			(xy 449.860099 -14.156684) (xy 449.898921 -14.081381) (xy 449.944724 -14.010109) (xy 449.997095 -13.943513)
			(xy 450.05556 -13.882198) (xy 450.119588 -13.826717) (xy 450.1886 -13.777574) (xy 450.26197 -13.735214)
			(xy 450.339035 -13.700019) (xy 450.419097 -13.67231) (xy 450.50143 -13.652336) (xy 450.585289 -13.640279)
			(xy 450.669914 -13.636248) (xy 450.754539 -13.640279) (xy 450.838398 -13.652336) (xy 450.920731 -13.67231)
			(xy 451.000793 -13.700019) (xy 451.077858 -13.735214) (xy 451.151228 -13.777574) (xy 451.22024 -13.826717)
			(xy 451.284268 -13.882198) (xy 451.342733 -13.943513) (xy 451.395104 -14.010109) (xy 451.440907 -14.081381)
			(xy 451.479729 -14.156684) (xy 451.511217 -14.235336) (xy 451.535085 -14.316626) (xy 451.551119 -14.399816)
			(xy 451.559172 -14.484153) (xy 451.559676 -14.526514) (xy 451.559114 -14.571839) (xy 451.549887 -14.662018)
			(xy 451.531531 -14.750791) (xy 451.504235 -14.837234) (xy 451.486778 -14.879066) (xy 451.483143 -14.888844)
			(xy 451.483128 -14.909681) (xy 451.486778 -14.919452) (xy 451.504363 -14.961485) (xy 451.531877 -15.048351)
			(xy 451.550364 -15.137575) (xy 451.559632 -15.228222) (xy 451.560184 -15.273782) (xy 451.559623 -15.318552)
			(xy 451.550621 -15.407639) (xy 451.532717 -15.495371) (xy 451.506092 -15.580861) (xy 451.489064 -15.62227)
			(xy 451.485509 -15.631864) (xy 451.485503 -15.652304) (xy 451.489064 -15.661894) (xy 451.50607 -15.703278)
			(xy 451.532693 -15.788702) (xy 451.550602 -15.876368) (xy 451.559616 -15.96539) (xy 451.560184 -16.010128)
			(xy 451.560184 -16.010382) (xy 451.55968 -16.05273) (xy 451.551629 -16.137044) (xy 451.5356 -16.22021)
			(xy 451.511739 -16.301477) (xy 451.48026 -16.380107) (xy 451.441449 -16.455388) (xy 451.395659 -16.52664)
			(xy 451.343303 -16.593216) (xy 451.284855 -16.654514) (xy 451.220845 -16.709979) (xy 451.151853 -16.759108)
			(xy 451.078503 -16.801457) (xy 451.00146 -16.836641) (xy 450.921421 -16.864343) (xy 450.839112 -16.884311)
			(xy 450.755277 -16.896364) (xy 450.670676 -16.900395) (xy 450.586075 -16.896364) (xy 450.50224 -16.884311)
			(xy 450.419931 -16.864343) (xy 450.339892 -16.836641) (xy 450.262849 -16.801457) (xy 450.189499 -16.759108)
			(xy 450.120507 -16.709979) (xy 450.056497 -16.654514) (xy 449.998049 -16.593216) (xy 449.945693 -16.52664)
			(xy 449.899903 -16.455388) (xy 449.861092 -16.380107) (xy 449.829613 -16.301477) (xy 449.805752 -16.22021)
			(xy 449.789723 -16.137044) (xy 449.781672 -16.05273) (xy 449.781168 -16.010382) (xy 449.781168 -16.010128)
			(xy 449.781731 -15.96539) (xy 449.790749 -15.876368) (xy 449.808655 -15.788701) (xy 449.83527 -15.703273)
			(xy 449.852288 -15.661894) (xy 449.855865 -15.652307) (xy 449.855859 -15.63186) (xy 449.852288 -15.62227)
			(xy 449.835263 -15.580859) (xy 449.808628 -15.495372) (xy 449.790721 -15.40764) (xy 449.781723 -15.318552)
			(xy 449.781168 -15.273782) (xy 449.781749 -15.228458) (xy 449.79099 -15.138283) (xy 449.809345 -15.049513)
			(xy 449.836623 -14.963067) (xy 449.854066 -14.92123) (xy 449.857691 -14.911438) (xy 449.857571 -14.890584)
			(xy 449.853812 -14.880844) (xy 449.836183 -14.838823) (xy 449.808624 -14.751958) (xy 449.790079 -14.662732)
			(xy 449.780742 -14.57208) (xy 449.780152 -14.526514) (xy 442.268155 -14.526514) (xy 442.246615 -14.568295)
			(xy 442.200812 -14.639567) (xy 442.148441 -14.706163) (xy 442.089976 -14.767478) (xy 442.025948 -14.822959)
			(xy 441.956936 -14.872102) (xy 441.883566 -14.914462) (xy 441.806501 -14.949657) (xy 441.726439 -14.977366)
			(xy 441.644106 -14.99734) (xy 441.560247 -15.009397) (xy 441.475622 -15.013429) (xy 441.390997 -15.009397)
			(xy 441.307138 -14.99734) (xy 441.224805 -14.977366) (xy 441.144743 -14.949657) (xy 441.067678 -14.914462)
			(xy 440.994308 -14.872102) (xy 440.925296 -14.822959) (xy 440.861268 -14.767478) (xy 440.802803 -14.706163)
			(xy 440.750432 -14.639567) (xy 440.704629 -14.568295) (xy 440.665807 -14.492992) (xy 440.634319 -14.41434)
			(xy 440.610451 -14.33305) (xy 440.594417 -14.24986) (xy 440.586364 -14.165523) (xy 440.58586 -14.123162)
			(xy 439.643167 -14.123162) (xy 439.614561 -14.149324) (xy 439.567661 -14.180907) (xy 439.516614 -14.205222)
			(xy 439.462537 -14.221736) (xy 439.406615 -14.230088) (xy 439.378344 -14.230604) (xy 439.350975 -14.230111)
			(xy 439.296797 -14.2223) (xy 439.244294 -14.206817) (xy 439.194547 -14.183981) (xy 439.148579 -14.154262)
			(xy 439.127646 -14.136624) (xy 439.127392 -14.13637) (xy 439.120314 -14.130771) (xy 439.103391 -14.124533)
			(xy 439.094372 -14.124178) (xy 439.027316 -14.124178) (xy 439.018301 -14.124547) (xy 439.001384 -14.130787)
			(xy 438.994296 -14.13637) (xy 438.994296 -14.136624) (xy 438.994042 -14.136624) (xy 438.973108 -14.154261)
			(xy 438.927135 -14.183972) (xy 438.877388 -14.206808) (xy 438.824888 -14.2223) (xy 438.770713 -14.230129)
			(xy 438.743344 -14.230604) (xy 438.713998 -14.230028) (xy 438.656001 -14.221024) (xy 438.600065 -14.203253)
			(xy 438.547506 -14.177132) (xy 438.499563 -14.143277) (xy 438.457364 -14.102486) (xy 438.421903 -14.055718)
			(xy 438.394015 -14.004075) (xy 438.38368 -13.976604) (xy 438.380221 -13.968026) (xy 438.368225 -13.953963)
			(xy 438.360312 -13.949172) (xy 438.333388 -13.93444) (xy 438.324705 -13.93016) (xy 438.305508 -13.927807)
			(xy 438.29605 -13.929868) (xy 438.259095 -13.939128) (xy 438.184005 -13.952036) (xy 438.108086 -13.958466)
			(xy 438.06999 -13.958824) (xy 438.028658 -13.958363) (xy 437.94635 -13.95071) (xy 437.865107 -13.935453)
			(xy 437.78563 -13.912724) (xy 437.708605 -13.882718) (xy 437.634696 -13.845694) (xy 437.564542 -13.801972)
			(xy 437.498747 -13.751929) (xy 437.43788 -13.695998) (xy 437.382465 -13.634659) (xy 437.332981 -13.568444)
			(xy 437.289854 -13.497922) (xy 437.253456 -13.423703) (xy 437.224103 -13.346427) (xy 437.202046 -13.266761)
			(xy 437.187477 -13.185391) (xy 437.18353 -13.144246) (xy 437.182106 -13.133691) (xy 437.171856 -13.11505)
			(xy 437.163718 -13.108178) (xy 437.131484 -13.082996) (xy 437.071245 -13.027653) (xy 437.016344 -12.967011)
			(xy 436.967245 -12.901582) (xy 436.924364 -12.831919) (xy 436.888063 -12.758612) (xy 436.858649 -12.682281)
			(xy 436.83637 -12.603571) (xy 436.821416 -12.523147) (xy 436.813913 -12.441689) (xy 436.813452 -12.400788)
			(xy 260.234662 -12.400788) (xy 260.203654 -12.412958) (xy 260.103162 -12.461353) (xy 260.006569 -12.517122)
			(xy 259.914413 -12.579954) (xy 259.82721 -12.649497) (xy 259.745448 -12.725362) (xy 259.669584 -12.807125)
			(xy 259.601843 -12.89207) (xy 431.453248 -12.89207) (xy 431.453248 -12.83753) (xy 431.46101 -12.783546)
			(xy 431.476376 -12.731216) (xy 431.499035 -12.681606) (xy 431.528523 -12.635726) (xy 431.564241 -12.594509)
			(xy 431.605461 -12.558796) (xy 431.651345 -12.529313) (xy 431.700957 -12.506661) (xy 431.753289 -12.4913)
			(xy 431.807274 -12.483544) (xy 431.834544 -12.483084) (xy 432.698144 -12.483084) (xy 432.725415 -12.483482)
			(xy 432.7794 -12.491249) (xy 432.83173 -12.50662) (xy 432.881341 -12.529282) (xy 432.927222 -12.558772)
			(xy 432.968439 -12.594492) (xy 433.004154 -12.635713) (xy 433.033639 -12.681598) (xy 433.056295 -12.731211)
			(xy 433.07166 -12.783543) (xy 433.079422 -12.837529) (xy 433.079422 -12.892071) (xy 433.07166 -12.946057)
			(xy 433.056295 -12.998389) (xy 433.033639 -13.048002) (xy 433.004154 -13.093887) (xy 432.968439 -13.135108)
			(xy 432.927222 -13.170828) (xy 432.881341 -13.200318) (xy 432.83173 -13.22298) (xy 432.7794 -13.238351)
			(xy 432.725415 -13.246118) (xy 432.698144 -13.246608) (xy 431.834544 -13.246608) (xy 431.807274 -13.246056)
			(xy 431.753289 -13.2383) (xy 431.700957 -13.222939) (xy 431.651345 -13.200287) (xy 431.605461 -13.170804)
			(xy 431.564241 -13.135091) (xy 431.528523 -13.093874) (xy 431.499035 -13.047994) (xy 431.476376 -12.998384)
			(xy 431.46101 -12.946054) (xy 431.453248 -12.89207) (xy 259.601843 -12.89207) (xy 259.600042 -12.894329)
			(xy 259.537211 -12.986486) (xy 259.481443 -13.08308) (xy 259.43305 -13.183572) (xy 259.392301 -13.287399)
			(xy 259.359426 -13.393981) (xy 259.334607 -13.502722) (xy 259.317984 -13.613014) (xy 259.309649 -13.724239)
			(xy 259.309108 -13.780008) (xy 259.309108 -17.126458) (xy 310.265572 -17.126458) (xy 310.265992 -17.082972)
			(xy 310.273576 -16.996331) (xy 310.288682 -16.910681) (xy 310.311195 -16.826674) (xy 310.340944 -16.744948)
			(xy 310.377702 -16.666126) (xy 310.421191 -16.590808) (xy 310.471078 -16.519566) (xy 310.526985 -16.452943)
			(xy 310.588485 -16.391447) (xy 310.65511 -16.335544) (xy 310.726355 -16.285661) (xy 310.801676 -16.242177)
			(xy 310.8805 -16.205422) (xy 310.962227 -16.175678) (xy 311.046236 -16.15317) (xy 311.131887 -16.138068)
			(xy 311.218528 -16.13049) (xy 311.262014 -16.130016) (xy 311.287414 -16.130016) (xy 311.33271 -16.130609)
			(xy 311.422936 -16.13873) (xy 311.512071 -16.154907) (xy 311.599397 -16.179009) (xy 311.684211 -16.210841)
			(xy 311.76583 -16.250148) (xy 311.843598 -16.296613) (xy 311.916887 -16.349861) (xy 311.985108 -16.409465)
			(xy 312.047712 -16.474944) (xy 312.104194 -16.545772) (xy 312.1541 -16.621377) (xy 312.197028 -16.701151)
			(xy 312.232632 -16.784452) (xy 312.260626 -16.870609) (xy 312.280784 -16.958929) (xy 312.292944 -17.0487)
			(xy 312.297009 -17.1392) (xy 312.292944 -17.2297) (xy 312.280784 -17.319471) (xy 312.260626 -17.407791)
			(xy 312.232632 -17.493948) (xy 312.197028 -17.577249) (xy 312.163448 -17.639652) (xy 389.652738 -17.639652)
			(xy 389.652738 -17.585148) (xy 389.660494 -17.531197) (xy 389.675849 -17.4789) (xy 389.69849 -17.42932)
			(xy 389.727956 -17.383466) (xy 389.763647 -17.342273) (xy 389.804838 -17.306578) (xy 389.850688 -17.277107)
			(xy 389.900266 -17.254462) (xy 389.952562 -17.239102) (xy 390.006512 -17.23134) (xy 390.033764 -17.230852)
			(xy 390.897364 -17.230852) (xy 390.924616 -17.231393) (xy 390.978565 -17.239145) (xy 391.030862 -17.254496)
			(xy 391.080441 -17.277134) (xy 391.126294 -17.306598) (xy 391.167486 -17.342288) (xy 391.20318 -17.383477)
			(xy 391.232649 -17.429327) (xy 391.255291 -17.478905) (xy 391.270648 -17.5312) (xy 391.278405 -17.585148)
			(xy 391.278405 -17.639652) (xy 395.240738 -17.639652) (xy 395.240738 -17.585148) (xy 395.248494 -17.531197)
			(xy 395.263849 -17.4789) (xy 395.28649 -17.42932) (xy 395.315956 -17.383466) (xy 395.351647 -17.342273)
			(xy 395.392838 -17.306578) (xy 395.438688 -17.277107) (xy 395.488266 -17.254462) (xy 395.540562 -17.239102)
			(xy 395.594512 -17.23134) (xy 395.621764 -17.230852) (xy 396.485364 -17.230852) (xy 396.512616 -17.231393)
			(xy 396.566565 -17.239145) (xy 396.618862 -17.254496) (xy 396.668441 -17.277134) (xy 396.714294 -17.306598)
			(xy 396.755486 -17.342288) (xy 396.79118 -17.383477) (xy 396.820649 -17.429327) (xy 396.843291 -17.478905)
			(xy 396.858648 -17.5312) (xy 396.866405 -17.585148) (xy 396.866405 -17.639652) (xy 400.828738 -17.639652)
			(xy 400.828738 -17.585148) (xy 400.836494 -17.531197) (xy 400.851849 -17.4789) (xy 400.87449 -17.42932)
			(xy 400.903956 -17.383466) (xy 400.939647 -17.342273) (xy 400.980838 -17.306578) (xy 401.026688 -17.277107)
			(xy 401.076266 -17.254462) (xy 401.128562 -17.239102) (xy 401.182512 -17.23134) (xy 401.209764 -17.230852)
			(xy 402.073364 -17.230852) (xy 402.100616 -17.231393) (xy 402.154565 -17.239145) (xy 402.206862 -17.254496)
			(xy 402.256441 -17.277134) (xy 402.302294 -17.306598) (xy 402.343486 -17.342288) (xy 402.37918 -17.383477)
			(xy 402.408649 -17.429327) (xy 402.431291 -17.478905) (xy 402.446648 -17.5312) (xy 402.454405 -17.585148)
			(xy 402.454405 -17.639652) (xy 402.454301 -17.640372) (xy 406.415424 -17.640372) (xy 406.415424 -17.585828)
			(xy 406.423187 -17.53184) (xy 406.438554 -17.479507) (xy 406.461214 -17.429893) (xy 406.490704 -17.38401)
			(xy 406.526425 -17.342791) (xy 406.567649 -17.307076) (xy 406.613536 -17.277591) (xy 406.663152 -17.254938)
			(xy 406.715487 -17.239576) (xy 406.769476 -17.23182) (xy 406.796748 -17.23136) (xy 407.660348 -17.23136)
			(xy 407.687617 -17.231806) (xy 407.741598 -17.239573) (xy 407.793925 -17.254944) (xy 407.843532 -17.277604)
			(xy 407.88941 -17.307093) (xy 407.930624 -17.34281) (xy 407.966336 -17.384029) (xy 407.995819 -17.42991)
			(xy 408.018473 -17.47952) (xy 408.033837 -17.531849) (xy 408.041598 -17.585831) (xy 408.041598 -17.640369)
			(xy 408.041598 -17.640372) (xy 412.003424 -17.640372) (xy 412.003424 -17.585828) (xy 412.011187 -17.53184)
			(xy 412.026554 -17.479507) (xy 412.049214 -17.429893) (xy 412.078704 -17.38401) (xy 412.114425 -17.342791)
			(xy 412.155649 -17.307076) (xy 412.201536 -17.277591) (xy 412.251152 -17.254938) (xy 412.303487 -17.239576)
			(xy 412.357476 -17.23182) (xy 412.384748 -17.23136) (xy 413.248348 -17.23136) (xy 413.275617 -17.231806)
			(xy 413.329598 -17.239573) (xy 413.381925 -17.254944) (xy 413.431532 -17.277604) (xy 413.47741 -17.307093)
			(xy 413.518624 -17.34281) (xy 413.554336 -17.384029) (xy 413.583819 -17.42991) (xy 413.606473 -17.47952)
			(xy 413.621837 -17.531849) (xy 413.629598 -17.585831) (xy 413.629598 -17.639653) (xy 417.898538 -17.639653)
			(xy 417.898538 -17.585147) (xy 417.906295 -17.531195) (xy 417.92165 -17.478897) (xy 417.944292 -17.429315)
			(xy 417.97376 -17.383461) (xy 418.009453 -17.342267) (xy 418.050645 -17.306572) (xy 418.096498 -17.277102)
			(xy 418.146078 -17.254457) (xy 418.198376 -17.239099) (xy 418.252327 -17.231339) (xy 418.27958 -17.230852)
			(xy 419.14318 -17.230852) (xy 419.170431 -17.231394) (xy 419.224378 -17.239148) (xy 419.276673 -17.2545)
			(xy 419.326251 -17.277139) (xy 419.372101 -17.306604) (xy 419.413292 -17.342294) (xy 419.448984 -17.383483)
			(xy 419.478451 -17.429332) (xy 419.501093 -17.478908) (xy 419.516448 -17.531202) (xy 419.524205 -17.585149)
			(xy 419.524205 -17.639651) (xy 419.524205 -17.639653) (xy 423.486538 -17.639653) (xy 423.486538 -17.585147)
			(xy 423.494295 -17.531195) (xy 423.50965 -17.478897) (xy 423.532292 -17.429315) (xy 423.56176 -17.383461)
			(xy 423.597453 -17.342267) (xy 423.638645 -17.306572) (xy 423.684498 -17.277102) (xy 423.734078 -17.254457)
			(xy 423.786376 -17.239099) (xy 423.840327 -17.231339) (xy 423.86758 -17.230852) (xy 424.73118 -17.230852)
			(xy 424.758431 -17.231394) (xy 424.812378 -17.239148) (xy 424.864673 -17.2545) (xy 424.914251 -17.277139)
			(xy 424.960101 -17.306604) (xy 425.001292 -17.342294) (xy 425.036984 -17.383483) (xy 425.066451 -17.429332)
			(xy 425.089093 -17.478908) (xy 425.104448 -17.531202) (xy 425.112205 -17.585149) (xy 425.112205 -17.639651)
			(xy 425.112102 -17.640368) (xy 429.107346 -17.640368) (xy 429.107346 -17.585832) (xy 429.115108 -17.531852)
			(xy 429.130472 -17.479525) (xy 429.153127 -17.429918) (xy 429.182611 -17.38404) (xy 429.218324 -17.342824)
			(xy 429.25954 -17.307111) (xy 429.305418 -17.277627) (xy 429.355025 -17.254972) (xy 429.407352 -17.239608)
			(xy 429.461332 -17.231846) (xy 429.4886 -17.23136) (xy 430.3522 -17.23136) (xy 430.379471 -17.231802)
			(xy 430.433458 -17.239565) (xy 430.48579 -17.254931) (xy 430.535403 -17.277588) (xy 430.581287 -17.307076)
			(xy 430.622507 -17.342793) (xy 430.658224 -17.384013) (xy 430.687712 -17.429897) (xy 430.710369 -17.47951)
			(xy 430.725735 -17.531842) (xy 430.733498 -17.585829) (xy 430.733498 -17.640371) (xy 430.725735 -17.694358)
			(xy 430.710369 -17.74669) (xy 430.687712 -17.796303) (xy 430.658224 -17.842187) (xy 430.622507 -17.883407)
			(xy 430.581287 -17.919124) (xy 430.535403 -17.948612) (xy 430.48579 -17.971269) (xy 430.433458 -17.986635)
			(xy 430.379471 -17.994398) (xy 430.3522 -17.994884) (xy 429.4886 -17.994884) (xy 429.461332 -17.994354)
			(xy 429.407352 -17.986592) (xy 429.355025 -17.971228) (xy 429.305418 -17.948573) (xy 429.25954 -17.919089)
			(xy 429.218324 -17.883376) (xy 429.182611 -17.84216) (xy 429.153127 -17.796282) (xy 429.130472 -17.746675)
			(xy 429.115108 -17.694348) (xy 429.107346 -17.640368) (xy 425.112102 -17.640368) (xy 425.104448 -17.693598)
			(xy 425.089093 -17.745892) (xy 425.066451 -17.795468) (xy 425.036984 -17.841317) (xy 425.001292 -17.882506)
			(xy 424.960101 -17.918196) (xy 424.914251 -17.947661) (xy 424.864673 -17.9703) (xy 424.812378 -17.985652)
			(xy 424.758431 -17.993406) (xy 424.73118 -17.993868) (xy 423.86758 -17.993868) (xy 423.840327 -17.993461)
			(xy 423.786376 -17.985701) (xy 423.734078 -17.970343) (xy 423.684498 -17.947698) (xy 423.638645 -17.918228)
			(xy 423.597453 -17.882533) (xy 423.56176 -17.841339) (xy 423.532292 -17.795485) (xy 423.50965 -17.745903)
			(xy 423.494295 -17.693605) (xy 423.486538 -17.639653) (xy 419.524205 -17.639653) (xy 419.516448 -17.693598)
			(xy 419.501093 -17.745892) (xy 419.478451 -17.795468) (xy 419.448984 -17.841317) (xy 419.413292 -17.882506)
			(xy 419.372101 -17.918196) (xy 419.326251 -17.947661) (xy 419.276673 -17.9703) (xy 419.224378 -17.985652)
			(xy 419.170431 -17.993406) (xy 419.14318 -17.993868) (xy 418.27958 -17.993868) (xy 418.252327 -17.993461)
			(xy 418.198376 -17.985701) (xy 418.146078 -17.970343) (xy 418.096498 -17.947698) (xy 418.050645 -17.918228)
			(xy 418.009453 -17.882533) (xy 417.97376 -17.841339) (xy 417.944292 -17.795485) (xy 417.92165 -17.745903)
			(xy 417.906295 -17.693605) (xy 417.898538 -17.639653) (xy 413.629598 -17.639653) (xy 413.629598 -17.640369)
			(xy 413.621837 -17.694351) (xy 413.606473 -17.74668) (xy 413.583819 -17.79629) (xy 413.554336 -17.842171)
			(xy 413.518624 -17.88339) (xy 413.47741 -17.919107) (xy 413.431532 -17.948596) (xy 413.381925 -17.971256)
			(xy 413.329598 -17.986627) (xy 413.275617 -17.994394) (xy 413.248348 -17.994884) (xy 412.384748 -17.994884)
			(xy 412.357476 -17.99438) (xy 412.303487 -17.986624) (xy 412.251152 -17.971262) (xy 412.201536 -17.948609)
			(xy 412.155649 -17.919124) (xy 412.114425 -17.883409) (xy 412.078704 -17.84219) (xy 412.049214 -17.796307)
			(xy 412.026554 -17.746693) (xy 412.011187 -17.69436) (xy 412.003424 -17.640372) (xy 408.041598 -17.640372)
			(xy 408.033837 -17.694351) (xy 408.018473 -17.74668) (xy 407.995819 -17.79629) (xy 407.966336 -17.842171)
			(xy 407.930624 -17.88339) (xy 407.88941 -17.919107) (xy 407.843532 -17.948596) (xy 407.793925 -17.971256)
			(xy 407.741598 -17.986627) (xy 407.687617 -17.994394) (xy 407.660348 -17.994884) (xy 406.796748 -17.994884)
			(xy 406.769476 -17.99438) (xy 406.715487 -17.986624) (xy 406.663152 -17.971262) (xy 406.613536 -17.948609)
			(xy 406.567649 -17.919124) (xy 406.526425 -17.883409) (xy 406.490704 -17.84219) (xy 406.461214 -17.796307)
			(xy 406.438554 -17.746693) (xy 406.423187 -17.69436) (xy 406.415424 -17.640372) (xy 402.454301 -17.640372)
			(xy 402.446648 -17.6936) (xy 402.431291 -17.745895) (xy 402.408649 -17.795473) (xy 402.37918 -17.841323)
			(xy 402.343486 -17.882512) (xy 402.302294 -17.918202) (xy 402.256441 -17.947666) (xy 402.206862 -17.970304)
			(xy 402.154565 -17.985655) (xy 402.100616 -17.993407) (xy 402.073364 -17.993868) (xy 401.209764 -17.993868)
			(xy 401.182512 -17.99346) (xy 401.128562 -17.985698) (xy 401.076266 -17.970338) (xy 401.026688 -17.947693)
			(xy 400.980838 -17.918222) (xy 400.939647 -17.882527) (xy 400.903956 -17.841334) (xy 400.87449 -17.79548)
			(xy 400.851849 -17.7459) (xy 400.836494 -17.693603) (xy 400.828738 -17.639652) (xy 396.866405 -17.639652)
			(xy 396.858648 -17.6936) (xy 396.843291 -17.745895) (xy 396.820649 -17.795473) (xy 396.79118 -17.841323)
			(xy 396.755486 -17.882512) (xy 396.714294 -17.918202) (xy 396.668441 -17.947666) (xy 396.618862 -17.970304)
			(xy 396.566565 -17.985655) (xy 396.512616 -17.993407) (xy 396.485364 -17.993868) (xy 395.621764 -17.993868)
			(xy 395.594512 -17.99346) (xy 395.540562 -17.985698) (xy 395.488266 -17.970338) (xy 395.438688 -17.947693)
			(xy 395.392838 -17.918222) (xy 395.351647 -17.882527) (xy 395.315956 -17.841334) (xy 395.28649 -17.79548)
			(xy 395.263849 -17.7459) (xy 395.248494 -17.693603) (xy 395.240738 -17.639652) (xy 391.278405 -17.639652)
			(xy 391.270648 -17.6936) (xy 391.255291 -17.745895) (xy 391.232649 -17.795473) (xy 391.20318 -17.841323)
			(xy 391.167486 -17.882512) (xy 391.126294 -17.918202) (xy 391.080441 -17.947666) (xy 391.030862 -17.970304)
			(xy 390.978565 -17.985655) (xy 390.924616 -17.993407) (xy 390.897364 -17.993868) (xy 390.033764 -17.993868)
			(xy 390.006512 -17.99346) (xy 389.952562 -17.985698) (xy 389.900266 -17.970338) (xy 389.850688 -17.947693)
			(xy 389.804838 -17.918222) (xy 389.763647 -17.882527) (xy 389.727956 -17.841334) (xy 389.69849 -17.79548)
			(xy 389.675849 -17.7459) (xy 389.660494 -17.693603) (xy 389.652738 -17.639652) (xy 312.163448 -17.639652)
			(xy 312.1541 -17.657023) (xy 312.104194 -17.732628) (xy 312.047712 -17.803456) (xy 311.985108 -17.868935)
			(xy 311.916887 -17.928539) (xy 311.843598 -17.981787) (xy 311.76583 -18.028252) (xy 311.684211 -18.067559)
			(xy 311.599397 -18.099391) (xy 311.512071 -18.123493) (xy 311.422936 -18.13967) (xy 311.33271 -18.147791)
			(xy 311.287414 -18.1483) (xy 311.28716 -18.1483) (xy 311.242573 -18.147831) (xy 311.153739 -18.140039)
			(xy 311.065923 -18.124536) (xy 310.979792 -18.101438) (xy 310.896001 -18.070922) (xy 310.815188 -18.033221)
			(xy 310.737969 -17.988621) (xy 310.664929 -17.937461) (xy 310.596626 -17.88013) (xy 310.533579 -17.817066)
			(xy 310.476268 -17.748747) (xy 310.425128 -17.675693) (xy 310.380549 -17.598461) (xy 310.34287 -17.517638)
			(xy 310.312377 -17.433839) (xy 310.289303 -17.347701) (xy 310.273824 -17.259881) (xy 310.266056 -17.171045)
			(xy 310.265572 -17.126458) (xy 259.309108 -17.126458) (xy 259.309108 -19.164372) (xy 392.445424 -19.164372)
			(xy 392.445424 -19.109828) (xy 392.453187 -19.05584) (xy 392.468554 -19.003507) (xy 392.491214 -18.953893)
			(xy 392.520704 -18.90801) (xy 392.556425 -18.866791) (xy 392.597649 -18.831076) (xy 392.643536 -18.801591)
			(xy 392.693152 -18.778938) (xy 392.745487 -18.763576) (xy 392.799476 -18.75582) (xy 392.826748 -18.75536)
			(xy 393.690348 -18.75536) (xy 393.717617 -18.755806) (xy 393.771598 -18.763573) (xy 393.823925 -18.778944)
			(xy 393.873532 -18.801604) (xy 393.91941 -18.831093) (xy 393.960624 -18.86681) (xy 393.996336 -18.908029)
			(xy 394.025819 -18.95391) (xy 394.048473 -19.00352) (xy 394.063837 -19.055849) (xy 394.071598 -19.109831)
			(xy 394.071598 -19.163652) (xy 398.034738 -19.163652) (xy 398.034738 -19.109148) (xy 398.042494 -19.055197)
			(xy 398.057849 -19.0029) (xy 398.08049 -18.95332) (xy 398.109956 -18.907466) (xy 398.145647 -18.866273)
			(xy 398.186838 -18.830578) (xy 398.232688 -18.801107) (xy 398.282266 -18.778462) (xy 398.334562 -18.763102)
			(xy 398.388512 -18.75534) (xy 398.415764 -18.754852) (xy 399.279364 -18.754852) (xy 399.306616 -18.755393)
			(xy 399.360565 -18.763145) (xy 399.412862 -18.778496) (xy 399.462441 -18.801134) (xy 399.508294 -18.830598)
			(xy 399.549486 -18.866288) (xy 399.58518 -18.907477) (xy 399.614649 -18.953327) (xy 399.637291 -19.002905)
			(xy 399.652648 -19.0552) (xy 399.660405 -19.109148) (xy 399.660405 -19.163652) (xy 403.622738 -19.163652)
			(xy 403.622738 -19.109148) (xy 403.630494 -19.055197) (xy 403.645849 -19.0029) (xy 403.66849 -18.95332)
			(xy 403.697956 -18.907466) (xy 403.733647 -18.866273) (xy 403.774838 -18.830578) (xy 403.820688 -18.801107)
			(xy 403.870266 -18.778462) (xy 403.922562 -18.763102) (xy 403.976512 -18.75534) (xy 404.003764 -18.754852)
			(xy 404.867364 -18.754852) (xy 404.894616 -18.755393) (xy 404.948565 -18.763145) (xy 405.000862 -18.778496)
			(xy 405.050441 -18.801134) (xy 405.096294 -18.830598) (xy 405.137486 -18.866288) (xy 405.17318 -18.907477)
			(xy 405.202649 -18.953327) (xy 405.225291 -19.002905) (xy 405.240648 -19.0552) (xy 405.248405 -19.109148)
			(xy 405.248405 -19.163652) (xy 409.210738 -19.163652) (xy 409.210738 -19.109148) (xy 409.218494 -19.055197)
			(xy 409.233849 -19.0029) (xy 409.25649 -18.95332) (xy 409.285956 -18.907466) (xy 409.321647 -18.866273)
			(xy 409.362838 -18.830578) (xy 409.408688 -18.801107) (xy 409.458266 -18.778462) (xy 409.510562 -18.763102)
			(xy 409.564512 -18.75534) (xy 409.591764 -18.754852) (xy 410.455364 -18.754852) (xy 410.482616 -18.755393)
			(xy 410.536565 -18.763145) (xy 410.588862 -18.778496) (xy 410.638441 -18.801134) (xy 410.684294 -18.830598)
			(xy 410.725486 -18.866288) (xy 410.76118 -18.907477) (xy 410.790649 -18.953327) (xy 410.813291 -19.002905)
			(xy 410.828648 -19.0552) (xy 410.836405 -19.109148) (xy 410.836405 -19.163652) (xy 410.836405 -19.163653)
			(xy 415.104538 -19.163653) (xy 415.104538 -19.109147) (xy 415.112295 -19.055195) (xy 415.12765 -19.002897)
			(xy 415.150292 -18.953315) (xy 415.17976 -18.907461) (xy 415.215453 -18.866267) (xy 415.256645 -18.830572)
			(xy 415.302498 -18.801102) (xy 415.352078 -18.778457) (xy 415.404376 -18.763099) (xy 415.458327 -18.755339)
			(xy 415.48558 -18.754852) (xy 416.34918 -18.754852) (xy 416.376431 -18.755394) (xy 416.430378 -18.763148)
			(xy 416.482673 -18.7785) (xy 416.532251 -18.801139) (xy 416.578101 -18.830604) (xy 416.619292 -18.866294)
			(xy 416.654984 -18.907483) (xy 416.684451 -18.953332) (xy 416.707093 -19.002908) (xy 416.722448 -19.055202)
			(xy 416.730205 -19.109149) (xy 416.730205 -19.163651) (xy 416.730102 -19.164366) (xy 420.691346 -19.164366)
			(xy 420.691346 -19.109834) (xy 420.699107 -19.055857) (xy 420.714469 -19.003533) (xy 420.737121 -18.953928)
			(xy 420.766602 -18.908051) (xy 420.802312 -18.866837) (xy 420.843523 -18.831124) (xy 420.889396 -18.801639)
			(xy 420.938999 -18.778982) (xy 420.991321 -18.763614) (xy 421.045298 -18.755849) (xy 421.072564 -18.75536)
			(xy 421.936164 -18.75536) (xy 421.963438 -18.755777) (xy 422.017432 -18.763536) (xy 422.069772 -18.7789)
			(xy 422.119393 -18.801556) (xy 422.165284 -18.831045) (xy 422.20651 -18.866764) (xy 422.242234 -18.907988)
			(xy 422.271726 -18.953876) (xy 422.294388 -19.003494) (xy 422.309757 -19.055833) (xy 422.31752 -19.109826)
			(xy 422.31752 -19.163656) (xy 426.314515 -19.163656) (xy 426.314515 -19.109144) (xy 426.322273 -19.055185)
			(xy 426.337632 -19.002881) (xy 426.360278 -18.953294) (xy 426.38975 -18.907436) (xy 426.42545 -18.866238)
			(xy 426.466648 -18.830541) (xy 426.512508 -18.80107) (xy 426.562096 -18.778426) (xy 426.614401 -18.76307)
			(xy 426.66836 -18.755314) (xy 426.695616 -18.754852) (xy 427.559216 -18.754852) (xy 427.586464 -18.755419)
			(xy 427.640404 -18.763177) (xy 427.692691 -18.778532) (xy 427.742261 -18.801171) (xy 427.788105 -18.830635)
			(xy 427.829289 -18.866323) (xy 427.864975 -18.907508) (xy 427.894436 -18.953353) (xy 427.917074 -19.002924)
			(xy 427.932427 -19.055212) (xy 427.940182 -19.109152) (xy 427.940182 -19.163648) (xy 427.940181 -19.163656)
			(xy 431.902515 -19.163656) (xy 431.902515 -19.109144) (xy 431.910273 -19.055185) (xy 431.925632 -19.002881)
			(xy 431.948278 -18.953294) (xy 431.97775 -18.907436) (xy 432.01345 -18.866238) (xy 432.054648 -18.830541)
			(xy 432.100508 -18.80107) (xy 432.150096 -18.778426) (xy 432.202401 -18.76307) (xy 432.25636 -18.755314)
			(xy 432.283616 -18.754852) (xy 433.147216 -18.754852) (xy 433.174464 -18.755419) (xy 433.228404 -18.763177)
			(xy 433.280691 -18.778532) (xy 433.330261 -18.801171) (xy 433.376105 -18.830635) (xy 433.417289 -18.866323)
			(xy 433.452975 -18.907508) (xy 433.482436 -18.953353) (xy 433.505074 -19.002924) (xy 433.520427 -19.055212)
			(xy 433.528182 -19.109152) (xy 433.528182 -19.163648) (xy 433.520427 -19.217588) (xy 433.505074 -19.269876)
			(xy 433.482436 -19.319447) (xy 433.452975 -19.365292) (xy 433.417289 -19.406477) (xy 433.376105 -19.442165)
			(xy 433.330261 -19.471629) (xy 433.280691 -19.494268) (xy 433.228404 -19.509623) (xy 433.174464 -19.517381)
			(xy 433.147216 -19.517868) (xy 432.283616 -19.517868) (xy 432.25636 -19.517486) (xy 432.202401 -19.50973)
			(xy 432.150096 -19.494374) (xy 432.100508 -19.47173) (xy 432.054648 -19.442259) (xy 432.01345 -19.406562)
			(xy 431.97775 -19.365364) (xy 431.948278 -19.319506) (xy 431.925632 -19.269919) (xy 431.910273 -19.217615)
			(xy 431.902515 -19.163656) (xy 427.940181 -19.163656) (xy 427.932427 -19.217588) (xy 427.917074 -19.269876)
			(xy 427.894436 -19.319447) (xy 427.864975 -19.365292) (xy 427.829289 -19.406477) (xy 427.788105 -19.442165)
			(xy 427.742261 -19.471629) (xy 427.692691 -19.494268) (xy 427.640404 -19.509623) (xy 427.586464 -19.517381)
			(xy 427.559216 -19.517868) (xy 426.695616 -19.517868) (xy 426.66836 -19.517486) (xy 426.614401 -19.50973)
			(xy 426.562096 -19.494374) (xy 426.512508 -19.47173) (xy 426.466648 -19.442259) (xy 426.42545 -19.406562)
			(xy 426.38975 -19.365364) (xy 426.360278 -19.319506) (xy 426.337632 -19.269919) (xy 426.322273 -19.217615)
			(xy 426.314515 -19.163656) (xy 422.31752 -19.163656) (xy 422.31752 -19.164374) (xy 422.309757 -19.218367)
			(xy 422.294388 -19.270706) (xy 422.271726 -19.320324) (xy 422.242234 -19.366212) (xy 422.20651 -19.407436)
			(xy 422.165284 -19.443155) (xy 422.119393 -19.472644) (xy 422.069772 -19.4953) (xy 422.017432 -19.510664)
			(xy 421.963438 -19.518423) (xy 421.936164 -19.518884) (xy 421.072564 -19.518884) (xy 421.045298 -19.518351)
			(xy 420.991321 -19.510586) (xy 420.938999 -19.495218) (xy 420.889396 -19.472561) (xy 420.843523 -19.443076)
			(xy 420.802312 -19.407363) (xy 420.766602 -19.366149) (xy 420.737121 -19.320272) (xy 420.714469 -19.270667)
			(xy 420.699107 -19.218343) (xy 420.691346 -19.164366) (xy 416.730102 -19.164366) (xy 416.722448 -19.217598)
			(xy 416.707093 -19.269892) (xy 416.684451 -19.319468) (xy 416.654984 -19.365317) (xy 416.619292 -19.406506)
			(xy 416.578101 -19.442196) (xy 416.532251 -19.471661) (xy 416.482673 -19.4943) (xy 416.430378 -19.509652)
			(xy 416.376431 -19.517406) (xy 416.34918 -19.517868) (xy 415.48558 -19.517868) (xy 415.458327 -19.517461)
			(xy 415.404376 -19.509701) (xy 415.352078 -19.494343) (xy 415.302498 -19.471698) (xy 415.256645 -19.442228)
			(xy 415.215453 -19.406533) (xy 415.17976 -19.365339) (xy 415.150292 -19.319485) (xy 415.12765 -19.269903)
			(xy 415.112295 -19.217605) (xy 415.104538 -19.163653) (xy 410.836405 -19.163653) (xy 410.828648 -19.2176)
			(xy 410.813291 -19.269895) (xy 410.790649 -19.319473) (xy 410.76118 -19.365323) (xy 410.725486 -19.406512)
			(xy 410.684294 -19.442202) (xy 410.638441 -19.471666) (xy 410.588862 -19.494304) (xy 410.536565 -19.509655)
			(xy 410.482616 -19.517407) (xy 410.455364 -19.517868) (xy 409.591764 -19.517868) (xy 409.564512 -19.51746)
			(xy 409.510562 -19.509698) (xy 409.458266 -19.494338) (xy 409.408688 -19.471693) (xy 409.362838 -19.442222)
			(xy 409.321647 -19.406527) (xy 409.285956 -19.365334) (xy 409.25649 -19.31948) (xy 409.233849 -19.2699)
			(xy 409.218494 -19.217603) (xy 409.210738 -19.163652) (xy 405.248405 -19.163652) (xy 405.240648 -19.2176)
			(xy 405.225291 -19.269895) (xy 405.202649 -19.319473) (xy 405.17318 -19.365323) (xy 405.137486 -19.406512)
			(xy 405.096294 -19.442202) (xy 405.050441 -19.471666) (xy 405.000862 -19.494304) (xy 404.948565 -19.509655)
			(xy 404.894616 -19.517407) (xy 404.867364 -19.517868) (xy 404.003764 -19.517868) (xy 403.976512 -19.51746)
			(xy 403.922562 -19.509698) (xy 403.870266 -19.494338) (xy 403.820688 -19.471693) (xy 403.774838 -19.442222)
			(xy 403.733647 -19.406527) (xy 403.697956 -19.365334) (xy 403.66849 -19.31948) (xy 403.645849 -19.2699)
			(xy 403.630494 -19.217603) (xy 403.622738 -19.163652) (xy 399.660405 -19.163652) (xy 399.652648 -19.2176)
			(xy 399.637291 -19.269895) (xy 399.614649 -19.319473) (xy 399.58518 -19.365323) (xy 399.549486 -19.406512)
			(xy 399.508294 -19.442202) (xy 399.462441 -19.471666) (xy 399.412862 -19.494304) (xy 399.360565 -19.509655)
			(xy 399.306616 -19.517407) (xy 399.279364 -19.517868) (xy 398.415764 -19.517868) (xy 398.388512 -19.51746)
			(xy 398.334562 -19.509698) (xy 398.282266 -19.494338) (xy 398.232688 -19.471693) (xy 398.186838 -19.442222)
			(xy 398.145647 -19.406527) (xy 398.109956 -19.365334) (xy 398.08049 -19.31948) (xy 398.057849 -19.2699)
			(xy 398.042494 -19.217603) (xy 398.034738 -19.163652) (xy 394.071598 -19.163652) (xy 394.071598 -19.164369)
			(xy 394.063837 -19.218351) (xy 394.048473 -19.27068) (xy 394.025819 -19.32029) (xy 393.996336 -19.366171)
			(xy 393.960624 -19.40739) (xy 393.91941 -19.443107) (xy 393.873532 -19.472596) (xy 393.823925 -19.495256)
			(xy 393.771598 -19.510627) (xy 393.717617 -19.518394) (xy 393.690348 -19.518884) (xy 392.826748 -19.518884)
			(xy 392.799476 -19.51838) (xy 392.745487 -19.510624) (xy 392.693152 -19.495262) (xy 392.643536 -19.472609)
			(xy 392.597649 -19.443124) (xy 392.556425 -19.407409) (xy 392.520704 -19.36619) (xy 392.491214 -19.320307)
			(xy 392.468554 -19.270693) (xy 392.453187 -19.21836) (xy 392.445424 -19.164372) (xy 259.309108 -19.164372)
			(xy 259.309108 -20.4061) (xy 368.50594 -20.4061) (xy 368.510005 -20.315592) (xy 368.522167 -20.225813)
			(xy 368.542328 -20.137486) (xy 368.570325 -20.051322) (xy 368.605934 -19.968014) (xy 368.648867 -19.888233)
			(xy 368.698779 -19.812623) (xy 368.755267 -19.741791) (xy 368.817878 -19.676308) (xy 368.886107 -19.616701)
			(xy 368.959405 -19.56345) (xy 369.037181 -19.516984) (xy 369.118809 -19.477677) (xy 369.203632 -19.445846)
			(xy 369.290966 -19.421746) (xy 369.38011 -19.405573) (xy 369.470345 -19.397455) (xy 369.515644 -19.396964)
			(xy 369.560233 -19.397442) (xy 369.649072 -19.405219) (xy 369.736895 -19.420711) (xy 369.823033 -19.443798)
			(xy 369.906831 -19.474305) (xy 369.987651 -19.512001) (xy 370.064878 -19.556597) (xy 370.137923 -19.607756)
			(xy 370.206232 -19.665086) (xy 370.269283 -19.728153) (xy 370.326597 -19.796475) (xy 370.377737 -19.869533)
			(xy 370.422315 -19.946771) (xy 370.459991 -20.0276) (xy 370.490478 -20.111405) (xy 370.513544 -20.197549)
			(xy 370.529013 -20.285376) (xy 370.536768 -20.374217) (xy 370.537232 -20.418806) (xy 370.536774 -20.462284)
			(xy 370.529196 -20.54891) (xy 370.514098 -20.634545) (xy 370.491595 -20.71854) (xy 370.485037 -20.73656)
			(xy 440.464956 -20.73656) (xy 440.465378 -20.698271) (xy 440.471981 -20.621977) (xy 440.485126 -20.546534)
			(xy 440.504715 -20.472503) (xy 440.51728 -20.436332) (xy 440.51995 -20.4279) (xy 440.519937 -20.410225)
			(xy 440.51728 -20.401788) (xy 440.50475 -20.365606) (xy 440.485173 -20.291575) (xy 440.472022 -20.216136)
			(xy 440.465394 -20.139848) (xy 440.464956 -20.10156) (xy 440.46549 -20.057765) (xy 440.474106 -19.9706)
			(xy 440.49125 -19.884704) (xy 440.516756 -19.80091) (xy 440.550377 -19.72003) (xy 440.57062 -19.68119)
			(xy 440.576064 -19.669733) (xy 440.576046 -19.644397) (xy 440.57062 -19.63293) (xy 440.550398 -19.594081)
			(xy 440.51679 -19.513198) (xy 440.491286 -19.429406) (xy 440.474133 -19.343514) (xy 440.465497 -19.256354)
			(xy 440.464956 -19.21256) (xy 440.465378 -19.174271) (xy 440.471981 -19.097977) (xy 440.485126 -19.022534)
			(xy 440.504715 -18.948503) (xy 440.51728 -18.912332) (xy 440.51995 -18.9039) (xy 440.519937 -18.886225)
			(xy 440.51728 -18.877788) (xy 440.50475 -18.841606) (xy 440.485173 -18.767575) (xy 440.472022 -18.692136)
			(xy 440.465394 -18.615848) (xy 440.464956 -18.57756) (xy 440.465414 -18.53645) (xy 440.473005 -18.45458)
			(xy 440.488119 -18.373761) (xy 440.510626 -18.294681) (xy 440.540334 -18.218015) (xy 440.576991 -18.144418)
			(xy 440.620282 -18.074518) (xy 440.66984 -18.008911) (xy 440.72524 -17.948157) (xy 440.78601 -17.892775)
			(xy 440.851631 -17.843237) (xy 440.921544 -17.799965) (xy 440.995152 -17.76333) (xy 441.071826 -17.733644)
			(xy 441.150912 -17.71116) (xy 441.231736 -17.69607) (xy 441.313608 -17.688502) (xy 441.354718 -17.688052)
			(xy 441.395668 -17.688478) (xy 441.477223 -17.695989) (xy 441.557742 -17.710965) (xy 441.636544 -17.733279)
			(xy 441.712961 -17.762742) (xy 441.786347 -17.799105) (xy 441.856079 -17.842059) (xy 441.921567 -17.891241)
			(xy 441.982258 -17.946234) (xy 442.010292 -17.976088) (xy 442.017449 -17.983101) (xy 442.035585 -17.991562)
			(xy 442.055576 -17.99248) (xy 442.065156 -17.98955) (xy 442.102033 -17.976445) (xy 442.177582 -17.955997)
			(xy 442.254637 -17.94227) (xy 442.3326 -17.935373) (xy 442.371734 -17.93494) (xy 442.412849 -17.93538)
			(xy 442.494727 -17.942971) (xy 442.575557 -17.958083) (xy 442.654646 -17.980589) (xy 442.731323 -18.010296)
			(xy 442.804931 -18.046951) (xy 442.874843 -18.090241) (xy 442.940462 -18.139797) (xy 443.001229 -18.195196)
			(xy 443.056626 -18.255966) (xy 443.106179 -18.321587) (xy 443.149467 -18.391501) (xy 443.186119 -18.46511)
			(xy 443.213248 -18.535142) (xy 451.165468 -18.535142) (xy 451.165468 -18.534888) (xy 451.166052 -18.49015)
			(xy 451.175063 -18.401129) (xy 451.192964 -18.313462) (xy 451.219572 -18.228034) (xy 451.236588 -18.186654)
			(xy 451.240131 -18.177057) (xy 451.240147 -18.15662) (xy 451.236588 -18.14703) (xy 451.219555 -18.105656)
			(xy 451.192939 -18.020228) (xy 451.175038 -17.932559) (xy 451.166032 -17.843535) (xy 451.165468 -17.798796)
			(xy 451.165468 -17.798542) (xy 451.165972 -17.756194) (xy 451.174023 -17.67188) (xy 451.190052 -17.588714)
			(xy 451.213913 -17.507447) (xy 451.245392 -17.428817) (xy 451.284203 -17.353536) (xy 451.329993 -17.282284)
			(xy 451.382349 -17.215708) (xy 451.440797 -17.15441) (xy 451.504807 -17.098945) (xy 451.573799 -17.049816)
			(xy 451.647149 -17.007467) (xy 451.724192 -16.972283) (xy 451.804231 -16.944581) (xy 451.88654 -16.924613)
			(xy 451.970375 -16.91256) (xy 452.054976 -16.90853) (xy 452.139577 -16.91256) (xy 452.223412 -16.924613)
			(xy 452.305721 -16.944581) (xy 452.38576 -16.972283) (xy 452.462803 -17.007467) (xy 452.536153 -17.049816)
			(xy 452.605145 -17.098945) (xy 452.669155 -17.15441) (xy 452.727603 -17.215708) (xy 452.779959 -17.282284)
			(xy 452.825749 -17.353536) (xy 452.86456 -17.428817) (xy 452.896039 -17.507447) (xy 452.9199 -17.588714)
			(xy 452.935929 -17.67188) (xy 452.94398 -17.756194) (xy 452.944484 -17.798542) (xy 452.944484 -17.798796)
			(xy 452.943898 -17.843534) (xy 452.934888 -17.932555) (xy 452.916988 -18.020222) (xy 452.890379 -18.10565)
			(xy 452.873364 -18.14703) (xy 452.869775 -18.156614) (xy 452.869791 -18.177063) (xy 452.873364 -18.186654)
			(xy 452.890389 -18.228031) (xy 452.917007 -18.313458) (xy 452.934911 -18.401126) (xy 452.943919 -18.490149)
			(xy 452.944484 -18.534888) (xy 452.944484 -18.535142) (xy 452.94398 -18.57749) (xy 452.935929 -18.661804)
			(xy 452.9199 -18.74497) (xy 452.896039 -18.826237) (xy 452.86456 -18.904867) (xy 452.825749 -18.980148)
			(xy 452.779959 -19.0514) (xy 452.727603 -19.117976) (xy 452.669155 -19.179274) (xy 452.605145 -19.234739)
			(xy 452.536153 -19.283868) (xy 452.462803 -19.326217) (xy 452.38576 -19.361401) (xy 452.305721 -19.389103)
			(xy 452.223412 -19.409071) (xy 452.139577 -19.421124) (xy 452.054976 -19.425155) (xy 451.970375 -19.421124)
			(xy 451.88654 -19.409071) (xy 451.804231 -19.389103) (xy 451.724192 -19.361401) (xy 451.647149 -19.326217)
			(xy 451.573799 -19.283868) (xy 451.504807 -19.234739) (xy 451.440797 -19.179274) (xy 451.382349 -19.117976)
			(xy 451.329993 -19.0514) (xy 451.284203 -18.980148) (xy 451.245392 -18.904867) (xy 451.213913 -18.826237)
			(xy 451.190052 -18.74497) (xy 451.174023 -18.661804) (xy 451.165972 -18.57749) (xy 451.165468 -18.535142)
			(xy 443.213248 -18.535142) (xy 443.215823 -18.541788) (xy 443.238325 -18.620878) (xy 443.253434 -18.701708)
			(xy 443.261021 -18.783587) (xy 443.261496 -18.824702) (xy 443.261095 -18.862992) (xy 443.254486 -18.939286)
			(xy 443.241336 -19.014729) (xy 443.221741 -19.088759) (xy 443.209172 -19.12493) (xy 443.206519 -19.133366)
			(xy 443.20652 -19.151037) (xy 443.209172 -19.159474) (xy 443.221718 -19.195651) (xy 443.24129 -19.269684)
			(xy 443.254437 -19.345124) (xy 443.261061 -19.421414) (xy 443.261496 -19.459702) (xy 443.260982 -19.503497)
			(xy 443.252361 -19.590663) (xy 443.235212 -19.676559) (xy 443.209701 -19.760353) (xy 443.176076 -19.841233)
			(xy 443.155832 -19.880072) (xy 443.15041 -19.891537) (xy 443.150411 -19.916866) (xy 443.155832 -19.928332)
			(xy 443.176073 -19.967172) (xy 443.209679 -20.048057) (xy 443.235179 -20.131851) (xy 443.252328 -20.217745)
			(xy 443.260958 -20.304908) (xy 443.261496 -20.348702) (xy 443.261095 -20.386992) (xy 443.254486 -20.463286)
			(xy 443.241336 -20.538729) (xy 443.221741 -20.612759) (xy 443.209172 -20.64893) (xy 443.206519 -20.657366)
			(xy 443.20652 -20.675037) (xy 443.209172 -20.683474) (xy 443.221718 -20.719651) (xy 443.24129 -20.793684)
			(xy 443.254437 -20.869124) (xy 443.261061 -20.945414) (xy 443.261496 -20.983702) (xy 443.260989 -21.024815)
			(xy 443.253402 -21.106691) (xy 443.238293 -21.187518) (xy 443.215791 -21.266605) (xy 443.186088 -21.343279)
			(xy 443.149437 -21.416886) (xy 443.106152 -21.486797) (xy 443.0566 -21.552416) (xy 443.001205 -21.613183)
			(xy 442.94044 -21.66858) (xy 442.874823 -21.718133) (xy 442.804914 -21.761422) (xy 442.731309 -21.798075)
			(xy 442.654636 -21.827781) (xy 442.575549 -21.850286) (xy 442.494723 -21.865398) (xy 442.412847 -21.872988)
			(xy 442.371734 -21.873464) (xy 442.330778 -21.872996) (xy 442.249213 -21.865468) (xy 442.168686 -21.850472)
			(xy 442.089879 -21.828136) (xy 442.013459 -21.798648) (xy 441.940074 -21.762259) (xy 441.870346 -21.719277)
			(xy 441.804865 -21.670066) (xy 441.744186 -21.615042) (xy 441.71616 -21.585174) (xy 441.709037 -21.578124)
			(xy 441.690882 -21.569676) (xy 441.670879 -21.568774) (xy 441.661296 -21.571712) (xy 441.624502 -21.584749)
			(xy 441.549137 -21.605106) (xy 441.472276 -21.618771) (xy 441.394513 -21.625637) (xy 441.35548 -21.626068)
			(xy 441.354718 -21.626068) (xy 441.313612 -21.62557) (xy 441.23175 -21.617988) (xy 441.150936 -21.602885)
			(xy 441.07186 -21.580392) (xy 440.995197 -21.5507) (xy 440.9216 -21.514062) (xy 440.851696 -21.470791)
			(xy 440.786082 -21.421255) (xy 440.725318 -21.365878) (xy 440.669922 -21.305132) (xy 440.620366 -21.239533)
			(xy 440.577073 -21.169643) (xy 440.540412 -21.096058) (xy 440.510696 -21.019403) (xy 440.488178 -20.940335)
			(xy 440.473051 -20.859526) (xy 440.465443 -20.777666) (xy 440.464956 -20.73656) (xy 370.485037 -20.73656)
			(xy 370.461858 -20.800254) (xy 370.425114 -20.879065) (xy 370.381641 -20.954375) (xy 370.331772 -21.02561)
			(xy 370.275884 -21.092228) (xy 370.214404 -21.153723) (xy 370.147799 -21.209627) (xy 370.076576 -21.259513)
			(xy 370.001276 -21.303004) (xy 369.922473 -21.339767) (xy 369.840767 -21.369523) (xy 369.756778 -21.392046)
			(xy 369.671146 -21.407165) (xy 369.584522 -21.414763) (xy 369.541044 -21.415248) (xy 369.515644 -21.415248)
			(xy 369.470345 -21.414745) (xy 369.38011 -21.406627) (xy 369.290966 -21.390454) (xy 369.203632 -21.366354)
			(xy 369.118809 -21.334523) (xy 369.037181 -21.295216) (xy 368.959405 -21.24875) (xy 368.886107 -21.195499)
			(xy 368.817878 -21.135892) (xy 368.755267 -21.070409) (xy 368.698779 -20.999577) (xy 368.648867 -20.923967)
			(xy 368.605934 -20.844186) (xy 368.570325 -20.760878) (xy 368.542328 -20.674714) (xy 368.522167 -20.586387)
			(xy 368.510005 -20.496608) (xy 368.50594 -20.4061) (xy 259.309108 -20.4061) (xy 259.309108 -25.982422)
			(xy 440.239912 -25.982422) (xy 440.240419 -25.939461) (xy 440.248702 -25.85394) (xy 440.265193 -25.769616)
			(xy 440.289738 -25.687275) (xy 440.322109 -25.607684) (xy 440.362003 -25.531586) (xy 440.40905 -25.459689)
			(xy 440.46281 -25.392664) (xy 440.522782 -25.331135) (xy 440.588408 -25.275676) (xy 440.659076 -25.226803)
			(xy 440.69635 -25.205436) (xy 440.704332 -25.200469) (xy 440.716316 -25.186006) (xy 440.719718 -25.177242)
			(xy 440.733823 -25.137039) (xy 440.768699 -25.059297) (xy 440.810847 -24.985247) (xy 440.859883 -24.915565)
			(xy 440.915357 -24.850891) (xy 440.97676 -24.791817) (xy 441.043529 -24.738885) (xy 441.115054 -24.692579)
			(xy 441.190679 -24.653323) (xy 441.26971 -24.621478) (xy 441.351424 -24.597336) (xy 441.435072 -24.581116)
			(xy 441.519887 -24.572969) (xy 441.56249 -24.572468) (xy 441.562998 -24.572468) (xy 441.606762 -24.572982)
			(xy 441.693869 -24.581557) (xy 441.77971 -24.598653) (xy 441.863455 -24.624106) (xy 441.944293 -24.657667)
			(xy 441.983114 -24.677878) (xy 441.994467 -24.683205) (xy 442.019513 -24.683205) (xy 442.030866 -24.677878)
			(xy 442.069745 -24.657673) (xy 442.150684 -24.6241) (xy 442.23453 -24.598641) (xy 442.320472 -24.581544)
			(xy 442.407677 -24.572973) (xy 442.45149 -24.572468) (xy 442.495305 -24.572971) (xy 442.582516 -24.581515)
			(xy 442.668462 -24.5986) (xy 442.752311 -24.62406) (xy 442.833246 -24.657648) (xy 442.872114 -24.677878)
			(xy 442.883467 -24.683205) (xy 442.908513 -24.683205) (xy 442.919866 -24.677878) (xy 442.959061 -24.657499)
			(xy 443.040701 -24.623735) (xy 443.125286 -24.598229) (xy 443.211982 -24.581233) (xy 443.255908 -24.576532)
			(xy 443.266358 -24.575008) (xy 443.284755 -24.564681) (xy 443.297434 -24.547819) (xy 443.300358 -24.53767)
			(xy 443.310609 -24.496358) (xy 443.337964 -24.415751) (xy 443.372893 -24.338124) (xy 443.415077 -24.264189)
			(xy 443.464129 -24.19462) (xy 443.519603 -24.130055) (xy 443.580989 -24.071084) (xy 443.647727 -24.018245)
			(xy 443.719207 -23.972023) (xy 443.794775 -23.932839) (xy 443.87374 -23.901052) (xy 443.955381 -23.876952)
			(xy 444.038949 -23.86076) (xy 444.123683 -23.852625) (xy 444.166244 -23.852124) (xy 444.207348 -23.852525)
			(xy 444.289205 -23.860114) (xy 444.370013 -23.875224) (xy 444.449082 -23.897725) (xy 444.525738 -23.927425)
			(xy 444.599326 -23.964072) (xy 444.669219 -24.007352) (xy 444.734821 -24.056897) (xy 444.795571 -24.112283)
			(xy 444.850952 -24.173038) (xy 444.900491 -24.238644) (xy 444.943765 -24.30854) (xy 444.980405 -24.382132)
			(xy 445.0101 -24.45879) (xy 445.032594 -24.537861) (xy 445.047697 -24.61867) (xy 445.055279 -24.700528)
			(xy 445.055752 -24.741632) (xy 445.055238 -24.782654) (xy 445.04768 -24.864348) (xy 445.032631 -24.944999)
			(xy 445.01022 -25.023921) (xy 444.980635 -25.100445) (xy 444.94413 -25.173919) (xy 444.901014 -25.243719)
			(xy 444.851653 -25.309252) (xy 444.796467 -25.369961) (xy 444.735925 -25.425331) (xy 444.670542 -25.47489)
			(xy 444.600873 -25.518217) (xy 444.52751 -25.554945) (xy 444.451076 -25.584761) (xy 444.372222 -25.607412)
			(xy 444.291617 -25.622705) (xy 444.250826 -25.627076) (xy 444.240379 -25.628618) (xy 444.221981 -25.638935)
			(xy 444.2093 -25.655791) (xy 444.206376 -25.665938) (xy 444.196473 -25.705794) (xy 444.170375 -25.783666)
			(xy 444.137208 -25.8588) (xy 444.097254 -25.930555) (xy 444.050854 -25.998321) (xy 443.998403 -26.061519)
			(xy 443.940348 -26.119612) (xy 443.877184 -26.172104) (xy 443.809448 -26.218548) (xy 443.773814 -26.238962)
			(xy 443.765845 -26.243946) (xy 443.753852 -26.258396) (xy 443.750446 -26.267156) (xy 443.736369 -26.307378)
			(xy 443.701515 -26.385148) (xy 443.659384 -26.459228) (xy 443.61036 -26.528939) (xy 443.554893 -26.593641)
			(xy 443.493492 -26.652741) (xy 443.42672 -26.705698) (xy 443.355189 -26.752025) (xy 443.279554 -26.791298)
			(xy 443.200511 -26.823158) (xy 443.118782 -26.847311) (xy 443.035118 -26.863536) (xy 442.950285 -26.871685)
			(xy 442.907674 -26.872184) (xy 442.863879 -26.871639) (xy 442.776715 -26.863025) (xy 442.690819 -26.845883)
			(xy 442.607025 -26.82038) (xy 442.526144 -26.786761) (xy 442.487304 -26.76652) (xy 442.475838 -26.761102)
			(xy 442.45051 -26.761102) (xy 442.439044 -26.76652) (xy 442.400209 -26.786769) (xy 442.319322 -26.820374)
			(xy 442.235526 -26.845873) (xy 442.149632 -26.863019) (xy 442.062468 -26.871647) (xy 442.018674 -26.872184)
			(xy 441.974879 -26.871639) (xy 441.887715 -26.863025) (xy 441.801819 -26.845883) (xy 441.718025 -26.82038)
			(xy 441.637144 -26.786761) (xy 441.598304 -26.76652) (xy 441.586838 -26.761102) (xy 441.56151 -26.761102)
			(xy 441.550044 -26.76652) (xy 441.511209 -26.786769) (xy 441.430322 -26.820374) (xy 441.346526 -26.845873)
			(xy 441.260632 -26.863019) (xy 441.173468 -26.871647) (xy 441.129674 -26.872184) (xy 441.08856 -26.871712)
			(xy 441.006683 -26.864123) (xy 440.925855 -26.849012) (xy 440.846767 -26.826507) (xy 440.770092 -26.796802)
			(xy 440.696485 -26.760149) (xy 440.626574 -26.71686) (xy 440.560955 -26.667306) (xy 440.500188 -26.61191)
			(xy 440.444791 -26.551142) (xy 440.395237 -26.485523) (xy 440.351949 -26.415612) (xy 440.315297 -26.342004)
			(xy 440.285592 -26.265329) (xy 440.263088 -26.186241) (xy 440.247977 -26.105413) (xy 440.240388 -26.023536)
			(xy 440.239912 -25.982422) (xy 259.309108 -25.982422) (xy 259.309108 -32.117846) (xy 455.218281 -32.117846)
			(xy 455.218281 -31.988706) (xy 455.226231 -31.859811) (xy 455.242101 -31.731651) (xy 455.26583 -31.60471)
			(xy 455.297329 -31.479471) (xy 455.336478 -31.356408) (xy 455.383129 -31.235989) (xy 455.437104 -31.11867)
			(xy 455.498199 -31.004896) (xy 455.566182 -30.895099) (xy 455.640796 -30.789696) (xy 455.721757 -30.689086)
			(xy 455.808757 -30.593651) (xy 455.901468 -30.503752) (xy 455.999538 -30.419731) (xy 456.102593 -30.341907)
			(xy 456.210244 -30.270575) (xy 456.322083 -30.206005) (xy 456.437684 -30.148443) (xy 456.556609 -30.098106)
			(xy 456.678408 -30.055186) (xy 456.802618 -30.019845) (xy 456.928767 -29.992218) (xy 457.056379 -29.972409)
			(xy 457.184968 -29.960493) (xy 457.314046 -29.956517) (xy 457.443124 -29.960493) (xy 457.571713 -29.972409)
			(xy 457.699325 -29.992218) (xy 457.825474 -30.019845) (xy 457.949684 -30.055186) (xy 458.071483 -30.098106)
			(xy 458.190408 -30.148443) (xy 458.306009 -30.206005) (xy 458.417848 -30.270575) (xy 458.525499 -30.341907)
			(xy 458.628554 -30.419731) (xy 458.726624 -30.503752) (xy 458.819335 -30.593651) (xy 458.906335 -30.689086)
			(xy 458.987296 -30.789696) (xy 459.06191 -30.895099) (xy 459.129893 -31.004896) (xy 459.190988 -31.11867)
			(xy 459.244963 -31.235989) (xy 459.291614 -31.356408) (xy 459.330763 -31.479471) (xy 459.362262 -31.60471)
			(xy 459.385991 -31.731651) (xy 459.401861 -31.859811) (xy 459.409811 -31.988706) (xy 459.410308 -32.053276)
			(xy 459.409811 -32.117846) (xy 459.401861 -32.246741) (xy 459.385991 -32.374901) (xy 459.362262 -32.501842)
			(xy 459.330763 -32.627081) (xy 459.291614 -32.750144) (xy 459.244963 -32.870563) (xy 459.190988 -32.987882)
			(xy 459.129893 -33.101656) (xy 459.06191 -33.211453) (xy 458.987296 -33.316856) (xy 458.906335 -33.417466)
			(xy 458.819335 -33.512901) (xy 458.726624 -33.6028) (xy 458.628554 -33.686821) (xy 458.525499 -33.764645)
			(xy 458.417848 -33.835977) (xy 458.307206 -33.899856) (xy 461.798924 -33.899856) (xy 461.798924 -32.299656)
			(xy 461.799422 -32.222373) (xy 461.807378 -32.068013) (xy 461.823271 -31.914267) (xy 461.847057 -31.761543)
			(xy 461.878674 -31.610247) (xy 461.918037 -31.460778) (xy 461.965042 -31.313534) (xy 462.019566 -31.168904)
			(xy 462.081462 -31.027274) (xy 462.150567 -30.889017) (xy 462.226698 -30.754502) (xy 462.309652 -30.624083)
			(xy 462.399211 -30.498108) (xy 462.495135 -30.376911) (xy 462.597172 -30.260812) (xy 462.705049 -30.15012)
			(xy 462.818482 -30.045128) (xy 462.93717 -29.946115) (xy 463.060797 -29.853342) (xy 463.189036 -29.767057)
			(xy 463.321547 -29.687488) (xy 463.457979 -29.614846) (xy 463.597969 -29.549324) (xy 463.741146 -29.491095)
			(xy 463.887131 -29.440314) (xy 464.035537 -29.397115) (xy 464.185969 -29.361613) (xy 464.33803 -29.333903)
			(xy 464.491316 -29.314057) (xy 464.64542 -29.302128) (xy 464.799934 -29.298149) (xy 464.954448 -29.302128)
			(xy 465.108552 -29.314057) (xy 465.261838 -29.333903) (xy 465.413899 -29.361613) (xy 465.564331 -29.397115)
			(xy 465.712737 -29.440314) (xy 465.858722 -29.491095) (xy 466.001899 -29.549324) (xy 466.141889 -29.614846)
			(xy 466.278321 -29.687488) (xy 466.410832 -29.767057) (xy 466.539071 -29.853342) (xy 466.662698 -29.946115)
			(xy 466.781386 -30.045128) (xy 466.894819 -30.15012) (xy 467.002696 -30.260812) (xy 467.104733 -30.376911)
			(xy 467.200657 -30.498108) (xy 467.290216 -30.624083) (xy 467.37317 -30.754502) (xy 467.449301 -30.889017)
			(xy 467.518406 -31.027274) (xy 467.580302 -31.168904) (xy 467.634826 -31.313534) (xy 467.681831 -31.460778)
			(xy 467.721194 -31.610247) (xy 467.752811 -31.761543) (xy 467.776597 -31.914267) (xy 467.79249 -32.068013)
			(xy 467.800446 -32.222373) (xy 467.800944 -32.299656) (xy 467.800944 -33.899856) (xy 467.800446 -33.977139)
			(xy 467.79249 -34.131499) (xy 467.776597 -34.285245) (xy 467.752811 -34.437969) (xy 467.721194 -34.589265)
			(xy 467.681831 -34.738734) (xy 467.634826 -34.885978) (xy 467.580302 -35.030608) (xy 467.518406 -35.172238)
			(xy 467.449301 -35.310495) (xy 467.37317 -35.44501) (xy 467.290216 -35.575429) (xy 467.200657 -35.701404)
			(xy 467.104733 -35.822601) (xy 467.002696 -35.9387) (xy 466.894819 -36.049392) (xy 466.781386 -36.154384)
			(xy 466.662698 -36.253397) (xy 466.539071 -36.34617) (xy 466.410832 -36.432455) (xy 466.278321 -36.512024)
			(xy 466.141889 -36.584666) (xy 466.001899 -36.650188) (xy 465.858722 -36.708417) (xy 465.712737 -36.759198)
			(xy 465.564331 -36.802397) (xy 465.413899 -36.837899) (xy 465.261838 -36.865609) (xy 465.108552 -36.885455)
			(xy 464.954448 -36.897384) (xy 464.799934 -36.901364) (xy 464.64542 -36.897384) (xy 464.491316 -36.885455)
			(xy 464.33803 -36.865609) (xy 464.185969 -36.837899) (xy 464.035537 -36.802397) (xy 463.887131 -36.759198)
			(xy 463.741146 -36.708417) (xy 463.597969 -36.650188) (xy 463.457979 -36.584666) (xy 463.321547 -36.512024)
			(xy 463.189036 -36.432455) (xy 463.060797 -36.34617) (xy 462.93717 -36.253397) (xy 462.818482 -36.154384)
			(xy 462.705049 -36.049392) (xy 462.597172 -35.9387) (xy 462.495135 -35.822601) (xy 462.399211 -35.701404)
			(xy 462.309652 -35.575429) (xy 462.226698 -35.44501) (xy 462.150567 -35.310495) (xy 462.081462 -35.172238)
			(xy 462.019566 -35.030608) (xy 461.965042 -34.885978) (xy 461.918037 -34.738734) (xy 461.878674 -34.589265)
			(xy 461.847057 -34.437969) (xy 461.823271 -34.285245) (xy 461.807378 -34.131499) (xy 461.799422 -33.977139)
			(xy 461.798924 -33.899856) (xy 458.307206 -33.899856) (xy 458.306009 -33.900547) (xy 458.190408 -33.958109)
			(xy 458.071483 -34.008446) (xy 457.949684 -34.051366) (xy 457.825474 -34.086707) (xy 457.699325 -34.114334)
			(xy 457.571713 -34.134143) (xy 457.443124 -34.146059) (xy 457.314046 -34.150036) (xy 457.184968 -34.146059)
			(xy 457.056379 -34.134143) (xy 456.928767 -34.114334) (xy 456.802618 -34.086707) (xy 456.678408 -34.051366)
			(xy 456.556609 -34.008446) (xy 456.437684 -33.958109) (xy 456.322083 -33.900547) (xy 456.210244 -33.835977)
			(xy 456.102593 -33.764645) (xy 455.999538 -33.686821) (xy 455.901468 -33.6028) (xy 455.808757 -33.512901)
			(xy 455.721757 -33.417466) (xy 455.640796 -33.316856) (xy 455.566182 -33.211453) (xy 455.498199 -33.101656)
			(xy 455.437104 -32.987882) (xy 455.383129 -32.870563) (xy 455.336478 -32.750144) (xy 455.297329 -32.627081)
			(xy 455.26583 -32.501842) (xy 455.242101 -32.374901) (xy 455.226231 -32.246741) (xy 455.218281 -32.117846)
			(xy 259.309108 -32.117846) (xy 259.309108 -34.120074) (xy 259.308624 -34.190457) (xy 259.300733 -34.331001)
			(xy 259.284973 -34.470882) (xy 259.261395 -34.609659) (xy 259.230073 -34.746896) (xy 259.191105 -34.882161)
			(xy 259.144614 -35.015028) (xy 259.090747 -35.145079) (xy 259.029671 -35.271905) (xy 258.961581 -35.395107)
			(xy 258.88669 -35.514297) (xy 258.805233 -35.629101) (xy 258.717468 -35.739156) (xy 258.62367 -35.844118)
			(xy 258.524134 -35.943655) (xy 258.419173 -36.037454) (xy 258.309118 -36.12522) (xy 258.194315 -36.206678)
			(xy 258.075126 -36.28157) (xy 257.951924 -36.349661) (xy 257.825099 -36.410738) (xy 257.695048 -36.464606)
			(xy 257.562182 -36.511099) (xy 257.426917 -36.550068) (xy 257.289681 -36.581391) (xy 257.150904 -36.60497)
			(xy 257.011023 -36.620731) (xy 256.870479 -36.628623) (xy 256.800096 -36.629086) (xy 225.300032 -36.629086)
			(xy 225.229649 -36.628602) (xy 225.089105 -36.620711) (xy 224.949224 -36.604952) (xy 224.810447 -36.581374)
			(xy 224.673211 -36.550052) (xy 224.537946 -36.511084) (xy 224.40508 -36.464594) (xy 224.275029 -36.410726)
			(xy 224.148203 -36.349651) (xy 224.025001 -36.28156) (xy 223.905811 -36.206669) (xy 223.791008 -36.125213)
			(xy 223.680953 -36.037447) (xy 223.575992 -35.943648) (xy 223.476456 -35.844112) (xy 223.382657 -35.739152)
			(xy 223.294891 -35.629097) (xy 223.213434 -35.514294) (xy 223.138543 -35.395104) (xy 223.070452 -35.271902)
			(xy 223.009377 -35.145077) (xy 222.955509 -35.015026) (xy 222.909017 -34.882159) (xy 222.870049 -34.746895)
			(xy 222.838727 -34.609659) (xy 222.815149 -34.470882) (xy 222.799389 -34.331001) (xy 222.791498 -34.190457)
			(xy 222.79102 -34.120074) (xy 222.79102 -13.780008) (xy 222.790499 -13.724238) (xy 222.782164 -13.613011)
			(xy 222.765541 -13.502717) (xy 222.740722 -13.393974) (xy 222.707846 -13.287389) (xy 222.667097 -13.183559)
			(xy 222.618703 -13.083065) (xy 222.562935 -12.986469) (xy 222.500103 -12.894309) (xy 222.430561 -12.807103)
			(xy 222.354696 -12.725338) (xy 222.272933 -12.64947) (xy 222.185729 -12.579925) (xy 222.093572 -12.517091)
			(xy 221.996977 -12.461319) (xy 221.896485 -12.412922) (xy 221.792656 -12.37217) (xy 221.686073 -12.339291)
			(xy 221.57733 -12.314468) (xy 221.467037 -12.297841) (xy 221.35581 -12.289503) (xy 221.30004 -12.289028)
			(xy 196.701918 -12.289028) (xy 196.631535 -12.288544) (xy 196.49099 -12.280652) (xy 196.35111 -12.264892)
			(xy 196.212332 -12.241314) (xy 196.075095 -12.209992) (xy 195.939831 -12.171024) (xy 195.806964 -12.124532)
			(xy 195.676913 -12.070665) (xy 195.550086 -12.009589) (xy 195.426884 -11.941499) (xy 195.307694 -11.866608)
			(xy 195.19289 -11.785152) (xy 195.082834 -11.697386) (xy 194.977873 -11.603588) (xy 194.878335 -11.504052)
			(xy 194.784536 -11.399092) (xy 194.696769 -11.289037) (xy 194.615311 -11.174234) (xy 194.540418 -11.055045)
			(xy 194.472326 -10.931844) (xy 194.411249 -10.805018) (xy 194.35738 -10.674968) (xy 194.310887 -10.542102)
			(xy 194.271917 -10.406837) (xy 194.240593 -10.269601) (xy 194.217013 -10.130824) (xy 194.201251 -9.990943)
			(xy 194.193357 -9.850399) (xy 194.192906 -9.780016) (xy 194.192906 -5.839714) (xy 194.192489 -5.82969)
			(xy 194.184822 -5.811168) (xy 194.170649 -5.79699) (xy 194.152129 -5.789315) (xy 194.142106 -5.788914)
			(xy 126.661926 -5.788914) (xy 126.651902 -5.789329) (xy 126.633379 -5.796995) (xy 126.619202 -5.811169)
			(xy 126.611531 -5.82969) (xy 126.611126 -5.839714) (xy 126.611126 -9.780016) (xy 126.610632 -9.850398)
			(xy 126.602738 -9.990941) (xy 126.586977 -10.13082) (xy 126.563397 -10.269595) (xy 126.532074 -10.40683)
			(xy 126.51969 -10.449814) (xy 127.350019 -10.449814) (xy 127.354025 -10.361883) (xy 127.366011 -10.27468)
			(xy 127.385876 -10.188928) (xy 127.413458 -10.105338) (xy 127.448526 -10.024603) (xy 127.490791 -9.947391)
			(xy 127.539902 -9.874342) (xy 127.595452 -9.806062) (xy 127.656981 -9.743116) (xy 127.723979 -9.686027)
			(xy 127.79589 -9.635266) (xy 127.87212 -9.591254) (xy 127.952036 -9.554357) (xy 128.034977 -9.52488)
			(xy 128.120254 -9.503068) (xy 128.207161 -9.4891) (xy 128.294979 -9.483093) (xy 128.382978 -9.485097)
			(xy 128.470431 -9.495094) (xy 128.556613 -9.513003) (xy 128.640809 -9.538675) (xy 128.722322 -9.571896)
			(xy 128.800476 -9.612392) (xy 128.874623 -9.659827) (xy 128.94415 -9.713809) (xy 129.008481 -9.773889)
			(xy 129.067081 -9.83957) (xy 129.119465 -9.910308) (xy 129.165201 -9.985516) (xy 129.203907 -10.064572)
			(xy 129.235265 -10.146819) (xy 129.259013 -10.231578) (xy 129.26619 -10.270552) (xy 131.639267 -10.270552)
			(xy 131.639267 -10.216048) (xy 131.647024 -10.162097) (xy 131.66238 -10.1098) (xy 131.685023 -10.060221)
			(xy 131.714491 -10.014369) (xy 131.750185 -9.973177) (xy 131.791377 -9.937485) (xy 131.83723 -9.908018)
			(xy 131.88681 -9.885377) (xy 131.939107 -9.870022) (xy 131.993058 -9.862267) (xy 132.02031 -9.861804)
			(xy 132.88391 -9.861804) (xy 132.911162 -9.862266) (xy 132.96511 -9.870024) (xy 133.017405 -9.885381)
			(xy 133.066983 -9.908023) (xy 133.112833 -9.937491) (xy 133.154024 -9.973183) (xy 133.189715 -10.014375)
			(xy 133.219181 -10.060226) (xy 133.241823 -10.109804) (xy 133.257178 -10.1621) (xy 133.264934 -10.216048)
			(xy 133.264934 -10.270552) (xy 133.257178 -10.3245) (xy 133.241823 -10.376796) (xy 133.219181 -10.426374)
			(xy 133.189715 -10.472225) (xy 133.154024 -10.513417) (xy 133.112833 -10.549109) (xy 133.066983 -10.578577)
			(xy 133.017405 -10.601219) (xy 132.96511 -10.616576) (xy 132.911162 -10.624334) (xy 132.88391 -10.62482)
			(xy 132.02031 -10.62482) (xy 131.993058 -10.624333) (xy 131.939107 -10.616578) (xy 131.88681 -10.601223)
			(xy 131.83723 -10.578582) (xy 131.791377 -10.549115) (xy 131.750185 -10.513423) (xy 131.714491 -10.472231)
			(xy 131.685023 -10.426379) (xy 131.66238 -10.3768) (xy 131.647024 -10.324503) (xy 131.639267 -10.270552)
			(xy 129.26619 -10.270552) (xy 129.274955 -10.318145) (xy 129.282959 -10.405803) (xy 129.28346 -10.449814)
			(xy 129.282959 -10.493825) (xy 129.274955 -10.581483) (xy 129.259013 -10.66805) (xy 129.235265 -10.752809)
			(xy 129.212257 -10.813156) (xy 169.954611 -10.813156) (xy 169.954611 -10.758644) (xy 169.962369 -10.704687)
			(xy 169.977727 -10.652382) (xy 170.000372 -10.602796) (xy 170.029844 -10.556938) (xy 170.065542 -10.51574)
			(xy 170.106739 -10.480043) (xy 170.152598 -10.450571) (xy 170.202184 -10.427926) (xy 170.254488 -10.412568)
			(xy 170.308446 -10.404811) (xy 170.335702 -10.404348) (xy 171.199302 -10.404348) (xy 171.22655 -10.404922)
			(xy 171.280491 -10.412678) (xy 171.33278 -10.428032) (xy 171.382351 -10.45067) (xy 171.428196 -10.480133)
			(xy 171.469381 -10.515821) (xy 171.505068 -10.557006) (xy 171.534531 -10.602851) (xy 171.557169 -10.652422)
			(xy 171.572522 -10.704711) (xy 171.580278 -10.758652) (xy 171.580278 -10.813148) (xy 171.572522 -10.867089)
			(xy 171.557169 -10.919378) (xy 171.534531 -10.968949) (xy 171.505068 -11.014794) (xy 171.469381 -11.055979)
			(xy 171.428196 -11.091667) (xy 171.382351 -11.12113) (xy 171.33278 -11.143768) (xy 171.280491 -11.159122)
			(xy 171.22655 -11.166878) (xy 171.199302 -11.167364) (xy 170.335702 -11.167364) (xy 170.308446 -11.166989)
			(xy 170.254488 -11.159232) (xy 170.202184 -11.143874) (xy 170.152598 -11.121229) (xy 170.106739 -11.091757)
			(xy 170.065542 -11.05606) (xy 170.029844 -11.014862) (xy 170.000372 -10.969004) (xy 169.977727 -10.919418)
			(xy 169.962369 -10.867113) (xy 169.954611 -10.813156) (xy 129.212257 -10.813156) (xy 129.203907 -10.835056)
			(xy 129.165201 -10.914112) (xy 129.119465 -10.98932) (xy 129.067081 -11.060058) (xy 129.008481 -11.125739)
			(xy 128.94415 -11.185819) (xy 128.874623 -11.239801) (xy 128.800476 -11.287236) (xy 128.722322 -11.327732)
			(xy 128.640809 -11.360953) (xy 128.556613 -11.386625) (xy 128.470431 -11.404534) (xy 128.382978 -11.414531)
			(xy 128.294979 -11.416535) (xy 128.207161 -11.410528) (xy 128.120254 -11.39656) (xy 128.034977 -11.374748)
			(xy 127.952036 -11.345271) (xy 127.87212 -11.308374) (xy 127.79589 -11.264362) (xy 127.723979 -11.213601)
			(xy 127.656981 -11.156512) (xy 127.595452 -11.093566) (xy 127.539902 -11.025286) (xy 127.490791 -10.952237)
			(xy 127.448526 -10.875025) (xy 127.413458 -10.79429) (xy 127.385876 -10.7107) (xy 127.366011 -10.624948)
			(xy 127.354025 -10.537745) (xy 127.350019 -10.449814) (xy 126.51969 -10.449814) (xy 126.493105 -10.542092)
			(xy 126.446613 -10.674957) (xy 126.392744 -10.805006) (xy 126.331668 -10.93183) (xy 126.263578 -11.05503)
			(xy 126.188687 -11.174218) (xy 126.10723 -11.28902) (xy 126.019465 -11.399074) (xy 125.925667 -11.504033)
			(xy 125.826132 -11.603569) (xy 125.721172 -11.697366) (xy 125.611118 -11.785131) (xy 125.496317 -11.866588)
			(xy 125.495706 -11.866972) (xy 129.833804 -11.866972) (xy 129.833804 -11.812428) (xy 129.841567 -11.758438)
			(xy 129.856934 -11.706103) (xy 129.879594 -11.656488) (xy 129.909085 -11.610603) (xy 129.944805 -11.569383)
			(xy 129.986029 -11.533665) (xy 130.031916 -11.504179) (xy 130.081533 -11.481523) (xy 130.13387 -11.46616)
			(xy 130.18786 -11.458401) (xy 130.215132 -11.45794) (xy 131.078732 -11.45794) (xy 131.106 -11.458425)
			(xy 131.15998 -11.46619) (xy 131.212306 -11.481558) (xy 131.261913 -11.504216) (xy 131.30779 -11.533703)
			(xy 131.349004 -11.569419) (xy 131.384716 -11.610636) (xy 131.414199 -11.656515) (xy 131.436853 -11.706124)
			(xy 131.452217 -11.758451) (xy 131.459978 -11.812432) (xy 131.459978 -11.866968) (xy 131.452217 -11.920949)
			(xy 131.436853 -11.973276) (xy 131.432747 -11.982267) (xy 135.233942 -11.982267) (xy 135.233942 -11.927733)
			(xy 135.241703 -11.873755) (xy 135.257066 -11.82143) (xy 135.279719 -11.771824) (xy 135.309201 -11.725946)
			(xy 135.344912 -11.684731) (xy 135.386124 -11.649018) (xy 135.431999 -11.619533) (xy 135.481603 -11.596876)
			(xy 135.533927 -11.581509) (xy 135.587905 -11.573744) (xy 135.615172 -11.573256) (xy 136.478772 -11.573256)
			(xy 136.506046 -11.573682) (xy 136.560038 -11.581441) (xy 136.612377 -11.596805) (xy 136.661996 -11.619462)
			(xy 136.707885 -11.648951) (xy 136.74911 -11.68467) (xy 136.784832 -11.725893) (xy 136.814324 -11.77178)
			(xy 136.836985 -11.821397) (xy 136.852353 -11.873735) (xy 136.860116 -11.927726) (xy 136.860116 -11.982274)
			(xy 136.852353 -12.036265) (xy 136.836985 -12.088603) (xy 136.814324 -12.13822) (xy 136.784832 -12.184107)
			(xy 136.74911 -12.22533) (xy 136.707885 -12.261049) (xy 136.661996 -12.290538) (xy 136.612377 -12.313195)
			(xy 136.560038 -12.328559) (xy 136.506046 -12.336318) (xy 136.478772 -12.33678) (xy 135.615172 -12.33678)
			(xy 135.587905 -12.336256) (xy 135.533927 -12.328491) (xy 135.481603 -12.313124) (xy 135.431999 -12.290467)
			(xy 135.386124 -12.260982) (xy 135.344912 -12.225269) (xy 135.309201 -12.184054) (xy 135.279719 -12.138176)
			(xy 135.257066 -12.08857) (xy 135.241703 -12.036245) (xy 135.233942 -11.982267) (xy 131.432747 -11.982267)
			(xy 131.414199 -12.022885) (xy 131.384716 -12.068764) (xy 131.349004 -12.109981) (xy 131.30779 -12.145697)
			(xy 131.261913 -12.175184) (xy 131.212306 -12.197842) (xy 131.15998 -12.21321) (xy 131.106 -12.220975)
			(xy 131.078732 -12.221464) (xy 130.215132 -12.221464) (xy 130.18786 -12.220999) (xy 130.13387 -12.21324)
			(xy 130.081533 -12.197877) (xy 130.031916 -12.175221) (xy 129.986029 -12.145735) (xy 129.944805 -12.110017)
			(xy 129.909085 -12.068797) (xy 129.879594 -12.022912) (xy 129.856934 -11.973297) (xy 129.841567 -11.920962)
			(xy 129.833804 -11.866972) (xy 125.495706 -11.866972) (xy 125.377128 -11.941479) (xy 125.253928 -12.009569)
			(xy 125.127104 -12.070645) (xy 124.997055 -12.124513) (xy 124.86419 -12.171005) (xy 124.728928 -12.209974)
			(xy 124.591693 -12.241298) (xy 124.452918 -12.264877) (xy 124.313039 -12.280639) (xy 124.172496 -12.288532)
			(xy 124.102114 -12.289028) (xy 83.70189 -12.289028) (xy 83.631508 -12.288534) (xy 83.490965 -12.280641)
			(xy 83.351086 -12.26488) (xy 83.21231 -12.2413) (xy 83.075075 -12.209977) (xy 82.939812 -12.171008)
			(xy 82.806947 -12.124516) (xy 82.676898 -12.070648) (xy 82.550073 -12.009572) (xy 82.426873 -11.941482)
			(xy 82.307684 -11.866591) (xy 82.192882 -11.785134) (xy 82.082828 -11.697369) (xy 81.977868 -11.603571)
			(xy 81.878333 -11.504036) (xy 81.784535 -11.399076) (xy 81.696769 -11.289022) (xy 81.615313 -11.174221)
			(xy 81.540421 -11.055032) (xy 81.47233 -10.931832) (xy 81.411254 -10.805008) (xy 81.357386 -10.674959)
			(xy 81.310894 -10.542094) (xy 81.271924 -10.406831) (xy 81.240601 -10.269596) (xy 81.217021 -10.13082)
			(xy 81.20126 -9.990941) (xy 81.193366 -9.850398) (xy 81.192878 -9.780016) (xy 81.192878 -0.559816)
			(xy 81.192461 -0.549794) (xy 81.184793 -0.531276) (xy 81.170619 -0.517104) (xy 81.1521 -0.509438)
			(xy 81.142078 -0.509016) (xy 13.661898 -0.509016) (xy 13.651878 -0.509436) (xy 13.633365 -0.517107)
			(xy 13.619197 -0.53128) (xy 13.611532 -0.549796) (xy 13.611098 -0.559816) (xy 13.611098 -5.169916)
			(xy 14.349991 -5.169916) (xy 14.353997 -5.081985) (xy 14.365983 -4.994782) (xy 14.385848 -4.90903)
			(xy 14.41343 -4.82544) (xy 14.448498 -4.744705) (xy 14.490763 -4.667493) (xy 14.539874 -4.594444)
			(xy 14.595424 -4.526164) (xy 14.656953 -4.463218) (xy 14.723951 -4.406129) (xy 14.795862 -4.355368)
			(xy 14.872092 -4.311356) (xy 14.952008 -4.274459) (xy 15.034949 -4.244982) (xy 15.120226 -4.22317)
			(xy 15.207133 -4.209202) (xy 15.294951 -4.203195) (xy 15.38295 -4.205199) (xy 15.470403 -4.215196)
			(xy 15.556585 -4.233105) (xy 15.640781 -4.258777) (xy 15.722294 -4.291998) (xy 15.800448 -4.332494)
			(xy 15.874595 -4.379929) (xy 15.944122 -4.433911) (xy 16.008453 -4.493991) (xy 16.067053 -4.559672)
			(xy 16.119437 -4.63041) (xy 16.165173 -4.705618) (xy 16.203879 -4.784674) (xy 16.235237 -4.866921)
			(xy 16.258985 -4.95168) (xy 16.266165 -4.990667) (xy 20.439138 -4.990667) (xy 20.439138 -4.936133)
			(xy 20.446899 -4.882153) (xy 20.462263 -4.829827) (xy 20.484917 -4.78022) (xy 20.5144 -4.734341)
			(xy 20.550112 -4.693126) (xy 20.591325 -4.657412) (xy 20.637202 -4.627926) (xy 20.686808 -4.60527)
			(xy 20.739133 -4.589903) (xy 20.793113 -4.58214) (xy 20.82038 -4.581652) (xy 21.68398 -4.581652)
			(xy 21.711253 -4.582086) (xy 21.765244 -4.589846) (xy 21.817581 -4.605211) (xy 21.867198 -4.627869)
			(xy 21.913086 -4.657357) (xy 21.95431 -4.693076) (xy 21.990031 -4.734298) (xy 22.019522 -4.780184)
			(xy 22.042182 -4.8298) (xy 22.057549 -4.882136) (xy 22.065312 -4.936127) (xy 22.065312 -4.990671)
			(xy 24.039016 -4.990671) (xy 24.039016 -4.936129) (xy 24.046778 -4.882142) (xy 24.062145 -4.82981)
			(xy 24.084803 -4.780197) (xy 24.114292 -4.734314) (xy 24.15001 -4.693095) (xy 24.191231 -4.657379)
			(xy 24.237116 -4.627893) (xy 24.28673 -4.605237) (xy 24.339064 -4.589873) (xy 24.393051 -4.582114)
			(xy 24.420322 -4.581652) (xy 25.283922 -4.581652) (xy 25.311191 -4.582112) (xy 25.365175 -4.589876)
			(xy 25.417503 -4.605244) (xy 25.467113 -4.627903) (xy 25.512992 -4.65739) (xy 25.554209 -4.693107)
			(xy 25.589923 -4.734325) (xy 25.619408 -4.780207) (xy 25.642063 -4.829817) (xy 25.657428 -4.882147)
			(xy 25.66519 -4.936131) (xy 25.66519 -4.990667) (xy 27.639038 -4.990667) (xy 27.639038 -4.936133)
			(xy 27.646799 -4.882155) (xy 27.662162 -4.82983) (xy 27.684814 -4.780224) (xy 27.714296 -4.734347)
			(xy 27.750006 -4.693131) (xy 27.791218 -4.657417) (xy 27.837092 -4.627932) (xy 27.886696 -4.605274)
			(xy 27.93902 -4.589906) (xy 27.992997 -4.582141) (xy 28.020264 -4.581652) (xy 28.883864 -4.581652)
			(xy 28.911138 -4.582085) (xy 28.96513 -4.589843) (xy 29.017469 -4.605207) (xy 29.067089 -4.627863)
			(xy 29.112979 -4.657351) (xy 29.154205 -4.69307) (xy 29.189927 -4.734292) (xy 29.219419 -4.78018)
			(xy 29.24208 -4.829797) (xy 29.257449 -4.882134) (xy 29.265212 -4.936126) (xy 29.265212 -4.990667)
			(xy 31.239238 -4.990667) (xy 31.239238 -4.936133) (xy 31.246999 -4.882155) (xy 31.262361 -4.829831)
			(xy 31.285014 -4.780225) (xy 31.314495 -4.734348) (xy 31.350205 -4.693133) (xy 31.391416 -4.657419)
			(xy 31.43729 -4.627933) (xy 31.486893 -4.605275) (xy 31.539216 -4.589907) (xy 31.593193 -4.582141)
			(xy 31.62046 -4.581652) (xy 32.48406 -4.581652) (xy 32.511334 -4.582085) (xy 32.565327 -4.589843)
			(xy 32.617666 -4.605206) (xy 32.667286 -4.627862) (xy 32.713177 -4.65735) (xy 32.754403 -4.693068)
			(xy 32.790126 -4.734291) (xy 32.819619 -4.780178) (xy 32.84228 -4.829796) (xy 32.857649 -4.882134)
			(xy 32.865412 -4.936126) (xy 32.865412 -4.990671) (xy 40.349116 -4.990671) (xy 40.349116 -4.936129)
			(xy 40.356878 -4.882142) (xy 40.372245 -4.829809) (xy 40.394903 -4.780196) (xy 40.424392 -4.734313)
			(xy 40.460111 -4.693094) (xy 40.501332 -4.657378) (xy 40.547217 -4.627892) (xy 40.596832 -4.605237)
			(xy 40.649165 -4.589873) (xy 40.703153 -4.582114) (xy 40.730424 -4.581652) (xy 41.594024 -4.581652)
			(xy 41.621293 -4.582112) (xy 41.675276 -4.589877) (xy 41.727605 -4.605245) (xy 41.777214 -4.627903)
			(xy 41.823093 -4.657391) (xy 41.86431 -4.693107) (xy 41.900024 -4.734326) (xy 41.929508 -4.780207)
			(xy 41.952164 -4.829818) (xy 41.967528 -4.882147) (xy 41.97529 -4.936131) (xy 41.97529 -4.990667)
			(xy 43.949138 -4.990667) (xy 43.949138 -4.936133) (xy 43.956899 -4.882155) (xy 43.972262 -4.82983)
			(xy 43.994915 -4.780224) (xy 44.024396 -4.734346) (xy 44.060107 -4.693131) (xy 44.101319 -4.657417)
			(xy 44.147194 -4.627931) (xy 44.196798 -4.605274) (xy 44.249121 -4.589906) (xy 44.303099 -4.582141)
			(xy 44.330366 -4.581652) (xy 45.193966 -4.581652) (xy 45.22124 -4.582085) (xy 45.275232 -4.589844)
			(xy 45.327571 -4.605208) (xy 45.37719 -4.627864) (xy 45.42308 -4.657352) (xy 45.464305 -4.693071)
			(xy 45.500028 -4.734293) (xy 45.52952 -4.78018) (xy 45.552181 -4.829797) (xy 45.567549 -4.882135)
			(xy 45.575312 -4.936126) (xy 45.575312 -4.990667) (xy 51.559238 -4.990667) (xy 51.559238 -4.936133)
			(xy 51.566999 -4.882155) (xy 51.582361 -4.829831) (xy 51.605014 -4.780225) (xy 51.634495 -4.734348)
			(xy 51.670205 -4.693133) (xy 51.711416 -4.657419) (xy 51.75729 -4.627933) (xy 51.806893 -4.605275)
			(xy 51.859216 -4.589907) (xy 51.913193 -4.582141) (xy 51.94046 -4.581652) (xy 52.80406 -4.581652)
			(xy 52.831334 -4.582085) (xy 52.885327 -4.589843) (xy 52.937666 -4.605206) (xy 52.987286 -4.627862)
			(xy 53.033177 -4.65735) (xy 53.074403 -4.693068) (xy 53.110126 -4.734291) (xy 53.139619 -4.780178)
			(xy 53.16228 -4.829796) (xy 53.177649 -4.882134) (xy 53.185412 -4.936126) (xy 53.185412 -4.99067)
			(xy 55.159115 -4.99067) (xy 55.159115 -4.93613) (xy 55.166877 -4.882145) (xy 55.182243 -4.829814)
			(xy 55.2049 -4.780202) (xy 55.234387 -4.73432) (xy 55.270103 -4.693102) (xy 55.311322 -4.657386)
			(xy 55.357204 -4.627899) (xy 55.406816 -4.605242) (xy 55.459147 -4.589877) (xy 55.513132 -4.582115)
			(xy 55.540402 -4.581652) (xy 56.404002 -4.581652) (xy 56.431272 -4.582111) (xy 56.485258 -4.589873)
			(xy 56.537589 -4.605239) (xy 56.587201 -4.627896) (xy 56.633083 -4.657383) (xy 56.674302 -4.6931)
			(xy 56.710018 -4.734319) (xy 56.739505 -4.780201) (xy 56.762162 -4.829813) (xy 56.777528 -4.882144)
			(xy 56.78529 -4.93613) (xy 56.78529 -4.99067) (xy 56.777528 -5.044656) (xy 56.762162 -5.096987) (xy 56.739505 -5.146599)
			(xy 56.710018 -5.192481) (xy 56.674302 -5.2337) (xy 56.633083 -5.269417) (xy 56.587201 -5.298904)
			(xy 56.537589 -5.321561) (xy 56.485258 -5.336927) (xy 56.431272 -5.344689) (xy 56.404002 -5.345176)
			(xy 55.540402 -5.345176) (xy 55.513132 -5.344685) (xy 55.459147 -5.336923) (xy 55.406816 -5.321558)
			(xy 55.357204 -5.298901) (xy 55.311322 -5.269414) (xy 55.270103 -5.233698) (xy 55.234387 -5.19248)
			(xy 55.2049 -5.146598) (xy 55.182243 -5.096986) (xy 55.166877 -5.044655) (xy 55.159115 -4.99067)
			(xy 53.185412 -4.99067) (xy 53.185412 -4.990674) (xy 53.177649 -5.044666) (xy 53.16228 -5.097004)
			(xy 53.139619 -5.146622) (xy 53.110126 -5.192509) (xy 53.074403 -5.233732) (xy 53.033177 -5.26945)
			(xy 52.987286 -5.298938) (xy 52.937666 -5.321594) (xy 52.885327 -5.336957) (xy 52.831334 -5.344715)
			(xy 52.80406 -5.345176) (xy 51.94046 -5.345176) (xy 51.913194 -5.344659) (xy 51.859216 -5.336893)
			(xy 51.806893 -5.321525) (xy 51.75729 -5.298867) (xy 51.711416 -5.269381) (xy 51.670205 -5.233667)
			(xy 51.634495 -5.192452) (xy 51.605014 -5.146575) (xy 51.582361 -5.096969) (xy 51.566999 -5.044645)
			(xy 51.559238 -4.990667) (xy 45.575312 -4.990667) (xy 45.575312 -4.990674) (xy 45.567549 -5.044665)
			(xy 45.552181 -5.097003) (xy 45.52952 -5.14662) (xy 45.500028 -5.192507) (xy 45.464305 -5.233729)
			(xy 45.42308 -5.269448) (xy 45.37719 -5.298936) (xy 45.327571 -5.321592) (xy 45.275232 -5.336956)
			(xy 45.22124 -5.344715) (xy 45.193966 -5.345176) (xy 44.330366 -5.345176) (xy 44.303099 -5.344659)
			(xy 44.249121 -5.336894) (xy 44.196798 -5.321526) (xy 44.147194 -5.298869) (xy 44.101319 -5.269383)
			(xy 44.060107 -5.233669) (xy 44.024396 -5.192454) (xy 43.994915 -5.146576) (xy 43.972262 -5.09697)
			(xy 43.956899 -5.044645) (xy 43.949138 -4.990667) (xy 41.97529 -4.990667) (xy 41.97529 -4.990669)
			(xy 41.967528 -5.044653) (xy 41.952164 -5.096982) (xy 41.929508 -5.146593) (xy 41.900024 -5.192474)
			(xy 41.86431 -5.233693) (xy 41.823093 -5.269409) (xy 41.777214 -5.298897) (xy 41.727605 -5.321555)
			(xy 41.675276 -5.336923) (xy 41.621293 -5.344688) (xy 41.594024 -5.345176) (xy 40.730424 -5.345176)
			(xy 40.703153 -5.344686) (xy 40.649165 -5.336927) (xy 40.596832 -5.321563) (xy 40.547217 -5.298908)
			(xy 40.501332 -5.269422) (xy 40.460111 -5.233706) (xy 40.424392 -5.192487) (xy 40.394903 -5.146604)
			(xy 40.372245 -5.096991) (xy 40.356878 -5.044658) (xy 40.349116 -4.990671) (xy 32.865412 -4.990671)
			(xy 32.865412 -4.990674) (xy 32.857649 -5.044666) (xy 32.84228 -5.097004) (xy 32.819619 -5.146622)
			(xy 32.790126 -5.192509) (xy 32.754403 -5.233732) (xy 32.713177 -5.26945) (xy 32.667286 -5.298938)
			(xy 32.617666 -5.321594) (xy 32.565327 -5.336957) (xy 32.511334 -5.344715) (xy 32.48406 -5.345176)
			(xy 31.62046 -5.345176) (xy 31.593194 -5.344659) (xy 31.539216 -5.336893) (xy 31.486893 -5.321525)
			(xy 31.43729 -5.298867) (xy 31.391416 -5.269381) (xy 31.350205 -5.233667) (xy 31.314495 -5.192452)
			(xy 31.285014 -5.146575) (xy 31.262361 -5.096969) (xy 31.246999 -5.044645) (xy 31.239238 -4.990667)
			(xy 29.265212 -4.990667) (xy 29.265212 -4.990674) (xy 29.257449 -5.044666) (xy 29.24208 -5.097003)
			(xy 29.219419 -5.14662) (xy 29.189927 -5.192508) (xy 29.154205 -5.23373) (xy 29.112979 -5.269449)
			(xy 29.067089 -5.298937) (xy 29.017469 -5.321593) (xy 28.96513 -5.336957) (xy 28.911138 -5.344715)
			(xy 28.883864 -5.345176) (xy 28.020264 -5.345176) (xy 27.992997 -5.344659) (xy 27.93902 -5.336894)
			(xy 27.886696 -5.321526) (xy 27.837092 -5.298868) (xy 27.791218 -5.269383) (xy 27.750006 -5.233669)
			(xy 27.714296 -5.192453) (xy 27.684814 -5.146576) (xy 27.662162 -5.09697) (xy 27.646799 -5.044645)
			(xy 27.639038 -4.990667) (xy 25.66519 -4.990667) (xy 25.66519 -4.990669) (xy 25.657428 -5.044653)
			(xy 25.642063 -5.096983) (xy 25.619408 -5.146593) (xy 25.589923 -5.192475) (xy 25.554209 -5.233693)
			(xy 25.512992 -5.26941) (xy 25.467113 -5.298897) (xy 25.417503 -5.321556) (xy 25.365175 -5.336924)
			(xy 25.311191 -5.344688) (xy 25.283922 -5.345176) (xy 24.420322 -5.345176) (xy 24.393051 -5.344686)
			(xy 24.339064 -5.336927) (xy 24.28673 -5.321563) (xy 24.237116 -5.298907) (xy 24.191231 -5.269421)
			(xy 24.15001 -5.233705) (xy 24.114292 -5.192486) (xy 24.084803 -5.146603) (xy 24.062145 -5.09699)
			(xy 24.046778 -5.044658) (xy 24.039016 -4.990671) (xy 22.065312 -4.990671) (xy 22.065312 -4.990673)
			(xy 22.057549 -5.044664) (xy 22.042182 -5.097) (xy 22.019522 -5.146616) (xy 21.990031 -5.192502)
			(xy 21.95431 -5.233724) (xy 21.913086 -5.269443) (xy 21.867198 -5.298931) (xy 21.817581 -5.321589)
			(xy 21.765244 -5.336954) (xy 21.711253 -5.344714) (xy 21.68398 -5.345176) (xy 20.82038 -5.345176)
			(xy 20.793113 -5.34466) (xy 20.739133 -5.336897) (xy 20.686808 -5.32153) (xy 20.637202 -5.298874)
			(xy 20.591325 -5.269388) (xy 20.550112 -5.233674) (xy 20.5144 -5.192459) (xy 20.484917 -5.14658)
			(xy 20.462263 -5.096973) (xy 20.446899 -5.044647) (xy 20.439138 -4.990667) (xy 16.266165 -4.990667)
			(xy 16.274927 -5.038247) (xy 16.282931 -5.125905) (xy 16.283432 -5.169916) (xy 16.282931 -5.213927)
			(xy 16.274927 -5.301585) (xy 16.258985 -5.388152) (xy 16.235237 -5.472911) (xy 16.203879 -5.555158)
			(xy 16.165173 -5.634214) (xy 16.119437 -5.709422) (xy 16.067053 -5.78016) (xy 16.008453 -5.845841)
			(xy 15.944122 -5.905921) (xy 15.874595 -5.959903) (xy 15.800448 -6.007338) (xy 15.722294 -6.047834)
			(xy 15.640781 -6.081055) (xy 15.556585 -6.106727) (xy 15.470403 -6.124636) (xy 15.38295 -6.134633)
			(xy 15.294951 -6.136637) (xy 15.207133 -6.13063) (xy 15.120226 -6.116662) (xy 15.034949 -6.09485)
			(xy 14.952008 -6.065373) (xy 14.872092 -6.028476) (xy 14.795862 -5.984464) (xy 14.723951 -5.933703)
			(xy 14.656953 -5.876614) (xy 14.595424 -5.813668) (xy 14.539874 -5.745388) (xy 14.490763 -5.672339)
			(xy 14.448498 -5.595127) (xy 14.41343 -5.514392) (xy 14.385848 -5.430802) (xy 14.365983 -5.34505)
			(xy 14.353997 -5.257847) (xy 14.349991 -5.169916) (xy 13.611098 -5.169916) (xy 13.611098 -6.169914)
			(xy 78.515217 -6.169914) (xy 78.519222 -6.082006) (xy 78.531205 -5.994826) (xy 78.551065 -5.909097)
			(xy 78.57864 -5.825529) (xy 78.613699 -5.744815) (xy 78.655952 -5.667623) (xy 78.70505 -5.594594)
			(xy 78.760586 -5.526332) (xy 78.822098 -5.463402) (xy 78.889079 -5.406328) (xy 78.960972 -5.35558)
			(xy 79.037181 -5.31158) (xy 79.117076 -5.274693) (xy 79.199995 -5.245224) (xy 79.28525 -5.223417)
			(xy 79.372134 -5.209453) (xy 79.459928 -5.203447) (xy 79.547905 -5.205451) (xy 79.635335 -5.215446)
			(xy 79.721494 -5.23335) (xy 79.805668 -5.259014) (xy 79.887159 -5.292227) (xy 79.965293 -5.332713)
			(xy 80.039421 -5.380135) (xy 80.108929 -5.434102) (xy 80.173243 -5.494167) (xy 80.231827 -5.559831)
			(xy 80.284198 -5.63055) (xy 80.329921 -5.705738) (xy 80.368618 -5.784773) (xy 80.399967 -5.866999)
			(xy 80.423709 -5.951735) (xy 80.439647 -6.038279) (xy 80.447649 -6.125914) (xy 80.44815 -6.169914)
			(xy 80.447649 -6.213914) (xy 80.439647 -6.301549) (xy 80.423709 -6.388093) (xy 80.399967 -6.472829)
			(xy 80.368618 -6.555055) (xy 80.329921 -6.63409) (xy 80.284198 -6.709278) (xy 80.231827 -6.779997)
			(xy 80.173243 -6.845661) (xy 80.108929 -6.905726) (xy 80.039421 -6.959693) (xy 79.965293 -7.007115)
			(xy 79.887159 -7.047601) (xy 79.805668 -7.080814) (xy 79.721494 -7.106478) (xy 79.635335 -7.124382)
			(xy 79.547905 -7.134377) (xy 79.459928 -7.136381) (xy 79.372134 -7.130375) (xy 79.28525 -7.116411)
			(xy 79.199995 -7.094604) (xy 79.117076 -7.065135) (xy 79.037181 -7.028248) (xy 78.960972 -6.984248)
			(xy 78.889079 -6.9335) (xy 78.822098 -6.876426) (xy 78.760586 -6.813496) (xy 78.70505 -6.745234)
			(xy 78.655952 -6.672205) (xy 78.613699 -6.595013) (xy 78.57864 -6.514299) (xy 78.551065 -6.430731)
			(xy 78.531205 -6.345002) (xy 78.519222 -6.257822) (xy 78.515217 -6.169914) (xy 13.611098 -6.169914)
			(xy 13.611098 -6.75243) (xy 18.634432 -6.75243) (xy 18.634432 -6.69789) (xy 18.642194 -6.643907)
			(xy 18.65756 -6.591577) (xy 18.680216 -6.541966) (xy 18.709702 -6.496085) (xy 18.745417 -6.454867)
			(xy 18.786635 -6.419152) (xy 18.832516 -6.389666) (xy 18.882127 -6.36701) (xy 18.934457 -6.351644)
			(xy 18.98844 -6.343882) (xy 19.01571 -6.343396) (xy 19.87931 -6.343396) (xy 19.906579 -6.343886)
			(xy 19.960563 -6.351648) (xy 20.012892 -6.367013) (xy 20.062502 -6.389669) (xy 20.108382 -6.419155)
			(xy 20.1496 -6.45487) (xy 20.185315 -6.496088) (xy 20.214801 -6.541968) (xy 20.237457 -6.591578)
			(xy 20.252822 -6.643907) (xy 20.260584 -6.697891) (xy 20.260584 -6.752429) (xy 20.260584 -6.752431)
			(xy 22.234349 -6.752431) (xy 22.234349 -6.697889) (xy 22.242112 -6.643901) (xy 22.257478 -6.591568)
			(xy 22.280136 -6.541955) (xy 22.309624 -6.496071) (xy 22.345342 -6.45485) (xy 22.386562 -6.419133)
			(xy 22.432447 -6.389645) (xy 22.48206 -6.366987) (xy 22.534393 -6.351621) (xy 22.588381 -6.343859)
			(xy 22.615652 -6.343396) (xy 23.479252 -6.343396) (xy 23.506521 -6.343887) (xy 23.560504 -6.351648)
			(xy 23.612833 -6.367014) (xy 23.662443 -6.38967) (xy 23.708323 -6.419156) (xy 23.749541 -6.454871)
			(xy 23.785255 -6.496088) (xy 23.814741 -6.541969) (xy 23.837397 -6.591579) (xy 23.852762 -6.643908)
			(xy 23.860524 -6.697891) (xy 23.860524 -6.752429) (xy 23.860518 -6.752472) (xy 25.834283 -6.752472)
			(xy 25.834283 -6.697928) (xy 25.842045 -6.643939) (xy 25.857412 -6.591604) (xy 25.88007 -6.541989)
			(xy 25.909558 -6.496103) (xy 25.945277 -6.454881) (xy 25.986498 -6.419162) (xy 26.032384 -6.389673)
			(xy 26.081998 -6.367014) (xy 26.134333 -6.351646) (xy 26.188322 -6.343883) (xy 26.215594 -6.343396)
			(xy 27.079194 -6.343396) (xy 27.106462 -6.343943) (xy 27.160444 -6.351704) (xy 27.212772 -6.367068)
			(xy 27.26238 -6.389722) (xy 27.308259 -6.419207) (xy 27.349476 -6.45492) (xy 27.38519 -6.496136)
			(xy 27.414675 -6.542015) (xy 27.43733 -6.591623) (xy 27.452695 -6.64395) (xy 27.460457 -6.697932)
			(xy 27.460457 -6.752468) (xy 27.460456 -6.752472) (xy 29.434483 -6.752472) (xy 29.434483 -6.697928)
			(xy 29.442245 -6.643939) (xy 29.457611 -6.591605) (xy 29.480269 -6.54199) (xy 29.509757 -6.496105)
			(xy 29.545476 -6.454883) (xy 29.586697 -6.419163) (xy 29.632581 -6.389674) (xy 29.682196 -6.367015)
			(xy 29.73453 -6.351647) (xy 29.788518 -6.343883) (xy 29.81579 -6.343396) (xy 30.67939 -6.343396)
			(xy 30.706658 -6.343943) (xy 30.76064 -6.351703) (xy 30.812969 -6.367067) (xy 30.862578 -6.389721)
			(xy 30.908457 -6.419205) (xy 30.949674 -6.454919) (xy 30.985389 -6.496135) (xy 31.014874 -6.542014)
			(xy 31.03753 -6.591622) (xy 31.052895 -6.64395) (xy 31.060657 -6.697932) (xy 31.060657 -6.752468)
			(xy 31.060657 -6.75247) (xy 38.544482 -6.75247) (xy 38.544482 -6.69793) (xy 38.552244 -6.643944)
			(xy 38.567608 -6.591613) (xy 38.590264 -6.542) (xy 38.619749 -6.496116) (xy 38.655463 -6.454895)
			(xy 38.696679 -6.419176) (xy 38.74256 -6.389686) (xy 38.792169 -6.367025) (xy 38.844499 -6.351654)
			(xy 38.898484 -6.343886) (xy 38.925754 -6.343396) (xy 39.789354 -6.343396) (xy 39.816624 -6.34394)
			(xy 39.87061 -6.351696) (xy 39.922943 -6.367057) (xy 39.972556 -6.389709) (xy 40.01844 -6.419192)
			(xy 40.059662 -6.454906) (xy 40.09538 -6.496123) (xy 40.124869 -6.542004) (xy 40.147527 -6.591614)
			(xy 40.162894 -6.643945) (xy 40.170656 -6.69793) (xy 40.170656 -6.75247) (xy 40.170656 -6.752472)
			(xy 42.144383 -6.752472) (xy 42.144383 -6.697928) (xy 42.152145 -6.643939) (xy 42.167512 -6.591604)
			(xy 42.19017 -6.541988) (xy 42.219659 -6.496103) (xy 42.255378 -6.454881) (xy 42.296599 -6.419161)
			(xy 42.342485 -6.389672) (xy 42.3921 -6.367013) (xy 42.444435 -6.351646) (xy 42.498424 -6.343883)
			(xy 42.525696 -6.343396) (xy 43.389296 -6.343396) (xy 43.416564 -6.343943) (xy 43.470546 -6.351704)
			(xy 43.522873 -6.367068) (xy 43.572481 -6.389723) (xy 43.61836 -6.419207) (xy 43.659576 -6.454921)
			(xy 43.69529 -6.496136) (xy 43.724775 -6.542015) (xy 43.74743 -6.591623) (xy 43.762795 -6.643951)
			(xy 43.770557 -6.697932) (xy 43.770557 -6.752468) (xy 43.770556 -6.752472) (xy 49.754483 -6.752472)
			(xy 49.754483 -6.697928) (xy 49.762245 -6.643939) (xy 49.777611 -6.591605) (xy 49.800269 -6.54199)
			(xy 49.829757 -6.496105) (xy 49.865476 -6.454883) (xy 49.906697 -6.419163) (xy 49.952581 -6.389674)
			(xy 50.002196 -6.367015) (xy 50.05453 -6.351647) (xy 50.108518 -6.343883) (xy 50.13579 -6.343396)
			(xy 50.99939 -6.343396) (xy 51.026658 -6.343943) (xy 51.08064 -6.351703) (xy 51.132969 -6.367067)
			(xy 51.182578 -6.389721) (xy 51.228457 -6.419205) (xy 51.269674 -6.454919) (xy 51.305389 -6.496135)
			(xy 51.334874 -6.542014) (xy 51.35753 -6.591622) (xy 51.372895 -6.64395) (xy 51.380657 -6.697932)
			(xy 51.380657 -6.752468) (xy 51.380656 -6.752475) (xy 53.35436 -6.752475) (xy 53.35436 -6.697925)
			(xy 53.362124 -6.643929) (xy 53.377493 -6.591588) (xy 53.400155 -6.541967) (xy 53.429649 -6.496077)
			(xy 53.465374 -6.454851) (xy 53.506603 -6.41913) (xy 53.552495 -6.38964) (xy 53.602118 -6.366982)
			(xy 53.65446 -6.351617) (xy 53.708457 -6.343857) (xy 53.735732 -6.343396) (xy 54.599332 -6.343396)
			(xy 54.626597 -6.343969) (xy 54.680571 -6.351733) (xy 54.732891 -6.367099) (xy 54.782492 -6.389755)
			(xy 54.828364 -6.419238) (xy 54.869573 -6.45495) (xy 54.905281 -6.496162) (xy 54.93476 -6.542036)
			(xy 54.957412 -6.591639) (xy 54.972774 -6.64396) (xy 54.980534 -6.697935) (xy 54.980534 -6.752465)
			(xy 54.980533 -6.752471) (xy 56.954382 -6.752471) (xy 56.954382 -6.697929) (xy 56.962144 -6.643942)
			(xy 56.97751 -6.591608) (xy 57.000167 -6.541994) (xy 57.029654 -6.49611) (xy 57.06537 -6.454888)
			(xy 57.106589 -6.419169) (xy 57.152472 -6.389679) (xy 57.202084 -6.367019) (xy 57.254416 -6.35165)
			(xy 57.308403 -6.343884) (xy 57.335674 -6.343396) (xy 58.199274 -6.343396) (xy 58.226543 -6.343942)
			(xy 58.280527 -6.3517) (xy 58.332857 -6.367062) (xy 58.382468 -6.389716) (xy 58.42835 -6.4192) (xy 58.469569 -6.454913)
			(xy 58.505285 -6.496129) (xy 58.534772 -6.542009) (xy 58.557429 -6.591619) (xy 58.564228 -6.614772)
			(xy 70.948992 -6.614772) (xy 70.948992 -6.560228) (xy 70.956754 -6.506238) (xy 70.972121 -6.453903)
			(xy 70.994781 -6.404288) (xy 71.02427 -6.358403) (xy 71.05999 -6.317181) (xy 71.101212 -6.281463)
			(xy 71.147099 -6.251975) (xy 71.196715 -6.229317) (xy 71.24905 -6.213952) (xy 71.30304 -6.206191)
			(xy 71.330312 -6.205728) (xy 72.193912 -6.205728) (xy 72.22118 -6.206235) (xy 72.275161 -6.213998)
			(xy 72.327488 -6.229364) (xy 72.377095 -6.25202) (xy 72.422973 -6.281506) (xy 72.464188 -6.31722)
			(xy 72.499901 -6.358436) (xy 72.529385 -6.404315) (xy 72.55204 -6.453924) (xy 72.567404 -6.506251)
			(xy 72.575166 -6.560232) (xy 72.575166 -6.614768) (xy 72.567404 -6.668749) (xy 72.55204 -6.721076)
			(xy 72.529385 -6.770685) (xy 72.499901 -6.816564) (xy 72.464188 -6.85778) (xy 72.422973 -6.893494)
			(xy 72.377095 -6.92298) (xy 72.327488 -6.945636) (xy 72.275161 -6.961002) (xy 72.22118 -6.968765)
			(xy 72.193912 -6.969252) (xy 71.330312 -6.969252) (xy 71.30304 -6.968809) (xy 71.24905 -6.961048)
			(xy 71.196715 -6.945683) (xy 71.147099 -6.923025) (xy 71.101212 -6.893537) (xy 71.05999 -6.857819)
			(xy 71.02427 -6.816597) (xy 70.994781 -6.770712) (xy 70.972121 -6.721097) (xy 70.956754 -6.668762)
			(xy 70.948992 -6.614772) (xy 58.564228 -6.614772) (xy 58.572795 -6.643948) (xy 58.580557 -6.697931)
			(xy 58.580557 -6.752469) (xy 58.572795 -6.806452) (xy 58.557429 -6.858781) (xy 58.534772 -6.908391)
			(xy 58.505285 -6.954271) (xy 58.469569 -6.995487) (xy 58.42835 -7.0312) (xy 58.382468 -7.060684)
			(xy 58.332857 -7.083338) (xy 58.280527 -7.0987) (xy 58.226543 -7.106458) (xy 58.199274 -7.10692)
			(xy 57.335674 -7.10692) (xy 57.308403 -7.106516) (xy 57.254416 -7.09875) (xy 57.202084 -7.083381)
			(xy 57.152472 -7.060721) (xy 57.106589 -7.031231) (xy 57.06537 -6.995512) (xy 57.029654 -6.95429)
			(xy 57.000167 -6.908406) (xy 56.97751 -6.858792) (xy 56.962144 -6.806458) (xy 56.954382 -6.752471)
			(xy 54.980533 -6.752471) (xy 54.972774 -6.80644) (xy 54.957412 -6.858761) (xy 54.93476 -6.908364)
			(xy 54.905281 -6.954238) (xy 54.869573 -6.99545) (xy 54.828364 -7.031162) (xy 54.782492 -7.060645)
			(xy 54.732891 -7.083301) (xy 54.680571 -7.098667) (xy 54.626597 -7.106431) (xy 54.599332 -7.10692)
			(xy 53.735732 -7.10692) (xy 53.708457 -7.106543) (xy 53.65446 -7.098783) (xy 53.602118 -7.083418)
			(xy 53.552495 -7.06076) (xy 53.506603 -7.03127) (xy 53.465374 -6.995549) (xy 53.429649 -6.954323)
			(xy 53.400155 -6.908433) (xy 53.377493 -6.858812) (xy 53.362124 -6.806471) (xy 53.35436 -6.752475)
			(xy 51.380656 -6.752475) (xy 51.372895 -6.80645) (xy 51.35753 -6.858778) (xy 51.334874 -6.908386)
			(xy 51.305389 -6.954265) (xy 51.269674 -6.995481) (xy 51.228457 -7.031195) (xy 51.182578 -7.060679)
			(xy 51.132969 -7.083333) (xy 51.08064 -7.098697) (xy 51.026658 -7.106457) (xy 50.99939 -7.10692)
			(xy 50.13579 -7.10692) (xy 50.108518 -7.106517) (xy 50.05453 -7.098753) (xy 50.002196 -7.083385)
			(xy 49.952581 -7.060726) (xy 49.906697 -7.031237) (xy 49.865476 -6.995517) (xy 49.829757 -6.954295)
			(xy 49.800269 -6.90841) (xy 49.777611 -6.858795) (xy 49.762245 -6.806461) (xy 49.754483 -6.752472)
			(xy 43.770556 -6.752472) (xy 43.762795 -6.806449) (xy 43.74743 -6.858777) (xy 43.724775 -6.908385)
			(xy 43.69529 -6.954264) (xy 43.659576 -6.995479) (xy 43.61836 -7.031193) (xy 43.572481 -7.060677)
			(xy 43.522873 -7.083332) (xy 43.470546 -7.098696) (xy 43.416564 -7.106457) (xy 43.389296 -7.10692)
			(xy 42.525696 -7.10692) (xy 42.498424 -7.106517) (xy 42.444435 -7.098754) (xy 42.3921 -7.083387)
			(xy 42.342485 -7.060728) (xy 42.296599 -7.031239) (xy 42.255378 -6.995519) (xy 42.219659 -6.954297)
			(xy 42.19017 -6.908412) (xy 42.167512 -6.858796) (xy 42.152145 -6.806461) (xy 42.144383 -6.752472)
			(xy 40.170656 -6.752472) (xy 40.162894 -6.806455) (xy 40.147527 -6.858786) (xy 40.124869 -6.908396)
			(xy 40.09538 -6.954277) (xy 40.059661 -6.995494) (xy 40.01844 -7.031208) (xy 39.972556 -7.060691)
			(xy 39.922943 -7.083343) (xy 39.87061 -7.098704) (xy 39.816624 -7.10646) (xy 39.789354 -7.10692)
			(xy 38.925754 -7.10692) (xy 38.898484 -7.106514) (xy 38.844499 -7.098746) (xy 38.792169 -7.083375)
			(xy 38.74256 -7.060714) (xy 38.696679 -7.031224) (xy 38.655463 -6.995505) (xy 38.619749 -6.954284)
			(xy 38.590264 -6.9084) (xy 38.567608 -6.858787) (xy 38.552244 -6.806456) (xy 38.544482 -6.75247)
			(xy 31.060657 -6.75247) (xy 31.052895 -6.80645) (xy 31.03753 -6.858778) (xy 31.014874 -6.908386)
			(xy 30.985389 -6.954265) (xy 30.949674 -6.995481) (xy 30.908457 -7.031195) (xy 30.862578 -7.060679)
			(xy 30.812969 -7.083333) (xy 30.76064 -7.098697) (xy 30.706658 -7.106457) (xy 30.67939 -7.10692)
			(xy 29.81579 -7.10692) (xy 29.788518 -7.106517) (xy 29.73453 -7.098753) (xy 29.682196 -7.083385)
			(xy 29.632581 -7.060726) (xy 29.586697 -7.031237) (xy 29.545476 -6.995517) (xy 29.509757 -6.954295)
			(xy 29.480269 -6.90841) (xy 29.457611 -6.858795) (xy 29.442245 -6.806461) (xy 29.434483 -6.752472)
			(xy 27.460456 -6.752472) (xy 27.452695 -6.80645) (xy 27.43733 -6.858777) (xy 27.414675 -6.908385)
			(xy 27.38519 -6.954264) (xy 27.349476 -6.99548) (xy 27.308259 -7.031193) (xy 27.26238 -7.060678)
			(xy 27.212772 -7.083332) (xy 27.160444 -7.098696) (xy 27.106462 -7.106457) (xy 27.079194 -7.10692)
			(xy 26.215594 -7.10692) (xy 26.188322 -7.106517) (xy 26.134333 -7.098754) (xy 26.081998 -7.083386)
			(xy 26.032384 -7.060727) (xy 25.986498 -7.031238) (xy 25.945277 -6.995519) (xy 25.909558 -6.954297)
			(xy 25.88007 -6.908411) (xy 25.857412 -6.858796) (xy 25.842045 -6.806461) (xy 25.834283 -6.752472)
			(xy 23.860518 -6.752472) (xy 23.852762 -6.806412) (xy 23.837397 -6.858741) (xy 23.814741 -6.908351)
			(xy 23.785255 -6.954232) (xy 23.749541 -6.995449) (xy 23.708323 -7.031164) (xy 23.662443 -7.06065)
			(xy 23.612833 -7.083306) (xy 23.560504 -7.098672) (xy 23.506521 -7.106433) (xy 23.479252 -7.10692)
			(xy 22.615652 -7.10692) (xy 22.588381 -7.106461) (xy 22.534393 -7.098699) (xy 22.48206 -7.083333)
			(xy 22.432447 -7.060675) (xy 22.386562 -7.031187) (xy 22.345342 -6.99547) (xy 22.309624 -6.954249)
			(xy 22.280136 -6.908365) (xy 22.257478 -6.858752) (xy 22.242112 -6.806419) (xy 22.234349 -6.752431)
			(xy 20.260584 -6.752431) (xy 20.252822 -6.806413) (xy 20.237457 -6.858742) (xy 20.214801 -6.908352)
			(xy 20.185315 -6.954232) (xy 20.1496 -6.99545) (xy 20.108382 -7.031165) (xy 20.062502 -7.060651)
			(xy 20.012892 -7.083307) (xy 19.960563 -7.098672) (xy 19.906579 -7.106434) (xy 19.87931 -7.10692)
			(xy 19.01571 -7.10692) (xy 18.98844 -7.106438) (xy 18.934457 -7.098676) (xy 18.882127 -7.08331) (xy 18.832516 -7.060654)
			(xy 18.786635 -7.031168) (xy 18.745417 -6.995453) (xy 18.709702 -6.954235) (xy 18.680216 -6.908354)
			(xy 18.65756 -6.858743) (xy 18.642194 -6.806413) (xy 18.634432 -6.75243) (xy 13.611098 -6.75243)
			(xy 13.611098 -9.780016) (xy 13.610604 -9.850398) (xy 13.602711 -9.990941) (xy 13.58695 -10.13082)
			(xy 13.563371 -10.269596) (xy 13.532048 -10.406831) (xy 13.493079 -10.542094) (xy 13.446587 -10.674959)
			(xy 13.392719 -10.805008) (xy 13.331643 -10.931832) (xy 13.263553 -11.055033) (xy 13.188662 -11.174221)
			(xy 13.107205 -11.289023) (xy 13.01944 -11.399077) (xy 12.925642 -11.504037) (xy 12.826107 -11.603572)
			(xy 12.721147 -11.69737) (xy 12.611093 -11.785135) (xy 12.496291 -11.866592) (xy 12.377103 -11.941483)
			(xy 12.253902 -12.009573) (xy 12.127078 -12.070649) (xy 11.997029 -12.124517) (xy 11.864164 -12.171009)
			(xy 11.728901 -12.209978) (xy 11.591666 -12.241301) (xy 11.45289 -12.26488) (xy 11.313011 -12.280641)
			(xy 11.172468 -12.288534) (xy 11.102086 -12.289028) (xy 1.999996 -12.289028) (xy 1.944227 -12.289537)
			(xy 1.833 -12.297872) (xy 1.722707 -12.314497) (xy 1.613965 -12.339317) (xy 1.507382 -12.372193)
			(xy 1.403554 -12.412943) (xy 1.353372 -12.43711) (xy 62.309756 -12.43711) (xy 62.310222 -12.396003)
			(xy 62.317806 -12.314139) (xy 62.332909 -12.233324) (xy 62.355404 -12.154247) (xy 62.385098 -12.077583)
			(xy 62.421737 -12.003984) (xy 62.46501 -11.93408) (xy 62.514548 -11.868466) (xy 62.569927 -11.807701)
			(xy 62.630676 -11.752305) (xy 62.696277 -11.70275) (xy 62.766169 -11.659457) (xy 62.839757 -11.622797)
			(xy 62.916414 -11.593082) (xy 62.995485 -11.570566) (xy 63.076295 -11.55544) (xy 63.158157 -11.547833)
			(xy 63.199264 -11.547348) (xy 63.243059 -11.547873) (xy 63.330225 -11.556491) (xy 63.416121 -11.573637)
			(xy 63.499915 -11.599145) (xy 63.580795 -11.632768) (xy 63.619634 -11.653012) (xy 63.6311 -11.65843)
			(xy 63.656428 -11.65843) (xy 63.667894 -11.653012) (xy 63.706738 -11.632781) (xy 63.787623 -11.599174)
			(xy 63.871416 -11.573672) (xy 63.957309 -11.556521) (xy 64.04447 -11.547888) (xy 64.088264 -11.547348)
			(xy 64.132059 -11.547873) (xy 64.219225 -11.556491) (xy 64.305121 -11.573637) (xy 64.388915 -11.599145)
			(xy 64.469795 -11.632768) (xy 64.508634 -11.653012) (xy 64.5201 -11.65843) (xy 64.545428 -11.65843)
			(xy 64.556894 -11.653012) (xy 64.595738 -11.632781) (xy 64.676623 -11.599174) (xy 64.760416 -11.573672)
			(xy 64.846309 -11.556521) (xy 64.93347 -11.547888) (xy 64.977264 -11.547348) (xy 65.021059 -11.547873)
			(xy 65.108225 -11.556491) (xy 65.194121 -11.573637) (xy 65.277915 -11.599145) (xy 65.358795 -11.632768)
			(xy 65.397634 -11.653012) (xy 65.4091 -11.65843) (xy 65.434428 -11.65843) (xy 65.445894 -11.653012)
			(xy 65.484738 -11.632781) (xy 65.565623 -11.599174) (xy 65.649416 -11.573672) (xy 65.735309 -11.556521)
			(xy 65.82247 -11.547888) (xy 65.866264 -11.547348) (xy 65.904554 -11.547763) (xy 65.980848 -11.554368)
			(xy 66.05629 -11.567515) (xy 66.130321 -11.587105) (xy 66.166492 -11.599672) (xy 66.174929 -11.602323)
			(xy 66.192599 -11.602323) (xy 66.201036 -11.599672) (xy 66.237216 -11.587135) (xy 66.311248 -11.56756)
			(xy 66.386687 -11.554411) (xy 66.462976 -11.547785) (xy 66.501264 -11.547348) (xy 66.54268 -11.547848)
			(xy 66.625149 -11.555593) (xy 66.706543 -11.570964) (xy 66.786158 -11.593827) (xy 66.863305 -11.623986)
			(xy 66.937318 -11.661178) (xy 66.972688 -11.68273) (xy 66.980074 -11.686987) (xy 66.996689 -11.690769)
			(xy 67.013625 -11.688896) (xy 67.021456 -11.685524) (xy 67.057233 -11.668994) (xy 67.131154 -11.641645)
			(xy 67.207206 -11.620946) (xy 67.284791 -11.607058) (xy 67.363301 -11.600092) (xy 67.40271 -11.599672)
			(xy 67.443826 -11.600089) (xy 67.525707 -11.607677) (xy 67.606539 -11.622789) (xy 67.685632 -11.645294)
			(xy 67.76231 -11.675001) (xy 67.835921 -11.711656) (xy 67.905835 -11.754947) (xy 67.971457 -11.804505)
			(xy 68.032226 -11.859906) (xy 68.087623 -11.920677) (xy 68.137178 -11.986301) (xy 68.180465 -12.056218)
			(xy 68.217117 -12.12983) (xy 68.24682 -12.20651) (xy 68.269321 -12.285604) (xy 68.284429 -12.366436)
			(xy 68.292013 -12.448318) (xy 68.292472 -12.489434) (xy 68.291907 -12.533047) (xy 68.283357 -12.619854)
			(xy 68.266352 -12.705408) (xy 68.241056 -12.788886) (xy 68.207711 -12.869488) (xy 68.195659 -12.892068)
			(xy 70.948547 -12.892068) (xy 70.948547 -12.837532) (xy 70.956309 -12.783551) (xy 70.971673 -12.731225)
			(xy 70.994328 -12.681617) (xy 71.023813 -12.635739) (xy 71.059526 -12.594524) (xy 71.100742 -12.558811)
			(xy 71.146621 -12.529327) (xy 71.196228 -12.506672) (xy 71.248555 -12.491308) (xy 71.302536 -12.483547)
			(xy 71.329804 -12.483084) (xy 72.193404 -12.483084) (xy 72.220676 -12.483479) (xy 72.274666 -12.491242)
			(xy 72.327001 -12.506609) (xy 72.376617 -12.529269) (xy 72.422503 -12.558758) (xy 72.463725 -12.594478)
			(xy 72.499444 -12.6357) (xy 72.528933 -12.681586) (xy 72.551592 -12.731202) (xy 72.566959 -12.783538)
			(xy 72.574721 -12.837528) (xy 72.574721 -12.892072) (xy 72.566959 -12.946062) (xy 72.551592 -12.998398)
			(xy 72.528933 -13.048014) (xy 72.499444 -13.0939) (xy 72.488173 -13.106908) (xy 191.037972 -13.106908)
			(xy 191.03849 -13.065179) (xy 191.046314 -12.98209) (xy 191.061883 -12.900098) (xy 191.085062 -12.819924)
			(xy 191.115646 -12.742273) (xy 191.153367 -12.667827) (xy 191.197893 -12.59724) (xy 191.248833 -12.531132)
			(xy 191.305739 -12.470085) (xy 191.368112 -12.414635) (xy 191.435403 -12.365269) (xy 191.507021 -12.32242)
			(xy 191.582336 -12.286466) (xy 191.660687 -12.257723) (xy 191.700912 -12.24661) (xy 191.713612 -12.243308)
			(xy 191.732408 -12.225274) (xy 191.765936 -12.117578) (xy 191.760348 -12.091924) (xy 191.751712 -12.082018)
			(xy 191.723476 -12.048682) (xy 191.672486 -11.977736) (xy 191.628113 -11.902474) (xy 191.590718 -11.823512)
			(xy 191.560607 -11.741496) (xy 191.538028 -11.657095) (xy 191.523163 -11.571) (xy 191.516135 -11.483915)
			(xy 191.517001 -11.39655) (xy 191.525753 -11.309621) (xy 191.542322 -11.223837) (xy 191.56657 -11.139901)
			(xy 191.5983 -11.058497) (xy 191.637253 -10.980292) (xy 191.683109 -10.905925) (xy 191.735495 -10.836003)
			(xy 191.793982 -10.771099) (xy 191.858092 -10.711742) (xy 191.927301 -10.658417) (xy 192.001043 -10.611562)
			(xy 192.078715 -10.571558) (xy 192.159684 -10.538733) (xy 192.243285 -10.513355) (xy 192.328838 -10.495631)
			(xy 192.415641 -10.485707) (xy 192.502986 -10.483662) (xy 192.590159 -10.489515) (xy 192.676446 -10.503218)
			(xy 192.761144 -10.524657) (xy 192.843559 -10.553659) (xy 192.923018 -10.589985) (xy 192.998871 -10.63334)
			(xy 193.070499 -10.683368) (xy 193.137315 -10.739661) (xy 193.198774 -10.801758) (xy 193.254374 -10.869153)
			(xy 193.303659 -10.941294) (xy 193.346227 -11.017591) (xy 193.381731 -11.097421) (xy 193.409879 -11.180131)
			(xy 193.430442 -11.265046) (xy 193.443252 -11.35147) (xy 193.448204 -11.438699) (xy 193.445257 -11.526018)
			(xy 193.434436 -11.612714) (xy 193.415829 -11.698079) (xy 193.389589 -11.781414) (xy 193.355929 -11.862038)
			(xy 193.315124 -11.939293) (xy 193.267509 -12.012547) (xy 193.213473 -12.081201) (xy 193.153457 -12.144694)
			(xy 193.121026 -12.173966) (xy 193.112347 -12.182457) (xy 193.103466 -12.205016) (xy 193.104008 -12.217146)
			(xy 193.112136 -12.298934) (xy 193.113935 -12.310868) (xy 193.126948 -12.331156) (xy 193.137028 -12.337796)
			(xy 193.137282 -12.33805) (xy 193.173525 -12.359702) (xy 193.242152 -12.408882) (xy 193.305811 -12.464344)
			(xy 193.363928 -12.525589) (xy 193.415979 -12.592065) (xy 193.461498 -12.663174) (xy 193.500073 -12.738277)
			(xy 193.531358 -12.816697) (xy 193.555071 -12.897729) (xy 193.570999 -12.980643) (xy 193.578999 -13.064693)
			(xy 193.579496 -13.106908) (xy 193.579055 -13.148019) (xy 193.571467 -13.22989) (xy 193.556355 -13.310712)
			(xy 193.533849 -13.389794) (xy 193.504141 -13.466462) (xy 193.467484 -13.540061) (xy 193.424192 -13.609963)
			(xy 193.374634 -13.675571) (xy 193.319232 -13.736326) (xy 193.25846 -13.791709) (xy 193.192836 -13.841247)
			(xy 193.122921 -13.884518) (xy 193.049311 -13.921151) (xy 192.972634 -13.950836) (xy 192.893545 -13.973317)
			(xy 192.812719 -13.988404) (xy 192.730845 -13.995968) (xy 192.689734 -13.996416) (xy 192.643339 -13.99582)
			(xy 192.551051 -13.986179) (xy 192.460267 -13.966987) (xy 192.371973 -13.938452) (xy 192.329308 -13.920216)
			(xy 192.319366 -13.91641) (xy 192.298102 -13.91641) (xy 192.28816 -13.920216) (xy 192.245553 -13.938427)
			(xy 192.157387 -13.966948) (xy 192.066733 -13.986143) (xy 191.974574 -13.995806) (xy 191.928242 -13.996416)
			(xy 191.927734 -13.996416) (xy 191.886626 -13.995955) (xy 191.804762 -13.988373) (xy 191.723946 -13.973271)
			(xy 191.644867 -13.950778) (xy 191.568202 -13.921085) (xy 191.494602 -13.884445) (xy 191.424697 -13.841172)
			(xy 191.359082 -13.791634) (xy 191.298317 -13.736254) (xy 191.24292 -13.675504) (xy 191.193365 -13.609903)
			(xy 191.150073 -13.540009) (xy 191.113413 -13.46642) (xy 191.083699 -13.389762) (xy 191.061184 -13.31069)
			(xy 191.04606 -13.229878) (xy 191.038456 -13.148015) (xy 191.037972 -13.106908) (xy 72.488173 -13.106908)
			(xy 72.463725 -13.135122) (xy 72.422503 -13.170842) (xy 72.376617 -13.200331) (xy 72.327001 -13.222991)
			(xy 72.274666 -13.238358) (xy 72.220676 -13.246121) (xy 72.193404 -13.246608) (xy 71.329804 -13.246608)
			(xy 71.302536 -13.246053) (xy 71.248555 -13.238292) (xy 71.196228 -13.222928) (xy 71.146621 -13.200273)
			(xy 71.100742 -13.170789) (xy 71.059526 -13.135076) (xy 71.023813 -13.093861) (xy 70.994328 -13.047983)
			(xy 70.971673 -12.998375) (xy 70.956309 -12.946049) (xy 70.948547 -12.892068) (xy 68.195659 -12.892068)
			(xy 68.166638 -12.946439) (xy 68.118231 -13.019001) (xy 68.062955 -13.086478) (xy 68.00134 -13.14822)
			(xy 67.933978 -13.203636) (xy 67.861516 -13.252193) (xy 67.823334 -13.273278) (xy 67.814055 -13.278811)
			(xy 67.800889 -13.295908) (xy 67.797934 -13.306298) (xy 67.787525 -13.3474) (xy 67.759881 -13.427561)
			(xy 67.724737 -13.504728) (xy 67.682409 -13.578201) (xy 67.633283 -13.647314) (xy 67.577804 -13.711439)
			(xy 67.516475 -13.769995) (xy 67.449854 -13.82245) (xy 67.378544 -13.868328) (xy 67.303192 -13.907213)
			(xy 67.224482 -13.938753) (xy 67.143129 -13.96266) (xy 67.05987 -13.978719) (xy 66.975461 -13.986784)
			(xy 66.933064 -13.987272) (xy 66.894775 -13.986847) (xy 66.818481 -13.980245) (xy 66.743038 -13.967101)
			(xy 66.669007 -13.947513) (xy 66.632836 -13.934948) (xy 66.624399 -13.932297) (xy 66.606729 -13.932297)
			(xy 66.598292 -13.934948) (xy 66.56211 -13.947478) (xy 66.488079 -13.967055) (xy 66.41264 -13.980205)
			(xy 66.336352 -13.986834) (xy 66.298064 -13.987272) (xy 66.254269 -13.986733) (xy 66.167104 -13.978118)
			(xy 66.081208 -13.960975) (xy 65.997414 -13.93547) (xy 65.916534 -13.90185) (xy 65.877694 -13.881608)
			(xy 65.866228 -13.87619) (xy 65.8409 -13.87619) (xy 65.829434 -13.881608) (xy 65.790581 -13.901822)
			(xy 65.709699 -13.935433) (xy 65.625908 -13.96094) (xy 65.540018 -13.978094) (xy 65.452857 -13.986731)
			(xy 65.409064 -13.987272) (xy 65.365269 -13.986733) (xy 65.278104 -13.978118) (xy 65.192208 -13.960975)
			(xy 65.108414 -13.93547) (xy 65.027534 -13.90185) (xy 64.988694 -13.881608) (xy 64.977228 -13.87619)
			(xy 64.9519 -13.87619) (xy 64.940434 -13.881608) (xy 64.901581 -13.901822) (xy 64.820699 -13.935433)
			(xy 64.736908 -13.96094) (xy 64.651018 -13.978094) (xy 64.563857 -13.986731) (xy 64.520064 -13.987272)
			(xy 64.476269 -13.986733) (xy 64.389104 -13.978118) (xy 64.303208 -13.960975) (xy 64.219414 -13.93547)
			(xy 64.138534 -13.90185) (xy 64.099694 -13.881608) (xy 64.088228 -13.87619) (xy 64.0629 -13.87619)
			(xy 64.051434 -13.881608) (xy 64.012581 -13.901822) (xy 63.931699 -13.935433) (xy 63.847908 -13.96094)
			(xy 63.762018 -13.978094) (xy 63.674857 -13.986731) (xy 63.631064 -13.987272) (xy 63.588804 -13.98679)
			(xy 63.504665 -13.978779) (xy 63.421665 -13.962822) (xy 63.340553 -13.939064) (xy 63.26206 -13.907718)
			(xy 63.186895 -13.869068) (xy 63.115735 -13.823463) (xy 63.049222 -13.771312) (xy 62.987956 -13.713088)
			(xy 62.93249 -13.649314) (xy 62.883323 -13.580566) (xy 62.840899 -13.507464) (xy 62.805601 -13.430668)
			(xy 62.777747 -13.35087) (xy 62.757589 -13.268789) (xy 62.750954 -13.22705) (xy 62.748768 -13.216225)
			(xy 62.736658 -13.197787) (xy 62.727586 -13.19149) (xy 62.693115 -13.169417) (xy 62.628004 -13.119803)
			(xy 62.567725 -13.064419) (xy 62.512788 -13.003732) (xy 62.463657 -12.938255) (xy 62.420747 -12.868543)
			(xy 62.384422 -12.795185) (xy 62.354987 -12.7188) (xy 62.332693 -12.640034) (xy 62.317728 -12.559554)
			(xy 62.310218 -12.47804) (xy 62.309756 -12.43711) (xy 1.353372 -12.43711) (xy 1.303061 -12.461339)
			(xy 1.206466 -12.517108) (xy 1.114309 -12.579941) (xy 1.027105 -12.649484) (xy 0.945341 -12.72535)
			(xy 0.869476 -12.807114) (xy 0.801731 -12.892064) (xy 56.95347 -12.892064) (xy 56.95347 -12.837536)
			(xy 56.96123 -12.783562) (xy 56.976591 -12.731243) (xy 56.999242 -12.681641) (xy 57.02872 -12.635768)
			(xy 57.064426 -12.594556) (xy 57.105634 -12.558845) (xy 57.151504 -12.529362) (xy 57.201103 -12.506706)
			(xy 57.253421 -12.491339) (xy 57.307394 -12.483573) (xy 57.334658 -12.483084) (xy 58.198258 -12.483084)
			(xy 58.225534 -12.483453) (xy 58.279532 -12.491211) (xy 58.331876 -12.506575) (xy 58.381501 -12.529233)
			(xy 58.427395 -12.558723) (xy 58.468625 -12.594445) (xy 58.504351 -12.635671) (xy 58.533847 -12.681562)
			(xy 58.55651 -12.731184) (xy 58.57188 -12.783527) (xy 58.579644 -12.837524) (xy 58.579644 -12.892076)
			(xy 58.57188 -12.946073) (xy 58.55651 -12.998416) (xy 58.533847 -13.048037) (xy 58.504351 -13.093929)
			(xy 58.468625 -13.135155) (xy 58.427395 -13.170877) (xy 58.381501 -13.200367) (xy 58.331876 -13.223025)
			(xy 58.279532 -13.238389) (xy 58.225534 -13.246147) (xy 58.198258 -13.246608) (xy 57.334658 -13.246608)
			(xy 57.307394 -13.246027) (xy 57.253421 -13.238261) (xy 57.201103 -13.222894) (xy 57.151504 -13.200238)
			(xy 57.105634 -13.170755) (xy 57.064426 -13.135044) (xy 57.02872 -13.093832) (xy 56.999242 -13.047959)
			(xy 56.976591 -12.998357) (xy 56.96123 -12.946038) (xy 56.95347 -12.892064) (xy 0.801731 -12.892064)
			(xy 0.799933 -12.894318) (xy 0.737102 -12.986476) (xy 0.681333 -13.083072) (xy 0.632939 -13.183565)
			(xy 0.59219 -13.287393) (xy 0.559313 -13.393977) (xy 0.534494 -13.502719) (xy 0.517871 -13.613012)
			(xy 0.509536 -13.724239) (xy 0.509016 -13.780008) (xy 0.509016 -16.5207) (xy 76.28834 -16.5207) (xy 76.29237 -16.436094)
			(xy 76.304425 -16.352254) (xy 76.324394 -16.26994) (xy 76.352098 -16.189896) (xy 76.387284 -16.112849)
			(xy 76.429635 -16.039495) (xy 76.478768 -15.970499) (xy 76.534236 -15.906485) (xy 76.595538 -15.848035)
			(xy 76.662118 -15.795676) (xy 76.733375 -15.749883) (xy 76.808661 -15.711071) (xy 76.887296 -15.679591)
			(xy 76.968567 -15.655728) (xy 77.051738 -15.639698) (xy 77.136057 -15.631648) (xy 77.178408 -15.63116)
			(xy 77.178916 -15.63116) (xy 77.224101 -15.631724) (xy 77.314005 -15.640873) (xy 77.402518 -15.659097)
			(xy 77.488725 -15.686205) (xy 77.530452 -15.70355) (xy 77.539034 -15.706862) (xy 77.557395 -15.707764)
			(xy 77.566266 -15.705328) (xy 77.610936 -15.69133) (xy 77.702468 -15.671687) (xy 77.795557 -15.661772)
			(xy 77.842364 -15.661132) (xy 77.84338 -15.661132) (xy 77.885732 -15.661539) (xy 77.970052 -15.669589)
			(xy 78.053225 -15.685618) (xy 78.134498 -15.70948) (xy 78.213134 -15.74096) (xy 78.288422 -15.779772)
			(xy 78.35968 -15.825565) (xy 78.426262 -15.877924) (xy 78.487566 -15.936376) (xy 78.543035 -16.00039)
			(xy 78.592169 -16.069387) (xy 78.634521 -16.142742) (xy 78.669709 -16.219791) (xy 78.697413 -16.299835)
			(xy 78.717383 -16.382151) (xy 78.722326 -16.416528) (xy 191.571372 -16.416528) (xy 191.571784 -16.378238)
			(xy 191.57839 -16.301944) (xy 191.591537 -16.226502) (xy 191.611129 -16.152471) (xy 191.623696 -16.1163)
			(xy 191.626331 -16.10786) (xy 191.62634 -16.090193) (xy 191.623696 -16.081756) (xy 191.611158 -16.045577)
			(xy 191.591583 -15.971544) (xy 191.578434 -15.896105) (xy 191.571809 -15.819816) (xy 191.571372 -15.781528)
			(xy 191.571879 -15.740418) (xy 191.579464 -15.65855) (xy 191.594572 -15.577731) (xy 191.617074 -15.498651)
			(xy 191.646778 -15.421985) (xy 191.68343 -15.348387) (xy 191.726718 -15.278486) (xy 191.776272 -15.212878)
			(xy 191.831669 -15.152124) (xy 191.892437 -15.096741) (xy 191.958056 -15.047202) (xy 192.027967 -15.00393)
			(xy 192.101573 -14.967295) (xy 192.178246 -14.937609) (xy 192.257331 -14.915125) (xy 192.338154 -14.900036)
			(xy 192.420024 -14.89247) (xy 192.461134 -14.89202) (xy 192.499451 -14.892376) (xy 192.575804 -14.898912)
			(xy 192.651311 -14.912) (xy 192.72541 -14.931543) (xy 192.761616 -14.94409) (xy 192.769932 -14.946676)
			(xy 192.787336 -14.946676) (xy 192.795652 -14.94409) (xy 192.831863 -14.931562) (xy 192.905965 -14.912041)
			(xy 192.981469 -14.898959) (xy 193.057819 -14.892413) (xy 193.096134 -14.89202) (xy 193.134451 -14.892376)
			(xy 193.210804 -14.898912) (xy 193.286311 -14.912) (xy 193.36041 -14.931543) (xy 193.396616 -14.94409)
			(xy 193.404932 -14.946676) (xy 193.422336 -14.946676) (xy 193.430652 -14.94409) (xy 193.466772 -14.93159)
			(xy 193.540685 -14.912102) (xy 193.615997 -14.899021) (xy 193.692153 -14.892442) (xy 193.730372 -14.89202)
			(xy 193.731134 -14.89202) (xy 193.772241 -14.89248) (xy 193.854104 -14.900067) (xy 193.934917 -14.915174)
			(xy 194.013993 -14.937671) (xy 194.090656 -14.967367) (xy 194.164253 -15.004008) (xy 194.234156 -15.047282)
			(xy 194.299769 -15.09682) (xy 194.360532 -15.152199) (xy 194.415928 -15.212948) (xy 194.465484 -15.278547)
			(xy 194.508776 -15.348439) (xy 194.545437 -15.422026) (xy 194.575153 -15.498681) (xy 194.597672 -15.577751)
			(xy 194.6128 -15.658561) (xy 194.620409 -15.740421) (xy 194.620896 -15.781528) (xy 194.620451 -15.819809)
			(xy 194.613795 -15.896082) (xy 194.600605 -15.971499) (xy 194.591178 -16.008604) (xy 194.588893 -16.019174)
			(xy 194.592456 -16.040487) (xy 194.598036 -16.049752) (xy 194.621836 -16.08633) (xy 194.662956 -16.163308)
			(xy 194.696348 -16.24394) (xy 194.721691 -16.327453) (xy 194.738741 -16.413043) (xy 194.747336 -16.499892)
			(xy 194.747896 -16.543528) (xy 194.747474 -16.584639) (xy 194.739884 -16.666511) (xy 194.72477 -16.747333)
			(xy 194.702263 -16.826416) (xy 194.672553 -16.903083) (xy 194.635895 -16.976682) (xy 194.592602 -17.046584)
			(xy 194.543042 -17.112192) (xy 194.487639 -17.172947) (xy 194.426866 -17.22833) (xy 194.361241 -17.277868)
			(xy 194.291325 -17.321138) (xy 194.217714 -17.357772) (xy 194.141037 -17.387456) (xy 194.061947 -17.409938)
			(xy 193.98112 -17.425024) (xy 193.899246 -17.432588) (xy 193.858134 -17.433036) (xy 193.814503 -17.432505)
			(xy 193.727659 -17.42397) (xy 193.642069 -17.40697) (xy 193.558556 -17.381667) (xy 193.477923 -17.348306)
			(xy 193.400945 -17.307207) (xy 193.364358 -17.28343) (xy 193.355108 -17.277824) (xy 193.333785 -17.274289)
			(xy 193.32321 -17.276572) (xy 193.286097 -17.285942) (xy 193.210677 -17.299046) (xy 193.134409 -17.305624)
			(xy 193.096134 -17.306036) (xy 193.057818 -17.305656) (xy 192.981465 -17.299127) (xy 192.905958 -17.286046)
			(xy 192.831859 -17.26651) (xy 192.795652 -17.253966) (xy 192.787336 -17.25138) (xy 192.769932 -17.25138)
			(xy 192.761616 -17.253966) (xy 192.725489 -17.266445) (xy 192.651578 -17.285939) (xy 192.576269 -17.299026)
			(xy 192.500115 -17.305611) (xy 192.461896 -17.306036) (xy 192.461134 -17.306036) (xy 192.420027 -17.305555)
			(xy 192.338163 -17.297973) (xy 192.257348 -17.282872) (xy 192.178271 -17.260379) (xy 192.101606 -17.230687)
			(xy 192.028008 -17.194048) (xy 191.958103 -17.150776) (xy 191.892489 -17.10124) (xy 191.831724 -17.045861)
			(xy 191.776328 -16.985113) (xy 191.726772 -16.919513) (xy 191.683479 -16.849621) (xy 191.646819 -16.776033)
			(xy 191.617104 -16.699377) (xy 191.594588 -16.620307) (xy 191.579463 -16.539496) (xy 191.571857 -16.457635)
			(xy 191.571372 -16.416528) (xy 78.722326 -16.416528) (xy 78.729438 -16.465992) (xy 78.733468 -16.5506)
			(xy 78.729438 -16.635208) (xy 78.717383 -16.719049) (xy 78.697413 -16.801365) (xy 78.669709 -16.881409)
			(xy 78.634521 -16.958458) (xy 78.592169 -17.031813) (xy 78.543035 -17.10081) (xy 78.487566 -17.164824)
			(xy 78.426262 -17.223276) (xy 78.35968 -17.275635) (xy 78.288422 -17.321428) (xy 78.213134 -17.36024)
			(xy 78.134498 -17.39172) (xy 78.053225 -17.415582) (xy 77.970052 -17.431611) (xy 77.885732 -17.439661)
			(xy 77.84338 -17.440148) (xy 77.842872 -17.440148) (xy 77.797687 -17.439588) (xy 77.707782 -17.430437)
			(xy 77.61927 -17.412213) (xy 77.533063 -17.385103) (xy 77.491336 -17.367758) (xy 77.482756 -17.36444)
			(xy 77.464393 -17.363542) (xy 77.455522 -17.36598) (xy 77.410853 -17.379982) (xy 77.319321 -17.399623)
			(xy 77.226231 -17.409537) (xy 77.179424 -17.410176) (xy 77.178408 -17.410176) (xy 77.136057 -17.409752)
			(xy 77.051738 -17.401702) (xy 76.968567 -17.385672) (xy 76.887296 -17.361809) (xy 76.808661 -17.330329)
			(xy 76.733375 -17.291517) (xy 76.662118 -17.245724) (xy 76.595538 -17.193365) (xy 76.534236 -17.134915)
			(xy 76.478768 -17.070901) (xy 76.429635 -17.001905) (xy 76.387284 -16.928551) (xy 76.352098 -16.851504)
			(xy 76.324394 -16.77146) (xy 76.304425 -16.689146) (xy 76.29237 -16.605306) (xy 76.28834 -16.5207)
			(xy 0.509016 -16.5207) (xy 0.509016 -17.639611) (xy 15.152858 -17.639611) (xy 15.152858 -17.585109)
			(xy 15.160614 -17.531161) (xy 15.175969 -17.478867) (xy 15.19861 -17.42929) (xy 15.228076 -17.383439)
			(xy 15.263768 -17.342249) (xy 15.304958 -17.306558) (xy 15.350808 -17.277091) (xy 15.400385 -17.25445)
			(xy 15.452679 -17.239095) (xy 15.506627 -17.231338) (xy 15.533878 -17.230852) (xy 16.397478 -17.230852)
			(xy 16.424731 -17.231315) (xy 16.478682 -17.239072) (xy 16.53098 -17.254428) (xy 16.580561 -17.27707)
			(xy 16.626414 -17.306538) (xy 16.667607 -17.342232) (xy 16.703301 -17.383424) (xy 16.732769 -17.429278)
			(xy 16.755412 -17.478858) (xy 16.770768 -17.531156) (xy 16.778525 -17.585107) (xy 16.778525 -17.639611)
			(xy 20.740858 -17.639611) (xy 20.740858 -17.585109) (xy 20.748614 -17.531161) (xy 20.763969 -17.478867)
			(xy 20.78661 -17.42929) (xy 20.816076 -17.383439) (xy 20.851768 -17.342249) (xy 20.892958 -17.306558)
			(xy 20.938808 -17.277091) (xy 20.988385 -17.25445) (xy 21.040679 -17.239095) (xy 21.094627 -17.231338)
			(xy 21.121878 -17.230852) (xy 21.985478 -17.230852) (xy 22.012729 -17.231394) (xy 22.066677 -17.239147)
			(xy 22.118972 -17.2545) (xy 22.168549 -17.277139) (xy 22.2144 -17.306603) (xy 22.255591 -17.342293)
			(xy 22.291284 -17.383482) (xy 22.320751 -17.429331) (xy 22.343392 -17.478908) (xy 22.358748 -17.531202)
			(xy 22.366505 -17.585149) (xy 22.366505 -17.639651) (xy 22.366505 -17.639653) (xy 26.328838 -17.639653)
			(xy 26.328838 -17.585147) (xy 26.336595 -17.531195) (xy 26.35195 -17.478897) (xy 26.374592 -17.429316)
			(xy 26.404059 -17.383462) (xy 26.439752 -17.342268) (xy 26.480944 -17.306573) (xy 26.526797 -17.277103)
			(xy 26.576376 -17.254458) (xy 26.628674 -17.239099) (xy 26.682625 -17.231339) (xy 26.709878 -17.230852)
			(xy 27.573478 -17.230852) (xy 27.600729 -17.231394) (xy 27.654677 -17.239147) (xy 27.706972 -17.2545)
			(xy 27.756549 -17.277139) (xy 27.8024 -17.306603) (xy 27.843591 -17.342293) (xy 27.879284 -17.383482)
			(xy 27.908751 -17.429331) (xy 27.931392 -17.478908) (xy 27.946748 -17.531202) (xy 27.954505 -17.585149)
			(xy 27.954505 -17.639651) (xy 27.954402 -17.640366) (xy 31.915646 -17.640366) (xy 31.915646 -17.585834)
			(xy 31.923406 -17.531857) (xy 31.938769 -17.479533) (xy 31.961421 -17.429928) (xy 31.990902 -17.384052)
			(xy 32.026611 -17.342838) (xy 32.067822 -17.307125) (xy 32.113695 -17.277639) (xy 32.163298 -17.254982)
			(xy 32.21562 -17.239615) (xy 32.269596 -17.231849) (xy 32.296862 -17.23136) (xy 33.160462 -17.23136)
			(xy 33.187736 -17.231777) (xy 33.24173 -17.239535) (xy 33.294071 -17.254899) (xy 33.343691 -17.277556)
			(xy 33.389583 -17.307044) (xy 33.43081 -17.342764) (xy 33.466533 -17.383987) (xy 33.496026 -17.429875)
			(xy 33.518688 -17.479494) (xy 33.534057 -17.531832) (xy 33.54182 -17.585826) (xy 33.54182 -17.640366)
			(xy 37.503646 -17.640366) (xy 37.503646 -17.585834) (xy 37.511406 -17.531857) (xy 37.526769 -17.479533)
			(xy 37.549421 -17.429928) (xy 37.578902 -17.384052) (xy 37.614611 -17.342838) (xy 37.655822 -17.307125)
			(xy 37.701695 -17.277639) (xy 37.751298 -17.254982) (xy 37.80362 -17.239615) (xy 37.857596 -17.231849)
			(xy 37.884862 -17.23136) (xy 38.748462 -17.23136) (xy 38.775736 -17.231777) (xy 38.82973 -17.239535)
			(xy 38.882071 -17.254899) (xy 38.931691 -17.277556) (xy 38.977583 -17.307044) (xy 39.01881 -17.342764)
			(xy 39.054533 -17.383987) (xy 39.084026 -17.429875) (xy 39.106688 -17.479494) (xy 39.122057 -17.531832)
			(xy 39.12982 -17.585826) (xy 39.12982 -17.639654) (xy 43.398638 -17.639654) (xy 43.398638 -17.585146)
			(xy 43.406395 -17.531193) (xy 43.421751 -17.478894) (xy 43.444395 -17.429312) (xy 43.473863 -17.383457)
			(xy 43.509558 -17.342262) (xy 43.550752 -17.306567) (xy 43.596606 -17.277097) (xy 43.646188 -17.254454)
			(xy 43.698487 -17.239096) (xy 43.75244 -17.231338) (xy 43.779694 -17.230852) (xy 44.643294 -17.230852)
			(xy 44.670544 -17.231395) (xy 44.72449 -17.23915) (xy 44.776783 -17.254504) (xy 44.826359 -17.277144)
			(xy 44.872208 -17.306609) (xy 44.913397 -17.342299) (xy 44.949088 -17.383487) (xy 44.978553 -17.429336)
			(xy 45.001194 -17.478911) (xy 45.016548 -17.531204) (xy 45.024305 -17.58515) (xy 45.024305 -17.63965)
			(xy 45.024304 -17.639654) (xy 48.986638 -17.639654) (xy 48.986638 -17.585146) (xy 48.994395 -17.531193)
			(xy 49.009751 -17.478894) (xy 49.032395 -17.429312) (xy 49.061863 -17.383457) (xy 49.097558 -17.342262)
			(xy 49.138752 -17.306567) (xy 49.184606 -17.277097) (xy 49.234188 -17.254454) (xy 49.286487 -17.239096)
			(xy 49.34044 -17.231338) (xy 49.367694 -17.230852) (xy 50.231294 -17.230852) (xy 50.258544 -17.231395)
			(xy 50.31249 -17.23915) (xy 50.364783 -17.254504) (xy 50.414359 -17.277144) (xy 50.460208 -17.306609)
			(xy 50.501397 -17.342299) (xy 50.537088 -17.383487) (xy 50.566553 -17.429336) (xy 50.589194 -17.478911)
			(xy 50.604548 -17.531204) (xy 50.612305 -17.58515) (xy 50.612305 -17.63965) (xy 50.612201 -17.64037)
			(xy 54.607423 -17.64037) (xy 54.607423 -17.58583) (xy 54.615186 -17.531845) (xy 54.630552 -17.479514)
			(xy 54.653209 -17.429903) (xy 54.682696 -17.384021) (xy 54.718413 -17.342803) (xy 54.759632 -17.307088)
			(xy 54.805515 -17.277602) (xy 54.855127 -17.254947) (xy 54.907459 -17.239583) (xy 54.961444 -17.231822)
			(xy 54.988714 -17.23136) (xy 55.852314 -17.23136) (xy 55.879584 -17.231803) (xy 55.933569 -17.239567)
			(xy 55.9859 -17.254935) (xy 56.035512 -17.277593) (xy 56.081393 -17.307081) (xy 56.122612 -17.342798)
			(xy 56.158328 -17.384018) (xy 56.187814 -17.429901) (xy 56.21047 -17.479513) (xy 56.225836 -17.531844)
			(xy 56.233598 -17.58583) (xy 56.233598 -17.64037) (xy 56.225836 -17.694356) (xy 56.21047 -17.746687)
			(xy 56.187814 -17.796299) (xy 56.158328 -17.842182) (xy 56.122612 -17.883402) (xy 56.081393 -17.919119)
			(xy 56.035512 -17.948607) (xy 55.9859 -17.971265) (xy 55.933569 -17.986633) (xy 55.879584 -17.994397)
			(xy 55.852314 -17.994884) (xy 54.988714 -17.994884) (xy 54.961444 -17.994378) (xy 54.907459 -17.986617)
			(xy 54.855127 -17.971253) (xy 54.805515 -17.948598) (xy 54.759632 -17.919112) (xy 54.718413 -17.883397)
			(xy 54.682696 -17.842179) (xy 54.653209 -17.796297) (xy 54.630552 -17.746686) (xy 54.615186 -17.694355)
			(xy 54.607423 -17.64037) (xy 50.612201 -17.64037) (xy 50.604548 -17.693596) (xy 50.589194 -17.745889)
			(xy 50.566553 -17.795464) (xy 50.537088 -17.841313) (xy 50.501397 -17.882501) (xy 50.460208 -17.918191)
			(xy 50.414359 -17.947656) (xy 50.364783 -17.970296) (xy 50.31249 -17.98565) (xy 50.258544 -17.993405)
			(xy 50.231294 -17.993868) (xy 49.367694 -17.993868) (xy 49.34044 -17.993462) (xy 49.286487 -17.985704)
			(xy 49.234188 -17.970346) (xy 49.184606 -17.947703) (xy 49.138752 -17.918233) (xy 49.097558 -17.882538)
			(xy 49.061863 -17.841343) (xy 49.032395 -17.795488) (xy 49.009751 -17.745906) (xy 48.994395 -17.693607)
			(xy 48.986638 -17.639654) (xy 45.024304 -17.639654) (xy 45.016548 -17.693596) (xy 45.001194 -17.745889)
			(xy 44.978553 -17.795464) (xy 44.949088 -17.841313) (xy 44.913397 -17.882501) (xy 44.872208 -17.918191)
			(xy 44.826359 -17.947656) (xy 44.776783 -17.970296) (xy 44.72449 -17.98565) (xy 44.670544 -17.993405)
			(xy 44.643294 -17.993868) (xy 43.779694 -17.993868) (xy 43.75244 -17.993462) (xy 43.698487 -17.985704)
			(xy 43.646188 -17.970346) (xy 43.596606 -17.947703) (xy 43.550752 -17.918233) (xy 43.509558 -17.882538)
			(xy 43.473863 -17.841343) (xy 43.444395 -17.795488) (xy 43.421751 -17.745906) (xy 43.406395 -17.693607)
			(xy 43.398638 -17.639654) (xy 39.12982 -17.639654) (xy 39.12982 -17.640374) (xy 39.122057 -17.694368)
			(xy 39.106688 -17.746706) (xy 39.084026 -17.796325) (xy 39.054533 -17.842213) (xy 39.01881 -17.883436)
			(xy 38.977583 -17.919156) (xy 38.931691 -17.948644) (xy 38.882071 -17.971301) (xy 38.82973 -17.986665)
			(xy 38.775736 -17.994423) (xy 38.748462 -17.994884) (xy 37.884862 -17.994884) (xy 37.857596 -17.994351)
			(xy 37.80362 -17.986585) (xy 37.751298 -17.971218) (xy 37.701695 -17.948561) (xy 37.655822 -17.919075)
			(xy 37.614611 -17.883362) (xy 37.578902 -17.842148) (xy 37.549421 -17.796272) (xy 37.526769 -17.746667)
			(xy 37.511406 -17.694343) (xy 37.503646 -17.640366) (xy 33.54182 -17.640366) (xy 33.54182 -17.640374)
			(xy 33.534057 -17.694368) (xy 33.518688 -17.746706) (xy 33.496026 -17.796325) (xy 33.466533 -17.842213)
			(xy 33.43081 -17.883436) (xy 33.389583 -17.919156) (xy 33.343691 -17.948644) (xy 33.294071 -17.971301)
			(xy 33.24173 -17.986665) (xy 33.187736 -17.994423) (xy 33.160462 -17.994884) (xy 32.296862 -17.994884)
			(xy 32.269596 -17.994351) (xy 32.21562 -17.986585) (xy 32.163298 -17.971218) (xy 32.113695 -17.948561)
			(xy 32.067822 -17.919075) (xy 32.026611 -17.883362) (xy 31.990902 -17.842148) (xy 31.961421 -17.796272)
			(xy 31.938769 -17.746667) (xy 31.923406 -17.694343) (xy 31.915646 -17.640366) (xy 27.954402 -17.640366)
			(xy 27.946748 -17.693598) (xy 27.931392 -17.745892) (xy 27.908751 -17.795469) (xy 27.879284 -17.841318)
			(xy 27.843591 -17.882507) (xy 27.8024 -17.918197) (xy 27.756549 -17.947661) (xy 27.706972 -17.9703)
			(xy 27.654677 -17.985653) (xy 27.600729 -17.993406) (xy 27.573478 -17.993868) (xy 26.709878 -17.993868)
			(xy 26.682625 -17.993461) (xy 26.628674 -17.985701) (xy 26.576376 -17.970342) (xy 26.526797 -17.947697)
			(xy 26.480944 -17.918227) (xy 26.439752 -17.882532) (xy 26.404059 -17.841338) (xy 26.374592 -17.795484)
			(xy 26.35195 -17.745903) (xy 26.336595 -17.693605) (xy 26.328838 -17.639653) (xy 22.366505 -17.639653)
			(xy 22.358748 -17.693598) (xy 22.343392 -17.745892) (xy 22.320751 -17.795469) (xy 22.291284 -17.841318)
			(xy 22.255591 -17.882507) (xy 22.2144 -17.918197) (xy 22.168549 -17.947661) (xy 22.118972 -17.9703)
			(xy 22.066677 -17.985653) (xy 22.012729 -17.993406) (xy 21.985478 -17.993868) (xy 21.121878 -17.993868)
			(xy 21.094627 -17.993382) (xy 21.040679 -17.985625) (xy 20.988385 -17.97027) (xy 20.938808 -17.947629)
			(xy 20.892958 -17.918162) (xy 20.851768 -17.882471) (xy 20.816076 -17.841281) (xy 20.78661 -17.79543)
			(xy 20.763969 -17.745853) (xy 20.748614 -17.693559) (xy 20.740858 -17.639611) (xy 16.778525 -17.639611)
			(xy 16.778525 -17.639613) (xy 16.770768 -17.693564) (xy 16.755412 -17.745862) (xy 16.732769 -17.795442)
			(xy 16.703301 -17.841296) (xy 16.667607 -17.882488) (xy 16.626414 -17.918182) (xy 16.580561 -17.94765)
			(xy 16.53098 -17.970292) (xy 16.478682 -17.985648) (xy 16.424731 -17.993405) (xy 16.397478 -17.993868)
			(xy 15.533878 -17.993868) (xy 15.506627 -17.993382) (xy 15.452679 -17.985625) (xy 15.400385 -17.97027)
			(xy 15.350808 -17.947629) (xy 15.304958 -17.918162) (xy 15.263768 -17.882471) (xy 15.228076 -17.841281)
			(xy 15.19861 -17.79543) (xy 15.175969 -17.745853) (xy 15.160614 -17.693559) (xy 15.152858 -17.639611)
			(xy 0.509016 -17.639611) (xy 0.509016 -19.164391) (xy 17.945563 -19.164391) (xy 17.945563 -19.109849)
			(xy 17.953326 -19.055862) (xy 17.968692 -19.00353) (xy 17.99135 -18.953917) (xy 18.020837 -18.908033)
			(xy 18.056555 -18.866813) (xy 18.097775 -18.831096) (xy 18.143658 -18.801609) (xy 18.193272 -18.778951)
			(xy 18.245604 -18.763585) (xy 18.299591 -18.755823) (xy 18.326862 -18.75536) (xy 19.190462 -18.75536)
			(xy 19.217731 -18.755843) (xy 19.271715 -18.763605) (xy 19.324045 -18.77897) (xy 19.373655 -18.801627)
			(xy 19.419536 -18.831113) (xy 19.460753 -18.866828) (xy 19.496469 -18.908046) (xy 19.525954 -18.953927)
			(xy 19.548611 -19.003537) (xy 19.563976 -19.055867) (xy 19.571738 -19.109851) (xy 19.571738 -19.163653)
			(xy 23.534838 -19.163653) (xy 23.534838 -19.109147) (xy 23.542595 -19.055195) (xy 23.55795 -19.002897)
			(xy 23.580592 -18.953316) (xy 23.610059 -18.907462) (xy 23.645752 -18.866268) (xy 23.686944 -18.830573)
			(xy 23.732797 -18.801103) (xy 23.782376 -18.778458) (xy 23.834674 -18.763099) (xy 23.888625 -18.755339)
			(xy 23.915878 -18.754852) (xy 24.779478 -18.754852) (xy 24.806729 -18.755394) (xy 24.860677 -18.763147)
			(xy 24.912972 -18.7785) (xy 24.962549 -18.801139) (xy 25.0084 -18.830603) (xy 25.049591 -18.866293)
			(xy 25.085284 -18.907482) (xy 25.114751 -18.953331) (xy 25.137392 -19.002908) (xy 25.152748 -19.055202)
			(xy 25.160505 -19.109149) (xy 25.160505 -19.163651) (xy 25.160505 -19.163653) (xy 29.122838 -19.163653)
			(xy 29.122838 -19.109147) (xy 29.130595 -19.055195) (xy 29.14595 -19.002897) (xy 29.168592 -18.953316)
			(xy 29.198059 -18.907462) (xy 29.233752 -18.866268) (xy 29.274944 -18.830573) (xy 29.320797 -18.801103)
			(xy 29.370376 -18.778458) (xy 29.422674 -18.763099) (xy 29.476625 -18.755339) (xy 29.503878 -18.754852)
			(xy 30.367478 -18.754852) (xy 30.394729 -18.755394) (xy 30.448677 -18.763147) (xy 30.500972 -18.7785)
			(xy 30.550549 -18.801139) (xy 30.5964 -18.830603) (xy 30.637591 -18.866293) (xy 30.673284 -18.907482)
			(xy 30.702751 -18.953331) (xy 30.725392 -19.002908) (xy 30.740748 -19.055202) (xy 30.748505 -19.109149)
			(xy 30.748505 -19.163651) (xy 30.748505 -19.163653) (xy 34.710838 -19.163653) (xy 34.710838 -19.109147)
			(xy 34.718595 -19.055195) (xy 34.73395 -19.002897) (xy 34.756592 -18.953316) (xy 34.786059 -18.907462)
			(xy 34.821752 -18.866268) (xy 34.862944 -18.830573) (xy 34.908797 -18.801103) (xy 34.958376 -18.778458)
			(xy 35.010674 -18.763099) (xy 35.064625 -18.755339) (xy 35.091878 -18.754852) (xy 35.955478 -18.754852)
			(xy 35.982729 -18.755394) (xy 36.036677 -18.763147) (xy 36.088972 -18.7785) (xy 36.138549 -18.801139)
			(xy 36.1844 -18.830603) (xy 36.225591 -18.866293) (xy 36.261284 -18.907482) (xy 36.290751 -18.953331)
			(xy 36.313392 -19.002908) (xy 36.328748 -19.055202) (xy 36.336505 -19.109149) (xy 36.336505 -19.163651)
			(xy 36.336505 -19.163654) (xy 40.604638 -19.163654) (xy 40.604638 -19.109146) (xy 40.612395 -19.055193)
			(xy 40.627751 -19.002894) (xy 40.650395 -18.953312) (xy 40.679863 -18.907457) (xy 40.715558 -18.866262)
			(xy 40.756752 -18.830567) (xy 40.802606 -18.801097) (xy 40.852188 -18.778454) (xy 40.904487 -18.763096)
			(xy 40.95844 -18.755338) (xy 40.985694 -18.754852) (xy 41.849294 -18.754852) (xy 41.876544 -18.755395)
			(xy 41.93049 -18.76315) (xy 41.982783 -18.778504) (xy 42.032359 -18.801144) (xy 42.078208 -18.830609)
			(xy 42.119397 -18.866299) (xy 42.155088 -18.907487) (xy 42.184553 -18.953336) (xy 42.207194 -19.002911)
			(xy 42.222548 -19.055204) (xy 42.230305 -19.10915) (xy 42.230305 -19.16365) (xy 42.230202 -19.164367)
			(xy 46.191446 -19.164367) (xy 46.191446 -19.109833) (xy 46.199207 -19.055855) (xy 46.21457 -19.00353)
			(xy 46.237224 -18.953924) (xy 46.266706 -18.908047) (xy 46.302417 -18.866832) (xy 46.343629 -18.831119)
			(xy 46.389505 -18.801634) (xy 46.439109 -18.778978) (xy 46.491433 -18.763612) (xy 46.545411 -18.755848)
			(xy 46.572678 -18.75536) (xy 47.436278 -18.75536) (xy 47.463552 -18.755778) (xy 47.517544 -18.763538)
			(xy 47.569882 -18.778903) (xy 47.619501 -18.801561) (xy 47.66539 -18.83105) (xy 47.706615 -18.866769)
			(xy 47.742337 -18.907992) (xy 47.771828 -18.95388) (xy 47.794489 -19.003497) (xy 47.809857 -19.055835)
			(xy 47.81762 -19.109826) (xy 47.81762 -19.163657) (xy 51.814615 -19.163657) (xy 51.814615 -19.109143)
			(xy 51.822374 -19.055184) (xy 51.837733 -19.002878) (xy 51.86038 -18.95329) (xy 51.889854 -18.907431)
			(xy 51.925554 -18.866233) (xy 51.966755 -18.830536) (xy 52.012617 -18.801065) (xy 52.062206 -18.778422)
			(xy 52.114513 -18.763067) (xy 52.168473 -18.755313) (xy 52.19573 -18.754852) (xy 53.05933 -18.754852)
			(xy 53.086577 -18.75542) (xy 53.140516 -18.763179) (xy 53.192801 -18.778535) (xy 53.24237 -18.801176)
			(xy 53.288211 -18.83064) (xy 53.329394 -18.866328) (xy 53.365078 -18.907513) (xy 53.394538 -18.953357)
			(xy 53.417175 -19.002927) (xy 53.432527 -19.055214) (xy 53.440282 -19.109153) (xy 53.440282 -19.163647)
			(xy 53.440281 -19.163657) (xy 57.402615 -19.163657) (xy 57.402615 -19.109143) (xy 57.410374 -19.055184)
			(xy 57.425733 -19.002878) (xy 57.44838 -18.95329) (xy 57.477854 -18.907431) (xy 57.513554 -18.866233)
			(xy 57.554755 -18.830536) (xy 57.600617 -18.801065) (xy 57.650206 -18.778422) (xy 57.702513 -18.763067)
			(xy 57.756473 -18.755313) (xy 57.78373 -18.754852) (xy 58.64733 -18.754852) (xy 58.674577 -18.75542)
			(xy 58.728516 -18.763179) (xy 58.780801 -18.778535) (xy 58.83037 -18.801176) (xy 58.876211 -18.83064)
			(xy 58.917394 -18.866328) (xy 58.953078 -18.907513) (xy 58.982538 -18.953357) (xy 59.005175 -19.002927)
			(xy 59.020527 -19.055214) (xy 59.028282 -19.109153) (xy 59.028282 -19.163647) (xy 59.020527 -19.217586)
			(xy 59.005175 -19.269873) (xy 58.982538 -19.319443) (xy 58.953078 -19.365287) (xy 58.917394 -19.406472)
			(xy 58.876211 -19.44216) (xy 58.83037 -19.471624) (xy 58.780801 -19.494265) (xy 58.728516 -19.509621)
			(xy 58.674577 -19.51738) (xy 58.64733 -19.517868) (xy 57.78373 -19.517868) (xy 57.756473 -19.517487)
			(xy 57.702513 -19.509733) (xy 57.650206 -19.494378) (xy 57.600617 -19.471735) (xy 57.554755 -19.442264)
			(xy 57.513554 -19.406567) (xy 57.477854 -19.365369) (xy 57.44838 -19.31951) (xy 57.425733 -19.269922)
			(xy 57.410374 -19.217616) (xy 57.402615 -19.163657) (xy 53.440281 -19.163657) (xy 53.432527 -19.217586)
			(xy 53.417175 -19.269873) (xy 53.394538 -19.319443) (xy 53.365078 -19.365287) (xy 53.329394 -19.406472)
			(xy 53.288211 -19.44216) (xy 53.24237 -19.471624) (xy 53.192801 -19.494265) (xy 53.140516 -19.509621)
			(xy 53.086577 -19.51738) (xy 53.05933 -19.517868) (xy 52.19573 -19.517868) (xy 52.168473 -19.517487)
			(xy 52.114513 -19.509733) (xy 52.062206 -19.494378) (xy 52.012617 -19.471735) (xy 51.966755 -19.442264)
			(xy 51.925554 -19.406567) (xy 51.889854 -19.365369) (xy 51.86038 -19.31951) (xy 51.837733 -19.269922)
			(xy 51.822374 -19.217616) (xy 51.814615 -19.163657) (xy 47.81762 -19.163657) (xy 47.81762 -19.164374)
			(xy 47.809857 -19.218365) (xy 47.794489 -19.270703) (xy 47.771828 -19.32032) (xy 47.742337 -19.366208)
			(xy 47.706615 -19.407431) (xy 47.66539 -19.44315) (xy 47.619501 -19.472639) (xy 47.569882 -19.495297)
			(xy 47.517544 -19.510662) (xy 47.463552 -19.518422) (xy 47.436278 -19.518884) (xy 46.572678 -19.518884)
			(xy 46.545411 -19.518352) (xy 46.491433 -19.510588) (xy 46.439109 -19.495222) (xy 46.389505 -19.472566)
			(xy 46.343629 -19.443081) (xy 46.302417 -19.407368) (xy 46.266706 -19.366153) (xy 46.237224 -19.320276)
			(xy 46.21457 -19.27067) (xy 46.199207 -19.218345) (xy 46.191446 -19.164367) (xy 42.230202 -19.164367)
			(xy 42.222548 -19.217596) (xy 42.207194 -19.269889) (xy 42.184553 -19.319464) (xy 42.155088 -19.365313)
			(xy 42.119397 -19.406501) (xy 42.078208 -19.442191) (xy 42.032359 -19.471656) (xy 41.982783 -19.494296)
			(xy 41.93049 -19.50965) (xy 41.876544 -19.517405) (xy 41.849294 -19.517868) (xy 40.985694 -19.517868)
			(xy 40.95844 -19.517462) (xy 40.904487 -19.509704) (xy 40.852188 -19.494346) (xy 40.802606 -19.471703)
			(xy 40.756752 -19.442233) (xy 40.715558 -19.406538) (xy 40.679863 -19.365343) (xy 40.650395 -19.319488)
			(xy 40.627751 -19.269906) (xy 40.612395 -19.217607) (xy 40.604638 -19.163654) (xy 36.336505 -19.163654)
			(xy 36.328748 -19.217598) (xy 36.313392 -19.269892) (xy 36.290751 -19.319469) (xy 36.261284 -19.365318)
			(xy 36.225591 -19.406507) (xy 36.1844 -19.442197) (xy 36.138549 -19.471661) (xy 36.088972 -19.4943)
			(xy 36.036677 -19.509653) (xy 35.982729 -19.517406) (xy 35.955478 -19.517868) (xy 35.091878 -19.517868)
			(xy 35.064625 -19.517461) (xy 35.010674 -19.509701) (xy 34.958376 -19.494342) (xy 34.908797 -19.471697)
			(xy 34.862944 -19.442227) (xy 34.821752 -19.406532) (xy 34.786059 -19.365338) (xy 34.756592 -19.319484)
			(xy 34.73395 -19.269903) (xy 34.718595 -19.217605) (xy 34.710838 -19.163653) (xy 30.748505 -19.163653)
			(xy 30.740748 -19.217598) (xy 30.725392 -19.269892) (xy 30.702751 -19.319469) (xy 30.673284 -19.365318)
			(xy 30.637591 -19.406507) (xy 30.5964 -19.442197) (xy 30.550549 -19.471661) (xy 30.500972 -19.4943)
			(xy 30.448677 -19.509653) (xy 30.394729 -19.517406) (xy 30.367478 -19.517868) (xy 29.503878 -19.517868)
			(xy 29.476625 -19.517461) (xy 29.422674 -19.509701) (xy 29.370376 -19.494342) (xy 29.320797 -19.471697)
			(xy 29.274944 -19.442227) (xy 29.233752 -19.406532) (xy 29.198059 -19.365338) (xy 29.168592 -19.319484)
			(xy 29.14595 -19.269903) (xy 29.130595 -19.217605) (xy 29.122838 -19.163653) (xy 25.160505 -19.163653)
			(xy 25.152748 -19.217598) (xy 25.137392 -19.269892) (xy 25.114751 -19.319469) (xy 25.085284 -19.365318)
			(xy 25.049591 -19.406507) (xy 25.0084 -19.442197) (xy 24.962549 -19.471661) (xy 24.912972 -19.4943)
			(xy 24.860677 -19.509653) (xy 24.806729 -19.517406) (xy 24.779478 -19.517868) (xy 23.915878 -19.517868)
			(xy 23.888625 -19.517461) (xy 23.834674 -19.509701) (xy 23.782376 -19.494342) (xy 23.732797 -19.471697)
			(xy 23.686944 -19.442227) (xy 23.645752 -19.406532) (xy 23.610059 -19.365338) (xy 23.580592 -19.319484)
			(xy 23.55795 -19.269903) (xy 23.542595 -19.217605) (xy 23.534838 -19.163653) (xy 19.571738 -19.163653)
			(xy 19.571738 -19.164389) (xy 19.563976 -19.218373) (xy 19.548611 -19.270703) (xy 19.525954 -19.320313)
			(xy 19.496469 -19.366194) (xy 19.460753 -19.407412) (xy 19.419536 -19.443127) (xy 19.373655 -19.472613)
			(xy 19.324045 -19.49527) (xy 19.271715 -19.510635) (xy 19.217731 -19.518397) (xy 19.190462 -19.518884)
			(xy 18.326862 -19.518884) (xy 18.299591 -19.518417) (xy 18.245604 -19.510655) (xy 18.193272 -19.495289)
			(xy 18.143658 -19.472631) (xy 18.097775 -19.443144) (xy 18.056555 -19.407427) (xy 18.020837 -19.366207)
			(xy 17.99135 -19.320323) (xy 17.968692 -19.27071) (xy 17.953326 -19.218378) (xy 17.945563 -19.164391)
			(xy 0.509016 -19.164391) (xy 0.509016 -20.327366) (xy 65.88506 -20.327366) (xy 65.885484 -20.289077)
			(xy 65.892086 -20.212783) (xy 65.90523 -20.13734) (xy 65.924819 -20.063309) (xy 65.937384 -20.027138)
			(xy 65.940051 -20.018705) (xy 65.94004 -20.001031) (xy 65.937384 -19.992594) (xy 65.924856 -19.956411)
			(xy 65.905279 -19.88238) (xy 65.892127 -19.806942) (xy 65.885498 -19.730654) (xy 65.88506 -19.692366)
			(xy 65.885582 -19.650174) (xy 65.893576 -19.56617) (xy 65.909488 -19.483301) (xy 65.933176 -19.402311)
			(xy 65.964427 -19.323927) (xy 66.00296 -19.248856) (xy 66.048429 -19.17777) (xy 66.074036 -19.144234)
			(xy 66.079883 -19.13601) (xy 66.085128 -19.116537) (xy 66.082515 -19.096539) (xy 66.077846 -19.087592)
			(xy 66.058798 -19.053767) (xy 66.026006 -18.983399) (xy 65.999468 -18.910441) (xy 65.979384 -18.83545)
			(xy 65.965909 -18.758994) (xy 65.959144 -18.681655) (xy 65.95872 -18.642838) (xy 65.95872 -18.642584)
			(xy 65.959137 -18.60148) (xy 65.966724 -18.519622) (xy 65.981831 -18.438814) (xy 66.00433 -18.359744)
			(xy 66.034029 -18.283087) (xy 66.070674 -18.209498) (xy 66.113953 -18.139604) (xy 66.163496 -18.074001)
			(xy 66.218881 -18.01325) (xy 66.279635 -17.957868) (xy 66.34524 -17.908328) (xy 66.415137 -17.865053)
			(xy 66.488728 -17.828411) (xy 66.565386 -17.798716) (xy 66.644456 -17.776221) (xy 66.725266 -17.761118)
			(xy 66.807124 -17.753535) (xy 66.848228 -17.753076) (xy 66.889911 -17.753577) (xy 66.972911 -17.761363)
			(xy 67.054819 -17.776882) (xy 67.134915 -17.799999) (xy 67.212496 -17.830511) (xy 67.286881 -17.868149)
			(xy 67.357417 -17.912584) (xy 67.423485 -17.963425) (xy 67.484504 -18.020226) (xy 67.53994 -18.082488)
			(xy 67.565016 -18.115788) (xy 67.56527 -18.116042) (xy 67.570757 -18.122776) (xy 67.585223 -18.132372)
			(xy 67.602063 -18.136587) (xy 67.610736 -18.136108) (xy 67.697858 -18.127726) (xy 67.706567 -18.126584)
			(xy 67.722478 -18.119178) (xy 67.734922 -18.1068) (xy 67.739006 -18.099024) (xy 67.739006 -18.098516)
			(xy 67.757258 -18.060702) (xy 67.799884 -17.988356) (xy 67.849141 -17.920351) (xy 67.90459 -17.857291)
			(xy 67.965736 -17.79974) (xy 68.032035 -17.748209) (xy 68.102897 -17.703158) (xy 68.17769 -17.664987)
			(xy 68.255748 -17.634037) (xy 68.336377 -17.610583) (xy 68.418857 -17.594835) (xy 68.502455 -17.586933)
			(xy 68.54444 -17.586452) (xy 68.5868 -17.58693) (xy 68.671136 -17.594986) (xy 68.754325 -17.611023)
			(xy 68.835612 -17.634895) (xy 68.914262 -17.666384) (xy 68.989563 -17.705208) (xy 69.060833 -17.751013)
			(xy 69.127426 -17.803385) (xy 69.18874 -17.86185) (xy 69.244218 -17.925878) (xy 69.293359 -17.99489)
			(xy 69.335718 -18.068261) (xy 69.370911 -18.145325) (xy 69.39862 -18.225386) (xy 69.401856 -18.238724)
			(xy 79.0321 -18.238724) (xy 79.032651 -18.193954) (xy 79.041664 -18.104869) (xy 79.059573 -18.017137)
			(xy 79.086195 -17.931647) (xy 79.10322 -17.890236) (xy 79.106772 -17.880641) (xy 79.106781 -17.860202)
			(xy 79.10322 -17.850612) (xy 79.086184 -17.809205) (xy 79.059551 -17.723717) (xy 79.041646 -17.635983)
			(xy 79.032653 -17.546895) (xy 79.0321 -17.502124) (xy 79.032604 -17.459763) (xy 79.040657 -17.375426)
			(xy 79.056691 -17.292236) (xy 79.080559 -17.210946) (xy 79.112047 -17.132294) (xy 79.150869 -17.056991)
			(xy 79.196672 -16.985719) (xy 79.249043 -16.919123) (xy 79.307508 -16.857808) (xy 79.371536 -16.802327)
			(xy 79.440548 -16.753184) (xy 79.513918 -16.710824) (xy 79.590983 -16.675629) (xy 79.671045 -16.64792)
			(xy 79.753378 -16.627946) (xy 79.837237 -16.615889) (xy 79.921862 -16.611858) (xy 80.006487 -16.615889)
			(xy 80.090346 -16.627946) (xy 80.172679 -16.64792) (xy 80.252741 -16.675629) (xy 80.329806 -16.710824)
			(xy 80.403176 -16.753184) (xy 80.472188 -16.802327) (xy 80.536216 -16.857808) (xy 80.594681 -16.919123)
			(xy 80.647052 -16.985719) (xy 80.692855 -17.056991) (xy 80.731677 -17.132294) (xy 80.763165 -17.210946)
			(xy 80.787033 -17.292236) (xy 80.803067 -17.375426) (xy 80.81112 -17.459763) (xy 80.811624 -17.502124)
			(xy 80.811054 -17.546893) (xy 80.802046 -17.635978) (xy 80.784143 -17.723709) (xy 80.757526 -17.809201)
			(xy 80.740504 -17.850612) (xy 80.736924 -17.860198) (xy 80.736933 -17.880645) (xy 80.740504 -17.890236)
			(xy 80.757551 -17.931638) (xy 80.784182 -18.017129) (xy 80.802084 -18.104863) (xy 80.808854 -18.171951)
			(xy 131.633699 -18.171951) (xy 131.633699 -18.117449) (xy 131.641456 -18.063503) (xy 131.656811 -18.011209)
			(xy 131.679453 -17.961633) (xy 131.708919 -17.915784) (xy 131.744611 -17.874596) (xy 131.785802 -17.838906)
			(xy 131.831653 -17.809442) (xy 131.88123 -17.786804) (xy 131.933524 -17.771451) (xy 131.987471 -17.763698)
			(xy 132.014722 -17.763236) (xy 132.878322 -17.763236) (xy 132.905575 -17.763635) (xy 132.959527 -17.771395)
			(xy 133.011825 -17.786754) (xy 133.061405 -17.809399) (xy 133.107258 -17.838869) (xy 133.148451 -17.874565)
			(xy 133.184144 -17.915759) (xy 133.213611 -17.961614) (xy 133.236254 -18.011196) (xy 133.251609 -18.063495)
			(xy 133.259366 -18.117447) (xy 133.259366 -18.171946) (xy 137.033822 -18.171946) (xy 137.033822 -18.117454)
			(xy 137.041577 -18.063516) (xy 137.056928 -18.01123) (xy 137.079564 -17.961661) (xy 137.109023 -17.915818)
			(xy 137.144706 -17.874633) (xy 137.185887 -17.838946) (xy 137.231728 -17.809482) (xy 137.281294 -17.786841)
			(xy 137.333578 -17.771485) (xy 137.387516 -17.763725) (xy 137.414762 -17.763236) (xy 138.278362 -17.763236)
			(xy 138.30562 -17.763608) (xy 138.359581 -17.771362) (xy 138.41189 -17.786716) (xy 138.46148 -17.809359)
			(xy 138.507344 -17.83883) (xy 138.548546 -17.874528) (xy 138.584247 -17.915726) (xy 138.613722 -17.961586)
			(xy 138.63637 -18.011175) (xy 138.65173 -18.063482) (xy 138.659489 -18.117442) (xy 138.659489 -18.17195)
			(xy 140.633699 -18.17195) (xy 140.633699 -18.11745) (xy 140.641455 -18.063505) (xy 140.65681 -18.011213)
			(xy 140.67945 -17.961638) (xy 140.708915 -17.91579) (xy 140.744605 -17.874602) (xy 140.785793 -17.838913)
			(xy 140.831642 -17.809448) (xy 140.881217 -17.786808) (xy 140.933509 -17.771455) (xy 140.987454 -17.763699)
			(xy 141.014704 -17.763236) (xy 141.878304 -17.763236) (xy 141.905558 -17.763634) (xy 141.959512 -17.771392)
			(xy 142.011812 -17.786749) (xy 142.061394 -17.809393) (xy 142.10725 -17.838863) (xy 142.148444 -17.874559)
			(xy 142.184139 -17.915754) (xy 142.213609 -17.961609) (xy 142.236252 -18.011192) (xy 142.251609 -18.063492)
			(xy 142.259366 -18.117446) (xy 142.259366 -18.171954) (xy 142.251609 -18.225908) (xy 142.236252 -18.278208)
			(xy 142.213609 -18.327791) (xy 142.184139 -18.373646) (xy 142.148444 -18.414841) (xy 142.10725 -18.450537)
			(xy 142.061394 -18.480007) (xy 142.011812 -18.502651) (xy 141.959512 -18.518008) (xy 141.905558 -18.525766)
			(xy 141.878304 -18.526252) (xy 141.014704 -18.526252) (xy 140.987454 -18.525701) (xy 140.933509 -18.517945)
			(xy 140.881217 -18.502592) (xy 140.831642 -18.479952) (xy 140.785793 -18.450487) (xy 140.744605 -18.414798)
			(xy 140.708915 -18.37361) (xy 140.67945 -18.327762) (xy 140.65681 -18.278187) (xy 140.641455 -18.225895)
			(xy 140.633699 -18.17195) (xy 138.659489 -18.17195) (xy 138.659489 -18.171958) (xy 138.65173 -18.225918)
			(xy 138.63637 -18.278225) (xy 138.613722 -18.327814) (xy 138.584247 -18.373674) (xy 138.548546 -18.414872)
			(xy 138.507344 -18.45057) (xy 138.46148 -18.480041) (xy 138.41189 -18.502684) (xy 138.359581 -18.518038)
			(xy 138.30562 -18.525792) (xy 138.278362 -18.526252) (xy 137.414762 -18.526252) (xy 137.387516 -18.525675)
			(xy 137.333578 -18.517915) (xy 137.281294 -18.502559) (xy 137.231728 -18.479918) (xy 137.185887 -18.450454)
			(xy 137.144706 -18.414767) (xy 137.109023 -18.373582) (xy 137.079564 -18.327739) (xy 137.056928 -18.27817)
			(xy 137.041577 -18.225884) (xy 137.033822 -18.171946) (xy 133.259366 -18.171946) (xy 133.259366 -18.171953)
			(xy 133.251609 -18.225905) (xy 133.236254 -18.278204) (xy 133.213611 -18.327786) (xy 133.184144 -18.373641)
			(xy 133.148451 -18.414835) (xy 133.107258 -18.450531) (xy 133.061405 -18.480001) (xy 133.011825 -18.502646)
			(xy 132.959527 -18.518005) (xy 132.905575 -18.525765) (xy 132.878322 -18.526252) (xy 132.014722 -18.526252)
			(xy 131.987471 -18.525702) (xy 131.933524 -18.517949) (xy 131.88123 -18.502596) (xy 131.831653 -18.479958)
			(xy 131.785802 -18.450494) (xy 131.744611 -18.414804) (xy 131.708919 -18.373616) (xy 131.679453 -18.327767)
			(xy 131.656811 -18.278191) (xy 131.641456 -18.225897) (xy 131.633699 -18.171951) (xy 80.808854 -18.171951)
			(xy 80.811074 -18.193953) (xy 80.811624 -18.238724) (xy 80.81112 -18.281085) (xy 80.803067 -18.365422)
			(xy 80.787033 -18.448612) (xy 80.763165 -18.529902) (xy 80.731677 -18.608554) (xy 80.692855 -18.683857)
			(xy 80.647052 -18.755129) (xy 80.594681 -18.821725) (xy 80.536216 -18.88304) (xy 80.472188 -18.938521)
			(xy 80.403176 -18.987664) (xy 80.329806 -19.030024) (xy 80.252741 -19.065219) (xy 80.172679 -19.092928)
			(xy 80.090346 -19.112902) (xy 80.006487 -19.124959) (xy 79.921862 -19.128991) (xy 79.837237 -19.124959)
			(xy 79.753378 -19.112902) (xy 79.671045 -19.092928) (xy 79.590983 -19.065219) (xy 79.513918 -19.030024)
			(xy 79.440548 -18.987664) (xy 79.371536 -18.938521) (xy 79.307508 -18.88304) (xy 79.249043 -18.821725)
			(xy 79.196672 -18.755129) (xy 79.150869 -18.683857) (xy 79.112047 -18.608554) (xy 79.080559 -18.529902)
			(xy 79.056691 -18.448612) (xy 79.040657 -18.365422) (xy 79.032604 -18.281085) (xy 79.0321 -18.238724)
			(xy 69.401856 -18.238724) (xy 69.418593 -18.307718) (xy 69.430649 -18.391576) (xy 69.434681 -18.4762)
			(xy 69.430649 -18.560824) (xy 69.418593 -18.644682) (xy 69.39862 -18.727014) (xy 69.370911 -18.807075)
			(xy 69.335718 -18.884139) (xy 69.293359 -18.95751) (xy 69.244218 -19.026522) (xy 69.18874 -19.09055)
			(xy 69.127426 -19.149015) (xy 69.060833 -19.201387) (xy 68.989563 -19.247192) (xy 68.914262 -19.286016)
			(xy 68.835612 -19.317505) (xy 68.754325 -19.341377) (xy 68.671136 -19.357414) (xy 68.5868 -19.36547)
			(xy 68.54444 -19.365976) (xy 68.502753 -19.365468) (xy 68.419745 -19.357644) (xy 68.337834 -19.342089)
			(xy 68.257737 -19.31894) (xy 68.180157 -19.288398) (xy 68.105774 -19.250734) (xy 68.035242 -19.206275)
			(xy 67.969177 -19.155414) (xy 67.90816 -19.098595) (xy 67.852727 -19.036317) (xy 67.827652 -19.00301)
			(xy 67.827398 -19.002756) (xy 67.821873 -18.996058) (xy 67.807425 -18.986454) (xy 67.790601 -18.982223)
			(xy 67.781932 -18.98269) (xy 67.69481 -18.991072) (xy 67.686098 -18.992195) (xy 67.670187 -18.999611)
			(xy 67.657745 -19.011995) (xy 67.653662 -19.019774) (xy 67.653662 -19.020282) (xy 67.63179 -19.065383)
			(xy 67.579339 -19.150805) (xy 67.549014 -19.190716) (xy 67.543272 -19.198996) (xy 67.538026 -19.218428)
			(xy 67.540615 -19.238388) (xy 67.545204 -19.247358) (xy 67.564269 -19.281203) (xy 67.597117 -19.351604)
			(xy 67.623706 -19.424598) (xy 67.643834 -19.499632) (xy 67.657349 -19.576134) (xy 67.664146 -19.653523)
			(xy 67.664584 -19.692366) (xy 67.664167 -19.730656) (xy 67.657563 -19.806949) (xy 67.644416 -19.882392)
			(xy 67.624826 -19.956423) (xy 67.61226 -19.992594) (xy 67.609626 -20.001035) (xy 67.609615 -20.018702)
			(xy 67.61226 -20.027138) (xy 67.624799 -20.063317) (xy 67.644373 -20.13735) (xy 67.653158 -20.187755)
			(xy 138.765443 -20.187755) (xy 138.765443 -20.133245) (xy 138.773201 -20.079289) (xy 138.788559 -20.026987)
			(xy 138.811205 -19.977403) (xy 138.840677 -19.931547) (xy 138.876376 -19.890352) (xy 138.917574 -19.854657)
			(xy 138.963433 -19.825189) (xy 139.013019 -19.802547) (xy 139.065322 -19.787194) (xy 139.119279 -19.779441)
			(xy 139.146534 -19.77898) (xy 140.137134 -19.77898) (xy 140.164383 -19.779493) (xy 140.218325 -19.787253)
			(xy 140.270614 -19.80261) (xy 140.320185 -19.825253) (xy 140.36603 -19.854719) (xy 140.407215 -19.890409)
			(xy 140.442901 -19.931597) (xy 140.449617 -19.942048) (xy 175.988472 -19.942048) (xy 175.988976 -19.899687)
			(xy 175.997029 -19.81535) (xy 176.013063 -19.73216) (xy 176.036931 -19.65087) (xy 176.068419 -19.572218)
			(xy 176.107241 -19.496915) (xy 176.153044 -19.425643) (xy 176.205415 -19.359047) (xy 176.26388 -19.297732)
			(xy 176.327908 -19.242251) (xy 176.39692 -19.193108) (xy 176.47029 -19.150748) (xy 176.547355 -19.115553)
			(xy 176.627417 -19.087844) (xy 176.70975 -19.06787) (xy 176.793609 -19.055813) (xy 176.878234 -19.051782)
			(xy 176.962859 -19.055813) (xy 177.046718 -19.06787) (xy 177.129051 -19.087844) (xy 177.209113 -19.115553)
			(xy 177.286178 -19.150748) (xy 177.359548 -19.193108) (xy 177.42856 -19.242251) (xy 177.492588 -19.297732)
			(xy 177.551053 -19.359047) (xy 177.603424 -19.425643) (xy 177.649227 -19.496915) (xy 177.688049 -19.572218)
			(xy 177.719537 -19.65087) (xy 177.743405 -19.73216) (xy 177.759439 -19.81535) (xy 177.767492 -19.899687)
			(xy 177.767996 -19.942048) (xy 177.767398 -19.98792) (xy 177.757891 -20.079169) (xy 177.739034 -20.168954)
			(xy 177.725578 -20.212812) (xy 177.722752 -20.223379) (xy 177.72523 -20.245087) (xy 177.730404 -20.254722)
			(xy 177.750836 -20.289402) (xy 177.786035 -20.361795) (xy 177.814552 -20.437071) (xy 177.836153 -20.514616)
			(xy 177.850661 -20.593794) (xy 177.857958 -20.67396) (xy 177.85842 -20.714208) (xy 177.85842 -20.715224)
			(xy 177.857839 -20.760561) (xy 177.84856 -20.850758) (xy 177.830152 -20.939544) (xy 177.817018 -20.98294)
			(xy 177.81462 -20.991841) (xy 177.815621 -21.010233) (xy 177.823067 -21.02708) (xy 177.835994 -21.040201)
			(xy 177.844196 -21.044408) (xy 177.8824 -21.062505) (xy 177.955518 -21.104946) (xy 178.024281 -21.15413)
			(xy 178.088069 -21.209614) (xy 178.146306 -21.270898) (xy 178.198469 -21.337429) (xy 178.244087 -21.408608)
			(xy 178.282748 -21.483792) (xy 178.314103 -21.562305) (xy 178.337871 -21.643437) (xy 178.353837 -21.726458)
			(xy 178.361856 -21.810619) (xy 178.362356 -21.85289) (xy 178.361892 -21.894005) (xy 178.354306 -21.975884)
			(xy 178.339197 -22.056714) (xy 178.316694 -22.135805) (xy 178.28699 -22.212482) (xy 178.250337 -22.286091)
			(xy 178.207049 -22.356005) (xy 178.157495 -22.421626) (xy 178.102097 -22.482394) (xy 178.041329 -22.537792)
			(xy 177.975708 -22.587347) (xy 177.905795 -22.630635) (xy 177.832186 -22.667288) (xy 177.755509 -22.696993)
			(xy 177.676418 -22.719496) (xy 177.595588 -22.734605) (xy 177.513709 -22.742192) (xy 177.472594 -22.742652)
			(xy 177.429071 -22.742084) (xy 177.34244 -22.73358) (xy 177.257055 -22.716655) (xy 177.173731 -22.69147)
			(xy 177.093266 -22.658267) (xy 177.016429 -22.617362) (xy 176.943956 -22.569146) (xy 176.876538 -22.514083)
			(xy 176.814822 -22.452697) (xy 176.759398 -22.385575) (xy 176.710795 -22.313361) (xy 176.669479 -22.236745)
			(xy 176.652174 -22.196806) (xy 176.647921 -22.187866) (xy 176.633936 -22.17388) (xy 176.624996 -22.169628)
			(xy 176.585068 -22.152314) (xy 176.508472 -22.110985) (xy 176.436278 -22.062372) (xy 176.369178 -22.006941)
			(xy 176.307813 -21.945221) (xy 176.252769 -21.877802) (xy 176.204574 -21.80533) (xy 176.163687 -21.728496)
			(xy 176.1305 -21.648037) (xy 176.105331 -21.564721) (xy 176.088419 -21.479345) (xy 176.079928 -21.392725)
			(xy 176.079404 -21.349208) (xy 176.079404 -21.348446) (xy 176.079814 -21.310226) (xy 176.086378 -21.234067)
			(xy 176.099462 -21.158755) (xy 176.118968 -21.084845) (xy 176.131474 -21.048726) (xy 176.134055 -21.040409)
			(xy 176.134058 -21.023006) (xy 176.131474 -21.01469) (xy 176.118957 -20.978475) (xy 176.099434 -20.904375)
			(xy 176.086349 -20.828871) (xy 176.079799 -20.752523) (xy 176.079404 -20.714208) (xy 176.07999 -20.668344)
			(xy 176.089425 -20.577104) (xy 176.108186 -20.487316) (xy 176.121568 -20.443444) (xy 176.124428 -20.432883)
			(xy 176.121929 -20.411168) (xy 176.116742 -20.401534) (xy 176.096312 -20.366847) (xy 176.06107 -20.294464)
			(xy 176.032509 -20.219194) (xy 176.010862 -20.141652) (xy 175.996306 -20.062472) (xy 175.988959 -19.982301)
			(xy 175.988472 -19.942048) (xy 140.449617 -19.942048) (xy 140.472364 -19.977445) (xy 140.495002 -20.027018)
			(xy 140.510354 -20.079308) (xy 140.51811 -20.133251) (xy 140.51811 -20.187749) (xy 140.510354 -20.241692)
			(xy 140.495002 -20.293982) (xy 140.472364 -20.343555) (xy 140.442901 -20.389403) (xy 140.407215 -20.430591)
			(xy 140.36603 -20.466281) (xy 140.320185 -20.495747) (xy 140.270614 -20.51839) (xy 140.218325 -20.533747)
			(xy 140.164383 -20.541507) (xy 140.137134 -20.541996) (xy 139.146534 -20.541996) (xy 139.119279 -20.541559)
			(xy 139.065322 -20.533806) (xy 139.013019 -20.518453) (xy 138.963433 -20.495811) (xy 138.917574 -20.466343)
			(xy 138.876376 -20.430648) (xy 138.840677 -20.389453) (xy 138.811205 -20.343597) (xy 138.788559 -20.294013)
			(xy 138.773201 -20.241711) (xy 138.765443 -20.187755) (xy 67.653158 -20.187755) (xy 67.657521 -20.212789)
			(xy 67.664147 -20.289078) (xy 67.664584 -20.327366) (xy 67.66408 -20.369727) (xy 67.656027 -20.454064)
			(xy 67.639993 -20.537254) (xy 67.616125 -20.618544) (xy 67.584637 -20.697196) (xy 67.545815 -20.772499)
			(xy 67.500012 -20.843771) (xy 67.447641 -20.910367) (xy 67.389176 -20.971682) (xy 67.325148 -21.027163)
			(xy 67.256136 -21.076306) (xy 67.182766 -21.118666) (xy 67.105701 -21.153861) (xy 67.025639 -21.18157)
			(xy 66.943306 -21.201544) (xy 66.859447 -21.213601) (xy 66.774822 -21.217633) (xy 66.690197 -21.213601)
			(xy 66.606338 -21.201544) (xy 66.524005 -21.18157) (xy 66.443943 -21.153861) (xy 66.366878 -21.118666)
			(xy 66.293508 -21.076306) (xy 66.224496 -21.027163) (xy 66.160468 -20.971682) (xy 66.102003 -20.910367)
			(xy 66.049632 -20.843771) (xy 66.003829 -20.772499) (xy 65.965007 -20.697196) (xy 65.933519 -20.618544)
			(xy 65.909651 -20.537254) (xy 65.893617 -20.454064) (xy 65.885564 -20.369727) (xy 65.88506 -20.327366)
			(xy 0.509016 -20.327366) (xy 0.509016 -22.309271) (xy 65.993006 -22.309271) (xy 65.993006 -22.224549)
			(xy 66.001059 -22.140212) (xy 66.017093 -22.057022) (xy 66.040961 -21.975732) (xy 66.072449 -21.89708)
			(xy 66.111271 -21.821777) (xy 66.157074 -21.750505) (xy 66.209445 -21.683909) (xy 66.26791 -21.622594)
			(xy 66.331938 -21.567113) (xy 66.40095 -21.51797) (xy 66.47432 -21.47561) (xy 66.551385 -21.440415)
			(xy 66.631447 -21.412706) (xy 66.71378 -21.392732) (xy 66.797639 -21.380675) (xy 66.882264 -21.376644)
			(xy 66.966889 -21.380675) (xy 67.050748 -21.392732) (xy 67.133081 -21.412706) (xy 67.213143 -21.440415)
			(xy 67.290208 -21.47561) (xy 67.363578 -21.51797) (xy 67.43259 -21.567113) (xy 67.496618 -21.622594)
			(xy 67.555083 -21.683909) (xy 67.607454 -21.750505) (xy 67.653257 -21.821777) (xy 67.692079 -21.89708)
			(xy 67.723567 -21.975732) (xy 67.747435 -22.057022) (xy 67.763469 -22.140212) (xy 67.771522 -22.224549)
			(xy 67.772026 -22.26691) (xy 67.771522 -22.309271) (xy 67.763469 -22.393608) (xy 67.747435 -22.476798)
			(xy 67.723567 -22.558088) (xy 67.722853 -22.559872) (xy 114.452596 -22.559872) (xy 114.452596 -22.505328)
			(xy 114.460358 -22.45134) (xy 114.475725 -22.399006) (xy 114.498383 -22.349391) (xy 114.527872 -22.303506)
			(xy 114.563591 -22.262285) (xy 114.604813 -22.226567) (xy 114.650698 -22.19708) (xy 114.700313 -22.174422)
			(xy 114.752648 -22.159056) (xy 114.806636 -22.151295) (xy 114.833908 -22.150832) (xy 115.697508 -22.150832)
			(xy 115.724777 -22.151331) (xy 115.778758 -22.159093) (xy 115.831086 -22.174459) (xy 115.880695 -22.197116)
			(xy 115.926574 -22.226601) (xy 115.96779 -22.262316) (xy 116.003504 -22.303533) (xy 116.032988 -22.349412)
			(xy 116.055644 -22.399021) (xy 116.071008 -22.451349) (xy 116.07877 -22.505331) (xy 116.07877 -22.559869)
			(xy 116.071008 -22.613851) (xy 116.055644 -22.666179) (xy 116.032988 -22.715788) (xy 116.003504 -22.761667)
			(xy 115.96779 -22.802884) (xy 115.926574 -22.838599) (xy 115.880695 -22.868084) (xy 115.831086 -22.890741)
			(xy 115.778758 -22.906107) (xy 115.724777 -22.913869) (xy 115.697508 -22.914356) (xy 114.833908 -22.914356)
			(xy 114.806636 -22.913905) (xy 114.752648 -22.906144) (xy 114.700313 -22.890778) (xy 114.650698 -22.86812)
			(xy 114.604813 -22.838633) (xy 114.563591 -22.802915) (xy 114.527872 -22.761694) (xy 114.498383 -22.715809)
			(xy 114.475725 -22.666194) (xy 114.460358 -22.61386) (xy 114.452596 -22.559872) (xy 67.722853 -22.559872)
			(xy 67.692079 -22.63674) (xy 67.653257 -22.712043) (xy 67.607454 -22.783315) (xy 67.555083 -22.849911)
			(xy 67.496618 -22.911226) (xy 67.43259 -22.966707) (xy 67.363578 -23.01585) (xy 67.361784 -23.016886)
			(xy 136.323137 -23.016886) (xy 136.327046 -22.962479) (xy 136.338661 -22.909183) (xy 136.357746 -22.858084)
			(xy 136.383911 -22.810221) (xy 136.416623 -22.766572) (xy 136.435592 -22.74697) (xy 137.046208 -22.1361)
			(xy 137.06783 -22.115331) (xy 137.116345 -22.080114) (xy 137.169764 -22.052902) (xy 137.226775 -22.034363)
			(xy 137.285982 -22.024951) (xy 137.315956 -22.02434) (xy 137.31621 -22.02434) (xy 137.34348 -22.024815)
			(xy 137.397464 -22.032578) (xy 137.449794 -22.047945) (xy 137.499404 -22.070602) (xy 137.545285 -22.10009)
			(xy 137.586503 -22.135806) (xy 137.622218 -22.177025) (xy 137.651703 -22.222907) (xy 137.674359 -22.272518)
			(xy 137.689724 -22.324848) (xy 137.697486 -22.378832) (xy 137.697972 -22.406102) (xy 137.697972 -22.406356)
			(xy 137.6974 -22.436336) (xy 137.688023 -22.495559) (xy 137.669494 -22.552585) (xy 137.64227 -22.606009)
			(xy 137.60702 -22.654514) (xy 137.586212 -22.676104) (xy 136.975342 -23.28672) (xy 136.955728 -23.305677)
			(xy 136.912079 -23.338389) (xy 136.864216 -23.364554) (xy 136.813117 -23.383639) (xy 136.759821 -23.395254)
			(xy 136.705414 -23.399163) (xy 136.651005 -23.395286) (xy 136.597702 -23.383703) (xy 136.546591 -23.364649)
			(xy 136.498713 -23.338513) (xy 136.455044 -23.305826) (xy 136.416474 -23.267256) (xy 136.383787 -23.223587)
			(xy 136.357651 -23.175709) (xy 136.338597 -23.124598) (xy 136.327014 -23.071295) (xy 136.323137 -23.016886)
			(xy 67.361784 -23.016886) (xy 67.290208 -23.05821) (xy 67.213143 -23.093405) (xy 67.133081 -23.121114)
			(xy 67.050748 -23.141088) (xy 66.966889 -23.153145) (xy 66.882264 -23.157177) (xy 66.797639 -23.153145)
			(xy 66.71378 -23.141088) (xy 66.631447 -23.121114) (xy 66.551385 -23.093405) (xy 66.47432 -23.05821)
			(xy 66.40095 -23.01585) (xy 66.331938 -22.966707) (xy 66.26791 -22.911226) (xy 66.209445 -22.849911)
			(xy 66.157074 -22.783315) (xy 66.111271 -22.712043) (xy 66.072449 -22.63674) (xy 66.040961 -22.558088)
			(xy 66.017093 -22.476798) (xy 66.001059 -22.393608) (xy 65.993006 -22.309271) (xy 0.509016 -22.309271)
			(xy 0.509016 -23.593552) (xy 189.619128 -23.593552) (xy 189.619128 -23.593298) (xy 189.619711 -23.54856)
			(xy 189.628722 -23.459539) (xy 189.646623 -23.371871) (xy 189.673232 -23.286444) (xy 189.690248 -23.245064)
			(xy 189.69384 -23.235481) (xy 189.693822 -23.215031) (xy 189.690248 -23.20544) (xy 189.673222 -23.164064)
			(xy 189.646604 -23.078637) (xy 189.6287 -22.990968) (xy 189.619692 -22.901945) (xy 189.619128 -22.857206)
			(xy 189.619128 -22.856952) (xy 189.619632 -22.814604) (xy 189.627683 -22.73029) (xy 189.643712 -22.647124)
			(xy 189.667573 -22.565857) (xy 189.699052 -22.487227) (xy 189.737863 -22.411946) (xy 189.783653 -22.340694)
			(xy 189.836009 -22.274118) (xy 189.894457 -22.21282) (xy 189.958467 -22.157355) (xy 190.027459 -22.108226)
			(xy 190.100809 -22.065877) (xy 190.177852 -22.030693) (xy 190.257891 -22.002991) (xy 190.3402 -21.983023)
			(xy 190.424035 -21.97097) (xy 190.508636 -21.96694) (xy 190.593237 -21.97097) (xy 190.677072 -21.983023)
			(xy 190.759381 -22.002991) (xy 190.83942 -22.030693) (xy 190.916463 -22.065877) (xy 190.989813 -22.108226)
			(xy 191.058805 -22.157355) (xy 191.122815 -22.21282) (xy 191.181263 -22.274118) (xy 191.233619 -22.340694)
			(xy 191.279409 -22.411946) (xy 191.31822 -22.487227) (xy 191.349699 -22.565857) (xy 191.37356 -22.647124)
			(xy 191.389589 -22.73029) (xy 191.39764 -22.814604) (xy 191.398144 -22.856952) (xy 191.398144 -22.857206)
			(xy 191.397557 -22.901944) (xy 191.388547 -22.990965) (xy 191.370647 -23.078632) (xy 191.344039 -23.16406)
			(xy 191.327024 -23.20544) (xy 191.323489 -23.215039) (xy 191.323471 -23.235473) (xy 191.327024 -23.245064)
			(xy 191.344055 -23.286438) (xy 191.370671 -23.371866) (xy 191.388573 -23.459535) (xy 191.39758 -23.548559)
			(xy 191.398144 -23.593298) (xy 191.398144 -23.593552) (xy 191.39764 -23.6359) (xy 191.389589 -23.720214)
			(xy 191.37356 -23.80338) (xy 191.349699 -23.884647) (xy 191.31822 -23.963277) (xy 191.279409 -24.038558)
			(xy 191.233619 -24.10981) (xy 191.181263 -24.176386) (xy 191.122815 -24.237684) (xy 191.058805 -24.293149)
			(xy 190.989813 -24.342278) (xy 190.916463 -24.384627) (xy 190.83942 -24.419811) (xy 190.759381 -24.447513)
			(xy 190.677072 -24.467481) (xy 190.593237 -24.479534) (xy 190.508636 -24.483565) (xy 190.424035 -24.479534)
			(xy 190.3402 -24.467481) (xy 190.257891 -24.447513) (xy 190.177852 -24.419811) (xy 190.100809 -24.384627)
			(xy 190.027459 -24.342278) (xy 189.958467 -24.293149) (xy 189.894457 -24.237684) (xy 189.836009 -24.176386)
			(xy 189.783653 -24.10981) (xy 189.737863 -24.038558) (xy 189.699052 -23.963277) (xy 189.667573 -23.884647)
			(xy 189.643712 -23.80338) (xy 189.627683 -23.720214) (xy 189.619632 -23.6359) (xy 189.619128 -23.593552)
			(xy 0.509016 -23.593552) (xy 0.509016 -25.56891) (xy 65.510156 -25.56891) (xy 65.510621 -25.527206)
			(xy 65.518403 -25.444163) (xy 65.533928 -25.362214) (xy 65.557059 -25.282079) (xy 65.587593 -25.204462)
			(xy 65.625262 -25.130046) (xy 65.669734 -25.059485) (xy 65.720619 -24.993398) (xy 65.777469 -24.932368)
			(xy 65.839786 -24.876929) (xy 65.873122 -24.851868) (xy 65.88167 -24.844931) (xy 65.892346 -24.825708)
			(xy 65.893696 -24.814784) (xy 65.897332 -24.773398) (xy 65.911399 -24.69151) (xy 65.933041 -24.611291)
			(xy 65.962067 -24.53344) (xy 65.998226 -24.458634) (xy 66.041203 -24.387525) (xy 66.090622 -24.320733)
			(xy 66.146054 -24.25884) (xy 66.207015 -24.202385) (xy 66.272974 -24.15186) (xy 66.343357 -24.107705)
			(xy 66.41755 -24.070304) (xy 66.494907 -24.039985) (xy 66.574755 -24.01701) (xy 66.656396 -24.00158)
			(xy 66.739121 -23.99383) (xy 66.780664 -23.993348) (xy 66.824459 -23.993873) (xy 66.911625 -24.002491)
			(xy 66.997521 -24.019637) (xy 67.081315 -24.045145) (xy 67.162195 -24.078768) (xy 67.201034 -24.099012)
			(xy 67.2125 -24.10443) (xy 67.237828 -24.10443) (xy 67.249294 -24.099012) (xy 67.288138 -24.078781)
			(xy 67.369023 -24.045174) (xy 67.452816 -24.019672) (xy 67.538709 -24.002521) (xy 67.62587 -23.993888)
			(xy 67.669664 -23.993348) (xy 67.713459 -23.993873) (xy 67.800625 -24.002491) (xy 67.886521 -24.019637)
			(xy 67.970315 -24.045145) (xy 68.051195 -24.078768) (xy 68.090034 -24.099012) (xy 68.1015 -24.10443)
			(xy 68.126828 -24.10443) (xy 68.138294 -24.099012) (xy 68.177138 -24.078781) (xy 68.258023 -24.045174)
			(xy 68.341816 -24.019672) (xy 68.427709 -24.002521) (xy 68.51487 -23.993888) (xy 68.558664 -23.993348)
			(xy 68.607651 -23.994055) (xy 68.705028 -24.00487) (xy 68.752974 -24.014938) (xy 68.762324 -24.016604)
			(xy 68.781086 -24.013776) (xy 68.797533 -24.004314) (xy 68.803774 -23.997158) (xy 68.831851 -23.962886)
			(xy 68.893786 -23.899527) (xy 68.961714 -23.842641) (xy 69.034963 -23.792791) (xy 69.112805 -23.750472)
			(xy 69.19447 -23.716104) (xy 69.279148 -23.690027) (xy 69.365999 -23.672499) (xy 69.454163 -23.663695)
			(xy 69.498464 -23.663148) (xy 69.540827 -23.663615) (xy 69.625169 -23.671665) (xy 69.708365 -23.687697)
			(xy 69.789659 -23.711564) (xy 69.868317 -23.743051) (xy 69.943625 -23.781873) (xy 70.014902 -23.827677)
			(xy 70.081502 -23.880049) (xy 70.142823 -23.938516) (xy 70.198307 -24.002546) (xy 70.247454 -24.071561)
			(xy 70.250564 -24.076947) (xy 112.652614 -24.076947) (xy 112.652614 -24.022453) (xy 112.660369 -23.968515)
			(xy 112.67572 -23.916228) (xy 112.698356 -23.866659) (xy 112.727815 -23.820815) (xy 112.763499 -23.77963)
			(xy 112.80468 -23.743942) (xy 112.85052 -23.714477) (xy 112.900087 -23.691836) (xy 112.952372 -23.676478)
			(xy 113.006309 -23.668717) (xy 113.033556 -23.668228) (xy 113.897156 -23.668228) (xy 113.924413 -23.668616)
			(xy 113.978374 -23.676369) (xy 114.030682 -23.691722) (xy 114.080273 -23.714364) (xy 114.126136 -23.743834)
			(xy 114.167338 -23.779531) (xy 114.20304 -23.820729) (xy 114.232514 -23.866588) (xy 114.255162 -23.916176)
			(xy 114.270522 -23.968483) (xy 114.278281 -24.022443) (xy 114.278281 -24.076957) (xy 114.270522 -24.130917)
			(xy 114.255235 -24.182975) (xy 116.218856 -24.182975) (xy 116.218856 -24.128425) (xy 116.226619 -24.074429)
			(xy 116.241989 -24.022088) (xy 116.264651 -23.972468) (xy 116.294144 -23.926577) (xy 116.329868 -23.885352)
			(xy 116.371096 -23.84963) (xy 116.416989 -23.820139) (xy 116.466611 -23.79748) (xy 116.518953 -23.782114)
			(xy 116.572949 -23.774354) (xy 116.600224 -23.773892) (xy 117.463824 -23.773892) (xy 117.491089 -23.774472)
			(xy 117.545063 -23.782235) (xy 117.597384 -23.797601) (xy 117.646985 -23.820256) (xy 117.692857 -23.849739)
			(xy 117.734067 -23.88545) (xy 117.769776 -23.926662) (xy 117.799256 -23.972536) (xy 117.821907 -24.022139)
			(xy 117.83727 -24.07446) (xy 117.84503 -24.128435) (xy 117.84503 -24.182965) (xy 117.83727 -24.23694)
			(xy 117.821907 -24.289261) (xy 117.799256 -24.338864) (xy 117.769776 -24.384738) (xy 117.734067 -24.42595)
			(xy 117.692857 -24.461661) (xy 117.646985 -24.491144) (xy 117.597384 -24.513799) (xy 117.545063 -24.529165)
			(xy 117.491089 -24.536928) (xy 117.463824 -24.537416) (xy 116.600224 -24.537416) (xy 116.572949 -24.537046)
			(xy 116.518953 -24.529286) (xy 116.466611 -24.51392) (xy 116.416989 -24.491261) (xy 116.371096 -24.46177)
			(xy 116.329868 -24.426049) (xy 116.294144 -24.384823) (xy 116.264651 -24.338932) (xy 116.241989 -24.289312)
			(xy 116.226619 -24.236971) (xy 116.218856 -24.182975) (xy 114.255235 -24.182975) (xy 114.255162 -24.183224)
			(xy 114.232514 -24.232812) (xy 114.20304 -24.278671) (xy 114.167338 -24.319869) (xy 114.126136 -24.355566)
			(xy 114.080273 -24.385036) (xy 114.030682 -24.407678) (xy 113.978374 -24.423031) (xy 113.924414 -24.430784)
			(xy 113.897156 -24.431244) (xy 113.033556 -24.431244) (xy 113.006309 -24.430683) (xy 112.952372 -24.422922)
			(xy 112.900087 -24.407564) (xy 112.85052 -24.384923) (xy 112.80468 -24.355458) (xy 112.763499 -24.31977)
			(xy 112.727815 -24.278585) (xy 112.698356 -24.232741) (xy 112.67572 -24.183172) (xy 112.660369 -24.130885)
			(xy 112.652614 -24.076947) (xy 70.250564 -24.076947) (xy 70.289818 -24.144935) (xy 70.325015 -24.222004)
			(xy 70.352727 -24.302069) (xy 70.372702 -24.384407) (xy 70.38476 -24.46827) (xy 70.388792 -24.5529)
			(xy 70.38476 -24.63753) (xy 70.37544 -24.702351) (xy 130.235962 -24.702351) (xy 130.235962 -24.647849)
			(xy 130.243717 -24.593903) (xy 130.259071 -24.541609) (xy 130.28171 -24.492033) (xy 130.311174 -24.446182)
			(xy 130.346863 -24.404991) (xy 130.38805 -24.369298) (xy 130.433897 -24.33983) (xy 130.483472 -24.317185)
			(xy 130.535764 -24.301826) (xy 130.589709 -24.294065) (xy 130.61696 -24.293576) (xy 131.48056 -24.293576)
			(xy 131.507814 -24.294069) (xy 131.561767 -24.301821) (xy 131.614067 -24.317173) (xy 131.66365 -24.339812)
			(xy 131.709506 -24.369277) (xy 131.750702 -24.40497) (xy 131.786399 -24.446162) (xy 131.815869 -24.492015)
			(xy 131.838513 -24.541595) (xy 131.853871 -24.593894) (xy 131.861629 -24.647846) (xy 131.861629 -24.702354)
			(xy 131.853871 -24.756306) (xy 131.838513 -24.808605) (xy 131.815869 -24.858185) (xy 131.786399 -24.904038)
			(xy 131.750702 -24.94523) (xy 131.709506 -24.980923) (xy 131.66365 -25.010388) (xy 131.614067 -25.033027)
			(xy 131.561767 -25.048379) (xy 131.507814 -25.056131) (xy 131.48056 -25.056592) (xy 130.61696 -25.056592)
			(xy 130.589709 -25.056135) (xy 130.535764 -25.048374) (xy 130.483472 -25.033015) (xy 130.433897 -25.01037)
			(xy 130.38805 -24.980902) (xy 130.346863 -24.945209) (xy 130.311174 -24.904018) (xy 130.28171 -24.858167)
			(xy 130.259071 -24.808591) (xy 130.243717 -24.756297) (xy 130.235962 -24.702351) (xy 70.37544 -24.702351)
			(xy 70.372702 -24.721393) (xy 70.352727 -24.803731) (xy 70.325015 -24.883796) (xy 70.289818 -24.960865)
			(xy 70.247454 -25.034239) (xy 70.198307 -25.103254) (xy 70.142823 -25.167284) (xy 70.081502 -25.225751)
			(xy 70.014902 -25.278123) (xy 69.943625 -25.323927) (xy 69.868317 -25.362749) (xy 69.789659 -25.394236)
			(xy 69.708365 -25.418103) (xy 69.625169 -25.434135) (xy 69.540827 -25.442185) (xy 69.498464 -25.442672)
			(xy 69.449476 -25.441976) (xy 69.3521 -25.431154) (xy 69.304154 -25.421082) (xy 69.294812 -25.41935)
			(xy 69.276039 -25.422204) (xy 69.259591 -25.431693) (xy 69.253354 -25.438862) (xy 69.228687 -25.46901)
			(xy 69.174875 -25.52534) (xy 69.116354 -25.57676) (xy 69.085206 -25.600152) (xy 69.076637 -25.607067)
			(xy 69.065975 -25.626306) (xy 69.065849 -25.62733) (xy 133.339332 -25.62733) (xy 133.339332 -24.76373)
			(xy 133.339818 -24.736479) (xy 133.347574 -24.682531) (xy 133.362929 -24.630236) (xy 133.385571 -24.580659)
			(xy 133.415037 -24.534809) (xy 133.450728 -24.493618) (xy 133.491919 -24.457927) (xy 133.537769 -24.428461)
			(xy 133.587346 -24.405819) (xy 133.639641 -24.390464) (xy 133.693589 -24.382708) (xy 133.748091 -24.382708)
			(xy 133.802039 -24.390464) (xy 133.854334 -24.405819) (xy 133.903911 -24.428461) (xy 133.949761 -24.457927)
			(xy 133.990952 -24.493618) (xy 134.026643 -24.534809) (xy 134.056109 -24.580659) (xy 134.078751 -24.630236)
			(xy 134.094106 -24.682531) (xy 134.101862 -24.736479) (xy 134.102348 -24.76373) (xy 134.102348 -25.62733)
			(xy 134.101862 -25.654581) (xy 134.094106 -25.708529) (xy 134.078751 -25.760824) (xy 134.056109 -25.810401)
			(xy 134.026643 -25.856251) (xy 133.990952 -25.897442) (xy 133.949761 -25.933133) (xy 133.903911 -25.962599)
			(xy 133.854334 -25.985241) (xy 133.802039 -26.000596) (xy 133.748091 -26.008352) (xy 133.693589 -26.008352)
			(xy 133.639641 -26.000596) (xy 133.587346 -25.985241) (xy 133.537769 -25.962599) (xy 133.491919 -25.933133)
			(xy 133.450728 -25.897442) (xy 133.415037 -25.856251) (xy 133.385571 -25.810401) (xy 133.362929 -25.760824)
			(xy 133.347574 -25.708529) (xy 133.339818 -25.654581) (xy 133.339332 -25.62733) (xy 69.065849 -25.62733)
			(xy 69.064632 -25.637236) (xy 69.060986 -25.678621) (xy 69.046917 -25.760507) (xy 69.025275 -25.840725)
			(xy 68.996248 -25.918575) (xy 68.960089 -25.99338) (xy 68.917113 -26.064488) (xy 68.867694 -26.131279)
			(xy 68.812263 -26.193171) (xy 68.751303 -26.249626) (xy 68.685345 -26.300151) (xy 68.614964 -26.344307)
			(xy 68.540772 -26.381708) (xy 68.463416 -26.412028) (xy 68.38357 -26.435004) (xy 68.30193 -26.450436)
			(xy 68.219207 -26.458189) (xy 68.177664 -26.458672) (xy 68.133869 -26.458133) (xy 68.046704 -26.449518)
			(xy 67.960808 -26.432375) (xy 67.877014 -26.40687) (xy 67.796134 -26.37325) (xy 67.757294 -26.353008)
			(xy 67.745828 -26.34759) (xy 67.7205 -26.34759) (xy 67.709034 -26.353008) (xy 67.670181 -26.373222)
			(xy 67.589299 -26.406833) (xy 67.505508 -26.43234) (xy 67.419618 -26.449494) (xy 67.332457 -26.458131)
			(xy 67.288664 -26.458672) (xy 67.244869 -26.458133) (xy 67.157704 -26.449518) (xy 67.071808 -26.432375)
			(xy 66.988014 -26.40687) (xy 66.907134 -26.37325) (xy 66.868294 -26.353008) (xy 66.856828 -26.34759)
			(xy 66.8315 -26.34759) (xy 66.820034 -26.353008) (xy 66.781181 -26.373222) (xy 66.700299 -26.406833)
			(xy 66.616508 -26.43234) (xy 66.530618 -26.449494) (xy 66.443457 -26.458131) (xy 66.399664 -26.458672)
			(xy 66.358552 -26.458282) (xy 66.276678 -26.45069) (xy 66.195855 -26.435576) (xy 66.116771 -26.413067)
			(xy 66.040102 -26.383356) (xy 65.966502 -26.346696) (xy 65.8966 -26.3034) (xy 65.830991 -26.253838)
			(xy 65.770236 -26.198433) (xy 65.714853 -26.137658) (xy 65.665316 -26.072031) (xy 65.622046 -26.002113)
			(xy 65.585413 -25.928499) (xy 65.55573 -25.85182) (xy 65.53325 -25.772728) (xy 65.518165 -25.691899)
			(xy 65.510603 -25.610022) (xy 65.510156 -25.56891) (xy 0.509016 -25.56891) (xy 0.509016 -29.026161)
			(xy 11.140205 -29.026161) (xy 11.147539 -28.866724) (xy 11.162812 -28.70785) (xy 11.185984 -28.549934)
			(xy 11.216999 -28.39337) (xy 11.255779 -28.238547) (xy 11.302228 -28.085849) (xy 11.35623 -27.935656)
			(xy 11.417652 -27.788341) (xy 11.48634 -27.644271) (xy 11.562123 -27.503804) (xy 11.644814 -27.367289)
			(xy 11.734207 -27.235065) (xy 11.830079 -27.107461) (xy 11.932193 -26.984794) (xy 12.040293 -26.86737)
			(xy 12.154112 -26.75548) (xy 12.273367 -26.649402) (xy 12.397761 -26.5494) (xy 12.526985 -26.455723)
			(xy 12.660717 -26.368604) (xy 12.798626 -26.288258) (xy 12.940368 -26.214886) (xy 13.085591 -26.148671)
			(xy 13.233934 -26.089776) (xy 13.385028 -26.038349) (xy 13.538498 -25.994517) (xy 13.693962 -25.958388)
			(xy 13.851033 -25.930054) (xy 14.009321 -25.909584) (xy 14.168433 -25.897029) (xy 14.327973 -25.892421)
			(xy 14.487544 -25.895771) (xy 14.64675 -25.90707) (xy 14.805195 -25.92629) (xy 14.962485 -25.953385)
			(xy 15.118229 -25.988285) (xy 15.272039 -26.030905) (xy 15.423535 -26.081139) (xy 15.572338 -26.138862)
			(xy 15.718078 -26.203929) (xy 15.860395 -26.27618) (xy 15.998933 -26.355436) (xy 16.133349 -26.441497)
			(xy 16.263308 -26.534152) (xy 16.388487 -26.633169) (xy 16.508575 -26.738303) (xy 16.623273 -26.849292)
			(xy 16.678148 -26.907236) (xy 17.470427 -27.75458) (xy 130.687572 -27.75458) (xy 130.687572 -26.76398)
			(xy 130.688058 -26.736729) (xy 130.695814 -26.682781) (xy 130.711169 -26.630486) (xy 130.733811 -26.580909)
			(xy 130.763277 -26.535059) (xy 130.798968 -26.493868) (xy 130.840159 -26.458177) (xy 130.886009 -26.428711)
			(xy 130.935586 -26.406069) (xy 130.987881 -26.390714) (xy 131.041829 -26.382958) (xy 131.096331 -26.382958)
			(xy 131.150279 -26.390714) (xy 131.202574 -26.406069) (xy 131.252151 -26.428711) (xy 131.298001 -26.458177)
			(xy 131.339192 -26.493868) (xy 131.374883 -26.535059) (xy 131.404349 -26.580909) (xy 131.426991 -26.630486)
			(xy 131.442346 -26.682781) (xy 131.450102 -26.736729) (xy 131.450588 -26.76398) (xy 131.450588 -26.76779)
			(xy 141.621764 -26.76779) (xy 141.621764 -25.90419) (xy 141.62225 -25.876921) (xy 141.630012 -25.822937)
			(xy 141.645377 -25.770607) (xy 141.668034 -25.720997) (xy 141.69752 -25.675116) (xy 141.733235 -25.633899)
			(xy 141.774452 -25.598184) (xy 141.820333 -25.568698) (xy 141.869943 -25.546041) (xy 141.922273 -25.530676)
			(xy 141.976257 -25.522914) (xy 142.030795 -25.522914) (xy 142.084779 -25.530676) (xy 142.137109 -25.546041)
			(xy 142.186719 -25.568698) (xy 142.2326 -25.598184) (xy 142.273817 -25.633899) (xy 142.309532 -25.675116)
			(xy 142.339018 -25.720997) (xy 142.361675 -25.770607) (xy 142.37704 -25.822937) (xy 142.384802 -25.876921)
			(xy 142.385288 -25.90419) (xy 142.385288 -26.634948) (xy 175.442372 -26.634948) (xy 175.442817 -26.593237)
			(xy 175.450618 -26.510181) (xy 175.466165 -26.428221) (xy 175.489321 -26.348077) (xy 175.519883 -26.270455)
			(xy 175.557582 -26.196038) (xy 175.602086 -26.125479) (xy 175.653004 -26.059399) (xy 175.709888 -25.99838)
			(xy 175.772239 -25.942957) (xy 175.805592 -25.917906) (xy 175.814178 -25.911009) (xy 175.82483 -25.891756)
			(xy 175.826166 -25.880822) (xy 175.829855 -25.839448) (xy 175.843941 -25.757582) (xy 175.865598 -25.677385)
			(xy 175.894637 -25.599556) (xy 175.930804 -25.524774) (xy 175.973785 -25.453688) (xy 176.023205 -25.386918)
			(xy 176.078634 -25.325046) (xy 176.13959 -25.268611) (xy 176.205541 -25.218103) (xy 176.275913 -25.173964)
			(xy 176.350094 -25.136576) (xy 176.427436 -25.106267) (xy 176.507267 -25.083299) (xy 176.588892 -25.067873)
			(xy 176.671599 -25.060123) (xy 176.713134 -25.05964) (xy 176.713642 -25.05964) (xy 176.757406 -25.060139)
			(xy 176.844513 -25.068717) (xy 176.930355 -25.085818) (xy 177.0141 -25.111273) (xy 177.094937 -25.144838)
			(xy 177.133758 -25.16505) (xy 177.145111 -25.170377) (xy 177.170157 -25.170377) (xy 177.18151 -25.16505)
			(xy 177.22038 -25.144826) (xy 177.301322 -25.111257) (xy 177.38517 -25.085803) (xy 177.471113 -25.068709)
			(xy 177.55832 -25.060143) (xy 177.602134 -25.05964) (xy 177.645949 -25.060116) (xy 177.733161 -25.068665)
			(xy 177.819109 -25.085756) (xy 177.902957 -25.111222) (xy 177.983891 -25.144816) (xy 178.022758 -25.16505)
			(xy 178.034111 -25.170377) (xy 178.059157 -25.170377) (xy 178.07051 -25.16505) (xy 178.10938 -25.144826)
			(xy 178.190322 -25.111257) (xy 178.27417 -25.085803) (xy 178.360113 -25.068709) (xy 178.44732 -25.060143)
			(xy 178.491134 -25.05964) (xy 178.541288 -25.060291) (xy 178.640969 -25.071493) (xy 178.690016 -25.081992)
			(xy 178.700529 -25.083816) (xy 178.72144 -25.079687) (xy 178.7389 -25.067462) (xy 178.74488 -25.058624)
			(xy 178.766746 -25.023211) (xy 178.816155 -24.956227) (xy 178.871604 -24.894151) (xy 178.932608 -24.837525)
			(xy 178.998633 -24.786843) (xy 179.069104 -24.742549) (xy 179.143403 -24.705031) (xy 179.220882 -24.674615)
			(xy 179.300862 -24.651569) (xy 179.382645 -24.636093) (xy 179.465517 -24.628322) (xy 179.507134 -24.62784)
			(xy 179.549484 -24.628249) (xy 179.633799 -24.636303) (xy 179.716968 -24.652336) (xy 179.798236 -24.676201)
			(xy 179.876867 -24.707683) (xy 179.95215 -24.746496) (xy 180.023403 -24.79229) (xy 180.08998 -24.844649)
			(xy 180.151278 -24.9031) (xy 180.206744 -24.967112) (xy 180.255873 -25.036107) (xy 180.298222 -25.10946)
			(xy 180.333407 -25.186506) (xy 180.361109 -25.266547) (xy 180.381077 -25.348859) (xy 180.39313 -25.432696)
			(xy 180.397161 -25.5173) (xy 180.39313 -25.601904) (xy 180.381077 -25.685741) (xy 180.361109 -25.768053)
			(xy 180.333407 -25.848094) (xy 180.298222 -25.92514) (xy 180.255873 -25.998493) (xy 180.206744 -26.067488)
			(xy 180.151278 -26.1315) (xy 180.08998 -26.189951) (xy 180.023403 -26.24231) (xy 179.95215 -26.288104)
			(xy 179.876867 -26.326917) (xy 179.798236 -26.358399) (xy 179.716968 -26.382264) (xy 179.633799 -26.398297)
			(xy 179.549484 -26.406351) (xy 179.507134 -26.406856) (xy 179.505864 -26.406856) (xy 179.456029 -26.406131)
			(xy 179.35699 -26.394927) (xy 179.308252 -26.384504) (xy 179.297742 -26.382653) (xy 179.276827 -26.386794)
			(xy 179.259367 -26.39903) (xy 179.253388 -26.407872) (xy 179.230217 -26.445289) (xy 179.177598 -26.515842)
			(xy 179.118275 -26.58086) (xy 179.052827 -26.639708) (xy 179.017676 -26.66619) (xy 179.009104 -26.673102)
			(xy 178.998441 -26.692343) (xy 178.997102 -26.703274) (xy 178.993441 -26.744651) (xy 178.979354 -26.826519)
			(xy 178.957697 -26.906717) (xy 178.928657 -26.984547) (xy 178.892489 -27.059331) (xy 178.849506 -27.130418)
			(xy 178.835198 -27.149749) (xy 180.032656 -27.149749) (xy 180.032656 -27.065027) (xy 180.040709 -26.98069)
			(xy 180.056743 -26.8975) (xy 180.080611 -26.81621) (xy 180.112099 -26.737558) (xy 180.150921 -26.662255)
			(xy 180.196724 -26.590983) (xy 180.249095 -26.524387) (xy 180.30756 -26.463072) (xy 180.371588 -26.407591)
			(xy 180.4406 -26.358448) (xy 180.51397 -26.316088) (xy 180.591035 -26.280893) (xy 180.671097 -26.253184)
			(xy 180.75343 -26.23321) (xy 180.837289 -26.221153) (xy 180.921914 -26.217122) (xy 181.006539 -26.221153)
			(xy 181.090398 -26.23321) (xy 181.172731 -26.253184) (xy 181.252793 -26.280893) (xy 181.329858 -26.316088)
			(xy 181.403228 -26.358448) (xy 181.47224 -26.407591) (xy 181.536268 -26.463072) (xy 181.594733 -26.524387)
			(xy 181.647104 -26.590983) (xy 181.692907 -26.662255) (xy 181.731729 -26.737558) (xy 181.763217 -26.81621)
			(xy 181.787085 -26.8975) (xy 181.803119 -26.98069) (xy 181.811172 -27.065027) (xy 181.811676 -27.107388)
			(xy 181.811172 -27.149749) (xy 181.803119 -27.234086) (xy 181.787085 -27.317276) (xy 181.763217 -27.398566)
			(xy 181.731729 -27.477218) (xy 181.692907 -27.552521) (xy 181.647104 -27.623793) (xy 181.594733 -27.690389)
			(xy 181.536268 -27.751704) (xy 181.47224 -27.807185) (xy 181.403228 -27.856328) (xy 181.329858 -27.898688)
			(xy 181.252793 -27.933883) (xy 181.172731 -27.961592) (xy 181.090398 -27.981566) (xy 181.006539 -27.993623)
			(xy 180.921914 -27.997655) (xy 180.837289 -27.993623) (xy 180.75343 -27.981566) (xy 180.671097 -27.961592)
			(xy 180.591035 -27.933883) (xy 180.51397 -27.898688) (xy 180.4406 -27.856328) (xy 180.371588 -27.807185)
			(xy 180.30756 -27.751704) (xy 180.249095 -27.690389) (xy 180.196724 -27.623793) (xy 180.150921 -27.552521)
			(xy 180.112099 -27.477218) (xy 180.080611 -27.398566) (xy 180.056743 -27.317276) (xy 180.040709 -27.234086)
			(xy 180.032656 -27.149749) (xy 178.835198 -27.149749) (xy 178.800084 -27.197189) (xy 178.744653 -27.259061)
			(xy 178.683695 -27.315497) (xy 178.617742 -27.366004) (xy 178.547367 -27.410143) (xy 178.473184 -27.447529)
			(xy 178.395839 -27.477837) (xy 178.316006 -27.500803) (xy 178.234379 -27.516227) (xy 178.15167 -27.523974)
			(xy 178.110134 -27.524456) (xy 178.109626 -27.524456) (xy 178.065862 -27.523929) (xy 177.978756 -27.515357)
			(xy 177.892915 -27.498263) (xy 177.809169 -27.472814) (xy 177.728331 -27.439255) (xy 177.68951 -27.419046)
			(xy 177.678157 -27.413719) (xy 177.653111 -27.413719) (xy 177.641758 -27.419046) (xy 177.602894 -27.439282)
			(xy 177.521951 -27.472849) (xy 177.438101 -27.498301) (xy 177.352156 -27.515391) (xy 177.264948 -27.523955)
			(xy 177.221134 -27.524456) (xy 177.177318 -27.523994) (xy 177.090106 -27.515442) (xy 177.004158 -27.498348)
			(xy 176.920311 -27.472879) (xy 176.839376 -27.439281) (xy 176.80051 -27.419046) (xy 176.789157 -27.413719)
			(xy 176.764111 -27.413719) (xy 176.752758 -27.419046) (xy 176.713921 -27.439222) (xy 176.633081 -27.472767)
			(xy 176.549339 -27.498216) (xy 176.463504 -27.515325) (xy 176.376404 -27.523927) (xy 176.332642 -27.524456)
			(xy 176.332134 -27.524456) (xy 176.291028 -27.523955) (xy 176.209165 -27.516374) (xy 176.128351 -27.501273)
			(xy 176.049275 -27.47878) (xy 175.972611 -27.449089) (xy 175.899013 -27.412452) (xy 175.829109 -27.369181)
			(xy 175.763495 -27.319646) (xy 175.702731 -27.264268) (xy 175.647335 -27.203522) (xy 175.597779 -27.137923)
			(xy 175.554486 -27.068033) (xy 175.517825 -26.994447) (xy 175.488109 -26.917792) (xy 175.465592 -26.838723)
			(xy 175.450465 -26.757914) (xy 175.442858 -26.676054) (xy 175.442372 -26.634948) (xy 142.385288 -26.634948)
			(xy 142.385288 -26.76779) (xy 142.384802 -26.795059) (xy 142.37704 -26.849043) (xy 142.361675 -26.901373)
			(xy 142.339018 -26.950983) (xy 142.309532 -26.996864) (xy 142.273817 -27.038081) (xy 142.2326 -27.073796)
			(xy 142.186719 -27.103282) (xy 142.137109 -27.125939) (xy 142.084779 -27.141304) (xy 142.030795 -27.149066)
			(xy 141.976257 -27.149066) (xy 141.922273 -27.141304) (xy 141.869943 -27.125939) (xy 141.820333 -27.103282)
			(xy 141.774452 -27.073796) (xy 141.733235 -27.038081) (xy 141.69752 -26.996864) (xy 141.668034 -26.950983)
			(xy 141.645377 -26.901373) (xy 141.630012 -26.849043) (xy 141.62225 -26.795059) (xy 141.621764 -26.76779)
			(xy 131.450588 -26.76779) (xy 131.450588 -27.75458) (xy 131.450102 -27.781831) (xy 131.442346 -27.835779)
			(xy 131.426991 -27.888074) (xy 131.404349 -27.937651) (xy 131.374883 -27.983501) (xy 131.339192 -28.024692)
			(xy 131.298001 -28.060383) (xy 131.252151 -28.089849) (xy 131.202574 -28.112491) (xy 131.150279 -28.127846)
			(xy 131.096331 -28.135602) (xy 131.041829 -28.135602) (xy 130.987881 -28.127846) (xy 130.935586 -28.112491)
			(xy 130.886009 -28.089849) (xy 130.840159 -28.060383) (xy 130.798968 -28.024692) (xy 130.763277 -27.983501)
			(xy 130.733811 -27.937651) (xy 130.711169 -27.888074) (xy 130.695814 -27.835779) (xy 130.688058 -27.781831)
			(xy 130.687572 -27.75458) (xy 17.470427 -27.75458) (xy 17.770856 -28.07589) (xy 17.824996 -28.134528)
			(xy 17.928078 -28.256394) (xy 18.024957 -28.383247) (xy 18.115392 -28.514772) (xy 18.199158 -28.650641)
			(xy 18.276047 -28.790516) (xy 18.345869 -28.934051) (xy 18.408448 -29.080887) (xy 18.463631 -29.230661)
			(xy 18.511279 -29.382999) (xy 18.546379 -29.51861) (xy 101.326696 -29.51861) (xy 101.326696 -28.65501)
			(xy 101.327182 -28.627759) (xy 101.334938 -28.573811) (xy 101.350293 -28.521516) (xy 101.372935 -28.471939)
			(xy 101.402401 -28.426089) (xy 101.438092 -28.384898) (xy 101.479283 -28.349207) (xy 101.525133 -28.319741)
			(xy 101.57471 -28.297099) (xy 101.627005 -28.281744) (xy 101.680953 -28.273988) (xy 101.735455 -28.273988)
			(xy 101.789403 -28.281744) (xy 101.841698 -28.297099) (xy 101.891275 -28.319741) (xy 101.937125 -28.349207)
			(xy 101.978316 -28.384898) (xy 102.014007 -28.426089) (xy 102.043473 -28.471939) (xy 102.066115 -28.521516)
			(xy 102.08147 -28.573811) (xy 102.089226 -28.627759) (xy 102.089712 -28.65501) (xy 102.089712 -29.24302)
			(xy 135.551672 -29.24302) (xy 135.551672 -28.25242) (xy 135.552158 -28.225169) (xy 135.559914 -28.171221)
			(xy 135.575269 -28.118926) (xy 135.597911 -28.069349) (xy 135.627377 -28.023499) (xy 135.663068 -27.982308)
			(xy 135.704259 -27.946617) (xy 135.750109 -27.917151) (xy 135.799686 -27.894509) (xy 135.851981 -27.879154)
			(xy 135.905929 -27.871398) (xy 135.960431 -27.871398) (xy 136.014379 -27.879154) (xy 136.066674 -27.894509)
			(xy 136.116251 -27.917151) (xy 136.162101 -27.946617) (xy 136.203292 -27.982308) (xy 136.238983 -28.023499)
			(xy 136.268449 -28.069349) (xy 136.291091 -28.118926) (xy 136.306446 -28.171221) (xy 136.314202 -28.225169)
			(xy 136.314688 -28.25242) (xy 136.314688 -28.526871) (xy 139.853386 -28.526871) (xy 139.853386 -28.472329)
			(xy 139.861148 -28.418343) (xy 139.876513 -28.366011) (xy 139.89917 -28.316397) (xy 139.928656 -28.270513)
			(xy 139.964371 -28.229293) (xy 140.005589 -28.193574) (xy 140.051471 -28.164084) (xy 140.101082 -28.141424)
			(xy 140.153414 -28.126054) (xy 140.207399 -28.118289) (xy 140.23467 -28.1178) (xy 141.09827 -28.1178)
			(xy 141.12554 -28.118337) (xy 141.179524 -28.126095) (xy 141.231856 -28.141457) (xy 141.281468 -28.164111)
			(xy 141.32735 -28.193595) (xy 141.36857 -28.229309) (xy 141.404287 -28.270526) (xy 141.433775 -28.316406)
			(xy 141.456432 -28.366016) (xy 141.471798 -28.418346) (xy 141.479561 -28.47233) (xy 141.479561 -28.52687)
			(xy 141.471798 -28.580854) (xy 141.456432 -28.633184) (xy 141.433775 -28.682794) (xy 141.404287 -28.728674)
			(xy 141.36857 -28.769891) (xy 141.32735 -28.805605) (xy 141.281468 -28.835089) (xy 141.231856 -28.857743)
			(xy 141.179524 -28.873105) (xy 141.12554 -28.880863) (xy 141.09827 -28.881324) (xy 140.23467 -28.881324)
			(xy 140.207399 -28.880911) (xy 140.153414 -28.873146) (xy 140.101082 -28.857776) (xy 140.051471 -28.835116)
			(xy 140.005589 -28.805626) (xy 139.964371 -28.769907) (xy 139.928656 -28.728687) (xy 139.89917 -28.682803)
			(xy 139.876513 -28.633189) (xy 139.861148 -28.580857) (xy 139.853386 -28.526871) (xy 136.314688 -28.526871)
			(xy 136.314688 -29.24302) (xy 136.314202 -29.270271) (xy 136.306446 -29.324219) (xy 136.291091 -29.376514)
			(xy 136.268449 -29.426091) (xy 136.238983 -29.471941) (xy 136.203292 -29.513132) (xy 136.162101 -29.548823)
			(xy 136.116251 -29.578289) (xy 136.066674 -29.600931) (xy 136.014379 -29.616286) (xy 135.960431 -29.624042)
			(xy 135.905929 -29.624042) (xy 135.851981 -29.616286) (xy 135.799686 -29.600931) (xy 135.750109 -29.578289)
			(xy 135.704259 -29.548823) (xy 135.663068 -29.513132) (xy 135.627377 -29.471941) (xy 135.597911 -29.426091)
			(xy 135.575269 -29.376514) (xy 135.559914 -29.324219) (xy 135.552158 -29.270271) (xy 135.551672 -29.24302)
			(xy 102.089712 -29.24302) (xy 102.089712 -29.51861) (xy 102.089226 -29.545861) (xy 102.08147 -29.599809)
			(xy 102.066115 -29.652104) (xy 102.043473 -29.701681) (xy 102.014007 -29.747531) (xy 101.978316 -29.788722)
			(xy 101.937125 -29.824413) (xy 101.891275 -29.853879) (xy 101.841698 -29.876521) (xy 101.789403 -29.891876)
			(xy 101.735455 -29.899632) (xy 101.680953 -29.899632) (xy 101.627005 -29.891876) (xy 101.57471 -29.876521)
			(xy 101.525133 -29.853879) (xy 101.479283 -29.824413) (xy 101.438092 -29.788722) (xy 101.402401 -29.747531)
			(xy 101.372935 -29.701681) (xy 101.350293 -29.652104) (xy 101.334938 -29.599809) (xy 101.327182 -29.545861)
			(xy 101.326696 -29.51861) (xy 18.546379 -29.51861) (xy 18.551274 -29.537523) (xy 18.583516 -29.693848)
			(xy 18.607926 -29.851586) (xy 18.624443 -30.010345) (xy 18.63109 -30.1338) (xy 197.595716 -30.1338)
			(xy 197.599747 -30.049172) (xy 197.611805 -29.965311) (xy 197.631779 -29.882976) (xy 197.65949 -29.802912)
			(xy 197.694686 -29.725844) (xy 197.737048 -29.652472) (xy 197.786193 -29.583458) (xy 197.841676 -29.519429)
			(xy 197.902994 -29.460963) (xy 197.969592 -29.408591) (xy 198.040866 -29.362787) (xy 198.116172 -29.323965)
			(xy 198.194827 -29.292477) (xy 198.276119 -29.268609) (xy 198.359312 -29.252576) (xy 198.443652 -29.244524)
			(xy 198.486014 -29.244036) (xy 198.524304 -29.244437) (xy 198.600598 -29.251046) (xy 198.676041 -29.264197)
			(xy 198.750071 -29.283791) (xy 198.786242 -29.29636) (xy 198.794679 -29.299011) (xy 198.812349 -29.299011)
			(xy 198.820786 -29.29636) (xy 198.856961 -29.283808) (xy 198.930995 -29.264238) (xy 199.006435 -29.251093)
			(xy 199.082726 -29.244471) (xy 199.121014 -29.244036) (xy 199.159304 -29.244437) (xy 199.235598 -29.251046)
			(xy 199.311041 -29.264197) (xy 199.385071 -29.283791) (xy 199.421242 -29.29636) (xy 199.429679 -29.299011)
			(xy 199.447349 -29.299011) (xy 199.455786 -29.29636) (xy 199.491961 -29.283808) (xy 199.565995 -29.264238)
			(xy 199.641435 -29.251093) (xy 199.717726 -29.244471) (xy 199.756014 -29.244036) (xy 199.794304 -29.244437)
			(xy 199.870598 -29.251046) (xy 199.946041 -29.264197) (xy 200.020071 -29.283791) (xy 200.056242 -29.29636)
			(xy 200.064679 -29.299011) (xy 200.082349 -29.299011) (xy 200.090786 -29.29636) (xy 200.126961 -29.283808)
			(xy 200.200995 -29.264238) (xy 200.276435 -29.251093) (xy 200.352726 -29.244471) (xy 200.391014 -29.244036)
			(xy 200.431702 -29.244422) (xy 200.512738 -29.251848) (xy 200.592757 -29.266645) (xy 200.67109 -29.288689)
			(xy 200.747082 -29.317797) (xy 200.820096 -29.353725) (xy 200.889524 -29.396173) (xy 200.954784 -29.444785)
			(xy 201.015331 -29.499155) (xy 201.070657 -29.558829) (xy 201.120302 -29.623307) (xy 201.163849 -29.69205)
			(xy 201.200934 -29.764484) (xy 201.216514 -29.802074) (xy 201.22098 -29.811942) (xy 201.236608 -29.826918)
			(xy 201.256995 -29.83419) (xy 201.267822 -29.833824) (xy 201.286077 -29.832403) (xy 201.322664 -29.83088)
			(xy 201.340974 -29.830776) (xy 201.383338 -29.831187) (xy 201.467682 -29.839239) (xy 201.550879 -29.855272)
			(xy 201.632176 -29.87914) (xy 201.710835 -29.910629) (xy 201.786145 -29.949452) (xy 201.857423 -29.995258)
			(xy 201.924025 -30.047632) (xy 201.985346 -30.1061) (xy 202.040832 -30.170132) (xy 202.08998 -30.239149)
			(xy 202.132344 -30.312525) (xy 202.167542 -30.389596) (xy 202.195254 -30.469663) (xy 202.21523 -30.552003)
			(xy 202.227288 -30.635868) (xy 202.23132 -30.7205) (xy 202.227288 -30.805132) (xy 202.21523 -30.888997)
			(xy 202.195254 -30.971337) (xy 202.167542 -31.051404) (xy 202.132344 -31.128475) (xy 202.08998 -31.201851)
			(xy 202.040832 -31.270868) (xy 201.985346 -31.3349) (xy 201.924025 -31.393368) (xy 201.857423 -31.445742)
			(xy 201.786145 -31.491548) (xy 201.710835 -31.530371) (xy 201.632176 -31.56186) (xy 201.550879 -31.585728)
			(xy 201.467682 -31.601761) (xy 201.383338 -31.609813) (xy 201.340974 -31.6103) (xy 201.302684 -31.609905)
			(xy 201.226389 -31.603295) (xy 201.150947 -31.590142) (xy 201.076917 -31.570546) (xy 201.040746 -31.557976)
			(xy 201.032309 -31.555325) (xy 201.014639 -31.555325) (xy 201.006202 -31.557976) (xy 200.970027 -31.570528)
			(xy 200.895993 -31.590099) (xy 200.820553 -31.603244) (xy 200.744262 -31.609866) (xy 200.705974 -31.6103)
			(xy 200.667684 -31.609905) (xy 200.591389 -31.603295) (xy 200.515947 -31.590142) (xy 200.441917 -31.570546)
			(xy 200.405746 -31.557976) (xy 200.397309 -31.555325) (xy 200.379639 -31.555325) (xy 200.371202 -31.557976)
			(xy 200.335027 -31.570528) (xy 200.260993 -31.590099) (xy 200.185553 -31.603244) (xy 200.109262 -31.609866)
			(xy 200.070974 -31.6103) (xy 200.032684 -31.609905) (xy 199.956389 -31.603295) (xy 199.880947 -31.590142)
			(xy 199.806917 -31.570546) (xy 199.770746 -31.557976) (xy 199.762309 -31.555325) (xy 199.744639 -31.555325)
			(xy 199.736202 -31.557976) (xy 199.700027 -31.570528) (xy 199.625993 -31.590099) (xy 199.550553 -31.603244)
			(xy 199.474262 -31.609866) (xy 199.435974 -31.6103) (xy 199.395288 -31.609814) (xy 199.314256 -31.602396)
			(xy 199.23424 -31.587608) (xy 199.15591 -31.565572) (xy 199.07992 -31.536472) (xy 199.006906 -31.500553)
			(xy 198.937478 -31.458114) (xy 198.872217 -31.40951) (xy 198.81167 -31.355148) (xy 198.756341 -31.295482)
			(xy 198.706694 -31.231012) (xy 198.663144 -31.162275) (xy 198.626056 -31.089848) (xy 198.610474 -31.052262)
			(xy 198.605924 -31.042441) (xy 198.590335 -31.027459) (xy 198.569982 -31.020164) (xy 198.559166 -31.020512)
			(xy 198.540911 -31.021927) (xy 198.504324 -31.023454) (xy 198.486014 -31.02356) (xy 198.443652 -31.023076)
			(xy 198.359312 -31.015024) (xy 198.276119 -30.998991) (xy 198.194827 -30.975123) (xy 198.116172 -30.943635)
			(xy 198.040866 -30.904813) (xy 197.969592 -30.859009) (xy 197.902994 -30.806637) (xy 197.841676 -30.748171)
			(xy 197.786193 -30.684142) (xy 197.737048 -30.615128) (xy 197.694686 -30.541756) (xy 197.65949 -30.464688)
			(xy 197.631779 -30.384624) (xy 197.611805 -30.302289) (xy 197.599747 -30.218428) (xy 197.595716 -30.1338)
			(xy 18.63109 -30.1338) (xy 18.633025 -30.16973) (xy 18.633652 -30.329344) (xy 18.626321 -30.488792)
			(xy 18.611051 -30.647675) (xy 18.587881 -30.8056) (xy 18.556867 -30.962174) (xy 18.518086 -31.117007)
			(xy 18.471636 -31.269714) (xy 18.417631 -31.419917) (xy 18.356206 -31.56724) (xy 18.287514 -31.711318)
			(xy 18.211725 -31.851793) (xy 18.129028 -31.988316) (xy 18.039629 -32.120546) (xy 17.943749 -32.248156)
			(xy 17.841627 -32.370828) (xy 17.733517 -32.488256) (xy 17.619688 -32.60015) (xy 17.500423 -32.70623)
			(xy 17.376019 -32.806234) (xy 17.246784 -32.899911) (xy 17.173557 -32.94761) (xy 102.642416 -32.94761)
			(xy 102.642416 -31.95701) (xy 102.642902 -31.929759) (xy 102.650658 -31.875811) (xy 102.666013 -31.823516)
			(xy 102.688655 -31.773939) (xy 102.718121 -31.728089) (xy 102.753812 -31.686898) (xy 102.795003 -31.651207)
			(xy 102.840853 -31.621741) (xy 102.89043 -31.599099) (xy 102.942725 -31.583744) (xy 102.996673 -31.575988)
			(xy 103.051175 -31.575988) (xy 103.105123 -31.583744) (xy 103.157418 -31.599099) (xy 103.206995 -31.621741)
			(xy 103.252845 -31.651207) (xy 103.294036 -31.686898) (xy 103.329727 -31.728089) (xy 103.359193 -31.773939)
			(xy 103.381835 -31.823516) (xy 103.39719 -31.875811) (xy 103.404946 -31.929759) (xy 103.405432 -31.95701)
			(xy 103.405432 -32.405066) (xy 105.659936 -32.405066) (xy 105.659936 -31.541466) (xy 105.660422 -31.514215)
			(xy 105.668178 -31.460267) (xy 105.683533 -31.407972) (xy 105.706175 -31.358395) (xy 105.735641 -31.312545)
			(xy 105.771332 -31.271354) (xy 105.812523 -31.235663) (xy 105.858373 -31.206197) (xy 105.90795 -31.183555)
			(xy 105.960245 -31.1682) (xy 106.014193 -31.160444) (xy 106.068695 -31.160444) (xy 106.122643 -31.1682)
			(xy 106.174938 -31.183555) (xy 106.224515 -31.206197) (xy 106.270365 -31.235663) (xy 106.311556 -31.271354)
			(xy 106.347247 -31.312545) (xy 106.376713 -31.358395) (xy 106.399355 -31.407972) (xy 106.41471 -31.460267)
			(xy 106.422466 -31.514215) (xy 106.422952 -31.541466) (xy 106.422952 -31.65856) (xy 140.278612 -31.65856)
			(xy 140.278612 -30.79496) (xy 140.279098 -30.767709) (xy 140.286854 -30.713761) (xy 140.302209 -30.661466)
			(xy 140.324851 -30.611889) (xy 140.354317 -30.566039) (xy 140.390008 -30.524848) (xy 140.431199 -30.489157)
			(xy 140.477049 -30.459691) (xy 140.526626 -30.437049) (xy 140.578921 -30.421694) (xy 140.632869 -30.413938)
			(xy 140.687371 -30.413938) (xy 140.741319 -30.421694) (xy 140.793614 -30.437049) (xy 140.843191 -30.459691)
			(xy 140.889041 -30.489157) (xy 140.930232 -30.524848) (xy 140.965923 -30.566039) (xy 140.995389 -30.611889)
			(xy 141.018031 -30.661466) (xy 141.033386 -30.713761) (xy 141.041142 -30.767709) (xy 141.041628 -30.79496)
			(xy 141.041628 -31.65856) (xy 141.041311 -31.67634) (xy 144.616932 -31.67634) (xy 144.616932 -30.81274)
			(xy 144.617418 -30.785489) (xy 144.625174 -30.731541) (xy 144.640529 -30.679246) (xy 144.663171 -30.629669)
			(xy 144.692637 -30.583819) (xy 144.728328 -30.542628) (xy 144.769519 -30.506937) (xy 144.815369 -30.477471)
			(xy 144.864946 -30.454829) (xy 144.917241 -30.439474) (xy 144.971189 -30.431718) (xy 145.025691 -30.431718)
			(xy 145.079639 -30.439474) (xy 145.131934 -30.454829) (xy 145.181511 -30.477471) (xy 145.227361 -30.506937)
			(xy 145.268552 -30.542628) (xy 145.304243 -30.583819) (xy 145.333709 -30.629669) (xy 145.356351 -30.679246)
			(xy 145.371706 -30.731541) (xy 145.379462 -30.785489) (xy 145.379948 -30.81274) (xy 145.379948 -31.67634)
			(xy 145.379462 -31.703591) (xy 145.371706 -31.757539) (xy 145.356351 -31.809834) (xy 145.333709 -31.859411)
			(xy 145.304243 -31.905261) (xy 145.268552 -31.946452) (xy 145.227361 -31.982143) (xy 145.181511 -32.011609)
			(xy 145.131934 -32.034251) (xy 145.079639 -32.049606) (xy 145.025691 -32.057362) (xy 144.971189 -32.057362)
			(xy 144.917241 -32.049606) (xy 144.864946 -32.034251) (xy 144.815369 -32.011609) (xy 144.769519 -31.982143)
			(xy 144.728328 -31.946452) (xy 144.692637 -31.905261) (xy 144.663171 -31.859411) (xy 144.640529 -31.809834)
			(xy 144.625174 -31.757539) (xy 144.617418 -31.703591) (xy 144.616932 -31.67634) (xy 141.041311 -31.67634)
			(xy 141.041142 -31.685811) (xy 141.033386 -31.739759) (xy 141.018031 -31.792054) (xy 140.995389 -31.841631)
			(xy 140.965923 -31.887481) (xy 140.930232 -31.928672) (xy 140.889041 -31.964363) (xy 140.843191 -31.993829)
			(xy 140.793614 -32.016471) (xy 140.741319 -32.031826) (xy 140.687371 -32.039582) (xy 140.632869 -32.039582)
			(xy 140.578921 -32.031826) (xy 140.526626 -32.016471) (xy 140.477049 -31.993829) (xy 140.431199 -31.964363)
			(xy 140.390008 -31.928672) (xy 140.354317 -31.887481) (xy 140.324851 -31.841631) (xy 140.302209 -31.792054)
			(xy 140.286854 -31.739759) (xy 140.279098 -31.685811) (xy 140.278612 -31.65856) (xy 106.422952 -31.65856)
			(xy 106.422952 -32.405066) (xy 106.422466 -32.432317) (xy 106.41471 -32.486265) (xy 106.399355 -32.53856)
			(xy 106.376713 -32.588137) (xy 106.347247 -32.633987) (xy 106.311556 -32.675178) (xy 106.270365 -32.710869)
			(xy 106.224515 -32.740335) (xy 106.174938 -32.762977) (xy 106.122643 -32.778332) (xy 106.068695 -32.786088)
			(xy 106.014193 -32.786088) (xy 105.960245 -32.778332) (xy 105.90795 -32.762977) (xy 105.858373 -32.740335)
			(xy 105.812523 -32.710869) (xy 105.771332 -32.675178) (xy 105.735641 -32.633987) (xy 105.706175 -32.588137)
			(xy 105.683533 -32.53856) (xy 105.668178 -32.486265) (xy 105.660422 -32.432317) (xy 105.659936 -32.405066)
			(xy 103.405432 -32.405066) (xy 103.405432 -32.94761) (xy 103.404946 -32.974861) (xy 103.39719 -33.028809)
			(xy 103.390276 -33.052356) (xy 119.734235 -33.052356) (xy 119.734235 -32.997844) (xy 119.741993 -32.943888)
			(xy 119.757352 -32.891585) (xy 119.779997 -32.842) (xy 119.80947 -32.796143) (xy 119.845169 -32.754947)
			(xy 119.886367 -32.719252) (xy 119.932226 -32.689783) (xy 119.981813 -32.667141) (xy 120.034117 -32.651787)
			(xy 120.088074 -32.644033) (xy 120.11533 -32.643572) (xy 120.97893 -32.643572) (xy 121.006178 -32.6441)
			(xy 121.06012 -32.65186) (xy 121.112408 -32.667217) (xy 121.161979 -32.689858) (xy 121.207823 -32.719324)
			(xy 121.249008 -32.755014) (xy 121.284694 -32.796201) (xy 121.314156 -32.842047) (xy 121.336794 -32.89162)
			(xy 121.352147 -32.943909) (xy 121.359902 -32.997852) (xy 121.359902 -33.052348) (xy 121.352147 -33.106291)
			(xy 121.336794 -33.15858) (xy 121.314156 -33.208153) (xy 121.284694 -33.253999) (xy 121.249008 -33.295186)
			(xy 121.207823 -33.330876) (xy 121.161979 -33.360342) (xy 121.112408 -33.382983) (xy 121.06012 -33.39834)
			(xy 121.006178 -33.4061) (xy 120.97893 -33.406588) (xy 120.11533 -33.406588) (xy 120.088074 -33.406167)
			(xy 120.034117 -33.398413) (xy 119.981813 -33.383059) (xy 119.932226 -33.360417) (xy 119.886367 -33.330948)
			(xy 119.845169 -33.295253) (xy 119.80947 -33.254057) (xy 119.779997 -33.2082) (xy 119.757352 -33.158615)
			(xy 119.741993 -33.106312) (xy 119.734235 -33.052356) (xy 103.390276 -33.052356) (xy 103.381835 -33.081104)
			(xy 103.359193 -33.130681) (xy 103.329727 -33.176531) (xy 103.294036 -33.217722) (xy 103.252845 -33.253413)
			(xy 103.206995 -33.282879) (xy 103.157418 -33.305521) (xy 103.105123 -33.320876) (xy 103.051175 -33.328632)
			(xy 102.996673 -33.328632) (xy 102.942725 -33.320876) (xy 102.89043 -33.305521) (xy 102.840853 -33.282879)
			(xy 102.795003 -33.253413) (xy 102.753812 -33.217722) (xy 102.718121 -33.176531) (xy 102.688655 -33.130681)
			(xy 102.666013 -33.081104) (xy 102.650658 -33.028809) (xy 102.642902 -32.974861) (xy 102.642416 -32.94761)
			(xy 17.173557 -32.94761) (xy 17.11304 -32.98703) (xy 16.975119 -33.067374) (xy 16.833366 -33.140743)
			(xy 16.688131 -33.206955) (xy 16.539776 -33.265845) (xy 16.38867 -33.317266) (xy 16.235188 -33.361091)
			(xy 16.079713 -33.397211) (xy 15.922631 -33.425536) (xy 15.764332 -33.445995) (xy 15.605209 -33.458538)
			(xy 15.44566 -33.463134) (xy 15.286079 -33.459771) (xy 15.126865 -33.448457) (xy 14.968413 -33.42922)
			(xy 14.811116 -33.402109) (xy 14.655367 -33.367191) (xy 14.501552 -33.324553) (xy 14.350053 -33.2743)
			(xy 14.201248 -33.216557) (xy 14.055506 -33.151469) (xy 13.91319 -33.079197) (xy 13.774653 -32.999921)
			(xy 13.64024 -32.913837) (xy 13.510286 -32.82116) (xy 13.385112 -32.72212) (xy 13.265032 -32.616964)
			(xy 13.150342 -32.505953) (xy 13.095478 -32.447992) (xy 12.00277 -31.279592) (xy 11.948692 -31.220903)
			(xy 11.845626 -31.099035) (xy 11.748763 -30.972182) (xy 11.658343 -30.840658) (xy 11.574591 -30.704792)
			(xy 11.497716 -30.564919) (xy 11.427907 -30.421388) (xy 11.36534 -30.274557) (xy 11.310169 -30.124789)
			(xy 11.262532 -29.972457) (xy 11.222547 -29.81794) (xy 11.190314 -29.661623) (xy 11.165912 -29.503893)
			(xy 11.149402 -29.345143) (xy 11.140826 -29.185767) (xy 11.140205 -29.026161) (xy 0.509016 -29.026161)
			(xy 0.509016 -33.838388) (xy 122.111008 -33.838388) (xy 122.111008 -32.974788) (xy 122.111494 -32.947519)
			(xy 122.119256 -32.893535) (xy 122.134621 -32.841205) (xy 122.157278 -32.791595) (xy 122.186764 -32.745714)
			(xy 122.222479 -32.704497) (xy 122.263696 -32.668782) (xy 122.309577 -32.639296) (xy 122.359187 -32.616639)
			(xy 122.411517 -32.601274) (xy 122.465501 -32.593512) (xy 122.520039 -32.593512) (xy 122.574023 -32.601274)
			(xy 122.626353 -32.616639) (xy 122.675963 -32.639296) (xy 122.721844 -32.668782) (xy 122.763061 -32.704497)
			(xy 122.798776 -32.745714) (xy 122.828262 -32.791595) (xy 122.850919 -32.841205) (xy 122.866284 -32.893535)
			(xy 122.874046 -32.947519) (xy 122.874532 -32.974788) (xy 122.874532 -33.413556) (xy 124.175423 -33.413556)
			(xy 124.175423 -33.359044) (xy 124.183181 -33.305087) (xy 124.198539 -33.252783) (xy 124.221185 -33.203197)
			(xy 124.250658 -33.157339) (xy 124.286357 -33.116142) (xy 124.327555 -33.080446) (xy 124.373415 -33.050976)
			(xy 124.423002 -33.028332) (xy 124.475306 -33.012977) (xy 124.529264 -33.005222) (xy 124.55652 -33.00476)
			(xy 125.42012 -33.00476) (xy 125.447368 -33.005312) (xy 125.501309 -33.01307) (xy 125.553597 -33.028425)
			(xy 125.603167 -33.051066) (xy 125.649011 -33.08053) (xy 125.690196 -33.116218) (xy 125.725882 -33.157405)
			(xy 125.755344 -33.20325) (xy 125.777982 -33.252822) (xy 125.793335 -33.305111) (xy 125.80109 -33.359052)
			(xy 125.80109 -33.413548) (xy 125.793335 -33.467489) (xy 125.777982 -33.519778) (xy 125.755344 -33.56935)
			(xy 125.725882 -33.615195) (xy 125.690196 -33.656382) (xy 125.649011 -33.69207) (xy 125.603167 -33.721534)
			(xy 125.553597 -33.744175) (xy 125.501309 -33.75953) (xy 125.447368 -33.767288) (xy 125.42012 -33.767776)
			(xy 124.55652 -33.767776) (xy 124.529264 -33.767378) (xy 124.475306 -33.759623) (xy 124.423002 -33.744268)
			(xy 124.373415 -33.721624) (xy 124.327555 -33.692154) (xy 124.286357 -33.656458) (xy 124.250658 -33.615261)
			(xy 124.221185 -33.569403) (xy 124.198539 -33.519817) (xy 124.183181 -33.467513) (xy 124.175423 -33.413556)
			(xy 122.874532 -33.413556) (xy 122.874532 -33.838388) (xy 122.874046 -33.865657) (xy 122.866284 -33.919641)
			(xy 122.850919 -33.971971) (xy 122.828262 -34.021581) (xy 122.798776 -34.067462) (xy 122.763061 -34.108679)
			(xy 122.721844 -34.144394) (xy 122.675963 -34.17388) (xy 122.626353 -34.196537) (xy 122.574023 -34.211902)
			(xy 122.520039 -34.219664) (xy 122.465501 -34.219664) (xy 122.411517 -34.211902) (xy 122.359187 -34.196537)
			(xy 122.309577 -34.17388) (xy 122.263696 -34.144394) (xy 122.222479 -34.108679) (xy 122.186764 -34.067462)
			(xy 122.157278 -34.021581) (xy 122.134621 -33.971971) (xy 122.119256 -33.919641) (xy 122.111494 -33.865657)
			(xy 122.111008 -33.838388) (xy 0.509016 -33.838388) (xy 0.509016 -36.080556) (xy 122.143423 -36.080556)
			(xy 122.143423 -36.026044) (xy 122.151181 -35.972087) (xy 122.166539 -35.919783) (xy 122.189185 -35.870197)
			(xy 122.218658 -35.824339) (xy 122.254357 -35.783142) (xy 122.295555 -35.747446) (xy 122.341415 -35.717976)
			(xy 122.391002 -35.695332) (xy 122.443306 -35.679977) (xy 122.497264 -35.672222) (xy 122.52452 -35.67176)
			(xy 123.38812 -35.67176) (xy 123.415368 -35.672312) (xy 123.469309 -35.68007) (xy 123.521597 -35.695425)
			(xy 123.571167 -35.718066) (xy 123.617011 -35.74753) (xy 123.658196 -35.783218) (xy 123.693882 -35.824405)
			(xy 123.723344 -35.87025) (xy 123.745982 -35.919822) (xy 123.761335 -35.972111) (xy 123.76909 -36.026052)
			(xy 123.76909 -36.080548) (xy 123.761335 -36.134489) (xy 123.745982 -36.186778) (xy 123.723344 -36.23635)
			(xy 123.693882 -36.282195) (xy 123.658196 -36.323382) (xy 123.617011 -36.35907) (xy 123.571167 -36.388534)
			(xy 123.521597 -36.411175) (xy 123.469309 -36.42653) (xy 123.415368 -36.434288) (xy 123.38812 -36.434776)
			(xy 122.52452 -36.434776) (xy 122.497264 -36.434378) (xy 122.443306 -36.426623) (xy 122.391002 -36.411268)
			(xy 122.341415 -36.388624) (xy 122.295555 -36.359154) (xy 122.254357 -36.323458) (xy 122.218658 -36.282261)
			(xy 122.189185 -36.236403) (xy 122.166539 -36.186817) (xy 122.151181 -36.134513) (xy 122.143423 -36.080556)
			(xy 0.509016 -36.080556) (xy 0.509016 -39.23137) (xy 9.080235 -39.23137) (xy 9.080235 -39.10223)
			(xy 9.088185 -38.973335) (xy 9.104055 -38.845175) (xy 9.127784 -38.718234) (xy 9.159283 -38.592995)
			(xy 9.198432 -38.469932) (xy 9.245083 -38.349513) (xy 9.299058 -38.232194) (xy 9.360153 -38.11842)
			(xy 9.428136 -38.008623) (xy 9.50275 -37.90322) (xy 9.583711 -37.80261) (xy 9.670711 -37.707175)
			(xy 9.763422 -37.617276) (xy 9.861492 -37.533255) (xy 9.964547 -37.455431) (xy 10.072198 -37.384099)
			(xy 10.184037 -37.319529) (xy 10.299638 -37.261967) (xy 10.418563 -37.21163) (xy 10.540362 -37.16871)
			(xy 10.664572 -37.133369) (xy 10.790721 -37.105742) (xy 10.918333 -37.085933) (xy 11.046922 -37.074017)
			(xy 11.176 -37.070041) (xy 11.305078 -37.074017) (xy 11.433667 -37.085933) (xy 11.521898 -37.099629)
			(xy 170.60087 -37.099629) (xy 170.60087 -37.000299) (xy 170.608862 -36.901292) (xy 170.624796 -36.803249)
			(xy 170.648567 -36.706806) (xy 170.680022 -36.612588) (xy 170.718955 -36.521208) (xy 170.765116 -36.433256)
			(xy 170.818204 -36.349304) (xy 170.877875 -36.269895) (xy 170.943743 -36.195546) (xy 171.01538 -36.126738)
			(xy 171.092321 -36.063918) (xy 171.174067 -36.007493) (xy 171.260089 -35.957828) (xy 171.349828 -35.915246)
			(xy 171.442702 -35.880024) (xy 171.53811 -35.852388) (xy 171.635432 -35.83252) (xy 171.734037 -35.820547)
			(xy 171.833286 -35.816548) (xy 171.932535 -35.820547) (xy 172.03114 -35.83252) (xy 172.128462 -35.852388)
			(xy 172.22387 -35.880024) (xy 172.316744 -35.915246) (xy 172.406483 -35.957828) (xy 172.492505 -36.007493)
			(xy 172.574251 -36.063918) (xy 172.651192 -36.126738) (xy 172.722829 -36.195546) (xy 172.788697 -36.269895)
			(xy 172.848368 -36.349304) (xy 172.901456 -36.433256) (xy 172.947617 -36.521208) (xy 172.98655 -36.612588)
			(xy 173.018005 -36.706806) (xy 173.041776 -36.803249) (xy 173.05771 -36.901292) (xy 173.065702 -37.000299)
			(xy 173.066202 -37.049964) (xy 173.065702 -37.099629) (xy 173.05771 -37.198636) (xy 173.041776 -37.296679)
			(xy 173.034033 -37.328094) (xy 197.270624 -37.328094) (xy 197.271107 -37.28698) (xy 197.278695 -37.205103)
			(xy 197.293804 -37.124275) (xy 197.316307 -37.045187) (xy 197.346011 -36.968512) (xy 197.382664 -36.894904)
			(xy 197.425951 -36.824993) (xy 197.475504 -36.759373) (xy 197.5309 -36.698606) (xy 197.591667 -36.643209)
			(xy 197.657286 -36.593655) (xy 197.727197 -36.550367) (xy 197.800804 -36.513715) (xy 197.877479 -36.48401)
			(xy 197.956568 -36.461506) (xy 198.037395 -36.446396) (xy 198.119272 -36.438808) (xy 198.160386 -36.438332)
			(xy 198.203952 -36.438853) (xy 198.290667 -36.447372) (xy 198.376134 -36.464329) (xy 198.459533 -36.489562)
			(xy 198.540065 -36.522829) (xy 198.616958 -36.563811) (xy 198.689475 -36.612116) (xy 198.756921 -36.66728)
			(xy 198.81865 -36.728775) (xy 198.87407 -36.796011) (xy 198.922649 -36.868345) (xy 198.963923 -36.945081)
			(xy 198.997496 -37.025486) (xy 199.010778 -37.066982) (xy 199.013703 -37.075249) (xy 199.024271 -37.089233)
			(xy 199.038923 -37.098854) (xy 199.047354 -37.101272) (xy 199.088321 -37.111837) (xy 199.168226 -37.13965)
			(xy 199.24513 -37.174922) (xy 199.318339 -37.217334) (xy 199.387193 -37.266504) (xy 199.451068 -37.321986)
			(xy 199.509389 -37.383281) (xy 199.529427 -37.408809) (xy 207.619596 -37.408809) (xy 207.619596 -37.324087)
			(xy 207.627649 -37.23975) (xy 207.643683 -37.15656) (xy 207.667551 -37.07527) (xy 207.699039 -36.996618)
			(xy 207.737861 -36.921315) (xy 207.783664 -36.850043) (xy 207.836035 -36.783447) (xy 207.8945 -36.722132)
			(xy 207.958528 -36.666651) (xy 208.02754 -36.617508) (xy 208.10091 -36.575148) (xy 208.177975 -36.539953)
			(xy 208.258037 -36.512244) (xy 208.34037 -36.49227) (xy 208.424229 -36.480213) (xy 208.508854 -36.476182)
			(xy 208.593479 -36.480213) (xy 208.677338 -36.49227) (xy 208.759671 -36.512244) (xy 208.839733 -36.539953)
			(xy 208.916798 -36.575148) (xy 208.990168 -36.617508) (xy 209.05918 -36.666651) (xy 209.123208 -36.722132)
			(xy 209.181673 -36.783447) (xy 209.234044 -36.850043) (xy 209.279847 -36.921315) (xy 209.318669 -36.996618)
			(xy 209.350157 -37.07527) (xy 209.374025 -37.15656) (xy 209.390059 -37.23975) (xy 209.398112 -37.324087)
			(xy 209.398616 -37.366448) (xy 209.398112 -37.408809) (xy 209.390059 -37.493146) (xy 209.374025 -37.576336)
			(xy 209.350157 -37.657626) (xy 209.318669 -37.736278) (xy 209.279847 -37.811581) (xy 209.234044 -37.882853)
			(xy 209.181673 -37.949449) (xy 209.123208 -38.010764) (xy 209.05918 -38.066245) (xy 208.990168 -38.115388)
			(xy 208.916798 -38.157748) (xy 208.839733 -38.192943) (xy 208.759671 -38.220652) (xy 208.677338 -38.240626)
			(xy 208.593479 -38.252683) (xy 208.508854 -38.256715) (xy 208.424229 -38.252683) (xy 208.34037 -38.240626)
			(xy 208.258037 -38.220652) (xy 208.177975 -38.192943) (xy 208.10091 -38.157748) (xy 208.02754 -38.115388)
			(xy 207.958528 -38.066245) (xy 207.8945 -38.010764) (xy 207.836035 -37.949449) (xy 207.783664 -37.882853)
			(xy 207.737861 -37.811581) (xy 207.699039 -37.736278) (xy 207.667551 -37.657626) (xy 207.643683 -37.576336)
			(xy 207.627649 -37.493146) (xy 207.619596 -37.408809) (xy 199.529427 -37.408809) (xy 199.561629 -37.449835)
			(xy 199.607316 -37.521047) (xy 199.646037 -37.596273) (xy 199.677444 -37.674835) (xy 199.701252 -37.756024)
			(xy 199.717247 -37.839106) (xy 199.725284 -37.92333) (xy 199.725788 -37.965634) (xy 199.72532 -38.006748)
			(xy 199.71773 -38.088625) (xy 199.702618 -38.169453) (xy 199.680113 -38.248541) (xy 199.650407 -38.325216)
			(xy 199.613754 -38.398823) (xy 199.570465 -38.468734) (xy 199.520911 -38.534353) (xy 199.465514 -38.595119)
			(xy 199.404746 -38.650516) (xy 199.339127 -38.70007) (xy 199.269216 -38.743357) (xy 199.195608 -38.78001)
			(xy 199.118933 -38.809716) (xy 199.039845 -38.83222) (xy 198.959017 -38.847331) (xy 198.87714 -38.85492)
			(xy 198.836026 -38.855396) (xy 198.792461 -38.854844) (xy 198.705747 -38.846327) (xy 198.620282 -38.829372)
			(xy 198.536884 -38.804141) (xy 198.456353 -38.770876) (xy 198.379461 -38.729896) (xy 198.306944 -38.681594)
			(xy 198.239498 -38.626432) (xy 198.177769 -38.56494) (xy 198.122348 -38.497707) (xy 198.073767 -38.425377)
			(xy 198.032492 -38.348643) (xy 197.998917 -38.26824) (xy 197.985634 -38.226746) (xy 197.982688 -38.218487)
			(xy 197.97213 -38.204501) (xy 197.957486 -38.194877) (xy 197.949058 -38.192456) (xy 197.908101 -38.181857)
			(xy 197.828197 -38.154046) (xy 197.751293 -38.118776) (xy 197.678085 -38.076367) (xy 197.609232 -38.0272)
			(xy 197.545356 -37.97172) (xy 197.487035 -37.910428) (xy 197.434795 -37.843877) (xy 197.389107 -37.772668)
			(xy 197.350384 -37.697444) (xy 197.318976 -37.618885) (xy 197.295165 -37.537699) (xy 197.279169 -37.454619)
			(xy 197.271129 -37.370397) (xy 197.270624 -37.328094) (xy 173.034033 -37.328094) (xy 173.018005 -37.393122)
			(xy 172.98655 -37.48734) (xy 172.947617 -37.57872) (xy 172.901456 -37.666672) (xy 172.848368 -37.750624)
			(xy 172.788697 -37.830033) (xy 172.722829 -37.904382) (xy 172.651192 -37.97319) (xy 172.574251 -38.03601)
			(xy 172.492505 -38.092435) (xy 172.406483 -38.1421) (xy 172.316744 -38.184682) (xy 172.22387 -38.219904)
			(xy 172.128462 -38.24754) (xy 172.03114 -38.267408) (xy 171.932535 -38.279381) (xy 171.833286 -38.283381)
			(xy 171.734037 -38.279381) (xy 171.635432 -38.267408) (xy 171.53811 -38.24754) (xy 171.442702 -38.219904)
			(xy 171.349828 -38.184682) (xy 171.260089 -38.1421) (xy 171.174067 -38.092435) (xy 171.092321 -38.03601)
			(xy 171.01538 -37.97319) (xy 170.943743 -37.904382) (xy 170.877875 -37.830033) (xy 170.818204 -37.750624)
			(xy 170.765116 -37.666672) (xy 170.718955 -37.57872) (xy 170.680022 -37.48734) (xy 170.648567 -37.393122)
			(xy 170.624796 -37.296679) (xy 170.608862 -37.198636) (xy 170.60087 -37.099629) (xy 11.521898 -37.099629)
			(xy 11.561279 -37.105742) (xy 11.687428 -37.133369) (xy 11.811638 -37.16871) (xy 11.933437 -37.21163)
			(xy 12.052362 -37.261967) (xy 12.167963 -37.319529) (xy 12.279802 -37.384099) (xy 12.387453 -37.455431)
			(xy 12.490508 -37.533255) (xy 12.588578 -37.617276) (xy 12.681289 -37.707175) (xy 12.768289 -37.80261)
			(xy 12.84925 -37.90322) (xy 12.923864 -38.008623) (xy 12.991847 -38.11842) (xy 13.052942 -38.232194)
			(xy 13.106917 -38.349513) (xy 13.153568 -38.469932) (xy 13.192717 -38.592995) (xy 13.224216 -38.718234)
			(xy 13.247945 -38.845175) (xy 13.263815 -38.973335) (xy 13.271765 -39.10223) (xy 13.272262 -39.1668)
			(xy 13.271765 -39.23137) (xy 13.263815 -39.360265) (xy 13.256012 -39.423283) (xy 254.45872 -39.423283)
			(xy 254.45872 -39.338561) (xy 254.466773 -39.254224) (xy 254.482807 -39.171034) (xy 254.506675 -39.089744)
			(xy 254.538163 -39.011092) (xy 254.576985 -38.935789) (xy 254.622788 -38.864517) (xy 254.675159 -38.797921)
			(xy 254.733624 -38.736606) (xy 254.797652 -38.681125) (xy 254.866664 -38.631982) (xy 254.940034 -38.589622)
			(xy 255.017099 -38.554427) (xy 255.097161 -38.526718) (xy 255.179494 -38.506744) (xy 255.263353 -38.494687)
			(xy 255.347978 -38.490656) (xy 255.432603 -38.494687) (xy 255.516462 -38.506744) (xy 255.598795 -38.526718)
			(xy 255.678857 -38.554427) (xy 255.755922 -38.589622) (xy 255.829292 -38.631982) (xy 255.898304 -38.681125)
			(xy 255.962332 -38.736606) (xy 256.020797 -38.797921) (xy 256.073168 -38.864517) (xy 256.118971 -38.935789)
			(xy 256.157793 -39.011092) (xy 256.189281 -39.089744) (xy 256.213149 -39.171034) (xy 256.229183 -39.254224)
			(xy 256.237236 -39.338561) (xy 256.23774 -39.380922) (xy 256.237236 -39.423283) (xy 256.229183 -39.50762)
			(xy 256.213149 -39.59081) (xy 256.189281 -39.6721) (xy 256.157793 -39.750752) (xy 256.118971 -39.826055)
			(xy 256.073168 -39.897327) (xy 256.020797 -39.963923) (xy 255.962332 -40.025238) (xy 255.898304 -40.080719)
			(xy 255.829292 -40.129862) (xy 255.755922 -40.172222) (xy 255.678857 -40.207417) (xy 255.598795 -40.235126)
			(xy 255.516462 -40.2551) (xy 255.432603 -40.267157) (xy 255.347978 -40.271189) (xy 255.263353 -40.267157)
			(xy 255.179494 -40.2551) (xy 255.097161 -40.235126) (xy 255.017099 -40.207417) (xy 254.940034 -40.172222)
			(xy 254.866664 -40.129862) (xy 254.797652 -40.080719) (xy 254.733624 -40.025238) (xy 254.675159 -39.963923)
			(xy 254.622788 -39.897327) (xy 254.576985 -39.826055) (xy 254.538163 -39.750752) (xy 254.506675 -39.6721)
			(xy 254.482807 -39.59081) (xy 254.466773 -39.50762) (xy 254.45872 -39.423283) (xy 13.256012 -39.423283)
			(xy 13.247945 -39.488425) (xy 13.224216 -39.615366) (xy 13.192717 -39.740605) (xy 13.153568 -39.863668)
			(xy 13.106917 -39.984087) (xy 13.052942 -40.101406) (xy 12.991847 -40.21518) (xy 12.923864 -40.324977)
			(xy 12.84925 -40.43038) (xy 12.768289 -40.53099) (xy 12.681289 -40.626425) (xy 12.588578 -40.716324)
			(xy 12.490508 -40.800345) (xy 12.413317 -40.858637) (xy 24.936192 -40.858637) (xy 24.936192 -40.773915)
			(xy 24.944245 -40.689578) (xy 24.960279 -40.606388) (xy 24.984147 -40.525098) (xy 25.015635 -40.446446)
			(xy 25.054457 -40.371143) (xy 25.10026 -40.299871) (xy 25.152631 -40.233275) (xy 25.211096 -40.17196)
			(xy 25.275124 -40.116479) (xy 25.344136 -40.067336) (xy 25.417506 -40.024976) (xy 25.494571 -39.989781)
			(xy 25.574633 -39.962072) (xy 25.656966 -39.942098) (xy 25.740825 -39.930041) (xy 25.82545 -39.92601)
			(xy 25.910075 -39.930041) (xy 25.993934 -39.942098) (xy 26.076267 -39.962072) (xy 26.156329 -39.989781)
			(xy 26.233394 -40.024976) (xy 26.306764 -40.067336) (xy 26.375776 -40.116479) (xy 26.439804 -40.17196)
			(xy 26.498269 -40.233275) (xy 26.55064 -40.299871) (xy 26.596443 -40.371143) (xy 26.635265 -40.446446)
			(xy 26.666753 -40.525098) (xy 26.690621 -40.606388) (xy 26.706655 -40.689578) (xy 26.711938 -40.744902)
			(xy 235.083357 -40.744902) (xy 235.087362 -40.656994) (xy 235.099345 -40.569814) (xy 235.119205 -40.484085)
			(xy 235.14678 -40.400517) (xy 235.181839 -40.319803) (xy 235.224092 -40.242611) (xy 235.27319 -40.169582)
			(xy 235.328726 -40.10132) (xy 235.390238 -40.03839) (xy 235.457219 -39.981316) (xy 235.529112 -39.930568)
			(xy 235.605321 -39.886568) (xy 235.685216 -39.849681) (xy 235.768135 -39.820212) (xy 235.85339 -39.798405)
			(xy 235.940274 -39.784441) (xy 236.028068 -39.778435) (xy 236.116045 -39.780439) (xy 236.203475 -39.790434)
			(xy 236.289634 -39.808338) (xy 236.373808 -39.834002) (xy 236.455299 -39.867215) (xy 236.533433 -39.907701)
			(xy 236.607561 -39.955123) (xy 236.677069 -40.00909) (xy 236.741383 -40.069155) (xy 236.799967 -40.134819)
			(xy 236.852338 -40.205538) (xy 236.898061 -40.280726) (xy 236.936758 -40.359761) (xy 236.968107 -40.441987)
			(xy 236.991849 -40.526723) (xy 237.007787 -40.613267) (xy 237.015789 -40.700902) (xy 237.01629 -40.744902)
			(xy 237.015789 -40.788902) (xy 237.007787 -40.876537) (xy 236.994276 -40.9499) (xy 246.935452 -40.9499)
			(xy 246.939482 -40.865295) (xy 246.951537 -40.781456) (xy 246.971506 -40.699142) (xy 246.999209 -40.619099)
			(xy 247.034396 -40.542053) (xy 247.076747 -40.468699) (xy 247.125879 -40.399704) (xy 247.181347 -40.335692)
			(xy 247.242648 -40.277242) (xy 247.309228 -40.224883) (xy 247.380484 -40.179091) (xy 247.45577 -40.14028)
			(xy 247.534404 -40.1088) (xy 247.615675 -40.084938) (xy 247.698846 -40.06891) (xy 247.783163 -40.060859)
			(xy 247.825514 -40.060372) (xy 247.868043 -40.060872) (xy 247.952713 -40.068982) (xy 248.036223 -40.085137)
			(xy 248.11781 -40.109189) (xy 248.196728 -40.140918) (xy 248.272258 -40.180035) (xy 248.343709 -40.226182)
			(xy 248.41043 -40.278938) (xy 248.441464 -40.308022) (xy 248.441718 -40.308276) (xy 248.44904 -40.314652)
			(xy 248.467069 -40.321822) (xy 248.47677 -40.322246) (xy 248.557288 -40.321992) (xy 248.575576 -40.314626)
			(xy 248.582688 -40.307514) (xy 248.613778 -40.278057) (xy 248.680689 -40.224588) (xy 248.752429 -40.177798)
			(xy 248.828335 -40.13812) (xy 248.907704 -40.105923) (xy 248.9898 -40.081504) (xy 249.073863 -40.065089)
			(xy 249.159115 -40.056831) (xy 249.20194 -40.056308) (xy 249.202448 -40.056308) (xy 249.244796 -40.056782)
			(xy 249.329107 -40.064837) (xy 249.412272 -40.08087) (xy 249.493536 -40.104735) (xy 249.572163 -40.136216)
			(xy 249.647442 -40.175029) (xy 249.718691 -40.220821) (xy 249.785265 -40.273178) (xy 249.84656 -40.331627)
			(xy 249.902022 -40.395637) (xy 249.951149 -40.464629) (xy 249.993496 -40.537978) (xy 250.028678 -40.615021)
			(xy 250.056379 -40.695058) (xy 250.076346 -40.777367) (xy 250.088399 -40.8612) (xy 250.092429 -40.9458)
			(xy 250.088399 -41.0304) (xy 250.076346 -41.114233) (xy 250.056379 -41.196542) (xy 250.028678 -41.276579)
			(xy 249.993496 -41.353622) (xy 249.951149 -41.426971) (xy 249.902022 -41.495963) (xy 249.84656 -41.559973)
			(xy 249.785265 -41.618422) (xy 249.718691 -41.670779) (xy 249.647442 -41.716571) (xy 249.572163 -41.755384)
			(xy 249.493536 -41.786865) (xy 249.412272 -41.81073) (xy 249.329107 -41.826763) (xy 249.244796 -41.834818)
			(xy 249.202448 -41.835324) (xy 249.159919 -41.834822) (xy 249.07525 -41.826709) (xy 248.991741 -41.810552)
			(xy 248.910155 -41.7865) (xy 248.831237 -41.754771) (xy 248.755707 -41.715655) (xy 248.684255 -41.66951)
			(xy 248.617533 -41.616756) (xy 248.586498 -41.587674) (xy 248.586244 -41.58742) (xy 248.578903 -41.58107)
			(xy 248.560888 -41.573885) (xy 248.551192 -41.57345) (xy 248.470674 -41.573704) (xy 248.452386 -41.58107)
			(xy 248.445274 -41.588182) (xy 248.414201 -41.617657) (xy 248.347287 -41.671125) (xy 248.275544 -41.717913)
			(xy 248.199635 -41.757589) (xy 248.120264 -41.789784) (xy 248.038166 -41.8142) (xy 247.954101 -41.830612)
			(xy 247.868848 -41.838866) (xy 247.826022 -41.839388) (xy 247.825514 -41.839388) (xy 247.783163 -41.838941)
			(xy 247.698846 -41.83089) (xy 247.615675 -41.814862) (xy 247.534404 -41.791) (xy 247.45577 -41.75952)
			(xy 247.380484 -41.720709) (xy 247.309228 -41.674917) (xy 247.242648 -41.622558) (xy 247.181347 -41.564108)
			(xy 247.125879 -41.500096) (xy 247.076747 -41.431101) (xy 247.034396 -41.357747) (xy 246.999209 -41.280701)
			(xy 246.971506 -41.200658) (xy 246.951537 -41.118344) (xy 246.939482 -41.034505) (xy 246.935452 -40.9499)
			(xy 236.994276 -40.9499) (xy 236.991849 -40.963081) (xy 236.968107 -41.047817) (xy 236.936758 -41.130043)
			(xy 236.898061 -41.209078) (xy 236.852338 -41.284266) (xy 236.799967 -41.354985) (xy 236.741383 -41.420649)
			(xy 236.677069 -41.480714) (xy 236.607561 -41.534681) (xy 236.533433 -41.582103) (xy 236.455299 -41.622589)
			(xy 236.373808 -41.655802) (xy 236.289634 -41.681466) (xy 236.203475 -41.69937) (xy 236.116045 -41.709365)
			(xy 236.028068 -41.711369) (xy 235.940274 -41.705363) (xy 235.85339 -41.691399) (xy 235.768135 -41.669592)
			(xy 235.685216 -41.640123) (xy 235.605321 -41.603236) (xy 235.529112 -41.559236) (xy 235.457219 -41.508488)
			(xy 235.390238 -41.451414) (xy 235.328726 -41.388484) (xy 235.27319 -41.320222) (xy 235.224092 -41.247193)
			(xy 235.181839 -41.170001) (xy 235.14678 -41.089287) (xy 235.119205 -41.005719) (xy 235.099345 -40.91999)
			(xy 235.087362 -40.83281) (xy 235.083357 -40.744902) (xy 26.711938 -40.744902) (xy 26.714708 -40.773915)
			(xy 26.715212 -40.816276) (xy 26.714708 -40.858637) (xy 26.706655 -40.942974) (xy 26.690621 -41.026164)
			(xy 26.666753 -41.107454) (xy 26.635265 -41.186106) (xy 26.596443 -41.261409) (xy 26.55064 -41.332681)
			(xy 26.498269 -41.399277) (xy 26.439804 -41.460592) (xy 26.375776 -41.516073) (xy 26.306764 -41.565216)
			(xy 26.233394 -41.607576) (xy 26.156329 -41.642771) (xy 26.076267 -41.67048) (xy 25.993934 -41.690454)
			(xy 25.910075 -41.702511) (xy 25.82545 -41.706543) (xy 25.740825 -41.702511) (xy 25.656966 -41.690454)
			(xy 25.574633 -41.67048) (xy 25.494571 -41.642771) (xy 25.417506 -41.607576) (xy 25.344136 -41.565216)
			(xy 25.275124 -41.516073) (xy 25.211096 -41.460592) (xy 25.152631 -41.399277) (xy 25.10026 -41.332681)
			(xy 25.054457 -41.261409) (xy 25.015635 -41.186106) (xy 24.984147 -41.107454) (xy 24.960279 -41.026164)
			(xy 24.944245 -40.942974) (xy 24.936192 -40.858637) (xy 12.413317 -40.858637) (xy 12.387453 -40.878169)
			(xy 12.279802 -40.949501) (xy 12.167963 -41.014071) (xy 12.052362 -41.071633) (xy 11.933437 -41.12197)
			(xy 11.811638 -41.16489) (xy 11.687428 -41.200231) (xy 11.561279 -41.227858) (xy 11.433667 -41.247667)
			(xy 11.305078 -41.259583) (xy 11.176 -41.26356) (xy 11.046922 -41.259583) (xy 10.918333 -41.247667)
			(xy 10.790721 -41.227858) (xy 10.664572 -41.200231) (xy 10.540362 -41.16489) (xy 10.418563 -41.12197)
			(xy 10.299638 -41.071633) (xy 10.184037 -41.014071) (xy 10.072198 -40.949501) (xy 9.964547 -40.878169)
			(xy 9.861492 -40.800345) (xy 9.763422 -40.716324) (xy 9.670711 -40.626425) (xy 9.583711 -40.53099)
			(xy 9.50275 -40.43038) (xy 9.428136 -40.324977) (xy 9.360153 -40.21518) (xy 9.299058 -40.101406)
			(xy 9.245083 -39.984087) (xy 9.198432 -39.863668) (xy 9.159283 -39.740605) (xy 9.127784 -39.615366)
			(xy 9.104055 -39.488425) (xy 9.088185 -39.360265) (xy 9.080235 -39.23137) (xy 0.509016 -39.23137)
			(xy 0.509016 -43.481752) (xy 178.630072 -43.481752) (xy 178.630072 -42.618152) (xy 178.630558 -42.590883)
			(xy 178.63832 -42.536899) (xy 178.653685 -42.484569) (xy 178.676342 -42.434959) (xy 178.705828 -42.389078)
			(xy 178.741543 -42.347861) (xy 178.78276 -42.312146) (xy 178.828641 -42.28266) (xy 178.878251 -42.260003)
			(xy 178.930581 -42.244638) (xy 178.984565 -42.236876) (xy 179.039103 -42.236876) (xy 179.093087 -42.244638)
			(xy 179.145417 -42.260003) (xy 179.195027 -42.28266) (xy 179.240908 -42.312146) (xy 179.282125 -42.347861)
			(xy 179.31784 -42.389078) (xy 179.347326 -42.434959) (xy 179.369983 -42.484569) (xy 179.385348 -42.536899)
			(xy 179.39311 -42.590883) (xy 179.393596 -42.618152) (xy 179.393596 -43.481752) (xy 179.39311 -43.509021)
			(xy 179.385348 -43.563005) (xy 179.369983 -43.615335) (xy 179.347326 -43.664945) (xy 179.31784 -43.710826)
			(xy 179.282125 -43.752043) (xy 179.240908 -43.787758) (xy 179.195027 -43.817244) (xy 179.145417 -43.839901)
			(xy 179.093087 -43.855266) (xy 179.039103 -43.863028) (xy 178.984565 -43.863028) (xy 178.930581 -43.855266)
			(xy 178.878251 -43.839901) (xy 178.828641 -43.817244) (xy 178.78276 -43.787758) (xy 178.741543 -43.752043)
			(xy 178.705828 -43.710826) (xy 178.676342 -43.664945) (xy 178.653685 -43.615335) (xy 178.63832 -43.563005)
			(xy 178.630558 -43.509021) (xy 178.630072 -43.481752) (xy 0.509016 -43.481752) (xy 0.509016 -47.04994)
			(xy 59.582066 -47.04994) (xy 59.586045 -46.890389) (xy 59.597972 -46.731234) (xy 59.617818 -46.572872)
			(xy 59.645532 -46.415696) (xy 59.681047 -46.260096) (xy 59.724273 -46.10646) (xy 59.775104 -45.95517)
			(xy 59.833413 -45.806602) (xy 59.899054 -45.661125) (xy 59.971866 -45.519101) (xy 60.051666 -45.380882)
			(xy 60.138257 -45.246813) (xy 60.231423 -45.117227) (xy 60.330933 -44.992446) (xy 60.436538 -44.87278)
			(xy 60.547978 -44.758527) (xy 60.664973 -44.649971) (xy 60.787235 -44.547381) (xy 60.914458 -44.451014)
			(xy 61.046326 -44.361107) (xy 61.182512 -44.277886) (xy 61.322677 -44.201556) (xy 61.466472 -44.132307)
			(xy 61.613541 -44.070313) (xy 61.763517 -44.015726) (xy 61.916027 -43.968683) (xy 62.070693 -43.9293)
			(xy 62.227129 -43.897676) (xy 62.384947 -43.873888) (xy 62.543755 -43.857997) (xy 62.703158 -43.850041)
			(xy 62.782958 -43.849544) (xy 64.382904 -43.849544) (xy 64.462705 -43.850033) (xy 64.622107 -43.857989)
			(xy 64.780916 -43.87388) (xy 64.938734 -43.897668) (xy 65.095171 -43.929293) (xy 65.249837 -43.968675)
			(xy 65.402347 -44.015719) (xy 65.552323 -44.070306) (xy 65.699392 -44.132301) (xy 65.843188 -44.201549)
			(xy 65.983353 -44.277879) (xy 66.119539 -44.361101) (xy 66.251408 -44.451008) (xy 66.378631 -44.547376)
			(xy 66.500893 -44.649966) (xy 66.617889 -44.758522) (xy 66.729328 -44.872775) (xy 66.834934 -44.992442)
			(xy 66.934444 -45.117223) (xy 67.02761 -45.246809) (xy 67.114201 -45.380878) (xy 67.194001 -45.519097)
			(xy 67.266813 -45.661122) (xy 67.332455 -45.806599) (xy 67.390764 -45.955168) (xy 67.441595 -46.106458)
			(xy 67.484821 -46.260094) (xy 67.520336 -46.415694) (xy 67.54805 -46.572871) (xy 67.567896 -46.731233)
			(xy 67.579823 -46.890388) (xy 67.583802 -47.04994) (xy 89.78165 -47.04994) (xy 89.78563 -46.895439)
			(xy 89.797557 -46.741349) (xy 89.817402 -46.588076) (xy 89.84511 -46.436028) (xy 89.880608 -46.285609)
			(xy 89.923803 -46.137216) (xy 89.97458 -45.991243) (xy 90.032804 -45.848078) (xy 90.098321 -45.708101)
			(xy 90.170957 -45.571681) (xy 90.250519 -45.439181) (xy 90.336796 -45.310953) (xy 90.42956 -45.187337)
			(xy 90.528565 -45.068659) (xy 90.633548 -44.955236) (xy 90.74423 -44.847368) (xy 90.860319 -44.74534)
			(xy 90.981506 -44.649424) (xy 91.10747 -44.559873) (xy 91.237877 -44.476926) (xy 91.372381 -44.400801)
			(xy 91.510626 -44.331702) (xy 91.652244 -44.269811) (xy 91.796861 -44.215293) (xy 91.944092 -44.168291)
			(xy 92.093548 -44.128931) (xy 92.244832 -44.097317) (xy 92.397543 -44.073533) (xy 92.551275 -44.057642)
			(xy 92.705622 -44.049686) (xy 92.782898 -44.049188) (xy 94.383098 -44.049188) (xy 94.460374 -44.049669)
			(xy 94.614722 -44.057625) (xy 94.768456 -44.073516) (xy 94.921168 -44.0973) (xy 95.072452 -44.128914)
			(xy 95.221909 -44.168274) (xy 95.369142 -44.215276) (xy 95.513759 -44.269795) (xy 95.655379 -44.331686)
			(xy 95.793624 -44.400785) (xy 95.928129 -44.47691) (xy 96.058537 -44.559858) (xy 96.184502 -44.649409)
			(xy 96.30569 -44.745326) (xy 96.421779 -44.847354) (xy 96.532463 -44.955223) (xy 96.555487 -44.980098)
			(xy 181.659784 -44.980098) (xy 181.659784 -44.116498) (xy 181.66027 -44.089229) (xy 181.668032 -44.035245)
			(xy 181.683397 -43.982915) (xy 181.706054 -43.933305) (xy 181.73554 -43.887424) (xy 181.771255 -43.846207)
			(xy 181.812472 -43.810492) (xy 181.858353 -43.781006) (xy 181.907963 -43.758349) (xy 181.960293 -43.742984)
			(xy 182.014277 -43.735222) (xy 182.068815 -43.735222) (xy 182.122799 -43.742984) (xy 182.175129 -43.758349)
			(xy 182.224739 -43.781006) (xy 182.27062 -43.810492) (xy 182.311837 -43.846207) (xy 182.347552 -43.887424)
			(xy 182.377038 -43.933305) (xy 182.399695 -43.982915) (xy 182.412218 -44.025566) (xy 236.740192 -44.025566)
			(xy 236.74068 -43.984453) (xy 236.74827 -43.902577) (xy 236.763381 -43.82175) (xy 236.785886 -43.742663)
			(xy 236.815591 -43.665989) (xy 236.852243 -43.592383) (xy 236.895531 -43.522473) (xy 236.945083 -43.456854)
			(xy 237.000479 -43.396088) (xy 237.061245 -43.340691) (xy 237.126863 -43.291137) (xy 237.196773 -43.247849)
			(xy 237.270378 -43.211196) (xy 237.347052 -43.181489) (xy 237.426139 -43.158984) (xy 237.506965 -43.143872)
			(xy 237.588841 -43.136281) (xy 237.629954 -43.135804) (xy 237.672596 -43.136331) (xy 237.757484 -43.144543)
			(xy 237.841197 -43.160838) (xy 237.922968 -43.185068) (xy 237.962694 -43.200574) (xy 237.971356 -43.203655)
			(xy 237.989722 -43.204046) (xy 237.998508 -43.201336) (xy 238.034032 -43.189272) (xy 238.106663 -43.170452)
			(xy 238.18062 -43.157817) (xy 238.25538 -43.151455) (xy 238.292894 -43.151044) (xy 238.332166 -43.151496)
			(xy 238.410399 -43.158477) (xy 238.487712 -43.172332) (xy 238.563501 -43.192954) (xy 238.600488 -43.206162)
			(xy 238.609037 -43.208926) (xy 238.626991 -43.208926) (xy 238.63554 -43.206162) (xy 238.672533 -43.192975)
			(xy 238.748323 -43.172363) (xy 238.825633 -43.158506) (xy 238.903863 -43.151512) (xy 238.943134 -43.151044)
			(xy 238.981423 -43.151469) (xy 239.057717 -43.158071) (xy 239.133159 -43.171215) (xy 239.207191 -43.190803)
			(xy 239.243362 -43.203368) (xy 239.251799 -43.206019) (xy 239.269469 -43.206019) (xy 239.277906 -43.203368)
			(xy 239.314089 -43.190839) (xy 239.38812 -43.171262) (xy 239.463558 -43.158111) (xy 239.539846 -43.151482)
			(xy 239.578134 -43.151044) (xy 239.616423 -43.151469) (xy 239.692717 -43.158071) (xy 239.768159 -43.171215)
			(xy 239.842191 -43.190803) (xy 239.878362 -43.203368) (xy 239.886799 -43.206019) (xy 239.904469 -43.206019)
			(xy 239.912906 -43.203368) (xy 239.949089 -43.190839) (xy 240.02312 -43.171262) (xy 240.098558 -43.158111)
			(xy 240.174846 -43.151482) (xy 240.213134 -43.151044) (xy 240.25606 -43.151581) (xy 240.341511 -43.159862)
			(xy 240.425768 -43.176335) (xy 240.508046 -43.200846) (xy 240.587581 -43.233168) (xy 240.613613 -43.246802)
			(xy 243.62918 -43.246802) (xy 243.629584 -43.208512) (xy 243.636192 -43.132218) (xy 243.649342 -43.056775)
			(xy 243.668936 -42.982745) (xy 243.681504 -42.946574) (xy 243.684156 -42.938137) (xy 243.684156 -42.920466)
			(xy 243.681504 -42.91203) (xy 243.668959 -42.875853) (xy 243.649386 -42.80182) (xy 243.636239 -42.72638)
			(xy 243.629616 -42.65009) (xy 243.62918 -42.611802) (xy 243.629684 -42.569441) (xy 243.637737 -42.485104)
			(xy 243.653771 -42.401914) (xy 243.677639 -42.320624) (xy 243.709127 -42.241972) (xy 243.747949 -42.166669)
			(xy 243.793752 -42.095397) (xy 243.846123 -42.028801) (xy 243.904588 -41.967486) (xy 243.968616 -41.912005)
			(xy 244.037628 -41.862862) (xy 244.110998 -41.820502) (xy 244.188063 -41.785307) (xy 244.268125 -41.757598)
			(xy 244.350458 -41.737624) (xy 244.434317 -41.725567) (xy 244.518942 -41.721536) (xy 244.603567 -41.725567)
			(xy 244.687426 -41.737624) (xy 244.769759 -41.757598) (xy 244.849821 -41.785307) (xy 244.926886 -41.820502)
			(xy 245.000256 -41.862862) (xy 245.069268 -41.912005) (xy 245.133296 -41.967486) (xy 245.191761 -42.028801)
			(xy 245.244132 -42.095397) (xy 245.289935 -42.166669) (xy 245.328757 -42.241972) (xy 245.360245 -42.320624)
			(xy 245.384113 -42.401914) (xy 245.400147 -42.485104) (xy 245.4082 -42.569441) (xy 245.408704 -42.611802)
			(xy 245.408302 -42.650092) (xy 245.401694 -42.726386) (xy 245.388543 -42.801829) (xy 245.368949 -42.875859)
			(xy 245.35638 -42.91203) (xy 245.353727 -42.920466) (xy 245.353728 -42.938137) (xy 245.35638 -42.946574)
			(xy 245.368926 -42.982751) (xy 245.388499 -43.056784) (xy 245.401645 -43.132224) (xy 245.408269 -43.208514)
			(xy 245.408704 -43.246802) (xy 245.4082 -43.289163) (xy 245.400147 -43.3735) (xy 245.384113 -43.45669)
			(xy 245.360245 -43.53798) (xy 245.328757 -43.616632) (xy 245.289935 -43.691935) (xy 245.244132 -43.763207)
			(xy 245.191761 -43.829803) (xy 245.133296 -43.891118) (xy 245.069268 -43.946599) (xy 245.000256 -43.995742)
			(xy 244.926886 -44.038102) (xy 244.849821 -44.073297) (xy 244.769759 -44.101006) (xy 244.687426 -44.12098)
			(xy 244.603567 -44.133037) (xy 244.518942 -44.137069) (xy 244.434317 -44.133037) (xy 244.350458 -44.12098)
			(xy 244.268125 -44.101006) (xy 244.188063 -44.073297) (xy 244.110998 -44.038102) (xy 244.037628 -43.995742)
			(xy 243.968616 -43.946599) (xy 243.904588 -43.891118) (xy 243.846123 -43.829803) (xy 243.793752 -43.763207)
			(xy 243.747949 -43.691935) (xy 243.709127 -43.616632) (xy 243.677639 -43.53798) (xy 243.653771 -43.45669)
			(xy 243.637737 -43.3735) (xy 243.629684 -43.289163) (xy 243.62918 -43.246802) (xy 240.613613 -43.246802)
			(xy 240.663633 -43.272999) (xy 240.735496 -43.31997) (xy 240.802501 -43.373643) (xy 240.864025 -43.433521)
			(xy 240.919496 -43.499046) (xy 240.968398 -43.569608) (xy 241.010277 -43.644552) (xy 241.044744 -43.723182)
			(xy 241.071477 -43.804765) (xy 241.090229 -43.888544) (xy 241.096038 -43.931078) (xy 241.097792 -43.94092)
			(xy 241.107661 -43.958279) (xy 241.123386 -43.970587) (xy 241.132868 -43.97375) (xy 241.172506 -43.985287)
			(xy 241.249638 -44.014728) (xy 241.32371 -44.051189) (xy 241.394086 -44.094356) (xy 241.460159 -44.143858)
			(xy 241.521362 -44.199269) (xy 241.577167 -44.260112) (xy 241.627095 -44.325864) (xy 241.670716 -44.395959)
			(xy 241.707655 -44.469795) (xy 241.737594 -44.546735) (xy 241.760276 -44.626118) (xy 241.775505 -44.707261)
			(xy 241.78315 -44.789466) (xy 241.783616 -44.830746) (xy 241.783231 -44.871862) (xy 241.775639 -44.953744)
			(xy 241.760525 -45.034576) (xy 241.738017 -45.113668) (xy 241.708307 -45.190346) (xy 241.671649 -45.263956)
			(xy 241.628355 -45.333869) (xy 241.578796 -45.39949) (xy 241.523393 -45.460258) (xy 241.462619 -45.515654)
			(xy 241.396993 -45.565207) (xy 241.327075 -45.608494) (xy 241.253462 -45.645144) (xy 241.176781 -45.674846)
			(xy 241.097686 -45.697346) (xy 241.016853 -45.712452) (xy 240.93497 -45.720035) (xy 240.893854 -45.720508)
			(xy 240.848047 -45.719908) (xy 240.756919 -45.710469) (xy 240.667241 -45.691726) (xy 240.579961 -45.663878)
			(xy 240.537746 -45.646086) (xy 240.528923 -45.642621) (xy 240.509997 -45.641842) (xy 240.500916 -45.644562)
			(xy 240.454475 -45.659757) (xy 240.359116 -45.681105) (xy 240.261993 -45.691873) (xy 240.213134 -45.692568)
			(xy 240.174844 -45.692152) (xy 240.09855 -45.685547) (xy 240.023108 -45.672401) (xy 239.949077 -45.652811)
			(xy 239.912906 -45.640244) (xy 239.904469 -45.637593) (xy 239.886799 -45.637593) (xy 239.878362 -45.640244)
			(xy 239.842183 -45.652782) (xy 239.76815 -45.672357) (xy 239.692711 -45.685505) (xy 239.616422 -45.692131)
			(xy 239.578134 -45.692568) (xy 239.539844 -45.692152) (xy 239.46355 -45.685547) (xy 239.388108 -45.672401)
			(xy 239.314077 -45.652811) (xy 239.277906 -45.640244) (xy 239.269469 -45.637593) (xy 239.251799 -45.637593)
			(xy 239.243362 -45.640244) (xy 239.207183 -45.652782) (xy 239.13315 -45.672357) (xy 239.057711 -45.685505)
			(xy 238.981422 -45.692131) (xy 238.943134 -45.692568) (xy 238.903862 -45.692107) (xy 238.825629 -45.685129)
			(xy 238.748316 -45.671276) (xy 238.672527 -45.650657) (xy 238.63554 -45.63745) (xy 238.626991 -45.634686)
			(xy 238.609037 -45.634686) (xy 238.600488 -45.63745) (xy 238.563502 -45.650659) (xy 238.48771 -45.671265)
			(xy 238.410397 -45.685115) (xy 238.332165 -45.692103) (xy 238.292894 -45.692568) (xy 238.24936 -45.692039)
			(xy 238.16271 -45.683524) (xy 238.077306 -45.666586) (xy 237.993965 -45.641387) (xy 237.913484 -45.608168)
			(xy 237.87481 -45.588174) (xy 237.86657 -45.584248) (xy 237.848476 -45.581916) (xy 237.839504 -45.583602)
			(xy 237.790336 -45.594179) (xy 237.690402 -45.605511) (xy 237.640114 -45.606208) (xy 237.599001 -45.605674)
			(xy 237.517127 -45.598088) (xy 237.436301 -45.582981) (xy 237.357214 -45.560481) (xy 237.280541 -45.53078)
			(xy 237.206935 -45.494131) (xy 237.137024 -45.450847) (xy 237.071406 -45.401297) (xy 237.010639 -45.345904)
			(xy 236.955242 -45.285141) (xy 236.905687 -45.219525) (xy 236.862399 -45.149618) (xy 236.825745 -45.076014)
			(xy 236.796038 -44.999343) (xy 236.773533 -44.920257) (xy 236.75842 -44.839433) (xy 236.750829 -44.757559)
			(xy 236.750352 -44.716446) (xy 236.750814 -44.676228) (xy 236.758123 -44.596123) (xy 236.772622 -44.517004)
			(xy 236.794193 -44.439513) (xy 236.80801 -44.40174) (xy 236.811025 -44.392621) (xy 236.810769 -44.373433)
			(xy 236.807502 -44.364402) (xy 236.791394 -44.324025) (xy 236.766206 -44.240819) (xy 236.749266 -44.15555)
			(xy 236.740738 -44.069034) (xy 236.740192 -44.025566) (xy 182.412218 -44.025566) (xy 182.41506 -44.035245)
			(xy 182.422822 -44.089229) (xy 182.423308 -44.116498) (xy 182.423308 -44.980098) (xy 182.422822 -45.007367)
			(xy 182.41506 -45.061351) (xy 182.399695 -45.113681) (xy 182.377038 -45.163291) (xy 182.347552 -45.209172)
			(xy 182.311837 -45.250389) (xy 182.27062 -45.286104) (xy 182.224739 -45.31559) (xy 182.175129 -45.338247)
			(xy 182.122799 -45.353612) (xy 182.068815 -45.361374) (xy 182.014277 -45.361374) (xy 181.960293 -45.353612)
			(xy 181.907963 -45.338247) (xy 181.858353 -45.31559) (xy 181.812472 -45.286104) (xy 181.771255 -45.250389)
			(xy 181.73554 -45.209172) (xy 181.706054 -45.163291) (xy 181.683397 -45.113681) (xy 181.668032 -45.061351)
			(xy 181.66027 -45.007367) (xy 181.659784 -44.980098) (xy 96.555487 -44.980098) (xy 96.637446 -45.068647)
			(xy 96.736452 -45.187325) (xy 96.829216 -45.310943) (xy 96.915495 -45.439171) (xy 96.995057 -45.571672)
			(xy 97.067693 -45.708092) (xy 97.133211 -45.848071) (xy 97.191435 -45.991237) (xy 97.242212 -46.13721)
			(xy 97.285407 -46.285604) (xy 97.320906 -46.436025) (xy 97.329238 -46.481746) (xy 178.630072 -46.481746)
			(xy 178.630072 -45.618146) (xy 178.630558 -45.590877) (xy 178.63832 -45.536893) (xy 178.653685 -45.484563)
			(xy 178.676342 -45.434953) (xy 178.705828 -45.389072) (xy 178.741543 -45.347855) (xy 178.78276 -45.31214)
			(xy 178.828641 -45.282654) (xy 178.878251 -45.259997) (xy 178.930581 -45.244632) (xy 178.984565 -45.23687)
			(xy 179.039103 -45.23687) (xy 179.093087 -45.244632) (xy 179.145417 -45.259997) (xy 179.195027 -45.282654)
			(xy 179.240908 -45.31214) (xy 179.282125 -45.347855) (xy 179.31784 -45.389072) (xy 179.347326 -45.434953)
			(xy 179.369983 -45.484563) (xy 179.385348 -45.536893) (xy 179.39311 -45.590877) (xy 179.393596 -45.618146)
			(xy 179.393596 -46.481746) (xy 179.39311 -46.509015) (xy 179.385348 -46.562999) (xy 179.369983 -46.615329)
			(xy 179.347326 -46.664939) (xy 179.31784 -46.71082) (xy 179.282125 -46.752037) (xy 179.240908 -46.787752)
			(xy 179.195027 -46.817238) (xy 179.145417 -46.839895) (xy 179.093087 -46.85526) (xy 179.039103 -46.863022)
			(xy 178.984565 -46.863022) (xy 178.930581 -46.85526) (xy 178.878251 -46.839895) (xy 178.828641 -46.817238)
			(xy 178.78276 -46.787752) (xy 178.741543 -46.752037) (xy 178.705828 -46.71082) (xy 178.676342 -46.664939)
			(xy 178.653685 -46.615329) (xy 178.63832 -46.562999) (xy 178.630558 -46.509015) (xy 178.630072 -46.481746)
			(xy 97.329238 -46.481746) (xy 97.348615 -46.588073) (xy 97.368459 -46.741347) (xy 97.380387 -46.895438)
			(xy 97.384366 -47.04994) (xy 97.380387 -47.204442) (xy 97.368459 -47.358533) (xy 97.348615 -47.511807)
			(xy 97.320906 -47.663855) (xy 97.285407 -47.814276) (xy 97.242212 -47.96267) (xy 97.219453 -48.028098)
			(xy 181.659784 -48.028098) (xy 181.659784 -47.164498) (xy 181.66027 -47.137229) (xy 181.668032 -47.083245)
			(xy 181.683397 -47.030915) (xy 181.706054 -46.981305) (xy 181.73554 -46.935424) (xy 181.771255 -46.894207)
			(xy 181.812472 -46.858492) (xy 181.858353 -46.829006) (xy 181.907963 -46.806349) (xy 181.960293 -46.790984)
			(xy 182.014277 -46.783222) (xy 182.068815 -46.783222) (xy 182.122799 -46.790984) (xy 182.175129 -46.806349)
			(xy 182.224739 -46.829006) (xy 182.27062 -46.858492) (xy 182.311837 -46.894207) (xy 182.347552 -46.935424)
			(xy 182.377038 -46.981305) (xy 182.399695 -47.030915) (xy 182.41506 -47.083245) (xy 182.422822 -47.137229)
			(xy 182.423308 -47.164498) (xy 182.423308 -48.028098) (xy 182.422822 -48.055367) (xy 182.41506 -48.109351)
			(xy 182.399695 -48.161681) (xy 182.377038 -48.211291) (xy 182.347552 -48.257172) (xy 182.311837 -48.298389)
			(xy 182.27062 -48.334104) (xy 182.224739 -48.36359) (xy 182.175129 -48.386247) (xy 182.122799 -48.401612)
			(xy 182.068815 -48.409374) (xy 182.014277 -48.409374) (xy 181.960293 -48.401612) (xy 181.907963 -48.386247)
			(xy 181.858353 -48.36359) (xy 181.812472 -48.334104) (xy 181.771255 -48.298389) (xy 181.73554 -48.257172)
			(xy 181.706054 -48.211291) (xy 181.683397 -48.161681) (xy 181.668032 -48.109351) (xy 181.66027 -48.055367)
			(xy 181.659784 -48.028098) (xy 97.219453 -48.028098) (xy 97.191435 -48.108643) (xy 97.133211 -48.251809)
			(xy 97.067693 -48.391788) (xy 96.995057 -48.528208) (xy 96.915495 -48.660709) (xy 96.829216 -48.788937)
			(xy 96.736452 -48.912555) (xy 96.637446 -49.031233) (xy 96.532463 -49.144657) (xy 96.421779 -49.252526)
			(xy 96.30569 -49.354554) (xy 96.184502 -49.450471) (xy 96.140518 -49.48174) (xy 178.630072 -49.48174)
			(xy 178.630072 -48.61814) (xy 178.630558 -48.590871) (xy 178.63832 -48.536887) (xy 178.653685 -48.484557)
			(xy 178.676342 -48.434947) (xy 178.705828 -48.389066) (xy 178.741543 -48.347849) (xy 178.78276 -48.312134)
			(xy 178.828641 -48.282648) (xy 178.878251 -48.259991) (xy 178.930581 -48.244626) (xy 178.984565 -48.236864)
			(xy 179.039103 -48.236864) (xy 179.093087 -48.244626) (xy 179.145417 -48.259991) (xy 179.195027 -48.282648)
			(xy 179.240908 -48.312134) (xy 179.282125 -48.347849) (xy 179.31784 -48.389066) (xy 179.347326 -48.434947)
			(xy 179.369983 -48.484557) (xy 179.385348 -48.536887) (xy 179.39311 -48.590871) (xy 179.393596 -48.61814)
			(xy 179.393596 -49.48174) (xy 179.39311 -49.509009) (xy 179.385348 -49.562993) (xy 179.369983 -49.615323)
			(xy 179.347326 -49.664933) (xy 179.31784 -49.710814) (xy 179.282125 -49.752031) (xy 179.240908 -49.787746)
			(xy 179.195027 -49.817232) (xy 179.145417 -49.839889) (xy 179.093087 -49.855254) (xy 179.039103 -49.863016)
			(xy 178.984565 -49.863016) (xy 178.930581 -49.855254) (xy 178.878251 -49.839889) (xy 178.828641 -49.817232)
			(xy 178.78276 -49.787746) (xy 178.741543 -49.752031) (xy 178.705828 -49.710814) (xy 178.676342 -49.664933)
			(xy 178.653685 -49.615323) (xy 178.63832 -49.562993) (xy 178.630558 -49.509009) (xy 178.630072 -49.48174)
			(xy 96.140518 -49.48174) (xy 96.058537 -49.540022) (xy 95.928129 -49.62297) (xy 95.793624 -49.699095)
			(xy 95.655379 -49.768194) (xy 95.513759 -49.830085) (xy 95.369142 -49.884604) (xy 95.221909 -49.931606)
			(xy 95.072452 -49.970966) (xy 94.921168 -50.00258) (xy 94.768456 -50.026364) (xy 94.614722 -50.042255)
			(xy 94.460374 -50.050211) (xy 94.383098 -50.0507) (xy 92.782898 -50.0507) (xy 92.705622 -50.050194)
			(xy 92.551275 -50.042238) (xy 92.397543 -50.026347) (xy 92.244832 -50.002563) (xy 92.093548 -49.970949)
			(xy 91.944092 -49.931589) (xy 91.796861 -49.884587) (xy 91.652244 -49.830069) (xy 91.510626 -49.768178)
			(xy 91.372381 -49.699079) (xy 91.237877 -49.622954) (xy 91.10747 -49.540007) (xy 90.981506 -49.450456)
			(xy 90.860319 -49.35454) (xy 90.74423 -49.252512) (xy 90.633548 -49.144644) (xy 90.528565 -49.031221)
			(xy 90.42956 -48.912543) (xy 90.336796 -48.788927) (xy 90.250519 -48.660699) (xy 90.170957 -48.528199)
			(xy 90.098321 -48.391779) (xy 90.032804 -48.251802) (xy 89.97458 -48.108637) (xy 89.923803 -47.962664)
			(xy 89.880608 -47.814271) (xy 89.84511 -47.663852) (xy 89.817402 -47.511804) (xy 89.797557 -47.358531)
			(xy 89.78563 -47.204441) (xy 89.78165 -47.04994) (xy 67.583802 -47.04994) (xy 67.579823 -47.209492)
			(xy 67.567896 -47.368647) (xy 67.54805 -47.527009) (xy 67.520336 -47.684186) (xy 67.484821 -47.839786)
			(xy 67.441595 -47.993422) (xy 67.390764 -48.144712) (xy 67.332455 -48.293281) (xy 67.266813 -48.438758)
			(xy 67.194001 -48.580783) (xy 67.114201 -48.719002) (xy 67.02761 -48.853071) (xy 66.934444 -48.982657)
			(xy 66.834934 -49.107438) (xy 66.729328 -49.227105) (xy 66.617889 -49.341358) (xy 66.500893 -49.449914)
			(xy 66.378631 -49.552504) (xy 66.251408 -49.648872) (xy 66.119539 -49.738779) (xy 65.983353 -49.822001)
			(xy 65.843188 -49.898331) (xy 65.699392 -49.967579) (xy 65.552323 -50.029574) (xy 65.402347 -50.084161)
			(xy 65.249837 -50.131205) (xy 65.095171 -50.170587) (xy 64.938734 -50.202212) (xy 64.780916 -50.226)
			(xy 64.622107 -50.241891) (xy 64.462705 -50.249847) (xy 64.382904 -50.250344) (xy 62.782958 -50.250344)
			(xy 62.703158 -50.249839) (xy 62.543755 -50.241883) (xy 62.384947 -50.225992) (xy 62.227129 -50.202204)
			(xy 62.070693 -50.17058) (xy 61.916027 -50.131197) (xy 61.763517 -50.084154) (xy 61.613541 -50.029567)
			(xy 61.466472 -49.967573) (xy 61.322677 -49.898324) (xy 61.182512 -49.821994) (xy 61.046326 -49.738773)
			(xy 60.914458 -49.648866) (xy 60.787235 -49.552499) (xy 60.664973 -49.449909) (xy 60.547978 -49.341353)
			(xy 60.436538 -49.2271) (xy 60.330933 -49.107434) (xy 60.231423 -48.982653) (xy 60.138257 -48.853067)
			(xy 60.051666 -48.718998) (xy 59.971866 -48.580779) (xy 59.899054 -48.438755) (xy 59.833413 -48.293278)
			(xy 59.775104 -48.14471) (xy 59.724273 -47.99342) (xy 59.681047 -47.839784) (xy 59.645532 -47.684184)
			(xy 59.617818 -47.527008) (xy 59.597972 -47.368646) (xy 59.586045 -47.209491) (xy 59.582066 -47.04994)
			(xy 0.509016 -47.04994) (xy 0.509016 -50.949098) (xy 181.659784 -50.949098) (xy 181.659784 -50.085498)
			(xy 181.66027 -50.058229) (xy 181.668032 -50.004245) (xy 181.683397 -49.951915) (xy 181.706054 -49.902305)
			(xy 181.73554 -49.856424) (xy 181.771255 -49.815207) (xy 181.812472 -49.779492) (xy 181.858353 -49.750006)
			(xy 181.907963 -49.727349) (xy 181.960293 -49.711984) (xy 182.014277 -49.704222) (xy 182.068815 -49.704222)
			(xy 182.122799 -49.711984) (xy 182.175129 -49.727349) (xy 182.224739 -49.750006) (xy 182.27062 -49.779492)
			(xy 182.311837 -49.815207) (xy 182.347552 -49.856424) (xy 182.377038 -49.902305) (xy 182.399695 -49.951915)
			(xy 182.41506 -50.004245) (xy 182.422822 -50.058229) (xy 182.423308 -50.085498) (xy 182.423308 -50.949098)
			(xy 182.422822 -50.976367) (xy 182.41506 -51.030351) (xy 182.399695 -51.082681) (xy 182.377038 -51.132291)
			(xy 182.347552 -51.178172) (xy 182.311837 -51.219389) (xy 182.27062 -51.255104) (xy 182.224739 -51.28459)
			(xy 182.175129 -51.307247) (xy 182.122799 -51.322612) (xy 182.068815 -51.330374) (xy 182.014277 -51.330374)
			(xy 181.960293 -51.322612) (xy 181.907963 -51.307247) (xy 181.858353 -51.28459) (xy 181.812472 -51.255104)
			(xy 181.771255 -51.219389) (xy 181.73554 -51.178172) (xy 181.706054 -51.132291) (xy 181.683397 -51.082681)
			(xy 181.668032 -51.030351) (xy 181.66027 -50.976367) (xy 181.659784 -50.949098) (xy 0.509016 -50.949098)
			(xy 0.509016 -52.481734) (xy 178.630072 -52.481734) (xy 178.630072 -51.618134) (xy 178.630558 -51.590865)
			(xy 178.63832 -51.536881) (xy 178.653685 -51.484551) (xy 178.676342 -51.434941) (xy 178.705828 -51.38906)
			(xy 178.741543 -51.347843) (xy 178.78276 -51.312128) (xy 178.828641 -51.282642) (xy 178.878251 -51.259985)
			(xy 178.930581 -51.24462) (xy 178.984565 -51.236858) (xy 179.039103 -51.236858) (xy 179.093087 -51.24462)
			(xy 179.145417 -51.259985) (xy 179.195027 -51.282642) (xy 179.240908 -51.312128) (xy 179.282125 -51.347843)
			(xy 179.31784 -51.38906) (xy 179.347326 -51.434941) (xy 179.369983 -51.484551) (xy 179.385348 -51.536881)
			(xy 179.39311 -51.590865) (xy 179.393596 -51.618134) (xy 179.393596 -51.999896) (xy 201.367397 -51.999896)
			(xy 201.371407 -51.837793) (xy 201.38343 -51.676088) (xy 201.403434 -51.515174) (xy 201.431372 -51.355447)
			(xy 201.467175 -51.197297) (xy 201.510755 -51.041111) (xy 201.562006 -50.887271) (xy 201.620802 -50.736154)
			(xy 201.687 -50.58813) (xy 201.760436 -50.44356) (xy 201.840933 -50.302799) (xy 201.928292 -50.166191)
			(xy 202.0223 -50.034071) (xy 202.122727 -49.906761) (xy 202.229327 -49.784573) (xy 202.341839 -49.667807)
			(xy 202.459987 -49.556748) (xy 202.583484 -49.451667) (xy 202.712026 -49.352823) (xy 202.845299 -49.260456)
			(xy 202.982977 -49.174793) (xy 203.124723 -49.096044) (xy 203.27019 -49.024401) (xy 203.419022 -48.960039)
			(xy 203.570854 -48.903117) (xy 203.725316 -48.853773) (xy 203.882029 -48.812128) (xy 204.04061 -48.778283)
			(xy 204.200671 -48.752323) (xy 204.361819 -48.73431) (xy 204.523661 -48.724289) (xy 204.685801 -48.722283)
			(xy 204.847842 -48.728299) (xy 205.009386 -48.74232) (xy 205.17004 -48.764313) (xy 205.32941 -48.794225)
			(xy 205.487105 -48.831981) (xy 205.64274 -48.877489) (xy 205.795934 -48.930639) (xy 205.946312 -48.9913)
			(xy 206.093507 -49.059323) (xy 206.237157 -49.134542) (xy 206.376912 -49.216773) (xy 206.512428 -49.305815)
			(xy 206.643376 -49.40145) (xy 206.769434 -49.503444) (xy 206.890294 -49.611547) (xy 207.00566 -49.725494)
			(xy 207.115249 -49.845008) (xy 207.218794 -49.969795) (xy 207.316041 -50.09955) (xy 207.406753 -50.233955)
			(xy 207.490706 -50.372682) (xy 207.567696 -50.515391) (xy 207.637535 -50.661732) (xy 207.70005 -50.811349)
			(xy 207.755091 -50.963874) (xy 207.802521 -51.118934) (xy 207.842224 -51.27615) (xy 207.874105 -51.435138)
			(xy 207.898083 -51.595507) (xy 207.914102 -51.756866) (xy 207.922121 -51.91882) (xy 207.922622 -51.999896)
			(xy 207.922121 -52.080972) (xy 207.921092 -52.10175) (xy 244.67947 -52.10175) (xy 244.679975 -52.075243)
			(xy 244.687334 -52.022743) (xy 244.701889 -51.971767) (xy 244.723361 -51.923297) (xy 244.751335 -51.878265)
			(xy 244.785274 -51.837539) (xy 244.824523 -51.801903) (xy 244.868327 -51.772043) (xy 244.915843 -51.748534)
			(xy 244.966156 -51.731829) (xy 244.992144 -51.726592) (xy 245.000543 -51.724726) (xy 245.015476 -51.716197)
			(xy 245.026755 -51.703216) (xy 245.030244 -51.69535) (xy 245.045663 -51.657494) (xy 245.082559 -51.584546)
			(xy 245.125992 -51.515291) (xy 245.175596 -51.450313) (xy 245.230952 -51.39016) (xy 245.291595 -51.335341)
			(xy 245.357011 -51.286316) (xy 245.426649 -51.2435) (xy 245.499922 -51.207254) (xy 245.576211 -51.177884)
			(xy 245.654873 -51.155637) (xy 245.735245 -51.140701) (xy 245.816648 -51.133203) (xy 245.857522 -51.13274)
			(xy 245.899843 -51.133258) (xy 245.984099 -51.14133) (xy 246.067208 -51.157371) (xy 246.148416 -51.181236)
			(xy 246.226989 -51.212708) (xy 246.302217 -51.251503) (xy 246.33809 -51.273964) (xy 246.346484 -51.278827)
			(xy 246.365522 -51.28248) (xy 246.38456 -51.278827) (xy 246.392954 -51.273964) (xy 246.42883 -51.25151)
			(xy 246.504063 -51.212731) (xy 246.582638 -51.181268) (xy 246.663845 -51.157405) (xy 246.74695 -51.141356)
			(xy 246.831202 -51.133268) (xy 246.873522 -51.13274) (xy 246.926862 -51.134518) (xy 246.938638 -51.134618)
			(xy 246.960306 -51.125466) (xy 246.975671 -51.107657) (xy 246.979186 -51.096418) (xy 246.990138 -51.056039)
			(xy 247.018713 -50.977397) (xy 247.054545 -50.901785) (xy 247.097317 -50.829872) (xy 247.146653 -50.762292)
			(xy 247.202115 -50.699642) (xy 247.263214 -50.642477) (xy 247.329411 -50.5913) (xy 247.40012 -50.546564)
			(xy 247.474717 -50.508665) (xy 247.552542 -50.477936) (xy 247.632909 -50.45465) (xy 247.715107 -50.439012)
			(xy 247.79841 -50.431161) (xy 247.840246 -50.430684) (xy 247.883752 -50.431235) (xy 247.970347 -50.439729)
			(xy 248.055699 -50.456641) (xy 248.138991 -50.481809) (xy 248.219426 -50.514992) (xy 248.296235 -50.555874)
			(xy 248.332752 -50.579528) (xy 248.341308 -50.584744) (xy 248.360946 -50.588653) (xy 248.380584 -50.584744)
			(xy 248.38914 -50.579528) (xy 248.425663 -50.555885) (xy 248.50248 -50.515022) (xy 248.582916 -50.481847)
			(xy 248.666204 -50.456676) (xy 248.751551 -50.439749) (xy 248.838142 -50.431227) (xy 248.881646 -50.430684)
			(xy 248.926403 -50.431259) (xy 249.015462 -50.440266) (xy 249.103167 -50.458165) (xy 249.188634 -50.484775)
			(xy 249.270999 -50.519828) (xy 249.349431 -50.562968) (xy 249.386598 -50.58791) (xy 249.394939 -50.593062)
			(xy 249.414052 -50.597328) (xy 249.433374 -50.594144) (xy 249.44197 -50.589434) (xy 249.4758 -50.569354)
			(xy 249.546346 -50.534523) (xy 249.619688 -50.506051) (xy 249.695257 -50.484158) (xy 249.772462 -50.469016)
			(xy 249.850701 -50.460742) (xy 249.890026 -50.45964) (xy 249.889772 -50.4444) (xy 249.889772 -50.443892)
			(xy 249.89024 -50.405527) (xy 249.896983 -50.329093) (xy 249.903234 -50.291238) (xy 249.904413 -50.282319)
			(xy 249.901131 -50.26464) (xy 249.891952 -50.249179) (xy 249.8852 -50.243232) (xy 249.851748 -50.215094)
			(xy 249.789907 -50.153305) (xy 249.734424 -50.08575) (xy 249.685833 -50.01308) (xy 249.644603 -49.935995)
			(xy 249.61113 -49.855239) (xy 249.585738 -49.771589) (xy 249.568671 -49.685852) (xy 249.560094 -49.598855)
			(xy 249.559572 -49.555146) (xy 249.560076 -49.512785) (xy 249.568129 -49.428448) (xy 249.584163 -49.345258)
			(xy 249.608031 -49.263968) (xy 249.639519 -49.185316) (xy 249.678341 -49.110013) (xy 249.724144 -49.038741)
			(xy 249.776515 -48.972145) (xy 249.83498 -48.91083) (xy 249.899008 -48.855349) (xy 249.96802 -48.806206)
			(xy 250.04139 -48.763846) (xy 250.118455 -48.728651) (xy 250.198517 -48.700942) (xy 250.28085 -48.680968)
			(xy 250.364709 -48.668911) (xy 250.449334 -48.66488) (xy 250.533959 -48.668911) (xy 250.617818 -48.680968)
			(xy 250.700151 -48.700942) (xy 250.780213 -48.728651) (xy 250.857278 -48.763846) (xy 250.930648 -48.806206)
			(xy 250.99966 -48.855349) (xy 251.063688 -48.91083) (xy 251.122153 -48.972145) (xy 251.174524 -49.038741)
			(xy 251.220327 -49.110013) (xy 251.259149 -49.185316) (xy 251.290637 -49.263968) (xy 251.314505 -49.345258)
			(xy 251.330539 -49.428448) (xy 251.338592 -49.512785) (xy 251.339096 -49.555146) (xy 251.338636 -49.593574)
			(xy 251.331894 -49.670136) (xy 251.325634 -49.708054) (xy 251.324473 -49.716974) (xy 251.32775 -49.73465)
			(xy 251.336921 -49.750111) (xy 251.343668 -49.75606) (xy 251.362142 -49.771471) (xy 251.397596 -49.803999)
			(xy 251.414534 -49.821084) (xy 251.422676 -49.828571) (xy 251.443355 -49.836348) (xy 251.454412 -49.83607)
			(xy 251.469822 -49.835031) (xy 251.50069 -49.833886) (xy 251.516134 -49.833784) (xy 251.557251 -49.834166)
			(xy 251.639133 -49.841757) (xy 251.719966 -49.85687) (xy 251.79906 -49.879378) (xy 251.875739 -49.909087)
			(xy 251.94935 -49.945745) (xy 252.019265 -49.989039) (xy 252.084886 -50.038598) (xy 252.145655 -50.094001)
			(xy 252.201053 -50.154775) (xy 252.250607 -50.220401) (xy 252.293894 -50.29032) (xy 252.330545 -50.363934)
			(xy 252.360248 -50.440616) (xy 252.382748 -50.519712) (xy 252.397854 -50.600546) (xy 252.405438 -50.682429)
			(xy 252.405896 -50.723546) (xy 252.405358 -50.767341) (xy 252.396743 -50.854506) (xy 252.379599 -50.940401)
			(xy 252.354094 -51.024196) (xy 252.320474 -51.105076) (xy 252.300232 -51.143916) (xy 252.29478 -51.15537)
			(xy 252.2948 -51.18071) (xy 252.300232 -51.192176) (xy 252.320452 -51.231026) (xy 252.354062 -51.311909)
			(xy 252.379567 -51.3957) (xy 252.39672 -51.481592) (xy 252.405355 -51.568752) (xy 252.405896 -51.612546)
			(xy 252.405358 -51.656341) (xy 252.396743 -51.743506) (xy 252.379599 -51.829401) (xy 252.354094 -51.913196)
			(xy 252.320474 -51.994076) (xy 252.317441 -51.999896) (xy 265.367523 -51.999896) (xy 265.371533 -51.837793)
			(xy 265.383556 -51.676088) (xy 265.40356 -51.515174) (xy 265.431498 -51.355447) (xy 265.467301 -51.197297)
			(xy 265.510881 -51.041111) (xy 265.562132 -50.887271) (xy 265.620928 -50.736154) (xy 265.687126 -50.58813)
			(xy 265.760562 -50.44356) (xy 265.841059 -50.302799) (xy 265.928418 -50.166191) (xy 266.022426 -50.034071)
			(xy 266.122853 -49.906761) (xy 266.229453 -49.784573) (xy 266.341965 -49.667807) (xy 266.460113 -49.556748)
			(xy 266.58361 -49.451667) (xy 266.712152 -49.352823) (xy 266.845425 -49.260456) (xy 266.983103 -49.174793)
			(xy 267.124849 -49.096044) (xy 267.270316 -49.024401) (xy 267.419148 -48.960039) (xy 267.57098 -48.903117)
			(xy 267.725442 -48.853773) (xy 267.882155 -48.812128) (xy 268.040736 -48.778283) (xy 268.200797 -48.752323)
			(xy 268.361945 -48.73431) (xy 268.523787 -48.724289) (xy 268.685927 -48.722283) (xy 268.847968 -48.728299)
			(xy 269.009512 -48.74232) (xy 269.170166 -48.764313) (xy 269.329536 -48.794225) (xy 269.487231 -48.831981)
			(xy 269.642866 -48.877489) (xy 269.79606 -48.930639) (xy 269.946438 -48.9913) (xy 270.093633 -49.059323)
			(xy 270.237283 -49.134542) (xy 270.377038 -49.216773) (xy 270.512554 -49.305815) (xy 270.643502 -49.40145)
			(xy 270.76956 -49.503444) (xy 270.89042 -49.611547) (xy 271.005786 -49.725494) (xy 271.115375 -49.845008)
			(xy 271.21892 -49.969795) (xy 271.316167 -50.09955) (xy 271.406879 -50.233955) (xy 271.490832 -50.372682)
			(xy 271.567822 -50.515391) (xy 271.637661 -50.661732) (xy 271.700176 -50.811349) (xy 271.755217 -50.963874)
			(xy 271.802647 -51.118934) (xy 271.84235 -51.27615) (xy 271.874231 -51.435138) (xy 271.898209 -51.595507)
			(xy 271.914228 -51.756866) (xy 271.922247 -51.91882) (xy 271.922748 -51.999896) (xy 271.922247 -52.080972)
			(xy 271.914228 -52.242926) (xy 271.898209 -52.404285) (xy 271.874231 -52.564654) (xy 271.84235 -52.723642)
			(xy 271.802647 -52.880858) (xy 271.755217 -53.035918) (xy 271.700176 -53.188443) (xy 271.637661 -53.33806)
			(xy 271.567822 -53.484401) (xy 271.490832 -53.62711) (xy 271.406879 -53.765837) (xy 271.316167 -53.900242)
			(xy 271.21892 -54.029997) (xy 271.115375 -54.154784) (xy 271.005786 -54.274298) (xy 270.89042 -54.388245)
			(xy 270.76956 -54.496348) (xy 270.643502 -54.598342) (xy 270.512554 -54.693977) (xy 270.377038 -54.783019)
			(xy 270.237283 -54.86525) (xy 270.093633 -54.940469) (xy 269.946438 -55.008492) (xy 269.79606 -55.069153)
			(xy 269.642866 -55.122303) (xy 269.487231 -55.167811) (xy 269.329536 -55.205567) (xy 269.170166 -55.235479)
			(xy 269.009512 -55.257472) (xy 268.847968 -55.271493) (xy 268.685927 -55.277509) (xy 268.523787 -55.275503)
			(xy 268.361945 -55.265482) (xy 268.200797 -55.247469) (xy 268.040736 -55.221509) (xy 267.882155 -55.187664)
			(xy 267.725442 -55.146019) (xy 267.57098 -55.096675) (xy 267.419148 -55.039753) (xy 267.270316 -54.975391)
			(xy 267.124849 -54.903748) (xy 266.983103 -54.824999) (xy 266.845425 -54.739336) (xy 266.712152 -54.646969)
			(xy 266.58361 -54.548125) (xy 266.460113 -54.443044) (xy 266.341965 -54.331985) (xy 266.229453 -54.215219)
			(xy 266.122853 -54.093031) (xy 266.022426 -53.965721) (xy 265.928418 -53.833601) (xy 265.841059 -53.696993)
			(xy 265.760562 -53.556232) (xy 265.687126 -53.411662) (xy 265.620928 -53.263638) (xy 265.562132 -53.112521)
			(xy 265.510881 -52.958681) (xy 265.467301 -52.802495) (xy 265.431498 -52.644345) (xy 265.40356 -52.484618)
			(xy 265.383556 -52.323704) (xy 265.371533 -52.161999) (xy 265.367523 -51.999896) (xy 252.317441 -51.999896)
			(xy 252.300232 -52.032916) (xy 252.29478 -52.04437) (xy 252.2948 -52.06971) (xy 252.300232 -52.081176)
			(xy 252.320452 -52.120026) (xy 252.354062 -52.200909) (xy 252.379567 -52.2847) (xy 252.39672 -52.370592)
			(xy 252.405355 -52.457752) (xy 252.405896 -52.501546) (xy 252.405431 -52.54266) (xy 252.39784 -52.624537)
			(xy 252.382728 -52.705364) (xy 252.360222 -52.784452) (xy 252.330515 -52.861127) (xy 252.293861 -52.934733)
			(xy 252.250573 -53.004644) (xy 252.201018 -53.070263) (xy 252.145621 -53.131029) (xy 252.084853 -53.186426)
			(xy 252.019234 -53.235979) (xy 251.949323 -53.279267) (xy 251.875716 -53.31592) (xy 251.799041 -53.345626)
			(xy 251.719952 -53.36813) (xy 251.639125 -53.383242) (xy 251.557248 -53.390832) (xy 251.516134 -53.391308)
			(xy 251.471924 -53.390745) (xy 251.383942 -53.381965) (xy 251.297264 -53.3645) (xy 251.212747 -53.33852)
			(xy 251.131225 -53.304282) (xy 251.053503 -53.262125) (xy 250.980346 -53.212465) (xy 250.912478 -53.15579)
			(xy 250.881134 -53.124608) (xy 250.873005 -53.117104) (xy 250.852316 -53.109337) (xy 250.841256 -53.109622)
			(xy 250.825846 -53.110663) (xy 250.794978 -53.111806) (xy 250.779534 -53.111908) (xy 250.737779 -53.111492)
			(xy 250.654637 -53.103677) (xy 250.572592 -53.088104) (xy 250.492369 -53.064909) (xy 250.414673 -53.034297)
			(xy 250.340188 -52.996537) (xy 250.269571 -52.951961) (xy 250.203442 -52.900963) (xy 250.142385 -52.843991)
			(xy 250.086937 -52.781547) (xy 250.037585 -52.714181) (xy 249.994765 -52.642486) (xy 249.958854 -52.567092)
			(xy 249.930167 -52.488665) (xy 249.908958 -52.407894) (xy 249.895413 -52.32549) (xy 249.892058 -52.283868)
			(xy 249.891061 -52.274773) (xy 249.88348 -52.258135) (xy 249.870549 -52.245209) (xy 249.853908 -52.237634)
			(xy 249.844814 -52.236624) (xy 249.805225 -52.23352) (xy 249.726783 -52.221122) (xy 249.649759 -52.201775)
			(xy 249.574769 -52.175634) (xy 249.50241 -52.142907) (xy 249.433259 -52.103855) (xy 249.400314 -52.081684)
			(xy 249.392012 -52.076461) (xy 249.372875 -52.072218) (xy 249.353539 -52.075433) (xy 249.344942 -52.08016)
			(xy 249.312459 -52.099495) (xy 249.244799 -52.133223) (xy 249.174522 -52.161088) (xy 249.13844 -52.172362)
			(xy 249.128616 -52.175851) (xy 249.112727 -52.189319) (xy 249.103444 -52.207965) (xy 249.102372 -52.218336)
			(xy 249.099675 -52.260463) (xy 249.087279 -52.34397) (xy 249.067027 -52.425926) (xy 249.039099 -52.505595)
			(xy 249.003748 -52.582258) (xy 248.961291 -52.655227) (xy 248.912112 -52.723845) (xy 248.856651 -52.787493)
			(xy 248.795409 -52.8456) (xy 248.728936 -52.897642) (xy 248.657831 -52.943151) (xy 248.582733 -52.981717)
			(xy 248.504319 -53.012994) (xy 248.423294 -53.036699) (xy 248.340387 -53.052621) (xy 248.256345 -53.060614)
			(xy 248.214134 -53.061108) (xy 248.171669 -53.060607) (xy 248.087125 -53.052507) (xy 248.003739 -53.036385)
			(xy 247.922268 -53.01239) (xy 247.843456 -52.98074) (xy 247.768018 -52.941722) (xy 247.696643 -52.895693)
			(xy 247.629979 -52.84307) (xy 247.568634 -52.784334) (xy 247.540526 -52.752498) (xy 247.534176 -52.745132)
			(xy 247.517412 -52.736496) (xy 247.429274 -52.726336) (xy 247.410986 -52.731416) (xy 247.403112 -52.737258)
			(xy 247.370277 -52.761024) (xy 247.301045 -52.803187) (xy 247.228263 -52.838875) (xy 247.152535 -52.867791)
			(xy 247.07449 -52.889697) (xy 246.994775 -52.904409) (xy 246.914052 -52.911805) (xy 246.873522 -52.912264)
			(xy 246.831202 -52.911724) (xy 246.746946 -52.903656) (xy 246.663838 -52.887619) (xy 246.58263 -52.863758)
			(xy 246.504056 -52.83229) (xy 246.428827 -52.793499) (xy 246.392954 -52.77104) (xy 246.38456 -52.766177)
			(xy 246.365522 -52.762524) (xy 246.346484 -52.766177) (xy 246.33809 -52.77104) (xy 246.302222 -52.793507)
			(xy 246.226987 -52.832285) (xy 246.148411 -52.863747) (xy 246.067203 -52.887609) (xy 245.984096 -52.903654)
			(xy 245.899842 -52.911738) (xy 245.857522 -52.912264) (xy 245.813221 -52.911666) (xy 245.725058 -52.90285)
			(xy 245.638208 -52.885314) (xy 245.553531 -52.85923) (xy 245.471867 -52.824858) (xy 245.394025 -52.782538)
			(xy 245.320775 -52.732689) (xy 245.252843 -52.675806) (xy 245.190903 -52.61245) (xy 245.135568 -52.543252)
			(xy 245.111016 -52.506372) (xy 245.106055 -52.499361) (xy 245.092457 -52.488884) (xy 245.076169 -52.483465)
			(xy 245.067582 -52.483258) (xy 245.060978 -52.483258) (xy 245.033722 -52.482865) (xy 244.979766 -52.475104)
			(xy 244.927464 -52.459743) (xy 244.87788 -52.437094) (xy 244.832025 -52.407619) (xy 244.790831 -52.371918)
			(xy 244.755138 -52.330717) (xy 244.725671 -52.284856) (xy 244.703032 -52.235269) (xy 244.68768 -52.182963)
			(xy 244.679929 -52.129006) (xy 244.67947 -52.10175) (xy 207.921092 -52.10175) (xy 207.914102 -52.242926)
			(xy 207.898083 -52.404285) (xy 207.874105 -52.564654) (xy 207.842224 -52.723642) (xy 207.802521 -52.880858)
			(xy 207.755091 -53.035918) (xy 207.70005 -53.188443) (xy 207.637535 -53.33806) (xy 207.567696 -53.484401)
			(xy 207.490706 -53.62711) (xy 207.406753 -53.765837) (xy 207.316041 -53.900242) (xy 207.218794 -54.029997)
			(xy 207.115249 -54.154784) (xy 207.00566 -54.274298) (xy 206.890294 -54.388245) (xy 206.769434 -54.496348)
			(xy 206.643376 -54.598342) (xy 206.512428 -54.693977) (xy 206.376912 -54.783019) (xy 206.237157 -54.86525)
			(xy 206.093507 -54.940469) (xy 205.946312 -55.008492) (xy 205.795934 -55.069153) (xy 205.64274 -55.122303)
			(xy 205.487105 -55.167811) (xy 205.32941 -55.205567) (xy 205.17004 -55.235479) (xy 205.009386 -55.257472)
			(xy 204.847842 -55.271493) (xy 204.685801 -55.277509) (xy 204.523661 -55.275503) (xy 204.361819 -55.265482)
			(xy 204.200671 -55.247469) (xy 204.04061 -55.221509) (xy 203.882029 -55.187664) (xy 203.725316 -55.146019)
			(xy 203.570854 -55.096675) (xy 203.419022 -55.039753) (xy 203.27019 -54.975391) (xy 203.124723 -54.903748)
			(xy 202.982977 -54.824999) (xy 202.845299 -54.739336) (xy 202.712026 -54.646969) (xy 202.583484 -54.548125)
			(xy 202.459987 -54.443044) (xy 202.341839 -54.331985) (xy 202.229327 -54.215219) (xy 202.122727 -54.093031)
			(xy 202.0223 -53.965721) (xy 201.928292 -53.833601) (xy 201.840933 -53.696993) (xy 201.760436 -53.556232)
			(xy 201.687 -53.411662) (xy 201.620802 -53.263638) (xy 201.562006 -53.112521) (xy 201.510755 -52.958681)
			(xy 201.467175 -52.802495) (xy 201.431372 -52.644345) (xy 201.403434 -52.484618) (xy 201.38343 -52.323704)
			(xy 201.371407 -52.161999) (xy 201.367397 -51.999896) (xy 179.393596 -51.999896) (xy 179.393596 -52.481734)
			(xy 179.39311 -52.509003) (xy 179.385348 -52.562987) (xy 179.369983 -52.615317) (xy 179.347326 -52.664927)
			(xy 179.31784 -52.710808) (xy 179.282125 -52.752025) (xy 179.240908 -52.78774) (xy 179.195027 -52.817226)
			(xy 179.145417 -52.839883) (xy 179.093087 -52.855248) (xy 179.039103 -52.86301) (xy 178.984565 -52.86301)
			(xy 178.930581 -52.855248) (xy 178.878251 -52.839883) (xy 178.828641 -52.817226) (xy 178.78276 -52.78774)
			(xy 178.741543 -52.752025) (xy 178.705828 -52.710808) (xy 178.676342 -52.664927) (xy 178.653685 -52.615317)
			(xy 178.63832 -52.562987) (xy 178.630558 -52.509003) (xy 178.630072 -52.481734) (xy 0.509016 -52.481734)
			(xy 0.509016 -53.954934) (xy 181.659784 -53.954934) (xy 181.659784 -53.091334) (xy 181.66027 -53.064065)
			(xy 181.668032 -53.010081) (xy 181.683397 -52.957751) (xy 181.706054 -52.908141) (xy 181.73554 -52.86226)
			(xy 181.771255 -52.821043) (xy 181.812472 -52.785328) (xy 181.858353 -52.755842) (xy 181.907963 -52.733185)
			(xy 181.960293 -52.71782) (xy 182.014277 -52.710058) (xy 182.068815 -52.710058) (xy 182.122799 -52.71782)
			(xy 182.175129 -52.733185) (xy 182.224739 -52.755842) (xy 182.27062 -52.785328) (xy 182.311837 -52.821043)
			(xy 182.347552 -52.86226) (xy 182.377038 -52.908141) (xy 182.399695 -52.957751) (xy 182.41506 -53.010081)
			(xy 182.422822 -53.064065) (xy 182.423308 -53.091334) (xy 182.423308 -53.954934) (xy 182.422822 -53.982203)
			(xy 182.41506 -54.036187) (xy 182.399695 -54.088517) (xy 182.377038 -54.138127) (xy 182.347552 -54.184008)
			(xy 182.311837 -54.225225) (xy 182.27062 -54.26094) (xy 182.224739 -54.290426) (xy 182.175129 -54.313083)
			(xy 182.122799 -54.328448) (xy 182.068815 -54.33621) (xy 182.014277 -54.33621) (xy 181.960293 -54.328448)
			(xy 181.907963 -54.313083) (xy 181.858353 -54.290426) (xy 181.812472 -54.26094) (xy 181.771255 -54.225225)
			(xy 181.73554 -54.184008) (xy 181.706054 -54.138127) (xy 181.683397 -54.088517) (xy 181.668032 -54.036187)
			(xy 181.66027 -53.982203) (xy 181.659784 -53.954934) (xy 0.509016 -53.954934) (xy 0.509016 -55.481728)
			(xy 178.630072 -55.481728) (xy 178.630072 -54.618128) (xy 178.630558 -54.590859) (xy 178.63832 -54.536875)
			(xy 178.653685 -54.484545) (xy 178.676342 -54.434935) (xy 178.705828 -54.389054) (xy 178.741543 -54.347837)
			(xy 178.78276 -54.312122) (xy 178.828641 -54.282636) (xy 178.878251 -54.259979) (xy 178.930581 -54.244614)
			(xy 178.984565 -54.236852) (xy 179.039103 -54.236852) (xy 179.093087 -54.244614) (xy 179.145417 -54.259979)
			(xy 179.195027 -54.282636) (xy 179.240908 -54.312122) (xy 179.282125 -54.347837) (xy 179.31784 -54.389054)
			(xy 179.347326 -54.434935) (xy 179.369983 -54.484545) (xy 179.385348 -54.536875) (xy 179.39311 -54.590859)
			(xy 179.393596 -54.618128) (xy 179.393596 -55.481728) (xy 179.39311 -55.508997) (xy 179.385348 -55.562981)
			(xy 179.369983 -55.615311) (xy 179.347326 -55.664921) (xy 179.31784 -55.710802) (xy 179.282125 -55.752019)
			(xy 179.240908 -55.787734) (xy 179.195027 -55.81722) (xy 179.145417 -55.839877) (xy 179.093087 -55.855242)
			(xy 179.039103 -55.863004) (xy 178.984565 -55.863004) (xy 178.930581 -55.855242) (xy 178.878251 -55.839877)
			(xy 178.828641 -55.81722) (xy 178.78276 -55.787734) (xy 178.741543 -55.752019) (xy 178.705828 -55.710802)
			(xy 178.676342 -55.664921) (xy 178.653685 -55.615311) (xy 178.63832 -55.562981) (xy 178.630558 -55.508997)
			(xy 178.630072 -55.481728) (xy 0.509016 -55.481728) (xy 0.509016 -57.094435) (xy 170.842169 -57.094435)
			(xy 170.842169 -57.005413) (xy 170.850149 -56.916749) (xy 170.866045 -56.829158) (xy 170.889728 -56.743343)
			(xy 170.921008 -56.659998) (xy 170.959634 -56.579792) (xy 171.005293 -56.503371) (xy 171.057619 -56.43135)
			(xy 171.11619 -56.36431) (xy 171.180535 -56.30279) (xy 171.250135 -56.247286) (xy 171.324431 -56.198244)
			(xy 171.402823 -56.156059) (xy 171.484682 -56.121071) (xy 171.569347 -56.093562) (xy 171.656137 -56.073752)
			(xy 171.744353 -56.061802) (xy 171.833286 -56.057809) (xy 171.922219 -56.061802) (xy 172.010435 -56.073752)
			(xy 172.097225 -56.093562) (xy 172.18189 -56.121071) (xy 172.263749 -56.156059) (xy 172.342141 -56.198244)
			(xy 172.416437 -56.247286) (xy 172.486037 -56.30279) (xy 172.550382 -56.36431) (xy 172.608953 -56.43135)
			(xy 172.661279 -56.503371) (xy 172.706938 -56.579792) (xy 172.745564 -56.659998) (xy 172.776844 -56.743343)
			(xy 172.800527 -56.829158) (xy 172.816423 -56.916749) (xy 172.824403 -57.005413) (xy 172.824902 -57.049924)
			(xy 172.824403 -57.094435) (xy 172.816423 -57.183099) (xy 172.800527 -57.27069) (xy 172.776844 -57.356505)
			(xy 172.745564 -57.43985) (xy 172.706938 -57.520056) (xy 172.661279 -57.596477) (xy 172.608953 -57.668498)
			(xy 172.550382 -57.735538) (xy 172.486037 -57.797058) (xy 172.416437 -57.852562) (xy 172.342141 -57.901604)
			(xy 172.263749 -57.943789) (xy 172.18189 -57.978777) (xy 172.097225 -58.006286) (xy 172.010435 -58.026096)
			(xy 171.922219 -58.038046) (xy 171.833286 -58.04204) (xy 171.744353 -58.038046) (xy 171.656137 -58.026096)
			(xy 171.569347 -58.006286) (xy 171.484682 -57.978777) (xy 171.402823 -57.943789) (xy 171.324431 -57.901604)
			(xy 171.250135 -57.852562) (xy 171.180535 -57.797058) (xy 171.11619 -57.735538) (xy 171.057619 -57.668498)
			(xy 171.005293 -57.596477) (xy 170.959634 -57.520056) (xy 170.921008 -57.43985) (xy 170.889728 -57.356505)
			(xy 170.866045 -57.27069) (xy 170.850149 -57.183099) (xy 170.842169 -57.094435) (xy 0.509016 -57.094435)
			(xy 0.509016 -60.375038) (xy 233.333297 -60.375038) (xy 233.337302 -60.28713) (xy 233.349285 -60.19995)
			(xy 233.369145 -60.114221) (xy 233.39672 -60.030653) (xy 233.431779 -59.949939) (xy 233.474032 -59.872747)
			(xy 233.52313 -59.799718) (xy 233.578666 -59.731456) (xy 233.640178 -59.668526) (xy 233.707159 -59.611452)
			(xy 233.779052 -59.560704) (xy 233.855261 -59.516704) (xy 233.935156 -59.479817) (xy 234.018075 -59.450348)
			(xy 234.10333 -59.428541) (xy 234.190214 -59.414577) (xy 234.278008 -59.408571) (xy 234.365985 -59.410575)
			(xy 234.453415 -59.42057) (xy 234.539574 -59.438474) (xy 234.623748 -59.464138) (xy 234.705239 -59.497351)
			(xy 234.783373 -59.537837) (xy 234.857501 -59.585259) (xy 234.927009 -59.639226) (xy 234.991323 -59.699291)
			(xy 235.049907 -59.764955) (xy 235.102278 -59.835674) (xy 235.148001 -59.910862) (xy 235.186698 -59.989897)
			(xy 235.218047 -60.072123) (xy 235.241789 -60.156859) (xy 235.257727 -60.243403) (xy 235.265729 -60.331038)
			(xy 235.26623 -60.375038) (xy 235.265729 -60.419038) (xy 235.257727 -60.506673) (xy 235.241789 -60.593217)
			(xy 235.218047 -60.677953) (xy 235.186698 -60.760179) (xy 235.148001 -60.839214) (xy 235.102278 -60.914402)
			(xy 235.049907 -60.985121) (xy 234.991323 -61.050785) (xy 234.927009 -61.11085) (xy 234.857501 -61.164817)
			(xy 234.783373 -61.212239) (xy 234.705239 -61.252725) (xy 234.623748 -61.285938) (xy 234.539574 -61.311602)
			(xy 234.453415 -61.329506) (xy 234.365985 -61.339501) (xy 234.278008 -61.341505) (xy 234.190214 -61.335499)
			(xy 234.10333 -61.321535) (xy 234.018075 -61.299728) (xy 233.935156 -61.270259) (xy 233.855261 -61.233372)
			(xy 233.779052 -61.189372) (xy 233.707159 -61.138624) (xy 233.640178 -61.08155) (xy 233.578666 -61.01862)
			(xy 233.52313 -60.950358) (xy 233.474032 -60.877329) (xy 233.431779 -60.800137) (xy 233.39672 -60.719423)
			(xy 233.369145 -60.635855) (xy 233.349285 -60.550126) (xy 233.337302 -60.462946) (xy 233.333297 -60.375038)
			(xy 0.509016 -60.375038) (xy 0.509016 -74.760836) (xy 39.554404 -74.760836) (xy 39.554404 -66.060828)
			(xy 39.554909 -65.955304) (xy 39.562993 -65.74441) (xy 39.579149 -65.533981) (xy 39.603352 -65.324324)
			(xy 39.635569 -65.115749) (xy 39.675751 -64.908561) (xy 39.723839 -64.703064) (xy 39.779763 -64.49956)
			(xy 39.84344 -64.298347) (xy 39.914778 -64.09972) (xy 39.993672 -63.903972) (xy 40.080005 -63.71139)
			(xy 40.173652 -63.522255) (xy 40.274474 -63.336846) (xy 40.382324 -63.155435) (xy 40.497043 -62.978288)
			(xy 40.618463 -62.805666) (xy 40.746406 -62.63782) (xy 40.880684 -62.474998) (xy 41.0211 -62.317439)
			(xy 41.167448 -62.165374) (xy 41.319513 -62.019026) (xy 41.477072 -61.87861) (xy 41.639894 -61.744332)
			(xy 41.80774 -61.616389) (xy 41.980362 -61.494969) (xy 42.157509 -61.38025) (xy 42.33892 -61.2724)
			(xy 42.524329 -61.171578) (xy 42.713464 -61.077931) (xy 42.906046 -60.991598) (xy 43.101794 -60.912704)
			(xy 43.300421 -60.841366) (xy 43.501634 -60.777689) (xy 43.705138 -60.721765) (xy 43.910635 -60.673677)
			(xy 44.117823 -60.633495) (xy 44.326398 -60.601278) (xy 44.536055 -60.577075) (xy 44.746484 -60.560919)
			(xy 44.957378 -60.552835) (xy 45.168426 -60.552835) (xy 45.37932 -60.560919) (xy 45.589749 -60.577075)
			(xy 45.799406 -60.601278) (xy 46.007981 -60.633495) (xy 46.215169 -60.673677) (xy 46.420666 -60.721765)
			(xy 46.62417 -60.777689) (xy 46.825383 -60.841366) (xy 47.02401 -60.912704) (xy 47.219758 -60.991598)
			(xy 47.41234 -61.077931) (xy 47.601475 -61.171578) (xy 47.786884 -61.2724) (xy 47.968295 -61.38025)
			(xy 48.145442 -61.494969) (xy 48.318064 -61.616389) (xy 48.48591 -61.744332) (xy 48.648732 -61.87861)
			(xy 48.806291 -62.019026) (xy 48.958356 -62.165374) (xy 49.104704 -62.317439) (xy 49.24512 -62.474998)
			(xy 49.379398 -62.63782) (xy 49.507341 -62.805666) (xy 49.628761 -62.978288) (xy 49.74348 -63.155435)
			(xy 49.85133 -63.336846) (xy 49.952152 -63.522255) (xy 50.045799 -63.71139) (xy 50.132132 -63.903972)
			(xy 50.211026 -64.09972) (xy 50.282364 -64.298347) (xy 50.346041 -64.49956) (xy 50.401965 -64.703064)
			(xy 50.450053 -64.908561) (xy 50.490235 -65.115749) (xy 50.522452 -65.324324) (xy 50.546655 -65.533981)
			(xy 50.562811 -65.74441) (xy 50.570895 -65.955304) (xy 50.5714 -66.060828) (xy 50.5714 -74.760836)
			(xy 50.571366 -74.767948) (xy 173.354492 -74.767948) (xy 173.354492 -66.06794) (xy 173.354997 -65.962416)
			(xy 173.363081 -65.751522) (xy 173.379237 -65.541093) (xy 173.40344 -65.331436) (xy 173.435657 -65.122861)
			(xy 173.475839 -64.915673) (xy 173.523927 -64.710176) (xy 173.579851 -64.506672) (xy 173.643528 -64.305459)
			(xy 173.714866 -64.106832) (xy 173.79376 -63.911084) (xy 173.880093 -63.718502) (xy 173.97374 -63.529367)
			(xy 174.074562 -63.343958) (xy 174.182412 -63.162547) (xy 174.297131 -62.9854) (xy 174.418551 -62.812778)
			(xy 174.546494 -62.644932) (xy 174.680772 -62.48211) (xy 174.821188 -62.324551) (xy 174.967536 -62.172486)
			(xy 175.119601 -62.026138) (xy 175.27716 -61.885722) (xy 175.439982 -61.751444) (xy 175.607828 -61.623501)
			(xy 175.78045 -61.502081) (xy 175.957597 -61.387362) (xy 176.139008 -61.279512) (xy 176.324417 -61.17869)
			(xy 176.513552 -61.085043) (xy 176.706134 -60.99871) (xy 176.901882 -60.919816) (xy 177.100509 -60.848478)
			(xy 177.301722 -60.784801) (xy 177.505226 -60.728877) (xy 177.710723 -60.680789) (xy 177.917911 -60.640607)
			(xy 178.126486 -60.60839) (xy 178.336143 -60.584187) (xy 178.546572 -60.568031) (xy 178.757466 -60.559947)
			(xy 178.968514 -60.559947) (xy 179.179408 -60.568031) (xy 179.389837 -60.584187) (xy 179.599494 -60.60839)
			(xy 179.808069 -60.640607) (xy 180.015257 -60.680789) (xy 180.220754 -60.728877) (xy 180.424258 -60.784801)
			(xy 180.625471 -60.848478) (xy 180.824098 -60.919816) (xy 181.019846 -60.99871) (xy 181.212428 -61.085043)
			(xy 181.401563 -61.17869) (xy 181.586972 -61.279512) (xy 181.768383 -61.387362) (xy 181.94553 -61.502081)
			(xy 182.118152 -61.623501) (xy 182.285998 -61.751444) (xy 182.44882 -61.885722) (xy 182.606379 -62.026138)
			(xy 182.758444 -62.172486) (xy 182.904792 -62.324551) (xy 183.045208 -62.48211) (xy 183.179486 -62.644932)
			(xy 183.307429 -62.812778) (xy 183.428849 -62.9854) (xy 183.543568 -63.162547) (xy 183.651418 -63.343958)
			(xy 183.75224 -63.529367) (xy 183.845887 -63.718502) (xy 183.93222 -63.911084) (xy 184.011114 -64.106832)
			(xy 184.082452 -64.305459) (xy 184.146129 -64.506672) (xy 184.202053 -64.710176) (xy 184.250141 -64.915673)
			(xy 184.290323 -65.122861) (xy 184.32254 -65.331436) (xy 184.346743 -65.541093) (xy 184.362899 -65.751522)
			(xy 184.370983 -65.962416) (xy 184.371488 -66.06794) (xy 184.371488 -74.760836) (xy 287.494472 -74.760836)
			(xy 287.494472 -66.060828) (xy 287.494977 -65.955304) (xy 287.503061 -65.74441) (xy 287.519217 -65.533981)
			(xy 287.54342 -65.324324) (xy 287.575637 -65.115749) (xy 287.615819 -64.908561) (xy 287.663907 -64.703064)
			(xy 287.719831 -64.49956) (xy 287.783508 -64.298347) (xy 287.854846 -64.09972) (xy 287.93374 -63.903972)
			(xy 288.020073 -63.71139) (xy 288.11372 -63.522255) (xy 288.214542 -63.336846) (xy 288.322392 -63.155435)
			(xy 288.437111 -62.978288) (xy 288.558531 -62.805666) (xy 288.686474 -62.63782) (xy 288.820752 -62.474998)
			(xy 288.961168 -62.317439) (xy 289.107516 -62.165374) (xy 289.259581 -62.019026) (xy 289.41714 -61.87861)
			(xy 289.579962 -61.744332) (xy 289.747808 -61.616389) (xy 289.92043 -61.494969) (xy 290.097577 -61.38025)
			(xy 290.278988 -61.2724) (xy 290.464397 -61.171578) (xy 290.653532 -61.077931) (xy 290.846114 -60.991598)
			(xy 291.041862 -60.912704) (xy 291.240489 -60.841366) (xy 291.441702 -60.777689) (xy 291.645206 -60.721765)
			(xy 291.850703 -60.673677) (xy 292.057891 -60.633495) (xy 292.266466 -60.601278) (xy 292.476123 -60.577075)
			(xy 292.686552 -60.560919) (xy 292.897446 -60.552835) (xy 293.108494 -60.552835) (xy 293.319388 -60.560919)
			(xy 293.529817 -60.577075) (xy 293.739474 -60.601278) (xy 293.948049 -60.633495) (xy 294.155237 -60.673677)
			(xy 294.360734 -60.721765) (xy 294.564238 -60.777689) (xy 294.765451 -60.841366) (xy 294.964078 -60.912704)
			(xy 295.159826 -60.991598) (xy 295.352408 -61.077931) (xy 295.541543 -61.171578) (xy 295.726952 -61.2724)
			(xy 295.908363 -61.38025) (xy 296.08551 -61.494969) (xy 296.258132 -61.616389) (xy 296.425978 -61.744332)
			(xy 296.5888 -61.87861) (xy 296.746359 -62.019026) (xy 296.898424 -62.165374) (xy 297.044772 -62.317439)
			(xy 297.185188 -62.474998) (xy 297.319466 -62.63782) (xy 297.447409 -62.805666) (xy 297.568829 -62.978288)
			(xy 297.683548 -63.155435) (xy 297.791398 -63.336846) (xy 297.89222 -63.522255) (xy 297.985867 -63.71139)
			(xy 298.0722 -63.903972) (xy 298.151094 -64.09972) (xy 298.222432 -64.298347) (xy 298.286109 -64.49956)
			(xy 298.342033 -64.703064) (xy 298.390121 -64.908561) (xy 298.430303 -65.115749) (xy 298.46252 -65.324324)
			(xy 298.486723 -65.533981) (xy 298.502879 -65.74441) (xy 298.510963 -65.955304) (xy 298.511468 -66.060828)
			(xy 298.511468 -74.760836) (xy 298.511434 -74.767948) (xy 421.29456 -74.767948) (xy 421.29456 -66.06794)
			(xy 421.295065 -65.962416) (xy 421.303149 -65.751522) (xy 421.319305 -65.541093) (xy 421.343508 -65.331436)
			(xy 421.375725 -65.122861) (xy 421.415907 -64.915673) (xy 421.463995 -64.710176) (xy 421.519919 -64.506672)
			(xy 421.583596 -64.305459) (xy 421.654934 -64.106832) (xy 421.733828 -63.911084) (xy 421.820161 -63.718502)
			(xy 421.913808 -63.529367) (xy 422.01463 -63.343958) (xy 422.12248 -63.162547) (xy 422.237199 -62.9854)
			(xy 422.358619 -62.812778) (xy 422.486562 -62.644932) (xy 422.62084 -62.48211) (xy 422.761256 -62.324551)
			(xy 422.907604 -62.172486) (xy 423.059669 -62.026138) (xy 423.217228 -61.885722) (xy 423.38005 -61.751444)
			(xy 423.547896 -61.623501) (xy 423.720518 -61.502081) (xy 423.897665 -61.387362) (xy 424.079076 -61.279512)
			(xy 424.264485 -61.17869) (xy 424.45362 -61.085043) (xy 424.646202 -60.99871) (xy 424.84195 -60.919816)
			(xy 425.040577 -60.848478) (xy 425.24179 -60.784801) (xy 425.445294 -60.728877) (xy 425.650791 -60.680789)
			(xy 425.857979 -60.640607) (xy 426.066554 -60.60839) (xy 426.276211 -60.584187) (xy 426.48664 -60.568031)
			(xy 426.697534 -60.559947) (xy 426.908582 -60.559947) (xy 427.119476 -60.568031) (xy 427.329905 -60.584187)
			(xy 427.539562 -60.60839) (xy 427.748137 -60.640607) (xy 427.955325 -60.680789) (xy 428.160822 -60.728877)
			(xy 428.364326 -60.784801) (xy 428.565539 -60.848478) (xy 428.764166 -60.919816) (xy 428.959914 -60.99871)
			(xy 429.152496 -61.085043) (xy 429.341631 -61.17869) (xy 429.52704 -61.279512) (xy 429.708451 -61.387362)
			(xy 429.885598 -61.502081) (xy 430.05822 -61.623501) (xy 430.226066 -61.751444) (xy 430.388888 -61.885722)
			(xy 430.546447 -62.026138) (xy 430.698512 -62.172486) (xy 430.84486 -62.324551) (xy 430.985276 -62.48211)
			(xy 431.119554 -62.644932) (xy 431.247497 -62.812778) (xy 431.368917 -62.9854) (xy 431.483636 -63.162547)
			(xy 431.591486 -63.343958) (xy 431.692308 -63.529367) (xy 431.785955 -63.718502) (xy 431.872288 -63.911084)
			(xy 431.951182 -64.106832) (xy 432.02252 -64.305459) (xy 432.086197 -64.506672) (xy 432.142121 -64.710176)
			(xy 432.190209 -64.915673) (xy 432.230391 -65.122861) (xy 432.262608 -65.331436) (xy 432.286811 -65.541093)
			(xy 432.302967 -65.751522) (xy 432.311051 -65.962416) (xy 432.311556 -66.06794) (xy 432.311556 -74.767948)
			(xy 432.311051 -74.873472) (xy 432.302967 -75.084366) (xy 432.286811 -75.294795) (xy 432.262608 -75.504452)
			(xy 432.230391 -75.713027) (xy 432.190209 -75.920215) (xy 432.142121 -76.125712) (xy 432.086197 -76.329216)
			(xy 432.02252 -76.530429) (xy 431.951182 -76.729056) (xy 431.872288 -76.924804) (xy 431.785955 -77.117386)
			(xy 431.692308 -77.306521) (xy 431.591486 -77.49193) (xy 431.483636 -77.673341) (xy 431.368917 -77.850488)
			(xy 431.247497 -78.02311) (xy 431.119554 -78.190956) (xy 430.985276 -78.353778) (xy 430.84486 -78.511337)
			(xy 430.698512 -78.663402) (xy 430.546447 -78.80975) (xy 430.388888 -78.950166) (xy 430.226066 -79.084444)
			(xy 430.05822 -79.212387) (xy 429.885598 -79.333807) (xy 429.708451 -79.448526) (xy 429.52704 -79.556376)
			(xy 429.341631 -79.657198) (xy 429.152496 -79.750845) (xy 428.959914 -79.837178) (xy 428.764166 -79.916072)
			(xy 428.565539 -79.98741) (xy 428.364326 -80.051087) (xy 428.160822 -80.107011) (xy 427.955325 -80.155099)
			(xy 427.748137 -80.195281) (xy 427.539562 -80.227498) (xy 427.329905 -80.251701) (xy 427.119476 -80.267857)
			(xy 426.908582 -80.275941) (xy 426.697534 -80.275941) (xy 426.48664 -80.267857) (xy 426.276211 -80.251701)
			(xy 426.066554 -80.227498) (xy 425.857979 -80.195281) (xy 425.650791 -80.155099) (xy 425.445294 -80.107011)
			(xy 425.24179 -80.051087) (xy 425.040577 -79.98741) (xy 424.84195 -79.916072) (xy 424.646202 -79.837178)
			(xy 424.45362 -79.750845) (xy 424.264485 -79.657198) (xy 424.079076 -79.556376) (xy 423.897665 -79.448526)
			(xy 423.720518 -79.333807) (xy 423.547896 -79.212387) (xy 423.38005 -79.084444) (xy 423.217228 -78.950166)
			(xy 423.059669 -78.80975) (xy 422.907604 -78.663402) (xy 422.761256 -78.511337) (xy 422.62084 -78.353778)
			(xy 422.486562 -78.190956) (xy 422.358619 -78.02311) (xy 422.237199 -77.850488) (xy 422.12248 -77.673341)
			(xy 422.01463 -77.49193) (xy 421.913808 -77.306521) (xy 421.820161 -77.117386) (xy 421.733828 -76.924804)
			(xy 421.654934 -76.729056) (xy 421.583596 -76.530429) (xy 421.519919 -76.329216) (xy 421.463995 -76.125712)
			(xy 421.415907 -75.920215) (xy 421.375725 -75.713027) (xy 421.343508 -75.504452) (xy 421.319305 -75.294795)
			(xy 421.303149 -75.084366) (xy 421.295065 -74.873472) (xy 421.29456 -74.767948) (xy 298.511434 -74.767948)
			(xy 298.510963 -74.86636) (xy 298.502879 -75.077254) (xy 298.486723 -75.287683) (xy 298.46252 -75.49734)
			(xy 298.430303 -75.705915) (xy 298.390121 -75.913103) (xy 298.342033 -76.1186) (xy 298.286109 -76.322104)
			(xy 298.222432 -76.523317) (xy 298.151094 -76.721944) (xy 298.0722 -76.917692) (xy 297.985867 -77.110274)
			(xy 297.89222 -77.299409) (xy 297.791398 -77.484818) (xy 297.683548 -77.666229) (xy 297.568829 -77.843376)
			(xy 297.447409 -78.015998) (xy 297.319466 -78.183844) (xy 297.185188 -78.346666) (xy 297.044772 -78.504225)
			(xy 296.898424 -78.65629) (xy 296.746359 -78.802638) (xy 296.5888 -78.943054) (xy 296.425978 -79.077332)
			(xy 296.258132 -79.205275) (xy 296.08551 -79.326695) (xy 295.908363 -79.441414) (xy 295.726952 -79.549264)
			(xy 295.541543 -79.650086) (xy 295.352408 -79.743733) (xy 295.159826 -79.830066) (xy 294.964078 -79.90896)
			(xy 294.765451 -79.980298) (xy 294.564238 -80.043975) (xy 294.360734 -80.099899) (xy 294.155237 -80.147987)
			(xy 293.948049 -80.188169) (xy 293.739474 -80.220386) (xy 293.529817 -80.244589) (xy 293.319388 -80.260745)
			(xy 293.108494 -80.268829) (xy 292.897446 -80.268829) (xy 292.686552 -80.260745) (xy 292.476123 -80.244589)
			(xy 292.266466 -80.220386) (xy 292.057891 -80.188169) (xy 291.850703 -80.147987) (xy 291.645206 -80.099899)
			(xy 291.441702 -80.043975) (xy 291.240489 -79.980298) (xy 291.041862 -79.90896) (xy 290.846114 -79.830066)
			(xy 290.653532 -79.743733) (xy 290.464397 -79.650086) (xy 290.278988 -79.549264) (xy 290.097577 -79.441414)
			(xy 289.92043 -79.326695) (xy 289.747808 -79.205275) (xy 289.579962 -79.077332) (xy 289.41714 -78.943054)
			(xy 289.259581 -78.802638) (xy 289.107516 -78.65629) (xy 288.961168 -78.504225) (xy 288.820752 -78.346666)
			(xy 288.686474 -78.183844) (xy 288.558531 -78.015998) (xy 288.437111 -77.843376) (xy 288.322392 -77.666229)
			(xy 288.214542 -77.484818) (xy 288.11372 -77.299409) (xy 288.020073 -77.110274) (xy 287.93374 -76.917692)
			(xy 287.854846 -76.721944) (xy 287.783508 -76.523317) (xy 287.719831 -76.322104) (xy 287.663907 -76.1186)
			(xy 287.615819 -75.913103) (xy 287.575637 -75.705915) (xy 287.54342 -75.49734) (xy 287.519217 -75.287683)
			(xy 287.503061 -75.077254) (xy 287.494977 -74.86636) (xy 287.494472 -74.760836) (xy 184.371488 -74.760836)
			(xy 184.371488 -74.767948) (xy 184.370983 -74.873472) (xy 184.362899 -75.084366) (xy 184.346743 -75.294795)
			(xy 184.32254 -75.504452) (xy 184.290323 -75.713027) (xy 184.250141 -75.920215) (xy 184.202053 -76.125712)
			(xy 184.146129 -76.329216) (xy 184.082452 -76.530429) (xy 184.011114 -76.729056) (xy 183.93222 -76.924804)
			(xy 183.845887 -77.117386) (xy 183.75224 -77.306521) (xy 183.651418 -77.49193) (xy 183.543568 -77.673341)
			(xy 183.428849 -77.850488) (xy 183.307429 -78.02311) (xy 183.179486 -78.190956) (xy 183.045208 -78.353778)
			(xy 182.904792 -78.511337) (xy 182.758444 -78.663402) (xy 182.606379 -78.80975) (xy 182.44882 -78.950166)
			(xy 182.285998 -79.084444) (xy 182.118152 -79.212387) (xy 181.94553 -79.333807) (xy 181.768383 -79.448526)
			(xy 181.586972 -79.556376) (xy 181.401563 -79.657198) (xy 181.212428 -79.750845) (xy 181.019846 -79.837178)
			(xy 180.824098 -79.916072) (xy 180.625471 -79.98741) (xy 180.424258 -80.051087) (xy 180.220754 -80.107011)
			(xy 180.015257 -80.155099) (xy 179.808069 -80.195281) (xy 179.599494 -80.227498) (xy 179.389837 -80.251701)
			(xy 179.179408 -80.267857) (xy 178.968514 -80.275941) (xy 178.757466 -80.275941) (xy 178.546572 -80.267857)
			(xy 178.336143 -80.251701) (xy 178.126486 -80.227498) (xy 177.917911 -80.195281) (xy 177.710723 -80.155099)
			(xy 177.505226 -80.107011) (xy 177.301722 -80.051087) (xy 177.100509 -79.98741) (xy 176.901882 -79.916072)
			(xy 176.706134 -79.837178) (xy 176.513552 -79.750845) (xy 176.324417 -79.657198) (xy 176.139008 -79.556376)
			(xy 175.957597 -79.448526) (xy 175.78045 -79.333807) (xy 175.607828 -79.212387) (xy 175.439982 -79.084444)
			(xy 175.27716 -78.950166) (xy 175.119601 -78.80975) (xy 174.967536 -78.663402) (xy 174.821188 -78.511337)
			(xy 174.680772 -78.353778) (xy 174.546494 -78.190956) (xy 174.418551 -78.02311) (xy 174.297131 -77.850488)
			(xy 174.182412 -77.673341) (xy 174.074562 -77.49193) (xy 173.97374 -77.306521) (xy 173.880093 -77.117386)
			(xy 173.79376 -76.924804) (xy 173.714866 -76.729056) (xy 173.643528 -76.530429) (xy 173.579851 -76.329216)
			(xy 173.523927 -76.125712) (xy 173.475839 -75.920215) (xy 173.435657 -75.713027) (xy 173.40344 -75.504452)
			(xy 173.379237 -75.294795) (xy 173.363081 -75.084366) (xy 173.354997 -74.873472) (xy 173.354492 -74.767948)
			(xy 50.571366 -74.767948) (xy 50.570895 -74.86636) (xy 50.562811 -75.077254) (xy 50.546655 -75.287683)
			(xy 50.522452 -75.49734) (xy 50.490235 -75.705915) (xy 50.450053 -75.913103) (xy 50.401965 -76.1186)
			(xy 50.346041 -76.322104) (xy 50.282364 -76.523317) (xy 50.211026 -76.721944) (xy 50.132132 -76.917692)
			(xy 50.045799 -77.110274) (xy 49.952152 -77.299409) (xy 49.85133 -77.484818) (xy 49.74348 -77.666229)
			(xy 49.628761 -77.843376) (xy 49.507341 -78.015998) (xy 49.379398 -78.183844) (xy 49.24512 -78.346666)
			(xy 49.104704 -78.504225) (xy 48.958356 -78.65629) (xy 48.806291 -78.802638) (xy 48.648732 -78.943054)
			(xy 48.48591 -79.077332) (xy 48.318064 -79.205275) (xy 48.145442 -79.326695) (xy 47.968295 -79.441414)
			(xy 47.786884 -79.549264) (xy 47.601475 -79.650086) (xy 47.41234 -79.743733) (xy 47.219758 -79.830066)
			(xy 47.02401 -79.90896) (xy 46.825383 -79.980298) (xy 46.62417 -80.043975) (xy 46.420666 -80.099899)
			(xy 46.215169 -80.147987) (xy 46.007981 -80.188169) (xy 45.799406 -80.220386) (xy 45.589749 -80.244589)
			(xy 45.37932 -80.260745) (xy 45.168426 -80.268829) (xy 44.957378 -80.268829) (xy 44.746484 -80.260745)
			(xy 44.536055 -80.244589) (xy 44.326398 -80.220386) (xy 44.117823 -80.188169) (xy 43.910635 -80.147987)
			(xy 43.705138 -80.099899) (xy 43.501634 -80.043975) (xy 43.300421 -79.980298) (xy 43.101794 -79.90896)
			(xy 42.906046 -79.830066) (xy 42.713464 -79.743733) (xy 42.524329 -79.650086) (xy 42.33892 -79.549264)
			(xy 42.157509 -79.441414) (xy 41.980362 -79.326695) (xy 41.80774 -79.205275) (xy 41.639894 -79.077332)
			(xy 41.477072 -78.943054) (xy 41.319513 -78.802638) (xy 41.167448 -78.65629) (xy 41.0211 -78.504225)
			(xy 40.880684 -78.346666) (xy 40.746406 -78.183844) (xy 40.618463 -78.015998) (xy 40.497043 -77.843376)
			(xy 40.382324 -77.666229) (xy 40.274474 -77.484818) (xy 40.173652 -77.299409) (xy 40.080005 -77.110274)
			(xy 39.993672 -76.917692) (xy 39.914778 -76.721944) (xy 39.84344 -76.523317) (xy 39.779763 -76.322104)
			(xy 39.723839 -76.1186) (xy 39.675751 -75.913103) (xy 39.635569 -75.705915) (xy 39.603352 -75.49734)
			(xy 39.579149 -75.287683) (xy 39.562993 -75.077254) (xy 39.554909 -74.86636) (xy 39.554404 -74.760836)
			(xy 0.509016 -74.760836) (xy 0.509016 -77.67193) (xy 0.5095 -77.725143) (xy 0.517108 -77.831296)
			(xy 0.532269 -77.936637) (xy 0.554904 -78.040627) (xy 0.584899 -78.142739) (xy 0.622101 -78.242451)
			(xy 0.666319 -78.339256) (xy 0.71733 -78.43266) (xy 0.774873 -78.522188) (xy 0.838654 -78.607384)
			(xy 0.90835 -78.687813) (xy 0.945642 -78.725776) (xy 1.77419 -79.554324) (xy 1.823612 -79.604428)
			(xy 1.917404 -79.709374) (xy 2.005163 -79.819414) (xy 2.086614 -79.934202) (xy 2.161501 -80.053377)
			(xy 2.229587 -80.176563) (xy 2.290658 -80.303374) (xy 2.344523 -80.433409) (xy 2.391012 -80.56626)
			(xy 2.429978 -80.701509) (xy 2.461299 -80.83873) (xy 2.484876 -80.977491) (xy 2.500635 -81.117356)
			(xy 2.508527 -81.257885) (xy 2.509012 -81.32826) (xy 2.509012 -81.691972) (xy 232.140715 -81.691972)
			(xy 232.145114 -81.518126) (xy 232.157548 -81.34467) (xy 232.177991 -81.171975) (xy 232.206398 -81.00041)
			(xy 232.242709 -80.830342) (xy 232.286847 -80.662135) (xy 232.338717 -80.49615) (xy 232.398207 -80.332741)
			(xy 232.465191 -80.172258) (xy 232.539525 -80.015044) (xy 232.62105 -79.861437) (xy 232.709592 -79.711764)
			(xy 232.804961 -79.566346) (xy 232.906953 -79.425495) (xy 233.015351 -79.289511) (xy 233.129921 -79.158685)
			(xy 233.250418 -79.033298) (xy 233.376586 -78.913618) (xy 233.508153 -78.799901) (xy 233.644839 -78.69239)
			(xy 233.715306 -78.641448) (xy 238.084614 -78.641448) (xy 238.155081 -78.69239) (xy 238.291767 -78.799901)
			(xy 238.423334 -78.913618) (xy 238.549502 -79.033298) (xy 238.669999 -79.158685) (xy 238.784569 -79.289511)
			(xy 238.892967 -79.425495) (xy 238.994959 -79.566346) (xy 239.090328 -79.711764) (xy 239.17887 -79.861437)
			(xy 239.260395 -80.015044) (xy 239.334729 -80.172258) (xy 239.401713 -80.332741) (xy 239.461203 -80.49615)
			(xy 239.513073 -80.662135) (xy 239.557211 -80.830342) (xy 239.593522 -81.00041) (xy 239.608937 -81.093507)
			(xy 398.275806 -81.093507) (xy 398.275806 -81.008785) (xy 398.283859 -80.924448) (xy 398.299893 -80.841258)
			(xy 398.323761 -80.759968) (xy 398.355249 -80.681316) (xy 398.394071 -80.606013) (xy 398.439874 -80.534741)
			(xy 398.492245 -80.468145) (xy 398.55071 -80.40683) (xy 398.614738 -80.351349) (xy 398.68375 -80.302206)
			(xy 398.75712 -80.259846) (xy 398.834185 -80.224651) (xy 398.914247 -80.196942) (xy 398.99658 -80.176968)
			(xy 399.080439 -80.164911) (xy 399.165064 -80.16088) (xy 399.249689 -80.164911) (xy 399.333548 -80.176968)
			(xy 399.415881 -80.196942) (xy 399.495943 -80.224651) (xy 399.573008 -80.259846) (xy 399.646378 -80.302206)
			(xy 399.71539 -80.351349) (xy 399.779418 -80.40683) (xy 399.837883 -80.468145) (xy 399.890254 -80.534741)
			(xy 399.936057 -80.606013) (xy 399.974879 -80.681316) (xy 400.006367 -80.759968) (xy 400.030235 -80.841258)
			(xy 400.046269 -80.924448) (xy 400.054322 -81.008785) (xy 400.054826 -81.051146) (xy 400.054322 -81.093507)
			(xy 400.046269 -81.177844) (xy 400.030235 -81.261034) (xy 400.006367 -81.342324) (xy 399.974879 -81.420976)
			(xy 399.936057 -81.496279) (xy 399.890254 -81.567551) (xy 399.837883 -81.634147) (xy 399.779418 -81.695462)
			(xy 399.71539 -81.750943) (xy 399.646378 -81.800086) (xy 399.573008 -81.842446) (xy 399.495943 -81.877641)
			(xy 399.415881 -81.90535) (xy 399.333548 -81.925324) (xy 399.249689 -81.937381) (xy 399.165064 -81.941413)
			(xy 399.080439 -81.937381) (xy 398.99658 -81.925324) (xy 398.914247 -81.90535) (xy 398.834185 -81.877641)
			(xy 398.75712 -81.842446) (xy 398.68375 -81.800086) (xy 398.614738 -81.750943) (xy 398.55071 -81.695462)
			(xy 398.492245 -81.634147) (xy 398.439874 -81.567551) (xy 398.394071 -81.496279) (xy 398.355249 -81.420976)
			(xy 398.323761 -81.342324) (xy 398.299893 -81.261034) (xy 398.283859 -81.177844) (xy 398.275806 -81.093507)
			(xy 239.608937 -81.093507) (xy 239.621929 -81.171975) (xy 239.642372 -81.34467) (xy 239.654806 -81.518126)
			(xy 239.659205 -81.691972) (xy 239.655559 -81.865835) (xy 239.643877 -82.039343) (xy 239.624183 -82.212126)
			(xy 239.596519 -82.383812) (xy 239.560945 -82.554036) (xy 239.517536 -82.722432) (xy 239.466387 -82.888641)
			(xy 239.407605 -83.052306) (xy 239.341317 -83.213078) (xy 239.267665 -83.370612) (xy 239.186806 -83.524571)
			(xy 239.098913 -83.674626) (xy 239.004175 -83.820455) (xy 238.902794 -83.961748) (xy 238.794987 -84.0982)
			(xy 238.680985 -84.229521) (xy 238.561032 -84.355429) (xy 238.435384 -84.475655) (xy 238.30431 -84.589941)
			(xy 238.168092 -84.698043) (xy 238.027019 -84.79973) (xy 237.881395 -84.894784) (xy 237.731531 -84.983001)
			(xy 237.577747 -85.064194) (xy 237.420373 -85.138187) (xy 237.259746 -85.204823) (xy 237.096208 -85.263959)
			(xy 236.930111 -85.315469) (xy 236.761809 -85.359242) (xy 236.591663 -85.395185) (xy 236.420037 -85.423221)
			(xy 236.247297 -85.443289) (xy 236.073815 -85.455348) (xy 235.89996 -85.45937) (xy 235.726105 -85.455348)
			(xy 235.552623 -85.443289) (xy 235.379883 -85.423221) (xy 235.208257 -85.395185) (xy 235.038111 -85.359242)
			(xy 234.869809 -85.315469) (xy 234.703712 -85.263959) (xy 234.540174 -85.204823) (xy 234.379547 -85.138187)
			(xy 234.222173 -85.064194) (xy 234.068389 -84.983001) (xy 233.918525 -84.894784) (xy 233.772901 -84.79973)
			(xy 233.631828 -84.698043) (xy 233.49561 -84.589941) (xy 233.364536 -84.475655) (xy 233.238888 -84.355429)
			(xy 233.118935 -84.229521) (xy 233.004933 -84.0982) (xy 232.897126 -83.961748) (xy 232.795745 -83.820455)
			(xy 232.701007 -83.674626) (xy 232.613114 -83.524571) (xy 232.532255 -83.370612) (xy 232.458603 -83.213078)
			(xy 232.392315 -83.052306) (xy 232.333533 -82.888641) (xy 232.282384 -82.722432) (xy 232.238975 -82.554036)
			(xy 232.203401 -82.383812) (xy 232.175737 -82.212126) (xy 232.156043 -82.039343) (xy 232.144361 -81.865835)
			(xy 232.140715 -81.691972) (xy 2.509012 -81.691972) (xy 2.509012 -84.065147) (xy 218.29831 -84.065147)
			(xy 218.29831 -84.010653) (xy 218.306065 -83.956712) (xy 218.321417 -83.904424) (xy 218.344054 -83.854854)
			(xy 218.373515 -83.809009) (xy 218.4092 -83.767823) (xy 218.450383 -83.732134) (xy 218.496225 -83.70267)
			(xy 218.545794 -83.680029) (xy 218.598081 -83.664672) (xy 218.652021 -83.656912) (xy 218.679268 -83.656424)
			(xy 219.542868 -83.656424) (xy 219.570125 -83.656821) (xy 219.624084 -83.664575) (xy 219.67639 -83.679929)
			(xy 219.725978 -83.702572) (xy 219.771839 -83.732041) (xy 219.813039 -83.767738) (xy 219.848739 -83.808935)
			(xy 219.878213 -83.854794) (xy 219.90086 -83.90438) (xy 219.916219 -83.956685) (xy 219.923977 -84.010643)
			(xy 219.923977 -84.065157) (xy 219.916219 -84.119115) (xy 219.90086 -84.17142) (xy 219.878213 -84.221006)
			(xy 219.848739 -84.266865) (xy 219.813039 -84.308062) (xy 219.771839 -84.343759) (xy 219.725978 -84.373228)
			(xy 219.67639 -84.395871) (xy 219.624084 -84.411225) (xy 219.570125 -84.418979) (xy 219.542868 -84.41944)
			(xy 218.679268 -84.41944) (xy 218.652021 -84.418888) (xy 218.598081 -84.411128) (xy 218.545794 -84.395771)
			(xy 218.496225 -84.37313) (xy 218.450383 -84.343666) (xy 218.4092 -84.307977) (xy 218.373515 -84.266791)
			(xy 218.344054 -84.220946) (xy 218.321417 -84.171376) (xy 218.306065 -84.119088) (xy 218.29831 -84.065147)
			(xy 2.509012 -84.065147) (xy 2.509012 -86.948548) (xy 217.344518 -86.948548) (xy 217.344518 -86.894052)
			(xy 217.352274 -86.84011) (xy 217.367627 -86.787821) (xy 217.390266 -86.738249) (xy 217.419729 -86.692404)
			(xy 217.455416 -86.651218) (xy 217.496602 -86.61553) (xy 217.542447 -86.586067) (xy 217.592019 -86.563428)
			(xy 217.644308 -86.548074) (xy 217.69825 -86.540318) (xy 217.725498 -86.539832) (xy 218.589098 -86.539832)
			(xy 218.616354 -86.540215) (xy 218.670311 -86.547972) (xy 218.722614 -86.56333) (xy 218.7722 -86.585975)
			(xy 218.818058 -86.615446) (xy 218.859255 -86.651143) (xy 218.894953 -86.69234) (xy 218.924424 -86.738198)
			(xy 218.947069 -86.787784) (xy 218.962427 -86.840087) (xy 218.970185 -86.894044) (xy 218.970185 -86.948556)
			(xy 218.962427 -87.002513) (xy 218.947069 -87.054816) (xy 218.924424 -87.104402) (xy 218.894953 -87.15026)
			(xy 218.859255 -87.191457) (xy 218.818058 -87.227154) (xy 218.7722 -87.256625) (xy 218.722614 -87.27927)
			(xy 218.670311 -87.294628) (xy 218.616354 -87.302385) (xy 218.589098 -87.302848) (xy 217.725498 -87.302848)
			(xy 217.69825 -87.302282) (xy 217.644308 -87.294526) (xy 217.592019 -87.279172) (xy 217.542447 -87.256533)
			(xy 217.496602 -87.22707) (xy 217.455416 -87.191382) (xy 217.419729 -87.150196) (xy 217.390266 -87.104351)
			(xy 217.367627 -87.054779) (xy 217.352274 -87.00249) (xy 217.344518 -86.948548) (xy 2.509012 -86.948548)
			(xy 2.509012 -106.447336) (xy 11.713464 -106.447336) (xy 11.713464 -105.456736) (xy 11.71395 -105.429467)
			(xy 11.721712 -105.375483) (xy 11.737077 -105.323153) (xy 11.759734 -105.273543) (xy 11.78922 -105.227662)
			(xy 11.824935 -105.186445) (xy 11.866152 -105.15073) (xy 11.912033 -105.121244) (xy 11.961643 -105.098587)
			(xy 12.013973 -105.083222) (xy 12.067957 -105.07546) (xy 12.122495 -105.07546) (xy 12.176479 -105.083222)
			(xy 12.228809 -105.098587) (xy 12.278419 -105.121244) (xy 12.3243 -105.15073) (xy 12.365517 -105.186445)
			(xy 12.401232 -105.227662) (xy 12.430718 -105.273543) (xy 12.453375 -105.323153) (xy 12.46874 -105.375483)
			(xy 12.476502 -105.429467) (xy 12.476988 -105.456736) (xy 12.476988 -105.664) (xy 15.57274 -105.664)
			(xy 15.57274 -104.6734) (xy 15.573226 -104.646131) (xy 15.580988 -104.592147) (xy 15.596353 -104.539817)
			(xy 15.61901 -104.490207) (xy 15.648496 -104.444326) (xy 15.684211 -104.403109) (xy 15.725428 -104.367394)
			(xy 15.771309 -104.337908) (xy 15.820919 -104.315251) (xy 15.873249 -104.299886) (xy 15.927233 -104.292124)
			(xy 15.981771 -104.292124) (xy 16.035755 -104.299886) (xy 16.088085 -104.315251) (xy 16.137695 -104.337908)
			(xy 16.146631 -104.343651) (xy 326.803 -104.343651) (xy 326.803 -104.258929) (xy 326.811053 -104.174592)
			(xy 326.827087 -104.091402) (xy 326.850955 -104.010112) (xy 326.882443 -103.93146) (xy 326.921265 -103.856157)
			(xy 326.967068 -103.784885) (xy 327.019439 -103.718289) (xy 327.077904 -103.656974) (xy 327.141932 -103.601493)
			(xy 327.210944 -103.55235) (xy 327.284314 -103.50999) (xy 327.361379 -103.474795) (xy 327.441441 -103.447086)
			(xy 327.523774 -103.427112) (xy 327.607633 -103.415055) (xy 327.692258 -103.411024) (xy 327.776883 -103.415055)
			(xy 327.860742 -103.427112) (xy 327.943075 -103.447086) (xy 328.023137 -103.474795) (xy 328.100202 -103.50999)
			(xy 328.173572 -103.55235) (xy 328.242584 -103.601493) (xy 328.306612 -103.656974) (xy 328.365077 -103.718289)
			(xy 328.417448 -103.784885) (xy 328.463251 -103.856157) (xy 328.502073 -103.93146) (xy 328.533561 -104.010112)
			(xy 328.557429 -104.091402) (xy 328.573463 -104.174592) (xy 328.581516 -104.258929) (xy 328.58202 -104.30129)
			(xy 328.581516 -104.343651) (xy 328.573463 -104.427988) (xy 328.557429 -104.511178) (xy 328.533561 -104.592468)
			(xy 328.502073 -104.67112) (xy 328.463251 -104.746423) (xy 328.417448 -104.817695) (xy 328.365077 -104.884291)
			(xy 328.306612 -104.945606) (xy 328.242584 -105.001087) (xy 328.173572 -105.05023) (xy 328.100202 -105.09259)
			(xy 328.023137 -105.127785) (xy 327.943075 -105.155494) (xy 327.860742 -105.175468) (xy 327.776883 -105.187525)
			(xy 327.692258 -105.191557) (xy 327.607633 -105.187525) (xy 327.523774 -105.175468) (xy 327.441441 -105.155494)
			(xy 327.361379 -105.127785) (xy 327.284314 -105.09259) (xy 327.210944 -105.05023) (xy 327.141932 -105.001087)
			(xy 327.077904 -104.945606) (xy 327.019439 -104.884291) (xy 326.967068 -104.817695) (xy 326.921265 -104.746423)
			(xy 326.882443 -104.67112) (xy 326.850955 -104.592468) (xy 326.827087 -104.511178) (xy 326.811053 -104.427988)
			(xy 326.803 -104.343651) (xy 16.146631 -104.343651) (xy 16.183576 -104.367394) (xy 16.224793 -104.403109)
			(xy 16.260508 -104.444326) (xy 16.289994 -104.490207) (xy 16.312651 -104.539817) (xy 16.328016 -104.592147)
			(xy 16.335778 -104.646131) (xy 16.336264 -104.6734) (xy 16.336264 -105.664) (xy 16.335778 -105.691269)
			(xy 16.328016 -105.745253) (xy 16.312651 -105.797583) (xy 16.289994 -105.847193) (xy 16.260508 -105.893074)
			(xy 16.224793 -105.934291) (xy 16.183576 -105.970006) (xy 16.137695 -105.999492) (xy 16.088085 -106.022149)
			(xy 16.035755 -106.037514) (xy 15.981771 -106.045276) (xy 15.927233 -106.045276) (xy 15.873249 -106.037514)
			(xy 15.820919 -106.022149) (xy 15.771309 -105.999492) (xy 15.725428 -105.970006) (xy 15.684211 -105.934291)
			(xy 15.648496 -105.893074) (xy 15.61901 -105.847193) (xy 15.596353 -105.797583) (xy 15.580988 -105.745253)
			(xy 15.573226 -105.691269) (xy 15.57274 -105.664) (xy 12.476988 -105.664) (xy 12.476988 -106.447336)
			(xy 12.476502 -106.474605) (xy 12.46874 -106.528589) (xy 12.453375 -106.580919) (xy 12.430718 -106.630529)
			(xy 12.401232 -106.67641) (xy 12.365517 -106.717627) (xy 12.3243 -106.753342) (xy 12.278419 -106.782828)
			(xy 12.228809 -106.805485) (xy 12.176479 -106.82085) (xy 12.122495 -106.828612) (xy 12.067957 -106.828612)
			(xy 12.013973 -106.82085) (xy 11.961643 -106.805485) (xy 11.912033 -106.782828) (xy 11.866152 -106.753342)
			(xy 11.824935 -106.717627) (xy 11.78922 -106.67641) (xy 11.759734 -106.630529) (xy 11.737077 -106.580919)
			(xy 11.721712 -106.528589) (xy 11.71395 -106.474605) (xy 11.713464 -106.447336) (xy 2.509012 -106.447336)
			(xy 2.509012 -108.943971) (xy 11.292822 -108.943971) (xy 11.292822 -108.889469) (xy 11.300578 -108.835522)
			(xy 11.315933 -108.783228) (xy 11.338574 -108.733651) (xy 11.36804 -108.687801) (xy 11.403731 -108.646611)
			(xy 11.444921 -108.61092) (xy 11.490771 -108.581454) (xy 11.540348 -108.558813) (xy 11.592642 -108.543458)
			(xy 11.646589 -108.535702) (xy 11.67384 -108.535216) (xy 12.53744 -108.535216) (xy 12.564692 -108.535694)
			(xy 12.61864 -108.54345) (xy 12.670935 -108.558806) (xy 12.720513 -108.581447) (xy 12.766364 -108.610914)
			(xy 12.807554 -108.646606) (xy 12.843246 -108.687796) (xy 12.872713 -108.733647) (xy 12.895354 -108.783225)
			(xy 12.91071 -108.83552) (xy 12.918466 -108.889468) (xy 12.918466 -108.943972) (xy 12.91071 -108.99792)
			(xy 12.895354 -109.050215) (xy 12.872713 -109.099793) (xy 12.843246 -109.145644) (xy 12.807554 -109.186834)
			(xy 12.766364 -109.222526) (xy 12.720513 -109.251993) (xy 12.670935 -109.274634) (xy 12.61864 -109.28999)
			(xy 12.564692 -109.297746) (xy 12.53744 -109.298232) (xy 11.67384 -109.298232) (xy 11.646589 -109.297738)
			(xy 11.592642 -109.289982) (xy 11.540348 -109.274627) (xy 11.490771 -109.251986) (xy 11.444921 -109.22252)
			(xy 11.403731 -109.186829) (xy 11.36804 -109.145639) (xy 11.338574 -109.099789) (xy 11.315933 -109.050212)
			(xy 11.300578 -108.997918) (xy 11.292822 -108.943971) (xy 2.509012 -108.943971) (xy 2.509012 -109.451973)
			(xy 15.092889 -109.451973) (xy 15.092889 -109.397467) (xy 15.100646 -109.343517) (xy 15.116002 -109.291219)
			(xy 15.138645 -109.241639) (xy 15.168113 -109.195786) (xy 15.203807 -109.154594) (xy 15.244999 -109.118901)
			(xy 15.290853 -109.089433) (xy 15.340433 -109.066791) (xy 15.39273 -109.051435) (xy 15.446681 -109.043679)
			(xy 15.473934 -109.043216) (xy 16.464534 -109.043216) (xy 16.491785 -109.043694) (xy 16.545733 -109.051451)
			(xy 16.598028 -109.066807) (xy 16.647605 -109.089448) (xy 16.693456 -109.118915) (xy 16.734646 -109.154607)
			(xy 16.770337 -109.195798) (xy 16.799804 -109.241648) (xy 16.822445 -109.291226) (xy 16.8378 -109.343521)
			(xy 16.845556 -109.397469) (xy 16.845556 -109.451971) (xy 16.8378 -109.505919) (xy 16.822445 -109.558214)
			(xy 16.799804 -109.607792) (xy 16.770337 -109.653642) (xy 16.734646 -109.694833) (xy 16.693456 -109.730525)
			(xy 16.647605 -109.759992) (xy 16.598028 -109.782633) (xy 16.545733 -109.797989) (xy 16.491785 -109.805746)
			(xy 16.464534 -109.806232) (xy 15.473934 -109.806232) (xy 15.446681 -109.805761) (xy 15.39273 -109.798005)
			(xy 15.340433 -109.782649) (xy 15.290853 -109.760007) (xy 15.244999 -109.730539) (xy 15.203807 -109.694846)
			(xy 15.168113 -109.653654) (xy 15.138645 -109.607801) (xy 15.116002 -109.558221) (xy 15.100646 -109.505923)
			(xy 15.092889 -109.451973) (xy 2.509012 -109.451973) (xy 2.509012 -114.734161) (xy 11.255226 -114.734161)
			(xy 11.255226 -114.679659) (xy 11.262982 -114.625711) (xy 11.278337 -114.573416) (xy 11.300979 -114.523839)
			(xy 11.330445 -114.477988) (xy 11.366136 -114.436798) (xy 11.407326 -114.401106) (xy 11.453177 -114.371639)
			(xy 11.502754 -114.348998) (xy 11.555049 -114.333643) (xy 11.608997 -114.325886) (xy 11.636248 -114.3254)
			(xy 12.499848 -114.3254) (xy 12.527101 -114.325867) (xy 12.581052 -114.333624) (xy 12.633349 -114.34898)
			(xy 12.68293 -114.371622) (xy 12.728783 -114.40109) (xy 12.769975 -114.436783) (xy 12.805669 -114.477976)
			(xy 12.835137 -114.523829) (xy 12.85778 -114.573409) (xy 12.873136 -114.625706) (xy 12.880893 -114.679657)
			(xy 12.880893 -114.734163) (xy 12.873136 -114.788114) (xy 12.85778 -114.840411) (xy 12.835137 -114.889991)
			(xy 12.805669 -114.935844) (xy 12.769975 -114.977037) (xy 12.728783 -115.01273) (xy 12.68293 -115.042198)
			(xy 12.633349 -115.06484) (xy 12.581052 -115.080196) (xy 12.527101 -115.087953) (xy 12.499848 -115.088416)
			(xy 11.636248 -115.088416) (xy 11.608997 -115.087934) (xy 11.555049 -115.080177) (xy 11.502754 -115.064822)
			(xy 11.453177 -115.042181) (xy 11.407326 -115.012714) (xy 11.366136 -114.977022) (xy 11.330445 -114.935832)
			(xy 11.300979 -114.889981) (xy 11.278337 -114.840404) (xy 11.262982 -114.788109) (xy 11.255226 -114.734161)
			(xy 2.509012 -114.734161) (xy 2.509012 -133.480302) (xy 20.179284 -133.480302) (xy 20.179284 -132.489702)
			(xy 20.17977 -132.462451) (xy 20.187526 -132.408503) (xy 20.202881 -132.356208) (xy 20.225523 -132.306631)
			(xy 20.254989 -132.260781) (xy 20.29068 -132.21959) (xy 20.331871 -132.183899) (xy 20.377721 -132.154433)
			(xy 20.427298 -132.131791) (xy 20.479593 -132.116436) (xy 20.533541 -132.10868) (xy 20.588043 -132.10868)
			(xy 20.641991 -132.116436) (xy 20.694286 -132.131791) (xy 20.743863 -132.154433) (xy 20.789713 -132.183899)
			(xy 20.830904 -132.21959) (xy 20.866595 -132.260781) (xy 20.896061 -132.306631) (xy 20.918703 -132.356208)
			(xy 20.934058 -132.408503) (xy 20.941814 -132.462451) (xy 20.9423 -132.489702) (xy 20.9423 -133.480302)
			(xy 20.941814 -133.507553) (xy 20.934058 -133.561501) (xy 20.918703 -133.613796) (xy 20.896061 -133.663373)
			(xy 20.866595 -133.709223) (xy 20.830904 -133.750414) (xy 20.789713 -133.786105) (xy 20.743863 -133.815571)
			(xy 20.694286 -133.838213) (xy 20.641991 -133.853568) (xy 20.588043 -133.861324) (xy 20.533541 -133.861324)
			(xy 20.479593 -133.853568) (xy 20.427298 -133.838213) (xy 20.377721 -133.815571) (xy 20.331871 -133.786105)
			(xy 20.29068 -133.750414) (xy 20.254989 -133.709223) (xy 20.225523 -133.663373) (xy 20.202881 -133.613796)
			(xy 20.187526 -133.561501) (xy 20.17977 -133.507553) (xy 20.179284 -133.480302) (xy 2.509012 -133.480302)
			(xy 2.509012 -138.001502) (xy 20.019264 -138.001502) (xy 20.019264 -137.010902) (xy 20.01975 -136.983651)
			(xy 20.027506 -136.929703) (xy 20.042861 -136.877408) (xy 20.065503 -136.827831) (xy 20.094969 -136.781981)
			(xy 20.13066 -136.74079) (xy 20.171851 -136.705099) (xy 20.217701 -136.675633) (xy 20.267278 -136.652991)
			(xy 20.319573 -136.637636) (xy 20.373521 -136.62988) (xy 20.428023 -136.62988) (xy 20.481971 -136.637636)
			(xy 20.534266 -136.652991) (xy 20.583843 -136.675633) (xy 20.629693 -136.705099) (xy 20.670884 -136.74079)
			(xy 20.706575 -136.781981) (xy 20.736041 -136.827831) (xy 20.758683 -136.877408) (xy 20.774038 -136.929703)
			(xy 20.781794 -136.983651) (xy 20.78228 -137.010902) (xy 20.78228 -138.001502) (xy 20.781794 -138.028753)
			(xy 20.774038 -138.082701) (xy 20.758683 -138.134996) (xy 20.736041 -138.184573) (xy 20.706575 -138.230423)
			(xy 20.670884 -138.271614) (xy 20.629693 -138.307305) (xy 20.583843 -138.336771) (xy 20.534266 -138.359413)
			(xy 20.481971 -138.374768) (xy 20.428023 -138.382524) (xy 20.373521 -138.382524) (xy 20.319573 -138.374768)
			(xy 20.267278 -138.359413) (xy 20.217701 -138.336771) (xy 20.171851 -138.307305) (xy 20.13066 -138.271614)
			(xy 20.094969 -138.230423) (xy 20.065503 -138.184573) (xy 20.042861 -138.134996) (xy 20.027506 -138.082701)
			(xy 20.01975 -138.028753) (xy 20.019264 -138.001502) (xy 2.509012 -138.001502) (xy 2.509012 -145.104166)
			(xy 163.29995 -145.104166) (xy 163.29995 -145.049634) (xy 163.30771 -144.995658) (xy 163.323072 -144.943336)
			(xy 163.345724 -144.893732) (xy 163.375204 -144.847856) (xy 163.410912 -144.806643) (xy 163.452121 -144.77093)
			(xy 163.497993 -144.741445) (xy 163.547595 -144.718788) (xy 163.599915 -144.70342) (xy 163.653891 -144.695653)
			(xy 163.681156 -144.695164) (xy 164.671756 -144.695164) (xy 164.699031 -144.695573) (xy 164.753026 -144.70333)
			(xy 164.805368 -144.718694) (xy 164.85499 -144.74135) (xy 164.900882 -144.770839) (xy 164.94211 -144.806559)
			(xy 164.977835 -144.847783) (xy 165.007329 -144.893672) (xy 165.029991 -144.943291) (xy 165.045361 -144.995631)
			(xy 165.053124 -145.049625) (xy 165.053124 -145.104175) (xy 165.045361 -145.158169) (xy 165.029991 -145.210509)
			(xy 165.007329 -145.260128) (xy 164.977835 -145.306017) (xy 164.94211 -145.347241) (xy 164.900882 -145.382961)
			(xy 164.85499 -145.41245) (xy 164.805368 -145.435106) (xy 164.753026 -145.45047) (xy 164.699031 -145.458227)
			(xy 164.671756 -145.458688) (xy 163.681156 -145.458688) (xy 163.653891 -145.458147) (xy 163.599915 -145.45038)
			(xy 163.547595 -145.435012) (xy 163.497993 -145.412355) (xy 163.452121 -145.38287) (xy 163.410912 -145.347157)
			(xy 163.375204 -145.305944) (xy 163.345724 -145.260068) (xy 163.323072 -145.210464) (xy 163.30771 -145.158142)
			(xy 163.29995 -145.104166) (xy 2.509012 -145.104166) (xy 2.509012 -153.765504) (xy 24.441921 -153.765504)
			(xy 24.445917 -153.555618) (xy 24.457902 -153.346036) (xy 24.477856 -153.137062) (xy 24.505752 -152.929)
			(xy 24.541549 -152.72215) (xy 24.585194 -152.516813) (xy 24.636626 -152.313287) (xy 24.695768 -152.111866)
			(xy 24.762536 -151.912843) (xy 24.836832 -151.716506) (xy 24.91855 -151.52314) (xy 25.007569 -151.333025)
			(xy 25.103762 -151.146437) (xy 25.206989 -150.963646) (xy 25.3171 -150.784918) (xy 25.433935 -150.610511)
			(xy 25.557325 -150.440679) (xy 25.687092 -150.275667) (xy 25.823046 -150.115716) (xy 25.964992 -149.961056)
			(xy 26.112722 -149.811912) (xy 26.266024 -149.668501) (xy 26.424674 -149.53103) (xy 26.588443 -149.399698)
			(xy 26.757093 -149.274697) (xy 26.930379 -149.156206) (xy 27.108051 -149.044399) (xy 27.289851 -148.939437)
			(xy 27.475515 -148.841472) (xy 27.664773 -148.750647) (xy 27.857353 -148.667093) (xy 28.052974 -148.59093)
			(xy 28.251352 -148.522271) (xy 28.452201 -148.461214) (xy 28.655228 -148.407847) (xy 28.860141 -148.362249)
			(xy 29.06664 -148.324484) (xy 29.274427 -148.294609) (xy 29.483202 -148.272666) (xy 29.69266 -148.258687)
			(xy 29.902499 -148.252692) (xy 30.112413 -148.254691) (xy 30.3221 -148.264679) (xy 30.531254 -148.282644)
			(xy 30.739572 -148.308558) (xy 30.946753 -148.342383) (xy 31.152497 -148.384072) (xy 31.356503 -148.433564)
			(xy 31.558478 -148.490786) (xy 31.758128 -148.555656) (xy 31.955163 -148.62808) (xy 32.149299 -148.707953)
			(xy 32.340252 -148.795159) (xy 32.527748 -148.889571) (xy 32.711513 -148.991053) (xy 32.891281 -149.099457)
			(xy 33.066792 -149.214627) (xy 33.237791 -149.336395) (xy 33.404031 -149.464584) (xy 33.56527 -149.59901)
			(xy 33.721274 -149.739477) (xy 33.871817 -149.885781) (xy 34.016681 -150.03771) (xy 34.155656 -150.195044)
			(xy 34.288541 -150.357555) (xy 34.415142 -150.525008) (xy 34.535277 -150.697158) (xy 34.648771 -150.873758)
			(xy 34.688915 -150.941786) (xy 108.742233 -150.941786) (xy 108.746238 -150.836037) (xy 108.758228 -150.730894)
			(xy 108.778137 -150.626959) (xy 108.805848 -150.524827) (xy 108.841205 -150.425083) (xy 108.884003 -150.328299)
			(xy 108.933999 -150.235029) (xy 108.990906 -150.145808) (xy 109.054397 -150.061145) (xy 109.124109 -149.981527)
			(xy 109.199643 -149.907409) (xy 109.280566 -149.839216) (xy 109.366415 -149.777338) (xy 109.456698 -149.722131)
			(xy 109.550897 -149.673909) (xy 109.648474 -149.632949) (xy 109.748869 -149.599487) (xy 109.851507 -149.573713)
			(xy 109.9558 -149.555775) (xy 110.061151 -149.545776) (xy 110.166957 -149.543773) (xy 110.272611 -149.549778)
			(xy 110.377508 -149.563757) (xy 110.481048 -149.585628) (xy 110.582637 -149.615268) (xy 110.681694 -149.652506)
			(xy 110.777651 -149.697128) (xy 110.869958 -149.74888) (xy 110.958087 -149.807465) (xy 111.041533 -149.872547)
			(xy 111.119817 -149.943753) (xy 111.187365 -150.015249) (xy 160.856694 -150.015249) (xy 160.856694 -149.960751)
			(xy 160.86445 -149.906808) (xy 160.879803 -149.854517) (xy 160.902441 -149.804944) (xy 160.931904 -149.759096)
			(xy 160.967592 -149.717909) (xy 161.008777 -149.682219) (xy 161.054623 -149.652753) (xy 161.104195 -149.630111)
			(xy 161.156484 -149.614755) (xy 161.210427 -149.606996) (xy 161.237676 -149.606508) (xy 162.228276 -149.606508)
			(xy 162.255531 -149.606937) (xy 162.309487 -149.614692) (xy 162.36179 -149.630046) (xy 162.411375 -149.652688)
			(xy 162.457233 -149.682157) (xy 162.498431 -149.717852) (xy 162.534128 -149.759047) (xy 162.5636 -149.804904)
			(xy 162.586245 -149.854488) (xy 162.601603 -149.90679) (xy 162.609361 -149.960745) (xy 162.609361 -149.967557)
			(xy 163.793819 -149.967557) (xy 163.793819 -149.913043) (xy 163.801578 -149.859084) (xy 163.816937 -149.806779)
			(xy 163.839584 -149.757192) (xy 163.869057 -149.711333) (xy 163.904758 -149.670135) (xy 163.945958 -149.634438)
			(xy 163.99182 -149.604968) (xy 164.041409 -149.582325) (xy 164.093716 -149.566971) (xy 164.147675 -149.559217)
			(xy 164.174932 -149.558756) (xy 165.165532 -149.558756) (xy 165.192779 -149.559316) (xy 165.246718 -149.567076)
			(xy 165.299004 -149.582432) (xy 165.348573 -149.605073) (xy 165.394415 -149.634537) (xy 165.435597 -149.670226)
			(xy 165.471282 -149.711411) (xy 165.500742 -149.757255) (xy 165.523379 -149.806826) (xy 165.538731 -149.859113)
			(xy 165.546486 -149.913053) (xy 165.546486 -149.967547) (xy 165.538731 -150.021487) (xy 165.523379 -150.073774)
			(xy 165.500742 -150.123345) (xy 165.471282 -150.169189) (xy 165.435597 -150.210374) (xy 165.394415 -150.246063)
			(xy 165.348573 -150.275527) (xy 165.299004 -150.298168) (xy 165.246718 -150.313524) (xy 165.192779 -150.321284)
			(xy 165.165532 -150.321772) (xy 164.174932 -150.321772) (xy 164.147675 -150.321383) (xy 164.093716 -150.313629)
			(xy 164.041409 -150.298275) (xy 163.99182 -150.275632) (xy 163.945958 -150.246162) (xy 163.904758 -150.210465)
			(xy 163.869057 -150.169267) (xy 163.839584 -150.123408) (xy 163.816937 -150.073821) (xy 163.801578 -150.021516)
			(xy 163.793819 -149.967557) (xy 162.609361 -149.967557) (xy 162.609361 -150.015255) (xy 162.601603 -150.06921)
			(xy 162.586245 -150.121512) (xy 162.5636 -150.171096) (xy 162.534128 -150.216953) (xy 162.498431 -150.258148)
			(xy 162.457233 -150.293843) (xy 162.411375 -150.323312) (xy 162.36179 -150.345954) (xy 162.309487 -150.361308)
			(xy 162.255531 -150.369063) (xy 162.228276 -150.369524) (xy 161.237676 -150.369524) (xy 161.210427 -150.369004)
			(xy 161.156484 -150.361245) (xy 161.104195 -150.345889) (xy 161.054623 -150.323247) (xy 161.008777 -150.293781)
			(xy 160.967592 -150.258091) (xy 160.931904 -150.216904) (xy 160.902441 -150.171056) (xy 160.879803 -150.121483)
			(xy 160.86445 -150.069192) (xy 160.856694 -150.015249) (xy 111.187365 -150.015249) (xy 111.192492 -150.020676)
			(xy 111.259142 -150.102876) (xy 111.319384 -150.18988) (xy 111.372873 -150.281191) (xy 111.419304 -150.376286)
			(xy 111.458409 -150.47462) (xy 111.489966 -150.575631) (xy 111.513793 -150.678738) (xy 111.529754 -150.783352)
			(xy 111.537758 -150.888874) (xy 111.538258 -150.941786) (xy 111.537758 -150.994698) (xy 111.529754 -151.10022)
			(xy 111.513793 -151.204834) (xy 111.489966 -151.307941) (xy 111.458409 -151.408952) (xy 111.419304 -151.507286)
			(xy 111.372873 -151.602381) (xy 111.319384 -151.693692) (xy 111.259142 -151.780696) (xy 111.192492 -151.862896)
			(xy 111.119817 -151.939819) (xy 111.041533 -152.011025) (xy 110.958087 -152.076107) (xy 110.869958 -152.134692)
			(xy 110.777651 -152.186444) (xy 110.681694 -152.231066) (xy 110.582637 -152.268304) (xy 110.481048 -152.297944)
			(xy 110.377508 -152.319815) (xy 110.272611 -152.333794) (xy 110.166957 -152.339799) (xy 110.061151 -152.337796)
			(xy 109.9558 -152.327797) (xy 109.851507 -152.309859) (xy 109.748869 -152.284085) (xy 109.648474 -152.250623)
			(xy 109.550897 -152.209663) (xy 109.456698 -152.161441) (xy 109.366415 -152.106234) (xy 109.280566 -152.044356)
			(xy 109.199643 -151.976163) (xy 109.124109 -151.902045) (xy 109.054397 -151.822427) (xy 108.990906 -151.737764)
			(xy 108.933999 -151.648543) (xy 108.884003 -151.555273) (xy 108.841205 -151.458489) (xy 108.805848 -151.358745)
			(xy 108.778137 -151.256613) (xy 108.758228 -151.152678) (xy 108.746238 -151.047535) (xy 108.742233 -150.941786)
			(xy 34.688915 -150.941786) (xy 34.755459 -151.05455) (xy 34.855186 -151.239273) (xy 34.947809 -151.427659)
			(xy 35.033193 -151.619434) (xy 35.111214 -151.814321) (xy 35.181759 -152.012037) (xy 35.244726 -152.212295)
			(xy 35.300023 -152.414805) (xy 35.34757 -152.619274) (xy 35.354948 -152.657556) (xy 115.368832 -152.657556)
			(xy 115.369254 -152.619267) (xy 115.375857 -152.542973) (xy 115.389002 -152.46753) (xy 115.40859 -152.393499)
			(xy 115.421156 -152.357328) (xy 115.423829 -152.348897) (xy 115.423815 -152.331221) (xy 115.421156 -152.322784)
			(xy 115.408624 -152.286603) (xy 115.389048 -152.212571) (xy 115.375898 -152.137132) (xy 115.36927 -152.060844)
			(xy 115.368832 -152.022556) (xy 115.369211 -151.981443) (xy 115.376803 -151.89957) (xy 115.391918 -151.818746)
			(xy 115.414428 -151.739662) (xy 115.44414 -151.662993) (xy 115.480801 -151.589393) (xy 115.524097 -151.51949)
			(xy 115.573659 -151.453881) (xy 115.629065 -151.393126) (xy 115.689841 -151.337743) (xy 115.755469 -151.288206)
			(xy 115.825388 -151.244936) (xy 115.899002 -151.208303) (xy 115.975683 -151.178621) (xy 116.054775 -151.156141)
			(xy 116.135605 -151.141056) (xy 116.217481 -151.133495) (xy 116.258594 -151.133048) (xy 116.29691 -151.133415)
			(xy 116.373264 -151.139947) (xy 116.448771 -151.153032) (xy 116.52287 -151.172572) (xy 116.559076 -151.185118)
			(xy 116.567392 -151.187704) (xy 116.584796 -151.187704) (xy 116.593112 -151.185118) (xy 116.629327 -151.172602)
			(xy 116.703427 -151.153078) (xy 116.778931 -151.139993) (xy 116.855279 -151.133443) (xy 116.893594 -151.133048)
			(xy 116.933808 -151.133478) (xy 117.01391 -151.140701) (xy 117.093031 -151.155132) (xy 117.170525 -151.176654)
			(xy 117.2083 -151.190452) (xy 117.217087 -151.193359) (xy 117.235581 -151.193359) (xy 117.244368 -151.190452)
			(xy 117.282145 -151.176662) (xy 117.359642 -151.155155) (xy 117.438762 -151.140723) (xy 117.518861 -151.133486)
			(xy 117.559074 -151.133048) (xy 117.59739 -151.133421) (xy 117.673744 -151.139951) (xy 117.74925 -151.153034)
			(xy 117.82335 -151.172573) (xy 117.859556 -151.185118) (xy 117.867872 -151.187704) (xy 117.885276 -151.187704)
			(xy 117.893592 -151.185118) (xy 117.929809 -151.172608) (xy 118.003908 -151.153082) (xy 118.079411 -151.139995)
			(xy 118.155759 -151.133444) (xy 118.194074 -151.133048) (xy 118.23239 -151.133421) (xy 118.308744 -151.139951)
			(xy 118.38425 -151.153034) (xy 118.45835 -151.172573) (xy 118.494556 -151.185118) (xy 118.502872 -151.187704)
			(xy 118.520276 -151.187704) (xy 118.528592 -151.185118) (xy 118.564809 -151.172608) (xy 118.638908 -151.153082)
			(xy 118.714411 -151.139995) (xy 118.790759 -151.133444) (xy 118.829074 -151.133048) (xy 118.86739 -151.133421)
			(xy 118.943744 -151.139951) (xy 119.01925 -151.153034) (xy 119.09335 -151.172573) (xy 119.129556 -151.185118)
			(xy 119.137872 -151.187704) (xy 119.155276 -151.187704) (xy 119.163592 -151.185118) (xy 119.199718 -151.172636)
			(xy 119.273629 -151.153143) (xy 119.348939 -151.140056) (xy 119.425093 -151.133472) (xy 119.463312 -151.133048)
			(xy 119.464074 -151.133048) (xy 119.505181 -151.133537) (xy 119.587043 -151.141119) (xy 119.667858 -151.156221)
			(xy 119.746934 -151.178714) (xy 119.823598 -151.208407) (xy 119.897196 -151.245045) (xy 119.9671 -151.288316)
			(xy 120.032714 -151.337852) (xy 120.093479 -151.39323) (xy 120.148875 -151.453978) (xy 120.198431 -151.519577)
			(xy 120.241724 -151.589468) (xy 120.278384 -151.663055) (xy 120.3081 -151.73971) (xy 120.330617 -151.818779)
			(xy 120.345743 -151.899589) (xy 120.35335 -151.98145) (xy 120.353836 -152.022556) (xy 120.353419 -152.060846)
			(xy 120.346814 -152.137139) (xy 120.333668 -152.212582) (xy 120.314078 -152.286613) (xy 120.301512 -152.322784)
			(xy 120.298884 -152.331226) (xy 120.29887 -152.348891) (xy 120.301512 -152.357328) (xy 120.314046 -152.393509)
			(xy 120.333622 -152.467541) (xy 120.346772 -152.542979) (xy 120.353399 -152.619268) (xy 120.353836 -152.657556)
			(xy 120.353306 -152.698665) (xy 120.345722 -152.780533) (xy 120.330616 -152.861351) (xy 120.308115 -152.940431)
			(xy 120.278413 -153.017096) (xy 120.241762 -153.090693) (xy 120.198476 -153.160594) (xy 120.148923 -153.226202)
			(xy 120.093528 -153.286957) (xy 120.032762 -153.34234) (xy 119.967144 -153.391879) (xy 119.897234 -153.435151)
			(xy 119.823629 -153.471786) (xy 119.746958 -153.501473) (xy 119.667874 -153.523957) (xy 119.587052 -153.539047)
			(xy 119.505183 -153.546614) (xy 119.464074 -153.547064) (xy 119.425757 -153.546706) (xy 119.349404 -153.540171)
			(xy 119.273897 -153.527084) (xy 119.199798 -153.507541) (xy 119.163592 -153.494994) (xy 119.155276 -153.492408)
			(xy 119.137872 -153.492408) (xy 119.129556 -153.494994) (xy 119.093344 -153.507519) (xy 119.019243 -153.527041)
			(xy 118.943738 -153.540123) (xy 118.867389 -153.546671) (xy 118.829074 -153.547064) (xy 118.790757 -153.546706)
			(xy 118.714404 -153.540171) (xy 118.638897 -153.527084) (xy 118.564798 -153.507541) (xy 118.528592 -153.494994)
			(xy 118.520276 -153.492408) (xy 118.502872 -153.492408) (xy 118.494556 -153.494994) (xy 118.458344 -153.507519)
			(xy 118.384243 -153.527041) (xy 118.308738 -153.540123) (xy 118.232389 -153.546671) (xy 118.194074 -153.547064)
			(xy 118.155757 -153.546706) (xy 118.079404 -153.540171) (xy 118.003897 -153.527084) (xy 117.929798 -153.507541)
			(xy 117.893592 -153.494994) (xy 117.885276 -153.492408) (xy 117.867872 -153.492408) (xy 117.859556 -153.494994)
			(xy 117.823344 -153.507519) (xy 117.749243 -153.527041) (xy 117.673738 -153.540123) (xy 117.597389 -153.546671)
			(xy 117.559074 -153.547064) (xy 117.51886 -153.546643) (xy 117.438758 -153.539418) (xy 117.359636 -153.524984)
			(xy 117.282143 -153.50346) (xy 117.244368 -153.48966) (xy 117.235581 -153.486753) (xy 117.217087 -153.486753)
			(xy 117.2083 -153.48966) (xy 117.170526 -153.50346) (xy 117.093029 -153.524965) (xy 117.013907 -153.539393)
			(xy 116.933807 -153.546627) (xy 116.893594 -153.547064) (xy 116.855277 -153.5467) (xy 116.778924 -153.540167)
			(xy 116.703417 -153.527082) (xy 116.629318 -153.50754) (xy 116.593112 -153.494994) (xy 116.584796 -153.492408)
			(xy 116.567392 -153.492408) (xy 116.559076 -153.494994) (xy 116.522953 -153.507485) (xy 116.449041 -153.526976)
			(xy 116.37373 -153.54006) (xy 116.297575 -153.546641) (xy 116.259356 -153.547064) (xy 116.258594 -153.547064)
			(xy 116.217487 -153.546593) (xy 116.135624 -153.539008) (xy 116.05481 -153.523904) (xy 115.975734 -153.501409)
			(xy 115.89907 -153.471714) (xy 115.825473 -153.435075) (xy 115.755569 -153.391802) (xy 115.689955 -153.342264)
			(xy 115.629192 -153.286885) (xy 115.573796 -153.226137) (xy 115.52424 -153.160537) (xy 115.480947 -153.090646)
			(xy 115.444287 -153.017059) (xy 115.414571 -152.940403) (xy 115.392053 -152.861333) (xy 115.376926 -152.780524)
			(xy 115.369318 -152.698663) (xy 115.368832 -152.657556) (xy 35.354948 -152.657556) (xy 35.387298 -152.825405)
			(xy 35.41915 -153.032898) (xy 35.44308 -153.241454) (xy 35.459052 -153.45077) (xy 35.467044 -153.660542)
			(xy 35.467544 -153.765504) (xy 35.467044 -153.870466) (xy 35.459052 -154.080238) (xy 35.44308 -154.289554)
			(xy 35.422918 -154.465274) (xy 127.823468 -154.465274) (xy 127.824038 -154.420505) (xy 127.833047 -154.33142)
			(xy 127.850949 -154.243689) (xy 127.877566 -154.158197) (xy 127.894588 -154.116786) (xy 127.89817 -154.1072)
			(xy 127.89816 -154.086753) (xy 127.894588 -154.077162) (xy 127.87754 -154.03576) (xy 127.850909 -153.95027)
			(xy 127.833008 -153.862535) (xy 127.824018 -153.773445) (xy 127.823468 -153.728674) (xy 127.824038 -153.683905)
			(xy 127.833047 -153.59482) (xy 127.850949 -153.507089) (xy 127.877566 -153.421597) (xy 127.894588 -153.380186)
			(xy 127.89817 -153.3706) (xy 127.89816 -153.350153) (xy 127.894588 -153.340562) (xy 127.87754 -153.29916)
			(xy 127.850909 -153.21367) (xy 127.833008 -153.125935) (xy 127.824018 -153.036845) (xy 127.823468 -152.992074)
			(xy 127.823874 -152.950958) (xy 127.831464 -152.869076) (xy 127.846576 -152.788245) (xy 127.869082 -152.709152)
			(xy 127.898791 -152.632473) (xy 127.935447 -152.558863) (xy 127.978739 -152.488949) (xy 128.028297 -152.423328)
			(xy 128.083699 -152.362559) (xy 128.144471 -152.307161) (xy 128.210095 -152.257607) (xy 128.280012 -152.21432)
			(xy 128.353625 -152.177668) (xy 128.430305 -152.147965) (xy 128.509399 -152.125463) (xy 128.590232 -152.110356)
			(xy 128.672114 -152.102771) (xy 128.71323 -152.102312) (xy 128.754841 -152.102773) (xy 128.837698 -152.110553)
			(xy 128.919467 -152.126031) (xy 128.999435 -152.149074) (xy 129.076903 -152.179479) (xy 129.151195 -152.216982)
			(xy 129.186686 -152.23871) (xy 129.195829 -152.243863) (xy 129.216542 -152.24708) (xy 129.236814 -152.241752)
			(xy 129.24536 -152.235662) (xy 129.278989 -152.209671) (xy 129.350383 -152.163546) (xy 129.425854 -152.124445)
			(xy 129.504712 -152.092724) (xy 129.586237 -152.068675) (xy 129.669685 -152.052515) (xy 129.754295 -152.044393)
			(xy 129.796794 -152.043892) (xy 129.837907 -152.044419) (xy 129.919782 -152.052005) (xy 130.000607 -152.067113)
			(xy 130.079694 -152.089613) (xy 130.156368 -152.119315) (xy 130.229974 -152.155965) (xy 130.299884 -152.19925)
			(xy 130.365503 -152.2488) (xy 130.42627 -152.304193) (xy 130.481667 -152.364957) (xy 130.531221 -152.430573)
			(xy 130.57451 -152.500481) (xy 130.611164 -152.574085) (xy 130.64087 -152.650756) (xy 130.663376 -152.729842)
			(xy 130.678488 -152.810667) (xy 130.686079 -152.892541) (xy 130.686556 -152.933654) (xy 130.685993 -152.978424)
			(xy 130.676983 -153.067509) (xy 130.659077 -153.15524) (xy 130.632459 -153.240731) (xy 130.615436 -153.282142)
			(xy 130.611899 -153.291741) (xy 130.611882 -153.312176) (xy 130.615436 -153.321766) (xy 130.63244 -153.363117)
			(xy 130.659051 -153.448479) (xy 130.676958 -153.536082) (xy 130.68598 -153.625039) (xy 130.686556 -153.669746)
			(xy 130.686556 -153.670762) (xy 130.686302 -153.682192) (xy 130.712781 -153.688138) (xy 130.765016 -153.702881)
			(xy 130.790696 -153.711656) (xy 130.798893 -153.71417) (xy 130.816027 -153.71417) (xy 130.824224 -153.711656)
			(xy 130.85944 -153.699695) (xy 130.931444 -153.681041) (xy 131.004765 -153.668532) (xy 131.07888 -153.662259)
			(xy 131.11607 -153.661872) (xy 131.153259 -153.662271) (xy 131.227372 -153.668558) (xy 131.300692 -153.681065)
			(xy 131.372698 -153.699703) (xy 131.407916 -153.711656) (xy 131.416113 -153.71417) (xy 131.433247 -153.71417)
			(xy 131.441444 -153.711656) (xy 131.476659 -153.699689) (xy 131.548662 -153.681037) (xy 131.621984 -153.66853)
			(xy 131.6961 -153.662258) (xy 131.73329 -153.661872) (xy 131.77523 -153.662267) (xy 131.858732 -153.670239)
			(xy 131.941097 -153.686113) (xy 132.02158 -153.709744) (xy 132.099453 -153.740919) (xy 132.165372 -153.774902)
			(xy 188.441847 -153.774902) (xy 188.445843 -153.565016) (xy 188.457828 -153.355434) (xy 188.477782 -153.14646)
			(xy 188.505678 -152.938398) (xy 188.541475 -152.731548) (xy 188.58512 -152.526211) (xy 188.636552 -152.322685)
			(xy 188.695694 -152.121264) (xy 188.762462 -151.922241) (xy 188.836758 -151.725904) (xy 188.918476 -151.532538)
			(xy 189.007495 -151.342423) (xy 189.103688 -151.155835) (xy 189.206915 -150.973044) (xy 189.317026 -150.794316)
			(xy 189.433861 -150.619909) (xy 189.557251 -150.450077) (xy 189.687018 -150.285065) (xy 189.822972 -150.125114)
			(xy 189.964918 -149.970454) (xy 190.112648 -149.82131) (xy 190.26595 -149.677899) (xy 190.4246 -149.540428)
			(xy 190.588369 -149.409096) (xy 190.757019 -149.284095) (xy 190.930305 -149.165604) (xy 191.107977 -149.053797)
			(xy 191.289777 -148.948835) (xy 191.475441 -148.85087) (xy 191.664699 -148.760045) (xy 191.857279 -148.676491)
			(xy 192.0529 -148.600328) (xy 192.251278 -148.531669) (xy 192.452127 -148.470612) (xy 192.655154 -148.417245)
			(xy 192.860067 -148.371647) (xy 193.066566 -148.333882) (xy 193.274353 -148.304007) (xy 193.483128 -148.282064)
			(xy 193.692586 -148.268085) (xy 193.902425 -148.26209) (xy 194.112339 -148.264089) (xy 194.322026 -148.274077)
			(xy 194.53118 -148.292042) (xy 194.739498 -148.317956) (xy 194.946679 -148.351781) (xy 195.152423 -148.39347)
			(xy 195.356429 -148.442962) (xy 195.558404 -148.500184) (xy 195.758054 -148.565054) (xy 195.955089 -148.637478)
			(xy 196.149225 -148.717351) (xy 196.340178 -148.804557) (xy 196.527674 -148.898969) (xy 196.711439 -149.000451)
			(xy 196.891207 -149.108855) (xy 197.066718 -149.224025) (xy 197.237717 -149.345793) (xy 197.403957 -149.473982)
			(xy 197.565196 -149.608408) (xy 197.7212 -149.748875) (xy 197.871743 -149.895179) (xy 198.016607 -150.047108)
			(xy 198.155582 -150.204442) (xy 198.288467 -150.366953) (xy 198.415068 -150.534406) (xy 198.535203 -150.706556)
			(xy 198.648697 -150.883156) (xy 198.755385 -151.063948) (xy 198.855112 -151.248671) (xy 198.947735 -151.437057)
			(xy 199.033119 -151.628832) (xy 199.11114 -151.823719) (xy 199.181685 -152.021435) (xy 199.244652 -152.221693)
			(xy 199.299949 -152.424203) (xy 199.347496 -152.628672) (xy 199.387224 -152.834803) (xy 199.419076 -153.042296)
			(xy 199.443006 -153.250852) (xy 199.458978 -153.460168) (xy 199.46697 -153.66994) (xy 199.467428 -153.766012)
			(xy 272.382243 -153.766012) (xy 272.386239 -153.556126) (xy 272.398224 -153.346544) (xy 272.418178 -153.13757)
			(xy 272.446074 -152.929508) (xy 272.481871 -152.722658) (xy 272.525516 -152.517321) (xy 272.576948 -152.313795)
			(xy 272.63609 -152.112374) (xy 272.702858 -151.913351) (xy 272.777154 -151.717014) (xy 272.858872 -151.523648)
			(xy 272.947891 -151.333533) (xy 273.044084 -151.146945) (xy 273.147311 -150.964154) (xy 273.257422 -150.785426)
			(xy 273.374257 -150.611019) (xy 273.497647 -150.441187) (xy 273.627414 -150.276175) (xy 273.763368 -150.116224)
			(xy 273.905314 -149.961564) (xy 274.053044 -149.81242) (xy 274.206346 -149.669009) (xy 274.364996 -149.531538)
			(xy 274.528765 -149.400206) (xy 274.697415 -149.275205) (xy 274.870701 -149.156714) (xy 275.048373 -149.044907)
			(xy 275.230173 -148.939945) (xy 275.415837 -148.84198) (xy 275.605095 -148.751155) (xy 275.797675 -148.667601)
			(xy 275.993296 -148.591438) (xy 276.191674 -148.522779) (xy 276.392523 -148.461722) (xy 276.59555 -148.408355)
			(xy 276.800463 -148.362757) (xy 277.006962 -148.324992) (xy 277.214749 -148.295117) (xy 277.423524 -148.273174)
			(xy 277.632982 -148.259195) (xy 277.842821 -148.2532) (xy 278.052735 -148.255199) (xy 278.262422 -148.265187)
			(xy 278.471576 -148.283152) (xy 278.679894 -148.309066) (xy 278.887075 -148.342891) (xy 279.092819 -148.38458)
			(xy 279.296825 -148.434072) (xy 279.4988 -148.491294) (xy 279.69845 -148.556164) (xy 279.895485 -148.628588)
			(xy 280.089621 -148.708461) (xy 280.280574 -148.795667) (xy 280.46807 -148.890079) (xy 280.651835 -148.991561)
			(xy 280.831603 -149.099965) (xy 281.007114 -149.215135) (xy 281.178113 -149.336903) (xy 281.344353 -149.465092)
			(xy 281.505592 -149.599518) (xy 281.661596 -149.739985) (xy 281.812139 -149.886289) (xy 281.957003 -150.038218)
			(xy 282.095978 -150.195552) (xy 282.228863 -150.358063) (xy 282.355464 -150.525516) (xy 282.475599 -150.697666)
			(xy 282.589093 -150.874266) (xy 282.695781 -151.055058) (xy 282.795508 -151.239781) (xy 282.888131 -151.428167)
			(xy 282.973515 -151.619942) (xy 283.051536 -151.814829) (xy 283.122081 -152.012545) (xy 283.185048 -152.212803)
			(xy 283.240345 -152.415313) (xy 283.287892 -152.619782) (xy 283.305746 -152.71242) (xy 358.186997 -152.71242)
			(xy 358.191002 -152.606671) (xy 358.202992 -152.501528) (xy 358.222901 -152.397593) (xy 358.250612 -152.295461)
			(xy 358.285969 -152.195717) (xy 358.328767 -152.098933) (xy 358.378763 -152.005663) (xy 358.43567 -151.916442)
			(xy 358.499161 -151.831779) (xy 358.568873 -151.752161) (xy 358.644407 -151.678043) (xy 358.72533 -151.60985)
			(xy 358.811179 -151.547972) (xy 358.901462 -151.492765) (xy 358.995661 -151.444543) (xy 359.093238 -151.403583)
			(xy 359.193633 -151.370121) (xy 359.296271 -151.344347) (xy 359.400564 -151.326409) (xy 359.505915 -151.31641)
			(xy 359.611721 -151.314407) (xy 359.717375 -151.320412) (xy 359.822272 -151.334391) (xy 359.925812 -151.356262)
			(xy 360.027401 -151.385902) (xy 360.126458 -151.42314) (xy 360.222415 -151.467762) (xy 360.314722 -151.519514)
			(xy 360.402851 -151.578099) (xy 360.486297 -151.643181) (xy 360.564581 -151.714387) (xy 360.637256 -151.79131)
			(xy 360.703906 -151.87351) (xy 360.764148 -151.960514) (xy 360.817637 -152.051825) (xy 360.864068 -152.14692)
			(xy 360.903173 -152.245254) (xy 360.93473 -152.346265) (xy 360.958557 -152.449372) (xy 360.974518 -152.553986)
			(xy 360.982522 -152.659508) (xy 360.983022 -152.71242) (xy 360.982522 -152.765332) (xy 360.974518 -152.870854)
			(xy 360.958557 -152.975468) (xy 360.93473 -153.078575) (xy 360.903173 -153.179586) (xy 360.864068 -153.27792)
			(xy 360.817637 -153.373015) (xy 360.764148 -153.464326) (xy 360.703906 -153.55133) (xy 360.637256 -153.63353)
			(xy 360.564581 -153.710453) (xy 360.486297 -153.781659) (xy 360.402851 -153.846741) (xy 360.314722 -153.905326)
			(xy 360.222415 -153.957078) (xy 360.126458 -154.0017) (xy 360.027401 -154.038938) (xy 359.925812 -154.068578)
			(xy 359.822272 -154.090449) (xy 359.717375 -154.104428) (xy 359.611721 -154.110433) (xy 359.505915 -154.10843)
			(xy 359.400564 -154.098431) (xy 359.296271 -154.080493) (xy 359.193633 -154.054719) (xy 359.093238 -154.021257)
			(xy 358.995661 -153.980297) (xy 358.901462 -153.932075) (xy 358.811179 -153.876868) (xy 358.72533 -153.81499)
			(xy 358.644407 -153.746797) (xy 358.568873 -153.672679) (xy 358.499161 -153.593061) (xy 358.43567 -153.508398)
			(xy 358.378763 -153.419177) (xy 358.328767 -153.325907) (xy 358.285969 -153.229123) (xy 358.250612 -153.129379)
			(xy 358.222901 -153.027247) (xy 358.202992 -152.923312) (xy 358.191002 -152.818169) (xy 358.186997 -152.71242)
			(xy 283.305746 -152.71242) (xy 283.32762 -152.825913) (xy 283.359472 -153.033406) (xy 283.383402 -153.241962)
			(xy 283.399374 -153.451278) (xy 283.407366 -153.66105) (xy 283.407866 -153.766012) (xy 283.407366 -153.870974)
			(xy 283.399374 -154.080746) (xy 283.383402 -154.290062) (xy 283.359472 -154.498618) (xy 283.32762 -154.706111)
			(xy 283.287892 -154.912242) (xy 283.240345 -155.116711) (xy 283.185048 -155.319221) (xy 283.122081 -155.519479)
			(xy 283.051536 -155.717195) (xy 282.973515 -155.912082) (xy 282.888131 -156.103857) (xy 282.795508 -156.292243)
			(xy 282.695781 -156.476966) (xy 282.589093 -156.657758) (xy 282.475599 -156.834358) (xy 282.355464 -157.006508)
			(xy 282.228863 -157.173961) (xy 282.095978 -157.336472) (xy 281.957003 -157.493806) (xy 281.812139 -157.645735)
			(xy 281.661596 -157.792039) (xy 281.505592 -157.932506) (xy 281.344353 -158.066932) (xy 281.178113 -158.195121)
			(xy 281.007114 -158.316889) (xy 280.831603 -158.432059) (xy 280.651835 -158.540463) (xy 280.46807 -158.641945)
			(xy 280.280574 -158.736357) (xy 280.089621 -158.823563) (xy 279.895485 -158.903436) (xy 279.69845 -158.97586)
			(xy 279.4988 -159.04073) (xy 279.382794 -159.073596) (xy 343.127076 -159.073596) (xy 343.127653 -159.028827)
			(xy 343.136659 -158.939742) (xy 343.15456 -158.852011) (xy 343.181175 -158.766519) (xy 343.198196 -158.725108)
			(xy 343.201765 -158.715518) (xy 343.201764 -158.695074) (xy 343.198196 -158.685484) (xy 343.181156 -158.644079)
			(xy 343.154522 -158.55859) (xy 343.136619 -158.470856) (xy 343.127627 -158.381767) (xy 343.127076 -158.336996)
			(xy 343.127653 -158.292227) (xy 343.136659 -158.203142) (xy 343.15456 -158.115411) (xy 343.181175 -158.029919)
			(xy 343.198196 -157.988508) (xy 343.201765 -157.978918) (xy 343.201764 -157.958474) (xy 343.198196 -157.948884)
			(xy 343.181156 -157.907479) (xy 343.154522 -157.82199) (xy 343.136619 -157.734256) (xy 343.127627 -157.645167)
			(xy 343.127076 -157.600396) (xy 343.127549 -157.559286) (xy 343.135137 -157.477416) (xy 343.150247 -157.396596)
			(xy 343.172752 -157.317516) (xy 343.202459 -157.240849) (xy 343.239114 -157.167252) (xy 343.282404 -157.097351)
			(xy 343.33196 -157.031743) (xy 343.387359 -156.970988) (xy 343.448129 -156.915605) (xy 343.51375 -156.866067)
			(xy 343.583663 -156.822796) (xy 343.657271 -156.786161) (xy 343.733945 -156.756475) (xy 343.813032 -156.733992)
			(xy 343.893856 -156.718903) (xy 343.975728 -156.711337) (xy 344.016838 -156.710888) (xy 344.058442 -156.711362)
			(xy 344.14129 -156.719094) (xy 344.223055 -156.734524) (xy 344.303022 -156.757517) (xy 344.380495 -156.787874)
			(xy 344.454797 -156.825328) (xy 344.490294 -156.847032) (xy 344.499434 -156.852189) (xy 344.520149 -156.855402)
			(xy 344.540422 -156.850073) (xy 344.548968 -156.843984) (xy 344.582592 -156.818029) (xy 344.653971 -156.771973)
			(xy 344.729414 -156.73293) (xy 344.808235 -156.701255) (xy 344.889716 -156.677237) (xy 344.973116 -156.661094)
			(xy 345.057674 -156.652974) (xy 345.100148 -156.652468) (xy 345.100402 -156.652468) (xy 345.14151 -156.652911)
			(xy 345.223374 -156.660496) (xy 345.30419 -156.6756) (xy 345.383268 -156.698096) (xy 345.459933 -156.727791)
			(xy 345.533532 -156.764433) (xy 345.603437 -156.807707) (xy 345.669051 -156.857246) (xy 345.729816 -156.912627)
			(xy 345.785212 -156.973378) (xy 345.806812 -157.001972) (xy 386.403596 -157.001972) (xy 386.40399 -156.963682)
			(xy 386.410601 -156.887387) (xy 386.423753 -156.811945) (xy 386.44335 -156.737915) (xy 386.45592 -156.701744)
			(xy 386.458586 -156.693311) (xy 386.458577 -156.675637) (xy 386.45592 -156.6672) (xy 386.443367 -156.631026)
			(xy 386.423796 -156.556991) (xy 386.410652 -156.481551) (xy 386.40403 -156.40526) (xy 386.403596 -156.366972)
			(xy 386.404015 -156.328179) (xy 386.410791 -156.25089) (xy 386.424264 -156.174482) (xy 386.44433 -156.099536)
			(xy 386.45719 -156.062934) (xy 386.459858 -156.054502) (xy 386.459846 -156.036827) (xy 386.45719 -156.02839)
			(xy 386.444324 -155.991789) (xy 386.424239 -155.916847) (xy 386.410766 -155.840438) (xy 386.404005 -155.763146)
			(xy 386.403596 -155.724352) (xy 386.404014 -155.686062) (xy 386.410618 -155.609769) (xy 386.423763 -155.534326)
			(xy 386.443354 -155.460295) (xy 386.45592 -155.424124) (xy 386.458596 -155.415693) (xy 386.45858 -155.398017)
			(xy 386.45592 -155.38958) (xy 386.443389 -155.353398) (xy 386.423812 -155.279367) (xy 386.410662 -155.203928)
			(xy 386.404034 -155.12764) (xy 386.403596 -155.089352) (xy 386.40407 -155.049438) (xy 386.411294 -154.969935)
			(xy 386.425601 -154.891398) (xy 386.446874 -154.814455) (xy 386.460492 -154.776932) (xy 386.463345 -154.768269)
			(xy 386.463329 -154.750041) (xy 386.460492 -154.741372) (xy 386.44684 -154.70386) (xy 386.425547 -154.626919)
			(xy 386.411244 -154.548377) (xy 386.404048 -154.468869) (xy 386.403596 -154.428952) (xy 386.404014 -154.390662)
			(xy 386.410618 -154.314369) (xy 386.423763 -154.238926) (xy 386.443354 -154.164895) (xy 386.45592 -154.128724)
			(xy 386.458596 -154.120293) (xy 386.45858 -154.102617) (xy 386.45592 -154.09418) (xy 386.443389 -154.057998)
			(xy 386.423812 -153.983967) (xy 386.410662 -153.908528) (xy 386.404034 -153.83224) (xy 386.403596 -153.793952)
			(xy 386.404007 -153.75284) (xy 386.411599 -153.670969) (xy 386.426714 -153.590147) (xy 386.449223 -153.511065)
			(xy 386.478934 -153.434397) (xy 386.515593 -153.360799) (xy 386.558887 -153.290897) (xy 386.608448 -153.225289)
			(xy 386.663851 -153.164535) (xy 386.724625 -153.109152) (xy 386.79025 -153.059614) (xy 386.860166 -153.016344)
			(xy 386.933777 -152.97971) (xy 387.010455 -152.950026) (xy 387.089545 -152.927544) (xy 387.170372 -152.912457)
			(xy 387.252246 -152.904893) (xy 387.293358 -152.904444) (xy 387.331674 -152.904822) (xy 387.408027 -152.91135)
			(xy 387.483534 -152.924432) (xy 387.557634 -152.94397) (xy 387.59384 -152.956514) (xy 387.602156 -152.9591)
			(xy 387.61956 -152.9591) (xy 387.627876 -152.956514) (xy 387.663994 -152.944008) (xy 387.737908 -152.924522)
			(xy 387.81322 -152.911442) (xy 387.889376 -152.904865) (xy 387.927596 -152.904444) (xy 387.928358 -152.904444)
			(xy 387.969464 -152.904953) (xy 388.051326 -152.912533) (xy 388.13214 -152.927634) (xy 388.211216 -152.950125)
			(xy 388.28788 -152.979816) (xy 388.361478 -153.016453) (xy 388.431382 -153.059723) (xy 388.496996 -153.109258)
			(xy 388.55776 -153.164634) (xy 388.613157 -153.225381) (xy 388.662713 -153.290979) (xy 388.706006 -153.360869)
			(xy 388.742667 -153.434454) (xy 388.772383 -153.511109) (xy 388.7949 -153.590177) (xy 388.810027 -153.670986)
			(xy 388.817634 -153.752846) (xy 388.817889 -153.774394) (xy 436.382169 -153.774394) (xy 436.386165 -153.564508)
			(xy 436.39815 -153.354926) (xy 436.418104 -153.145952) (xy 436.446 -152.93789) (xy 436.481797 -152.73104)
			(xy 436.525442 -152.525703) (xy 436.576874 -152.322177) (xy 436.636016 -152.120756) (xy 436.702784 -151.921733)
			(xy 436.77708 -151.725396) (xy 436.858798 -151.53203) (xy 436.947817 -151.341915) (xy 437.04401 -151.155327)
			(xy 437.147237 -150.972536) (xy 437.257348 -150.793808) (xy 437.374183 -150.619401) (xy 437.497573 -150.449569)
			(xy 437.62734 -150.284557) (xy 437.763294 -150.124606) (xy 437.90524 -149.969946) (xy 438.05297 -149.820802)
			(xy 438.206272 -149.677391) (xy 438.364922 -149.53992) (xy 438.528691 -149.408588) (xy 438.697341 -149.283587)
			(xy 438.870627 -149.165096) (xy 439.048299 -149.053289) (xy 439.230099 -148.948327) (xy 439.415763 -148.850362)
			(xy 439.605021 -148.759537) (xy 439.797601 -148.675983) (xy 439.993222 -148.59982) (xy 440.1916 -148.531161)
			(xy 440.392449 -148.470104) (xy 440.595476 -148.416737) (xy 440.800389 -148.371139) (xy 441.006888 -148.333374)
			(xy 441.214675 -148.303499) (xy 441.42345 -148.281556) (xy 441.632908 -148.267577) (xy 441.842747 -148.261582)
			(xy 442.052661 -148.263581) (xy 442.262348 -148.273569) (xy 442.471502 -148.291534) (xy 442.67982 -148.317448)
			(xy 442.887001 -148.351273) (xy 443.092745 -148.392962) (xy 443.296751 -148.442454) (xy 443.498726 -148.499676)
			(xy 443.698376 -148.564546) (xy 443.895411 -148.63697) (xy 444.089547 -148.716843) (xy 444.2805 -148.804049)
			(xy 444.467996 -148.898461) (xy 444.651761 -148.999943) (xy 444.831529 -149.108347) (xy 445.00704 -149.223517)
			(xy 445.178039 -149.345285) (xy 445.344279 -149.473474) (xy 445.505518 -149.6079) (xy 445.661522 -149.748367)
			(xy 445.812065 -149.894671) (xy 445.956929 -150.0466) (xy 446.095904 -150.203934) (xy 446.228789 -150.366445)
			(xy 446.35539 -150.533898) (xy 446.475525 -150.706048) (xy 446.589019 -150.882648) (xy 446.695707 -151.06344)
			(xy 446.795434 -151.248163) (xy 446.888057 -151.436549) (xy 446.973441 -151.628324) (xy 447.051462 -151.823211)
			(xy 447.122007 -152.020927) (xy 447.184974 -152.221185) (xy 447.240271 -152.423695) (xy 447.287818 -152.628164)
			(xy 447.327546 -152.834295) (xy 447.359398 -153.041788) (xy 447.383328 -153.250344) (xy 447.3993 -153.45966)
			(xy 447.407292 -153.669432) (xy 447.407792 -153.774394) (xy 447.407292 -153.879356) (xy 447.3993 -154.089128)
			(xy 447.383328 -154.298444) (xy 447.359398 -154.507) (xy 447.327546 -154.714493) (xy 447.287818 -154.920624)
			(xy 447.240271 -155.125093) (xy 447.184974 -155.327603) (xy 447.122007 -155.527861) (xy 447.051462 -155.725577)
			(xy 446.973441 -155.920464) (xy 446.888057 -156.112239) (xy 446.795434 -156.300625) (xy 446.695707 -156.485348)
			(xy 446.589019 -156.66614) (xy 446.475525 -156.84274) (xy 446.35539 -157.01489) (xy 446.228789 -157.182343)
			(xy 446.095904 -157.344854) (xy 445.956929 -157.502188) (xy 445.812065 -157.654117) (xy 445.661522 -157.800421)
			(xy 445.505518 -157.940888) (xy 445.344279 -158.075314) (xy 445.178039 -158.203503) (xy 445.00704 -158.325271)
			(xy 444.831529 -158.440441) (xy 444.651761 -158.548845) (xy 444.467996 -158.650327) (xy 444.2805 -158.744739)
			(xy 444.089547 -158.831945) (xy 443.895411 -158.911818) (xy 443.698376 -158.984242) (xy 443.498726 -159.049112)
			(xy 443.296751 -159.106334) (xy 443.092745 -159.155826) (xy 442.887001 -159.197515) (xy 442.67982 -159.23134)
			(xy 442.471502 -159.257254) (xy 442.262348 -159.275219) (xy 442.052661 -159.285207) (xy 441.842747 -159.287206)
			(xy 441.632908 -159.281211) (xy 441.42345 -159.267232) (xy 441.214675 -159.245289) (xy 441.006888 -159.215414)
			(xy 440.800389 -159.177649) (xy 440.595476 -159.132051) (xy 440.392449 -159.078684) (xy 440.1916 -159.017627)
			(xy 439.993222 -158.948968) (xy 439.797601 -158.872805) (xy 439.605021 -158.789251) (xy 439.415763 -158.698426)
			(xy 439.230099 -158.600461) (xy 439.048299 -158.495499) (xy 438.870627 -158.383692) (xy 438.697341 -158.265201)
			(xy 438.528691 -158.1402) (xy 438.364922 -158.008868) (xy 438.206272 -157.871397) (xy 438.05297 -157.727986)
			(xy 437.90524 -157.578842) (xy 437.763294 -157.424182) (xy 437.62734 -157.264231) (xy 437.497573 -157.099219)
			(xy 437.374183 -156.929387) (xy 437.257348 -156.75498) (xy 437.147237 -156.576252) (xy 437.04401 -156.393461)
			(xy 436.947817 -156.206873) (xy 436.858798 -156.016758) (xy 436.77708 -155.823392) (xy 436.702784 -155.627055)
			(xy 436.636016 -155.428032) (xy 436.576874 -155.226611) (xy 436.525442 -155.023085) (xy 436.481797 -154.817748)
			(xy 436.446 -154.610898) (xy 436.418104 -154.402836) (xy 436.39815 -154.193862) (xy 436.386165 -153.98428)
			(xy 436.382169 -153.774394) (xy 388.817889 -153.774394) (xy 388.81812 -153.793952) (xy 388.817702 -153.832242)
			(xy 388.811098 -153.908535) (xy 388.797953 -153.983978) (xy 388.778362 -154.058009) (xy 388.765796 -154.09418)
			(xy 388.763168 -154.102623) (xy 388.763152 -154.120288) (xy 388.765796 -154.128724) (xy 388.778328 -154.164905)
			(xy 388.797905 -154.238937) (xy 388.811055 -154.314375) (xy 388.817683 -154.390664) (xy 388.81812 -154.428952)
			(xy 388.817646 -154.468866) (xy 388.810422 -154.548369) (xy 388.796115 -154.626906) (xy 388.774842 -154.703849)
			(xy 388.761224 -154.741372) (xy 388.758419 -154.750047) (xy 388.758403 -154.768264) (xy 388.761224 -154.776932)
			(xy 388.774878 -154.814443) (xy 388.79617 -154.891385) (xy 388.810472 -154.969927) (xy 388.817668 -155.049435)
			(xy 388.81812 -155.089352) (xy 388.817702 -155.127642) (xy 388.811098 -155.203935) (xy 388.797953 -155.279378)
			(xy 388.778362 -155.353409) (xy 388.765796 -155.38958) (xy 388.763168 -155.398023) (xy 388.763152 -155.415688)
			(xy 388.765796 -155.424124) (xy 388.778328 -155.460305) (xy 388.797905 -155.534337) (xy 388.811055 -155.609775)
			(xy 388.817683 -155.686064) (xy 388.81812 -155.724352) (xy 388.817677 -155.763144) (xy 388.810908 -155.840433)
			(xy 388.797442 -155.916841) (xy 388.777382 -155.991787) (xy 388.764526 -156.02839) (xy 388.761895 -156.036832)
			(xy 388.761883 -156.054497) (xy 388.764526 -156.062934) (xy 388.7774 -156.099532) (xy 388.797482 -156.174476)
			(xy 388.810953 -156.250885) (xy 388.817712 -156.328178) (xy 388.81812 -156.366972) (xy 388.817708 -156.405262)
			(xy 388.811103 -156.481556) (xy 388.797955 -156.556998) (xy 388.778363 -156.631029) (xy 388.765796 -156.6672)
			(xy 388.763157 -156.67564) (xy 388.763148 -156.693308) (xy 388.765796 -156.701744) (xy 388.778334 -156.737923)
			(xy 388.797909 -156.811956) (xy 388.811058 -156.887395) (xy 388.817683 -156.963684) (xy 388.81812 -157.001972)
			(xy 388.817621 -157.043082) (xy 388.810036 -157.124951) (xy 388.794928 -157.20577) (xy 388.772425 -157.284851)
			(xy 388.742721 -157.361517) (xy 388.706068 -157.435115) (xy 388.66278 -157.505016) (xy 388.613226 -157.570624)
			(xy 388.557828 -157.631379) (xy 388.49706 -157.686762) (xy 388.43144 -157.736301) (xy 388.361528 -157.779573)
			(xy 388.287921 -157.816208) (xy 388.211248 -157.845893) (xy 388.132162 -157.868377) (xy 388.051339 -157.883465)
			(xy 387.969468 -157.891031) (xy 387.928358 -157.89148) (xy 387.890041 -157.891126) (xy 387.813688 -157.88459)
			(xy 387.738181 -157.871501) (xy 387.664082 -157.851957) (xy 387.627876 -157.83941) (xy 387.61956 -157.836824)
			(xy 387.602156 -157.836824) (xy 387.59384 -157.83941) (xy 387.557721 -157.851912) (xy 387.483807 -157.871399)
			(xy 387.408495 -157.88448) (xy 387.33234 -157.891059) (xy 387.29412 -157.89148) (xy 387.293358 -157.89148)
			(xy 387.252251 -157.891028) (xy 387.170388 -157.88344) (xy 387.089574 -157.868332) (xy 387.010498 -157.845835)
			(xy 386.933835 -157.816138) (xy 386.860238 -157.779497) (xy 386.790335 -157.736222) (xy 386.724722 -157.686684)
			(xy 386.663959 -157.631304) (xy 386.608563 -157.570555) (xy 386.559008 -157.504955) (xy 386.515715 -157.435063)
			(xy 386.479055 -157.361475) (xy 386.449338 -157.28482) (xy 386.42682 -157.20575) (xy 386.411692 -157.12494)
			(xy 386.404083 -157.043079) (xy 386.403596 -157.001972) (xy 345.806812 -157.001972) (xy 345.834767 -157.03898)
			(xy 345.878059 -157.108874) (xy 345.914719 -157.182463) (xy 345.944433 -157.259121) (xy 345.966949 -157.338193)
			(xy 345.982074 -157.419006) (xy 345.989679 -157.500868) (xy 345.990164 -157.541976) (xy 345.989609 -157.586746)
			(xy 345.980596 -157.675831) (xy 345.962689 -157.763562) (xy 345.936068 -157.849053) (xy 345.919044 -157.890464)
			(xy 345.915494 -157.900059) (xy 345.915485 -157.920497) (xy 345.919044 -157.930088) (xy 345.936056 -157.971436)
			(xy 345.962665 -158.056799) (xy 345.980569 -158.144403) (xy 345.989589 -158.233361) (xy 345.990164 -158.278068)
			(xy 345.990164 -158.279084) (xy 345.98991 -158.290514) (xy 346.016389 -158.296459) (xy 346.068624 -158.311202)
			(xy 346.094304 -158.319978) (xy 346.102501 -158.322492) (xy 346.119635 -158.322492) (xy 346.127832 -158.319978)
			(xy 346.163048 -158.308033) (xy 346.235059 -158.289446) (xy 346.308381 -158.277006) (xy 346.382492 -158.2708)
			(xy 346.419678 -158.270448) (xy 346.456862 -158.27082) (xy 346.53097 -158.277041) (xy 346.60429 -158.289483)
			(xy 346.676301 -158.308056) (xy 346.711524 -158.319978) (xy 346.719721 -158.322492) (xy 346.736855 -158.322492)
			(xy 346.745052 -158.319978) (xy 346.780146 -158.308069) (xy 346.851906 -158.289524) (xy 346.924971 -158.277084)
			(xy 346.998824 -158.270837) (xy 347.035882 -158.270448) (xy 347.036898 -158.270448) (xy 347.078822 -158.270999)
			(xy 347.162292 -158.278969) (xy 347.244625 -158.294837) (xy 347.325078 -158.31846) (xy 347.40292 -158.349624)
			(xy 347.477448 -158.388045) (xy 347.547987 -158.433377) (xy 347.613896 -158.485209) (xy 347.674581 -158.543071)
			(xy 347.72949 -158.60644) (xy 347.778127 -158.674741) (xy 347.820052 -158.747357) (xy 347.854884 -158.823628)
			(xy 347.882308 -158.902865) (xy 347.902076 -158.984351) (xy 347.914009 -159.067346) (xy 347.917999 -159.1511)
			(xy 347.914009 -159.234854) (xy 347.902076 -159.317849) (xy 347.882308 -159.399335) (xy 347.854884 -159.478572)
			(xy 347.820052 -159.554843) (xy 347.778127 -159.627459) (xy 347.72949 -159.69576) (xy 347.674581 -159.759129)
			(xy 347.613896 -159.816991) (xy 347.547987 -159.868823) (xy 347.477448 -159.914155) (xy 347.40292 -159.952576)
			(xy 347.325078 -159.98374) (xy 347.244625 -160.007363) (xy 347.162292 -160.023231) (xy 347.078822 -160.031201)
			(xy 347.036898 -160.031684) (xy 347.035882 -160.031684) (xy 346.998825 -160.031285) (xy 346.924976 -160.025019)
			(xy 346.851913 -160.012575) (xy 346.780153 -159.994041) (xy 346.745052 -159.982154) (xy 346.736855 -159.97964)
			(xy 346.719721 -159.97964) (xy 346.711524 -159.982154) (xy 346.684116 -159.991499) (xy 346.628318 -160.007008)
			(xy 346.600018 -160.013142) (xy 346.590235 -160.015622) (xy 346.573598 -160.027019) (xy 346.562626 -160.04394)
			(xy 346.560394 -160.053782) (xy 346.550929 -160.102889) (xy 346.522417 -160.19875) (xy 346.503498 -160.245044)
			(xy 346.499892 -160.254619) (xy 346.499745 -160.275056) (xy 346.503244 -160.284668) (xy 346.520278 -160.326041)
			(xy 346.546893 -160.41147) (xy 346.564794 -160.499139) (xy 346.5738 -160.588163) (xy 346.574364 -160.632902)
			(xy 346.574364 -160.633156) (xy 346.57386 -160.675504) (xy 346.565809 -160.759818) (xy 346.54978 -160.842984)
			(xy 346.525919 -160.924251) (xy 346.49444 -161.002881) (xy 346.455629 -161.078162) (xy 346.409839 -161.149414)
			(xy 346.357483 -161.21599) (xy 346.299035 -161.277288) (xy 346.235025 -161.332753) (xy 346.166033 -161.381882)
			(xy 346.092683 -161.424231) (xy 346.01564 -161.459415) (xy 345.935601 -161.487117) (xy 345.853292 -161.507085)
			(xy 345.769457 -161.519138) (xy 345.684856 -161.523169) (xy 345.600255 -161.519138) (xy 345.51642 -161.507085)
			(xy 345.434111 -161.487117) (xy 345.354072 -161.459415) (xy 345.277029 -161.424231) (xy 345.203679 -161.381882)
			(xy 345.134687 -161.332753) (xy 345.070677 -161.277288) (xy 345.012229 -161.21599) (xy 344.959873 -161.149414)
			(xy 344.914083 -161.078162) (xy 344.875272 -161.002881) (xy 344.843793 -160.924251) (xy 344.819932 -160.842984)
			(xy 344.803903 -160.759818) (xy 344.795852 -160.675504) (xy 344.795348 -160.633156) (xy 344.795348 -160.632902)
			(xy 344.795938 -160.588164) (xy 344.804948 -160.499143) (xy 344.822847 -160.411476) (xy 344.849453 -160.326048)
			(xy 344.866468 -160.284668) (xy 344.870056 -160.275084) (xy 344.87004 -160.254635) (xy 344.866468 -160.245044)
			(xy 344.849433 -160.203637) (xy 344.822801 -160.118148) (xy 344.804897 -160.030415) (xy 344.795901 -159.941327)
			(xy 344.795348 -159.896556) (xy 344.795678 -159.859467) (xy 344.801776 -159.78554) (xy 344.814009 -159.712377)
			(xy 344.82278 -159.676338) (xy 344.824538 -159.668008) (xy 344.823098 -159.651057) (xy 344.816174 -159.635517)
			(xy 344.810588 -159.629094) (xy 344.770202 -159.586168) (xy 344.758264 -159.588708) (xy 344.749364 -159.591023)
			(xy 344.733871 -159.600904) (xy 344.728038 -159.608012) (xy 344.702891 -159.640664) (xy 344.647483 -159.701681)
			(xy 344.586669 -159.757312) (xy 344.520971 -159.807081) (xy 344.450952 -159.850561) (xy 344.377213 -159.887379)
			(xy 344.300384 -159.917221) (xy 344.221125 -159.93983) (xy 344.140115 -159.955012) (xy 344.058048 -159.962637)
			(xy 344.016838 -159.963104) (xy 343.975733 -159.962551) (xy 343.893874 -159.954971) (xy 343.813062 -159.939871)
			(xy 343.733989 -159.917381) (xy 343.657327 -159.887692) (xy 343.583731 -159.851057) (xy 343.513829 -159.807789)
			(xy 343.448216 -159.758257) (xy 343.387452 -159.702884) (xy 343.332056 -159.642141) (xy 343.2825 -159.576547)
			(xy 343.239206 -159.506661) (xy 343.202543 -159.433078) (xy 343.172826 -159.356428) (xy 343.150306 -159.277363)
			(xy 343.135175 -159.196557) (xy 343.127564 -159.114701) (xy 343.127076 -159.073596) (xy 279.382794 -159.073596)
			(xy 279.296825 -159.097952) (xy 279.092819 -159.147444) (xy 278.887075 -159.189133) (xy 278.679894 -159.222958)
			(xy 278.471576 -159.248872) (xy 278.262422 -159.266837) (xy 278.052735 -159.276825) (xy 277.842821 -159.278824)
			(xy 277.632982 -159.272829) (xy 277.423524 -159.25885) (xy 277.214749 -159.236907) (xy 277.006962 -159.207032)
			(xy 276.800463 -159.169267) (xy 276.59555 -159.123669) (xy 276.392523 -159.070302) (xy 276.191674 -159.009245)
			(xy 275.993296 -158.940586) (xy 275.797675 -158.864423) (xy 275.605095 -158.780869) (xy 275.415837 -158.690044)
			(xy 275.230173 -158.592079) (xy 275.048373 -158.487117) (xy 274.870701 -158.37531) (xy 274.697415 -158.256819)
			(xy 274.528765 -158.131818) (xy 274.364996 -158.000486) (xy 274.206346 -157.863015) (xy 274.053044 -157.719604)
			(xy 273.905314 -157.57046) (xy 273.763368 -157.4158) (xy 273.627414 -157.255849) (xy 273.497647 -157.090837)
			(xy 273.374257 -156.921005) (xy 273.257422 -156.746598) (xy 273.147311 -156.56787) (xy 273.044084 -156.385079)
			(xy 272.947891 -156.198491) (xy 272.858872 -156.008376) (xy 272.777154 -155.81501) (xy 272.702858 -155.618673)
			(xy 272.63609 -155.41965) (xy 272.576948 -155.218229) (xy 272.525516 -155.014703) (xy 272.481871 -154.809366)
			(xy 272.446074 -154.602516) (xy 272.418178 -154.394454) (xy 272.398224 -154.18548) (xy 272.386239 -153.975898)
			(xy 272.382243 -153.766012) (xy 199.467428 -153.766012) (xy 199.46747 -153.774902) (xy 199.46697 -153.879864)
			(xy 199.458978 -154.089636) (xy 199.443006 -154.298952) (xy 199.419076 -154.507508) (xy 199.387224 -154.715001)
			(xy 199.347496 -154.921132) (xy 199.299949 -155.125601) (xy 199.244652 -155.328111) (xy 199.181685 -155.528369)
			(xy 199.11114 -155.726085) (xy 199.033119 -155.920972) (xy 198.947735 -156.112747) (xy 198.855112 -156.301133)
			(xy 198.755385 -156.485856) (xy 198.648697 -156.666648) (xy 198.535203 -156.843248) (xy 198.415068 -157.015398)
			(xy 198.288467 -157.182851) (xy 198.155582 -157.345362) (xy 198.016607 -157.502696) (xy 197.871743 -157.654625)
			(xy 197.7212 -157.800929) (xy 197.565196 -157.941396) (xy 197.403957 -158.075822) (xy 197.237717 -158.204011)
			(xy 197.066718 -158.325779) (xy 196.891207 -158.440949) (xy 196.711439 -158.549353) (xy 196.527674 -158.650835)
			(xy 196.340178 -158.745247) (xy 196.149225 -158.832453) (xy 195.955089 -158.912326) (xy 195.758054 -158.98475)
			(xy 195.558404 -159.04962) (xy 195.356429 -159.106842) (xy 195.152423 -159.156334) (xy 194.946679 -159.198023)
			(xy 194.739498 -159.231848) (xy 194.53118 -159.257762) (xy 194.322026 -159.275727) (xy 194.112339 -159.285715)
			(xy 193.902425 -159.287714) (xy 193.692586 -159.281719) (xy 193.483128 -159.26774) (xy 193.274353 -159.245797)
			(xy 193.066566 -159.215922) (xy 192.860067 -159.178157) (xy 192.655154 -159.132559) (xy 192.452127 -159.079192)
			(xy 192.251278 -159.018135) (xy 192.0529 -158.949476) (xy 191.857279 -158.873313) (xy 191.664699 -158.789759)
			(xy 191.475441 -158.698934) (xy 191.289777 -158.600969) (xy 191.107977 -158.496007) (xy 190.930305 -158.3842)
			(xy 190.757019 -158.265709) (xy 190.588369 -158.140708) (xy 190.4246 -158.009376) (xy 190.26595 -157.871905)
			(xy 190.112648 -157.728494) (xy 189.964918 -157.57935) (xy 189.822972 -157.42469) (xy 189.687018 -157.264739)
			(xy 189.557251 -157.099727) (xy 189.433861 -156.929895) (xy 189.317026 -156.755488) (xy 189.206915 -156.57676)
			(xy 189.103688 -156.393969) (xy 189.007495 -156.207381) (xy 188.918476 -156.017266) (xy 188.836758 -155.8239)
			(xy 188.762462 -155.627563) (xy 188.695694 -155.42854) (xy 188.636552 -155.227119) (xy 188.58512 -155.023593)
			(xy 188.541475 -154.818256) (xy 188.505678 -154.611406) (xy 188.477782 -154.403344) (xy 188.457828 -154.19437)
			(xy 188.445843 -153.984788) (xy 188.441847 -153.774902) (xy 132.165372 -153.774902) (xy 132.17401 -153.779355)
			(xy 132.244575 -153.824704) (xy 132.31051 -153.876555) (xy 132.371218 -153.934439) (xy 132.426149 -153.997832)
			(xy 132.474805 -154.066159) (xy 132.516746 -154.138802) (xy 132.551591 -154.215103) (xy 132.579026 -154.29437)
			(xy 132.598802 -154.375887) (xy 132.61074 -154.458914) (xy 132.614731 -154.5427) (xy 132.61074 -154.626486)
			(xy 132.598802 -154.709513) (xy 132.579026 -154.79103) (xy 132.551591 -154.870297) (xy 132.516746 -154.946598)
			(xy 132.474805 -155.019241) (xy 132.426149 -155.087568) (xy 132.371218 -155.150961) (xy 132.31051 -155.208845)
			(xy 132.244575 -155.260696) (xy 132.17401 -155.306045) (xy 132.099453 -155.344481) (xy 132.02158 -155.375656)
			(xy 131.941097 -155.399287) (xy 131.858732 -155.415161) (xy 131.77523 -155.423133) (xy 131.73329 -155.423616)
			(xy 131.6961 -155.423229) (xy 131.621987 -155.416939) (xy 131.548668 -155.404428) (xy 131.476662 -155.385787)
			(xy 131.441444 -155.373832) (xy 131.433247 -155.371318) (xy 131.416113 -155.371318) (xy 131.407916 -155.373832)
			(xy 131.374578 -155.385154) (xy 131.306486 -155.403082) (xy 131.237181 -155.41552) (xy 131.202176 -155.419298)
			(xy 131.192163 -155.420682) (xy 131.174401 -155.43031) (xy 131.161723 -155.446041) (xy 131.158488 -155.45562)
			(xy 131.151035 -155.480306) (xy 131.133624 -155.528851) (xy 131.12369 -155.552648) (xy 131.120082 -155.562222)
			(xy 131.119936 -155.58266) (xy 131.123436 -155.592272) (xy 131.140471 -155.633645) (xy 131.167086 -155.719073)
			(xy 131.184987 -155.806743) (xy 131.193992 -155.895767) (xy 131.194556 -155.940506) (xy 131.194556 -155.94076)
			(xy 131.194052 -155.983108) (xy 131.186001 -156.067422) (xy 131.169972 -156.150588) (xy 131.146111 -156.231855)
			(xy 131.114632 -156.310485) (xy 131.075821 -156.385766) (xy 131.030031 -156.457018) (xy 130.977675 -156.523594)
			(xy 130.919227 -156.584892) (xy 130.855217 -156.640357) (xy 130.786225 -156.689486) (xy 130.712875 -156.731835)
			(xy 130.635832 -156.767019) (xy 130.555793 -156.794721) (xy 130.473484 -156.814689) (xy 130.389649 -156.826742)
			(xy 130.305048 -156.830773) (xy 130.220447 -156.826742) (xy 130.136612 -156.814689) (xy 130.054303 -156.794721)
			(xy 129.974264 -156.767019) (xy 129.897221 -156.731835) (xy 129.823871 -156.689486) (xy 129.754879 -156.640357)
			(xy 129.690869 -156.584892) (xy 129.632421 -156.523594) (xy 129.580065 -156.457018) (xy 129.534275 -156.385766)
			(xy 129.495464 -156.310485) (xy 129.463985 -156.231855) (xy 129.440124 -156.150588) (xy 129.424095 -156.067422)
			(xy 129.416044 -155.983108) (xy 129.41554 -155.94076) (xy 129.41554 -155.940506) (xy 129.416091 -155.895767)
			(xy 129.425111 -155.806745) (xy 129.443021 -155.719078) (xy 129.46964 -155.633651) (xy 129.48666 -155.592272)
			(xy 129.490247 -155.582688) (xy 129.490232 -155.562239) (xy 129.48666 -155.552648) (xy 129.471663 -155.516314)
			(xy 129.447353 -155.441557) (xy 129.429731 -155.364948) (xy 129.418932 -155.287083) (xy 129.416556 -155.247848)
			(xy 129.415794 -155.233878) (xy 129.400046 -155.21051) (xy 129.29235 -155.160472) (xy 129.264664 -155.16352)
			(xy 129.253234 -155.172156) (xy 129.220015 -155.196974) (xy 129.149739 -155.241) (xy 129.075668 -155.27829)
			(xy 128.998447 -155.308521) (xy 128.918747 -155.33143) (xy 128.83726 -155.346818) (xy 128.754694 -155.354552)
			(xy 128.71323 -155.355036) (xy 128.672115 -155.354573) (xy 128.590235 -155.346988) (xy 128.509404 -155.33188)
			(xy 128.430313 -155.309379) (xy 128.353635 -155.279675) (xy 128.280025 -155.243023) (xy 128.210111 -155.199735)
			(xy 128.144489 -155.150181) (xy 128.08372 -155.094783) (xy 128.028322 -155.034014) (xy 127.978767 -154.968393)
			(xy 127.935479 -154.898479) (xy 127.898826 -154.824869) (xy 127.869122 -154.748191) (xy 127.84662 -154.669099)
			(xy 127.831512 -154.588269) (xy 127.823927 -154.506389) (xy 127.823468 -154.465274) (xy 35.422918 -154.465274)
			(xy 35.41915 -154.49811) (xy 35.387298 -154.705603) (xy 35.34757 -154.911734) (xy 35.300023 -155.116203)
			(xy 35.244726 -155.318713) (xy 35.181759 -155.518971) (xy 35.111214 -155.716687) (xy 35.033193 -155.911574)
			(xy 34.947809 -156.103349) (xy 34.855186 -156.291735) (xy 34.755459 -156.476458) (xy 34.648771 -156.65725)
			(xy 34.535277 -156.83385) (xy 34.415142 -157.006) (xy 34.288541 -157.173453) (xy 34.155656 -157.335964)
			(xy 34.016681 -157.493298) (xy 33.871817 -157.645227) (xy 33.721274 -157.791531) (xy 33.56527 -157.931998)
			(xy 33.404031 -158.066424) (xy 33.237791 -158.194613) (xy 33.066792 -158.316381) (xy 32.891281 -158.431551)
			(xy 32.711513 -158.539955) (xy 32.527748 -158.641437) (xy 32.340252 -158.735849) (xy 32.149299 -158.823055)
			(xy 31.955163 -158.902928) (xy 31.758128 -158.975352) (xy 31.558478 -159.040222) (xy 31.356503 -159.097444)
			(xy 31.152497 -159.146936) (xy 30.946753 -159.188625) (xy 30.739572 -159.22245) (xy 30.531254 -159.248364)
			(xy 30.3221 -159.266329) (xy 30.112413 -159.276317) (xy 29.902499 -159.278316) (xy 29.69266 -159.272321)
			(xy 29.483202 -159.258342) (xy 29.274427 -159.236399) (xy 29.06664 -159.206524) (xy 28.860141 -159.168759)
			(xy 28.655228 -159.123161) (xy 28.452201 -159.069794) (xy 28.251352 -159.008737) (xy 28.052974 -158.940078)
			(xy 27.857353 -158.863915) (xy 27.664773 -158.780361) (xy 27.475515 -158.689536) (xy 27.289851 -158.591571)
			(xy 27.108051 -158.486609) (xy 26.930379 -158.374802) (xy 26.757093 -158.256311) (xy 26.588443 -158.13131)
			(xy 26.424674 -157.999978) (xy 26.266024 -157.862507) (xy 26.112722 -157.719096) (xy 25.964992 -157.569952)
			(xy 25.823046 -157.415292) (xy 25.687092 -157.255341) (xy 25.557325 -157.090329) (xy 25.433935 -156.920497)
			(xy 25.3171 -156.74609) (xy 25.206989 -156.567362) (xy 25.103762 -156.384571) (xy 25.007569 -156.197983)
			(xy 24.91855 -156.007868) (xy 24.836832 -155.814502) (xy 24.762536 -155.618165) (xy 24.695768 -155.419142)
			(xy 24.636626 -155.217721) (xy 24.585194 -155.014195) (xy 24.541549 -154.808858) (xy 24.505752 -154.602008)
			(xy 24.477856 -154.393946) (xy 24.457902 -154.184972) (xy 24.445917 -153.97539) (xy 24.441921 -153.765504)
			(xy 2.509012 -153.765504) (xy 2.509012 -164.097716) (xy 86.129368 -164.097716) (xy 86.129877 -164.05494)
			(xy 86.138089 -163.969783) (xy 86.154448 -163.88581) (xy 86.178803 -163.803797) (xy 86.194392 -163.76396)
			(xy 86.19746 -163.755511) (xy 86.19811 -163.737557) (xy 86.195662 -163.728908) (xy 86.181097 -163.683434)
			(xy 86.160666 -163.590154) (xy 86.150355 -163.495221) (xy 86.149688 -163.447476) (xy 86.150084 -163.409186)
			(xy 86.156694 -163.332892) (xy 86.169846 -163.257449) (xy 86.189443 -163.183419) (xy 86.202012 -163.147248)
			(xy 86.204676 -163.138815) (xy 86.204669 -163.121141) (xy 86.202012 -163.112704) (xy 86.18946 -163.076529)
			(xy 86.169889 -163.002495) (xy 86.156744 -162.927055) (xy 86.150122 -162.850764) (xy 86.149688 -162.812476)
			(xy 86.15013 -162.771365) (xy 86.157719 -162.689494) (xy 86.172832 -162.608673) (xy 86.195339 -162.529592)
			(xy 86.225048 -162.452925) (xy 86.261705 -162.379327) (xy 86.304997 -162.309425) (xy 86.354555 -162.243817)
			(xy 86.409957 -162.183063) (xy 86.470728 -162.12768) (xy 86.536351 -162.078142) (xy 86.606266 -162.034871)
			(xy 86.679876 -161.998237) (xy 86.756552 -161.968552) (xy 86.83564 -161.94607) (xy 86.916466 -161.930982)
			(xy 86.998339 -161.923417) (xy 87.03945 -161.922968) (xy 87.077766 -161.923352) (xy 87.154119 -161.92988)
			(xy 87.229626 -161.94296) (xy 87.303725 -161.962495) (xy 87.339932 -161.975038) (xy 87.348248 -161.977624)
			(xy 87.365652 -161.977624) (xy 87.373968 -161.975038) (xy 87.410177 -161.962503) (xy 87.484279 -161.942985)
			(xy 87.559785 -161.929905) (xy 87.636135 -161.92336) (xy 87.67445 -161.922968) (xy 87.712766 -161.923352)
			(xy 87.789119 -161.92988) (xy 87.864626 -161.94296) (xy 87.938725 -161.962495) (xy 87.974932 -161.975038)
			(xy 87.983248 -161.977624) (xy 88.000652 -161.977624) (xy 88.008968 -161.975038) (xy 88.045177 -161.962503)
			(xy 88.119279 -161.942985) (xy 88.194785 -161.929905) (xy 88.271135 -161.92336) (xy 88.30945 -161.922968)
			(xy 88.347766 -161.923352) (xy 88.424119 -161.92988) (xy 88.499626 -161.94296) (xy 88.573725 -161.962495)
			(xy 88.609932 -161.975038) (xy 88.618248 -161.977624) (xy 88.635652 -161.977624) (xy 88.643968 -161.975038)
			(xy 88.680177 -161.962503) (xy 88.754279 -161.942985) (xy 88.829785 -161.929905) (xy 88.906135 -161.92336)
			(xy 88.94445 -161.922968) (xy 88.982766 -161.923352) (xy 89.059119 -161.92988) (xy 89.134626 -161.94296)
			(xy 89.208725 -161.962495) (xy 89.244932 -161.975038) (xy 89.253248 -161.977624) (xy 89.270652 -161.977624)
			(xy 89.278968 -161.975038) (xy 89.315177 -161.962503) (xy 89.389279 -161.942985) (xy 89.464785 -161.929905)
			(xy 89.541135 -161.92336) (xy 89.57945 -161.922968) (xy 89.62106 -161.923438) (xy 89.703917 -161.931201)
			(xy 89.785687 -161.946663) (xy 89.865658 -161.96969) (xy 89.90457 -161.984436) (xy 89.913248 -161.987466)
			(xy 89.931617 -161.98771) (xy 89.940384 -161.984944) (xy 89.976385 -161.972506) (xy 90.050053 -161.953122)
			(xy 90.125108 -161.940106) (xy 90.201001 -161.933552) (xy 90.239088 -161.933128) (xy 90.23985 -161.933128)
			(xy 90.280956 -161.93366) (xy 90.362817 -161.94124) (xy 90.443629 -161.956339) (xy 90.522705 -161.97883)
			(xy 90.599368 -162.008519) (xy 90.672965 -162.045155) (xy 90.742868 -162.088423) (xy 90.808482 -162.137957)
			(xy 90.869246 -162.193332) (xy 90.924643 -162.254076) (xy 90.974199 -162.319673) (xy 91.017492 -162.389561)
			(xy 91.054154 -162.463145) (xy 91.08387 -162.539798) (xy 91.106389 -162.618865) (xy 91.121517 -162.699672)
			(xy 91.129125 -162.781531) (xy 91.129612 -162.822636) (xy 91.12919 -162.860925) (xy 91.122588 -162.937219)
			(xy 91.109443 -163.012662) (xy 91.089854 -163.086693) (xy 91.077288 -163.122864) (xy 91.076082 -163.126674)
			(xy 119.365268 -163.126674) (xy 119.365838 -163.081905) (xy 119.374847 -162.99282) (xy 119.392749 -162.905089)
			(xy 119.419366 -162.819597) (xy 119.436388 -162.778186) (xy 119.43997 -162.7686) (xy 119.43996 -162.748153)
			(xy 119.436388 -162.738562) (xy 119.41934 -162.69716) (xy 119.392709 -162.61167) (xy 119.374808 -162.523935)
			(xy 119.365818 -162.434845) (xy 119.365268 -162.390074) (xy 119.365838 -162.345305) (xy 119.374847 -162.25622)
			(xy 119.392749 -162.168489) (xy 119.419366 -162.082997) (xy 119.436388 -162.041586) (xy 119.43997 -162.032)
			(xy 119.43996 -162.011553) (xy 119.436388 -162.001962) (xy 119.41934 -161.96056) (xy 119.392709 -161.87507)
			(xy 119.374808 -161.787335) (xy 119.365818 -161.698245) (xy 119.365268 -161.653474) (xy 119.365674 -161.612358)
			(xy 119.373264 -161.530476) (xy 119.388376 -161.449645) (xy 119.410882 -161.370552) (xy 119.440591 -161.293873)
			(xy 119.477247 -161.220263) (xy 119.520539 -161.150349) (xy 119.570097 -161.084728) (xy 119.625499 -161.023959)
			(xy 119.686271 -160.968561) (xy 119.751895 -160.919007) (xy 119.821812 -160.87572) (xy 119.895425 -160.839068)
			(xy 119.972105 -160.809365) (xy 120.051199 -160.786863) (xy 120.132032 -160.771756) (xy 120.213914 -160.764171)
			(xy 120.25503 -160.763712) (xy 120.296641 -160.764173) (xy 120.379498 -160.771953) (xy 120.461267 -160.787431)
			(xy 120.541235 -160.810474) (xy 120.618703 -160.840879) (xy 120.692995 -160.878382) (xy 120.728486 -160.90011)
			(xy 120.737629 -160.905263) (xy 120.758342 -160.90848) (xy 120.778614 -160.903152) (xy 120.78716 -160.897062)
			(xy 120.820789 -160.871071) (xy 120.892183 -160.824946) (xy 120.967654 -160.785845) (xy 121.046512 -160.754124)
			(xy 121.128037 -160.730075) (xy 121.211485 -160.713915) (xy 121.296095 -160.705793) (xy 121.338594 -160.705292)
			(xy 121.379707 -160.705819) (xy 121.461582 -160.713405) (xy 121.542407 -160.728513) (xy 121.621494 -160.751013)
			(xy 121.698168 -160.780715) (xy 121.771774 -160.817365) (xy 121.841684 -160.86065) (xy 121.907303 -160.9102)
			(xy 121.96807 -160.965593) (xy 122.023467 -161.026357) (xy 122.073021 -161.091973) (xy 122.11631 -161.161881)
			(xy 122.152964 -161.235485) (xy 122.18267 -161.312156) (xy 122.205176 -161.391242) (xy 122.220288 -161.472067)
			(xy 122.227879 -161.553941) (xy 122.228356 -161.595054) (xy 122.227793 -161.639824) (xy 122.218783 -161.728909)
			(xy 122.200877 -161.81664) (xy 122.174259 -161.902131) (xy 122.157236 -161.943542) (xy 122.153699 -161.953141)
			(xy 122.153682 -161.973576) (xy 122.157236 -161.983166) (xy 122.17424 -162.024517) (xy 122.200851 -162.109879)
			(xy 122.218758 -162.197482) (xy 122.22778 -162.286439) (xy 122.228356 -162.331146) (xy 122.228356 -162.332162)
			(xy 122.228102 -162.343592) (xy 122.254581 -162.349538) (xy 122.306816 -162.364281) (xy 122.332496 -162.373056)
			(xy 122.340693 -162.37557) (xy 122.357827 -162.37557) (xy 122.366024 -162.373056) (xy 122.40124 -162.361095)
			(xy 122.473244 -162.342441) (xy 122.546565 -162.329932) (xy 122.62068 -162.323659) (xy 122.65787 -162.323272)
			(xy 122.695059 -162.323671) (xy 122.769172 -162.329958) (xy 122.842492 -162.342465) (xy 122.914498 -162.361103)
			(xy 122.949716 -162.373056) (xy 122.957913 -162.37557) (xy 122.975047 -162.37557) (xy 122.983244 -162.373056)
			(xy 123.018459 -162.361089) (xy 123.090462 -162.342437) (xy 123.163784 -162.32993) (xy 123.2379 -162.323658)
			(xy 123.27509 -162.323272) (xy 123.31703 -162.323667) (xy 123.400532 -162.331639) (xy 123.482897 -162.347513)
			(xy 123.56338 -162.371144) (xy 123.641253 -162.402319) (xy 123.71581 -162.440755) (xy 123.786375 -162.486104)
			(xy 123.85231 -162.537955) (xy 123.913018 -162.595839) (xy 123.913877 -162.59683) (xy 376.471695 -162.59683)
			(xy 376.4757 -162.491081) (xy 376.48769 -162.385938) (xy 376.507599 -162.282003) (xy 376.53531 -162.179871)
			(xy 376.570667 -162.080127) (xy 376.613465 -161.983343) (xy 376.663461 -161.890073) (xy 376.720368 -161.800852)
			(xy 376.783859 -161.716189) (xy 376.853571 -161.636571) (xy 376.929105 -161.562453) (xy 377.010028 -161.49426)
			(xy 377.095877 -161.432382) (xy 377.18616 -161.377175) (xy 377.280359 -161.328953) (xy 377.377936 -161.287993)
			(xy 377.478331 -161.254531) (xy 377.580969 -161.228757) (xy 377.685262 -161.210819) (xy 377.790613 -161.20082)
			(xy 377.896419 -161.198817) (xy 378.002073 -161.204822) (xy 378.10697 -161.218801) (xy 378.21051 -161.240672)
			(xy 378.312099 -161.270312) (xy 378.411156 -161.30755) (xy 378.507113 -161.352172) (xy 378.59942 -161.403924)
			(xy 378.687549 -161.462509) (xy 378.770995 -161.527591) (xy 378.849279 -161.598797) (xy 378.921954 -161.67572)
			(xy 378.988604 -161.75792) (xy 379.048846 -161.844924) (xy 379.102335 -161.936235) (xy 379.148766 -162.03133)
			(xy 379.187871 -162.129664) (xy 379.219428 -162.230675) (xy 379.243255 -162.333782) (xy 379.259216 -162.438396)
			(xy 379.26722 -162.543918) (xy 379.26772 -162.59683) (xy 379.26722 -162.649742) (xy 379.266995 -162.65271)
			(xy 385.808735 -162.65271) (xy 385.81274 -162.546961) (xy 385.82473 -162.441818) (xy 385.844639 -162.337883)
			(xy 385.87235 -162.235751) (xy 385.907707 -162.136007) (xy 385.950505 -162.039223) (xy 386.000501 -161.945953)
			(xy 386.057408 -161.856732) (xy 386.120899 -161.772069) (xy 386.190611 -161.692451) (xy 386.266145 -161.618333)
			(xy 386.347068 -161.55014) (xy 386.432917 -161.488262) (xy 386.5232 -161.433055) (xy 386.617399 -161.384833)
			(xy 386.714976 -161.343873) (xy 386.815371 -161.310411) (xy 386.918009 -161.284637) (xy 387.022302 -161.266699)
			(xy 387.127653 -161.2567) (xy 387.233459 -161.254697) (xy 387.339113 -161.260702) (xy 387.44401 -161.274681)
			(xy 387.54755 -161.296552) (xy 387.649139 -161.326192) (xy 387.748196 -161.36343) (xy 387.844153 -161.408052)
			(xy 387.93646 -161.459804) (xy 388.024589 -161.518389) (xy 388.108035 -161.583471) (xy 388.186319 -161.654677)
			(xy 388.231017 -161.701988) (xy 409.929076 -161.701988) (xy 409.92965 -161.657219) (xy 409.938657 -161.568134)
			(xy 409.956559 -161.480403) (xy 409.983175 -161.394911) (xy 410.000196 -161.3535) (xy 410.00377 -161.343912)
			(xy 410.003765 -161.323466) (xy 410.000196 -161.313876) (xy 409.983153 -161.272472) (xy 409.956521 -161.186983)
			(xy 409.938618 -161.099248) (xy 409.929627 -161.010159) (xy 409.929076 -160.965388) (xy 409.92965 -160.920619)
			(xy 409.938657 -160.831534) (xy 409.956559 -160.743803) (xy 409.983175 -160.658311) (xy 410.000196 -160.6169)
			(xy 410.00377 -160.607312) (xy 410.003765 -160.586866) (xy 410.000196 -160.577276) (xy 409.983153 -160.535872)
			(xy 409.956521 -160.450383) (xy 409.938618 -160.362648) (xy 409.929627 -160.273559) (xy 409.929076 -160.228788)
			(xy 409.929541 -160.187678) (xy 409.93713 -160.105808) (xy 409.952241 -160.024988) (xy 409.974747 -159.945907)
			(xy 410.004454 -159.869241) (xy 410.041109 -159.795643) (xy 410.0844 -159.725742) (xy 410.133957 -159.660134)
			(xy 410.189357 -159.59938) (xy 410.250127 -159.543997) (xy 410.315748 -159.494459) (xy 410.385662 -159.451187)
			(xy 410.45927 -159.414553) (xy 410.535944 -159.384867) (xy 410.615031 -159.362384) (xy 410.695856 -159.347295)
			(xy 410.777728 -159.339729) (xy 410.818838 -159.33928) (xy 410.860442 -159.339755) (xy 410.94329 -159.347487)
			(xy 411.025054 -159.362917) (xy 411.105022 -159.38591) (xy 411.182495 -159.416266) (xy 411.256796 -159.45372)
			(xy 411.292294 -159.475424) (xy 411.301434 -159.480582) (xy 411.322149 -159.483796) (xy 411.342422 -159.478466)
			(xy 411.350968 -159.472376) (xy 411.384591 -159.44642) (xy 411.45597 -159.400364) (xy 411.531414 -159.361321)
			(xy 411.610235 -159.329647) (xy 411.691716 -159.305629) (xy 411.775116 -159.289486) (xy 411.859674 -159.281366)
			(xy 411.902148 -159.28086) (xy 411.902402 -159.28086) (xy 411.943509 -159.281311) (xy 412.025374 -159.288895)
			(xy 412.106189 -159.304) (xy 412.185267 -159.326496) (xy 412.261931 -159.356191) (xy 412.33553 -159.392831)
			(xy 412.405434 -159.436106) (xy 412.471048 -159.485644) (xy 412.531813 -159.541025) (xy 412.587209 -159.601775)
			(xy 412.636764 -159.667376) (xy 412.680057 -159.737269) (xy 412.716716 -159.810858) (xy 412.746431 -159.887515)
			(xy 412.768947 -159.966587) (xy 412.784073 -160.047398) (xy 412.791679 -160.129261) (xy 412.792164 -160.170368)
			(xy 412.791606 -160.215138) (xy 412.782594 -160.304223) (xy 412.764688 -160.391954) (xy 412.738068 -160.477445)
			(xy 412.721044 -160.518856) (xy 412.717498 -160.528452) (xy 412.717487 -160.548889) (xy 412.721044 -160.55848)
			(xy 412.738053 -160.599829) (xy 412.764663 -160.685192) (xy 412.782568 -160.772795) (xy 412.791589 -160.861753)
			(xy 412.792164 -160.90646) (xy 412.792164 -160.907476) (xy 412.79191 -160.918906) (xy 412.818389 -160.924851)
			(xy 412.870624 -160.939594) (xy 412.896304 -160.94837) (xy 412.904501 -160.950884) (xy 412.921635 -160.950884)
			(xy 412.929832 -160.94837) (xy 412.96505 -160.936429) (xy 413.037059 -160.91784) (xy 413.110382 -160.905398)
			(xy 413.184492 -160.899192) (xy 413.221678 -160.89884) (xy 413.258862 -160.899213) (xy 413.33297 -160.905434)
			(xy 413.40629 -160.917875) (xy 413.478301 -160.936448) (xy 413.513524 -160.94837) (xy 413.521721 -160.950884)
			(xy 413.538855 -160.950884) (xy 413.547052 -160.94837) (xy 413.582146 -160.93646) (xy 413.653906 -160.917916)
			(xy 413.726971 -160.905476) (xy 413.800824 -160.899229) (xy 413.837882 -160.89884) (xy 413.838898 -160.89884)
			(xy 413.880822 -160.899407) (xy 413.964291 -160.907377) (xy 414.046623 -160.923245) (xy 414.127075 -160.946868)
			(xy 414.204917 -160.978031) (xy 414.279444 -161.016452) (xy 414.349982 -161.061784) (xy 414.415891 -161.113615)
			(xy 414.476575 -161.171477) (xy 414.531484 -161.234845) (xy 414.580121 -161.303146) (xy 414.622045 -161.37576)
			(xy 414.656876 -161.452031) (xy 414.684301 -161.531268) (xy 414.704068 -161.612752) (xy 414.716001 -161.695747)
			(xy 414.719991 -161.7795) (xy 414.716001 -161.863253) (xy 414.704068 -161.946248) (xy 414.684301 -162.027732)
			(xy 414.656876 -162.106969) (xy 414.622045 -162.18324) (xy 414.580121 -162.255854) (xy 414.531484 -162.324155)
			(xy 414.476575 -162.387523) (xy 414.415891 -162.445385) (xy 414.349982 -162.497216) (xy 414.279444 -162.542548)
			(xy 414.204917 -162.580969) (xy 414.127075 -162.612132) (xy 414.046623 -162.635755) (xy 413.964291 -162.651623)
			(xy 413.880822 -162.659593) (xy 413.838898 -162.660076) (xy 413.837882 -162.660076) (xy 413.800825 -162.659672)
			(xy 413.726976 -162.653407) (xy 413.653913 -162.640964) (xy 413.582153 -162.622432) (xy 413.547052 -162.610546)
			(xy 413.538855 -162.608032) (xy 413.521721 -162.608032) (xy 413.513524 -162.610546) (xy 413.484638 -162.620383)
			(xy 413.425785 -162.636529) (xy 413.395922 -162.642804) (xy 413.386334 -162.645159) (xy 413.369889 -162.656054)
			(xy 413.358796 -162.672367) (xy 413.356298 -162.68192) (xy 413.34617 -162.726275) (xy 413.318046 -162.812805)
			(xy 413.300164 -162.85464) (xy 413.296347 -162.864579) (xy 413.296353 -162.885846) (xy 413.300164 -162.895788)
			(xy 413.318394 -162.938388) (xy 413.346909 -163.026556) (xy 413.366099 -163.117213) (xy 413.375757 -163.209373)
			(xy 413.376364 -163.255706) (xy 413.376364 -163.256214) (xy 413.37586 -163.298562) (xy 413.367809 -163.382876)
			(xy 413.35178 -163.466042) (xy 413.327919 -163.547309) (xy 413.29644 -163.625939) (xy 413.257629 -163.70122)
			(xy 413.230169 -163.74395) (xy 431.840894 -163.74395) (xy 431.840894 -163.68945) (xy 431.84865 -163.635505)
			(xy 431.864004 -163.583213) (xy 431.886644 -163.533639) (xy 431.916109 -163.48779) (xy 431.951798 -163.446602)
			(xy 431.992986 -163.410912) (xy 432.038833 -163.381447) (xy 432.088408 -163.358807) (xy 432.140699 -163.343452)
			(xy 432.194644 -163.335695) (xy 432.221894 -163.335208) (xy 433.212494 -163.335208) (xy 433.239748 -163.335638)
			(xy 433.293702 -163.343395) (xy 433.346003 -163.358751) (xy 433.395586 -163.381394) (xy 433.441442 -163.410863)
			(xy 433.482637 -163.446559) (xy 433.518333 -163.487753) (xy 433.547803 -163.533609) (xy 433.570447 -163.583191)
			(xy 433.585804 -163.635492) (xy 433.593561 -163.689446) (xy 433.593561 -163.743954) (xy 433.585804 -163.797908)
			(xy 433.570447 -163.850209) (xy 433.547803 -163.899791) (xy 433.518333 -163.945647) (xy 433.482637 -163.986841)
			(xy 433.441442 -164.022537) (xy 433.395586 -164.052006) (xy 433.346003 -164.074649) (xy 433.293702 -164.090005)
			(xy 433.239748 -164.097762) (xy 433.212494 -164.098224) (xy 432.221894 -164.098224) (xy 432.194644 -164.097705)
			(xy 432.140699 -164.089948) (xy 432.088408 -164.074593) (xy 432.038833 -164.051953) (xy 431.992986 -164.022488)
			(xy 431.951798 -163.986798) (xy 431.916109 -163.94561) (xy 431.886644 -163.899761) (xy 431.864004 -163.850187)
			(xy 431.84865 -163.797895) (xy 431.840894 -163.74395) (xy 413.230169 -163.74395) (xy 413.211839 -163.772472)
			(xy 413.159483 -163.839048) (xy 413.101035 -163.900346) (xy 413.037025 -163.955811) (xy 412.968033 -164.00494)
			(xy 412.894683 -164.047289) (xy 412.81764 -164.082473) (xy 412.737601 -164.110175) (xy 412.655292 -164.130143)
			(xy 412.571457 -164.142196) (xy 412.486856 -164.146227) (xy 412.402255 -164.142196) (xy 412.31842 -164.130143)
			(xy 412.236111 -164.110175) (xy 412.156072 -164.082473) (xy 412.079029 -164.047289) (xy 412.005679 -164.00494)
			(xy 411.936687 -163.955811) (xy 411.872677 -163.900346) (xy 411.814229 -163.839048) (xy 411.761873 -163.772472)
			(xy 411.716083 -163.70122) (xy 411.677272 -163.625939) (xy 411.645793 -163.547309) (xy 411.621932 -163.466042)
			(xy 411.605903 -163.382876) (xy 411.597852 -163.298562) (xy 411.597348 -163.256214) (xy 411.597348 -163.255706)
			(xy 411.597963 -163.209374) (xy 411.607632 -163.117217) (xy 411.626825 -163.026563) (xy 411.655334 -162.938394)
			(xy 411.673548 -162.895788) (xy 411.677348 -162.885844) (xy 411.677353 -162.864582) (xy 411.673548 -162.85464)
			(xy 411.655311 -162.811974) (xy 411.626764 -162.723684) (xy 411.607569 -162.632899) (xy 411.597934 -162.54061)
			(xy 411.597348 -162.494214) (xy 411.597953 -162.446404) (xy 411.608131 -162.351329) (xy 411.617668 -162.304476)
			(xy 411.61964 -162.292071) (xy 411.612727 -162.267957) (xy 411.60446 -162.258502) (xy 411.56382 -162.216338)
			(xy 411.560264 -162.2171) (xy 411.551416 -162.219411) (xy 411.536053 -162.229303) (xy 411.530292 -162.236404)
			(xy 411.505137 -162.269067) (xy 411.449717 -162.33011) (xy 411.388886 -162.385763) (xy 411.323166 -162.435548)
			(xy 411.253121 -162.479037) (xy 411.179352 -162.515858) (xy 411.102492 -162.545694) (xy 411.023201 -162.56829)
			(xy 410.942159 -162.583451) (xy 410.860062 -162.591047) (xy 410.818838 -162.591496) (xy 410.777733 -162.590951)
			(xy 410.695873 -162.583371) (xy 410.615061 -162.568271) (xy 410.535987 -162.54578) (xy 410.459325 -162.516091)
			(xy 410.385729 -162.479456) (xy 410.315826 -162.436187) (xy 410.250213 -162.386655) (xy 410.18945 -162.331281)
			(xy 410.134053 -162.270538) (xy 410.084497 -162.204943) (xy 410.041203 -162.135056) (xy 410.004541 -162.061473)
			(xy 409.974824 -161.984822) (xy 409.952304 -161.905756) (xy 409.937174 -161.82495) (xy 409.929564 -161.743093)
			(xy 409.929076 -161.701988) (xy 388.231017 -161.701988) (xy 388.258994 -161.7316) (xy 388.325644 -161.8138)
			(xy 388.385886 -161.900804) (xy 388.439375 -161.992115) (xy 388.485806 -162.08721) (xy 388.524911 -162.185544)
			(xy 388.556468 -162.286555) (xy 388.580295 -162.389662) (xy 388.596256 -162.494276) (xy 388.60426 -162.599798)
			(xy 388.60476 -162.65271) (xy 388.60426 -162.705622) (xy 388.596256 -162.811144) (xy 388.580295 -162.915758)
			(xy 388.556468 -163.018865) (xy 388.524911 -163.119876) (xy 388.485806 -163.21821) (xy 388.439375 -163.313305)
			(xy 388.385886 -163.404616) (xy 388.325644 -163.49162) (xy 388.258994 -163.57382) (xy 388.186319 -163.650743)
			(xy 388.108035 -163.721949) (xy 388.024589 -163.787031) (xy 387.93646 -163.845616) (xy 387.844153 -163.897368)
			(xy 387.748196 -163.94199) (xy 387.649139 -163.979228) (xy 387.54755 -164.008868) (xy 387.44401 -164.030739)
			(xy 387.339113 -164.044718) (xy 387.233459 -164.050723) (xy 387.127653 -164.04872) (xy 387.022302 -164.038721)
			(xy 386.918009 -164.020783) (xy 386.815371 -163.995009) (xy 386.714976 -163.961547) (xy 386.617399 -163.920587)
			(xy 386.5232 -163.872365) (xy 386.432917 -163.817158) (xy 386.347068 -163.75528) (xy 386.266145 -163.687087)
			(xy 386.190611 -163.612969) (xy 386.120899 -163.533351) (xy 386.057408 -163.448688) (xy 386.000501 -163.359467)
			(xy 385.950505 -163.266197) (xy 385.907707 -163.169413) (xy 385.87235 -163.069669) (xy 385.844639 -162.967537)
			(xy 385.82473 -162.863602) (xy 385.81274 -162.758459) (xy 385.808735 -162.65271) (xy 379.266995 -162.65271)
			(xy 379.259216 -162.755264) (xy 379.243255 -162.859878) (xy 379.219428 -162.962985) (xy 379.187871 -163.063996)
			(xy 379.148766 -163.16233) (xy 379.102335 -163.257425) (xy 379.048846 -163.348736) (xy 378.988604 -163.43574)
			(xy 378.921954 -163.51794) (xy 378.849279 -163.594863) (xy 378.770995 -163.666069) (xy 378.687549 -163.731151)
			(xy 378.59942 -163.789736) (xy 378.507113 -163.841488) (xy 378.411156 -163.88611) (xy 378.312099 -163.923348)
			(xy 378.21051 -163.952988) (xy 378.10697 -163.974859) (xy 378.002073 -163.988838) (xy 377.896419 -163.994843)
			(xy 377.790613 -163.99284) (xy 377.685262 -163.982841) (xy 377.580969 -163.964903) (xy 377.478331 -163.939129)
			(xy 377.377936 -163.905667) (xy 377.280359 -163.864707) (xy 377.18616 -163.816485) (xy 377.095877 -163.761278)
			(xy 377.010028 -163.6994) (xy 376.929105 -163.631207) (xy 376.853571 -163.557089) (xy 376.783859 -163.477471)
			(xy 376.720368 -163.392808) (xy 376.663461 -163.303587) (xy 376.613465 -163.210317) (xy 376.570667 -163.113533)
			(xy 376.53531 -163.013789) (xy 376.507599 -162.911657) (xy 376.48769 -162.807722) (xy 376.4757 -162.702579)
			(xy 376.471695 -162.59683) (xy 123.913877 -162.59683) (xy 123.967949 -162.659232) (xy 124.016605 -162.727559)
			(xy 124.058546 -162.800202) (xy 124.093391 -162.876503) (xy 124.120826 -162.95577) (xy 124.140602 -163.037287)
			(xy 124.15254 -163.120314) (xy 124.156531 -163.2041) (xy 124.15254 -163.287886) (xy 124.140602 -163.370913)
			(xy 124.120826 -163.45243) (xy 124.093391 -163.531697) (xy 124.058546 -163.607998) (xy 124.016605 -163.680641)
			(xy 123.967949 -163.748968) (xy 123.913018 -163.812361) (xy 123.85231 -163.870245) (xy 123.786375 -163.922096)
			(xy 123.71581 -163.967445) (xy 123.641253 -164.005881) (xy 123.56338 -164.037056) (xy 123.482897 -164.060687)
			(xy 123.400532 -164.076561) (xy 123.31703 -164.084533) (xy 123.27509 -164.085016) (xy 123.2379 -164.084629)
			(xy 123.163787 -164.078339) (xy 123.090468 -164.065828) (xy 123.018462 -164.047187) (xy 122.983244 -164.035232)
			(xy 122.975047 -164.032718) (xy 122.957913 -164.032718) (xy 122.949716 -164.035232) (xy 122.907233 -164.049509)
			(xy 122.820068 -164.070379) (xy 122.775726 -164.076888) (xy 122.765804 -164.078672) (xy 122.748385 -164.088778)
			(xy 122.736231 -164.104835) (xy 122.733308 -164.11448) (xy 122.724748 -164.14638) (xy 122.70352 -164.20893)
			(xy 122.69089 -164.239448) (xy 122.687282 -164.249022) (xy 122.687136 -164.26946) (xy 122.690636 -164.279072)
			(xy 122.707671 -164.320445) (xy 122.734286 -164.405873) (xy 122.752187 -164.493543) (xy 122.756237 -164.53358)
			(xy 365.854996 -164.53358) (xy 365.855358 -164.495263) (xy 365.861892 -164.41891) (xy 365.874978 -164.343403)
			(xy 365.89452 -164.269304) (xy 365.907066 -164.233098) (xy 365.909662 -164.224784) (xy 365.909655 -164.207378)
			(xy 365.907066 -164.199062) (xy 365.894569 -164.162941) (xy 365.875081 -164.089028) (xy 365.861998 -164.013717)
			(xy 365.855418 -163.937561) (xy 365.854996 -163.899342) (xy 365.854996 -163.89858) (xy 365.855448 -163.857477)
			(xy 365.863034 -163.775622) (xy 365.878141 -163.694816) (xy 365.900639 -163.615749) (xy 365.930337 -163.539095)
			(xy 365.966981 -163.465508) (xy 366.010258 -163.395615) (xy 366.059799 -163.330014) (xy 366.115181 -163.269264)
			(xy 366.175933 -163.213883) (xy 366.241535 -163.164344) (xy 366.311429 -163.121069) (xy 366.385017 -163.084427)
			(xy 366.461672 -163.054732) (xy 366.54074 -163.032236) (xy 366.621546 -163.017131) (xy 366.703401 -163.009546)
			(xy 366.744504 -163.009072) (xy 366.745266 -163.009072) (xy 366.783487 -163.009474) (xy 366.859645 -163.01604)
			(xy 366.934958 -163.029126) (xy 367.008868 -163.048635) (xy 367.044986 -163.061142) (xy 367.053302 -163.063728)
			(xy 367.070706 -163.063728) (xy 367.079022 -163.061142) (xy 367.115235 -163.04862) (xy 367.189336 -163.029098)
			(xy 367.26484 -163.016015) (xy 367.341189 -163.009466) (xy 367.379504 -163.009072) (xy 367.419718 -163.009498)
			(xy 367.49982 -163.016721) (xy 367.578942 -163.031153) (xy 367.656435 -163.052677) (xy 367.69421 -163.066476)
			(xy 367.702997 -163.069383) (xy 367.721491 -163.069383) (xy 367.730278 -163.066476) (xy 367.768054 -163.052684)
			(xy 367.845551 -163.031177) (xy 367.924672 -163.016746) (xy 368.004771 -163.00951) (xy 368.044984 -163.009072)
			(xy 368.0833 -163.009446) (xy 368.159653 -163.015977) (xy 368.23516 -163.029059) (xy 368.309259 -163.048598)
			(xy 368.345466 -163.061142) (xy 368.353782 -163.063728) (xy 368.371186 -163.063728) (xy 368.379502 -163.061142)
			(xy 368.415717 -163.048626) (xy 368.489817 -163.029103) (xy 368.565321 -163.016017) (xy 368.641669 -163.009467)
			(xy 368.679984 -163.009072) (xy 368.7183 -163.009446) (xy 368.794653 -163.015977) (xy 368.87016 -163.029059)
			(xy 368.944259 -163.048598) (xy 368.980466 -163.061142) (xy 368.988782 -163.063728) (xy 369.006186 -163.063728)
			(xy 369.014502 -163.061142) (xy 369.050717 -163.048626) (xy 369.124817 -163.029103) (xy 369.200321 -163.016017)
			(xy 369.276669 -163.009467) (xy 369.314984 -163.009072) (xy 369.3533 -163.009446) (xy 369.429653 -163.015977)
			(xy 369.50516 -163.029059) (xy 369.579259 -163.048598) (xy 369.615466 -163.061142) (xy 369.623782 -163.063728)
			(xy 369.641186 -163.063728) (xy 369.649502 -163.061142) (xy 369.685717 -163.048626) (xy 369.759817 -163.029103)
			(xy 369.835321 -163.016017) (xy 369.911669 -163.009467) (xy 369.949984 -163.009072) (xy 369.994754 -163.009635)
			(xy 370.083841 -163.018637) (xy 370.171573 -163.03654) (xy 370.257063 -163.063164) (xy 370.298472 -163.080192)
			(xy 370.308063 -163.083757) (xy 370.328505 -163.083757) (xy 370.338096 -163.080192) (xy 370.379479 -163.063183)
			(xy 370.464904 -163.036561) (xy 370.55257 -163.018653) (xy 370.641592 -163.00964) (xy 370.68633 -163.009072)
			(xy 370.686584 -163.009072) (xy 370.727686 -163.009582) (xy 370.809538 -163.017165) (xy 370.890342 -163.032268)
			(xy 370.969408 -163.054763) (xy 371.046061 -163.084457) (xy 371.119647 -163.121096) (xy 371.189538 -163.16437)
			(xy 371.255139 -163.213907) (xy 371.315889 -163.269286) (xy 371.37127 -163.330033) (xy 371.42081 -163.395632)
			(xy 371.464086 -163.465522) (xy 371.500729 -163.539106) (xy 371.530426 -163.615758) (xy 371.552923 -163.694823)
			(xy 371.56803 -163.775626) (xy 371.575616 -163.857478) (xy 371.576092 -163.89858) (xy 371.576092 -163.899342)
			(xy 371.575679 -163.937562) (xy 371.569116 -164.013721) (xy 371.556033 -164.089033) (xy 371.536527 -164.162943)
			(xy 371.524022 -164.199062) (xy 371.521447 -164.207381) (xy 371.52144 -164.224782) (xy 371.524022 -164.233098)
			(xy 371.536535 -164.269314) (xy 371.55606 -164.343414) (xy 371.569146 -164.418917) (xy 371.575697 -164.495265)
			(xy 371.576092 -164.53358) (xy 371.575734 -164.571323) (xy 371.569392 -164.646543) (xy 371.556692 -164.720953)
			(xy 371.537726 -164.794018) (xy 371.525546 -164.829744) (xy 371.522818 -164.838516) (xy 371.52307 -164.85687)
			(xy 371.526054 -164.865558) (xy 371.541045 -164.904681) (xy 371.564495 -164.985121) (xy 371.58028 -165.067409)
			(xy 371.588259 -165.150817) (xy 371.588792 -165.19271) (xy 371.588792 -165.19398) (xy 371.588329 -165.235083)
			(xy 371.580745 -165.316939) (xy 371.565641 -165.397747) (xy 371.543146 -165.476815) (xy 371.51345 -165.553471)
			(xy 371.476808 -165.62706) (xy 371.433533 -165.696954) (xy 371.383993 -165.762556) (xy 371.328611 -165.823308)
			(xy 371.267859 -165.87869) (xy 371.202257 -165.92823) (xy 371.132363 -165.971506) (xy 371.058775 -166.008149)
			(xy 370.982119 -166.037844) (xy 370.90305 -166.06034) (xy 370.822243 -166.075445) (xy 370.740387 -166.083029)
			(xy 370.699284 -166.083488) (xy 370.69903 -166.083488) (xy 370.654291 -166.082927) (xy 370.56527 -166.07391)
			(xy 370.477602 -166.056003) (xy 370.392175 -166.029387) (xy 370.350796 -166.012368) (xy 370.341205 -166.008803)
			(xy 370.320763 -166.008803) (xy 370.311172 -166.012368) (xy 370.269762 -166.029396) (xy 370.184274 -166.056029)
			(xy 370.096542 -166.073935) (xy 370.007454 -166.082933) (xy 369.962684 -166.083488) (xy 369.924367 -166.083126)
			(xy 369.848014 -166.076592) (xy 369.772507 -166.063506) (xy 369.698408 -166.043964) (xy 369.662202 -166.031418)
			(xy 369.653886 -166.028832) (xy 369.636482 -166.028832) (xy 369.628166 -166.031418) (xy 369.591953 -166.043941)
			(xy 369.517852 -166.063463) (xy 369.442348 -166.076546) (xy 369.365999 -166.083094) (xy 369.327684 -166.083488)
			(xy 369.289367 -166.083126) (xy 369.213014 -166.076592) (xy 369.137507 -166.063506) (xy 369.063408 -166.043964)
			(xy 369.027202 -166.031418) (xy 369.018886 -166.028832) (xy 369.001482 -166.028832) (xy 368.993166 -166.031418)
			(xy 368.956953 -166.043941) (xy 368.882852 -166.063463) (xy 368.807348 -166.076546) (xy 368.730999 -166.083094)
			(xy 368.692684 -166.083488) (xy 368.654367 -166.083126) (xy 368.578014 -166.076592) (xy 368.502507 -166.063506)
			(xy 368.428408 -166.043964) (xy 368.392202 -166.031418) (xy 368.383886 -166.028832) (xy 368.366482 -166.028832)
			(xy 368.358166 -166.031418) (xy 368.321953 -166.043941) (xy 368.247852 -166.063463) (xy 368.172348 -166.076546)
			(xy 368.095999 -166.083094) (xy 368.057684 -166.083488) (xy 368.01747 -166.083062) (xy 367.937368 -166.075838)
			(xy 367.858246 -166.061406) (xy 367.780753 -166.039883) (xy 367.742978 -166.026084) (xy 367.734191 -166.023177)
			(xy 367.715697 -166.023177) (xy 367.70691 -166.026084) (xy 367.669134 -166.039877) (xy 367.591637 -166.061385)
			(xy 367.512517 -166.075815) (xy 367.432417 -166.083051) (xy 367.392204 -166.083488) (xy 367.353888 -166.08312)
			(xy 367.277534 -166.076588) (xy 367.202027 -166.063503) (xy 367.127928 -166.043963) (xy 367.091722 -166.031418)
			(xy 367.083406 -166.028832) (xy 367.066002 -166.028832) (xy 367.057686 -166.031418) (xy 367.021563 -166.043908)
			(xy 366.947651 -166.063398) (xy 366.87234 -166.076483) (xy 366.796185 -166.083065) (xy 366.757966 -166.083488)
			(xy 366.757204 -166.083488) (xy 366.7161 -166.083044) (xy 366.634244 -166.075459) (xy 366.553436 -166.060354)
			(xy 366.474367 -166.037857) (xy 366.397711 -166.00816) (xy 366.324122 -165.971516) (xy 366.254228 -165.928239)
			(xy 366.188625 -165.878698) (xy 366.127874 -165.823315) (xy 366.072492 -165.762562) (xy 366.022951 -165.696959)
			(xy 365.979676 -165.627064) (xy 365.943034 -165.553475) (xy 365.913338 -165.476818) (xy 365.890843 -165.397748)
			(xy 365.875739 -165.316941) (xy 365.868155 -165.235084) (xy 365.867696 -165.19398) (xy 365.867696 -165.192964)
			(xy 365.868115 -165.155349) (xy 365.874496 -165.080389) (xy 365.887191 -165.006237) (xy 365.906111 -164.933424)
			(xy 365.918242 -164.897816) (xy 365.920992 -164.889049) (xy 365.920727 -164.87069) (xy 365.917734 -164.862002)
			(xy 365.902679 -164.822733) (xy 365.879172 -164.741978) (xy 365.863391 -164.659366) (xy 365.855475 -164.575633)
			(xy 365.854996 -164.53358) (xy 122.756237 -164.53358) (xy 122.761192 -164.582567) (xy 122.761756 -164.627306)
			(xy 122.761756 -164.62756) (xy 122.761252 -164.669908) (xy 122.753201 -164.754222) (xy 122.737172 -164.837388)
			(xy 122.713311 -164.918655) (xy 122.681832 -164.997285) (xy 122.643021 -165.072566) (xy 122.597231 -165.143818)
			(xy 122.544875 -165.210394) (xy 122.486427 -165.271692) (xy 122.422417 -165.327157) (xy 122.353425 -165.376286)
			(xy 122.280075 -165.418635) (xy 122.203032 -165.453819) (xy 122.122993 -165.481521) (xy 122.040684 -165.501489)
			(xy 121.956849 -165.513542) (xy 121.872248 -165.517573) (xy 121.787647 -165.513542) (xy 121.703812 -165.501489)
			(xy 121.621503 -165.481521) (xy 121.541464 -165.453819) (xy 121.464421 -165.418635) (xy 121.391071 -165.376286)
			(xy 121.322079 -165.327157) (xy 121.258069 -165.271692) (xy 121.199621 -165.210394) (xy 121.147265 -165.143818)
			(xy 121.101475 -165.072566) (xy 121.062664 -164.997285) (xy 121.031185 -164.918655) (xy 121.007324 -164.837388)
			(xy 120.991295 -164.754222) (xy 120.983244 -164.669908) (xy 120.98274 -164.62756) (xy 120.98274 -164.627306)
			(xy 120.983291 -164.582567) (xy 120.992311 -164.493545) (xy 121.010221 -164.405878) (xy 121.03684 -164.320451)
			(xy 121.05386 -164.279072) (xy 121.057447 -164.269488) (xy 121.057432 -164.249039) (xy 121.05386 -164.239448)
			(xy 121.037012 -164.19848) (xy 121.010567 -164.113931) (xy 120.992664 -164.027171) (xy 120.983478 -163.939061)
			(xy 120.98274 -163.89477) (xy 120.982373 -163.885212) (xy 120.975335 -163.867438) (xy 120.962255 -163.853496)
			(xy 120.953784 -163.84905) (xy 120.870726 -163.809934) (xy 120.861899 -163.806187) (xy 120.842781 -163.804911)
			(xy 120.824539 -163.810771) (xy 120.816878 -163.816538) (xy 120.782853 -163.843559) (xy 120.710459 -163.891613)
			(xy 120.633724 -163.93238) (xy 120.55338 -163.965469) (xy 120.470192 -163.990568) (xy 120.384953 -164.007435)
			(xy 120.298476 -164.01591) (xy 120.25503 -164.016436) (xy 120.213915 -164.015973) (xy 120.132035 -164.008388)
			(xy 120.051204 -163.99328) (xy 119.972113 -163.970779) (xy 119.895435 -163.941075) (xy 119.821825 -163.904423)
			(xy 119.751911 -163.861135) (xy 119.686289 -163.811581) (xy 119.62552 -163.756183) (xy 119.570122 -163.695414)
			(xy 119.520567 -163.629793) (xy 119.477279 -163.559879) (xy 119.440626 -163.486269) (xy 119.410922 -163.409591)
			(xy 119.38842 -163.330499) (xy 119.373312 -163.249669) (xy 119.365727 -163.167789) (xy 119.365268 -163.126674)
			(xy 91.076082 -163.126674) (xy 91.074618 -163.131296) (xy 91.074629 -163.148971) (xy 91.077288 -163.157408)
			(xy 91.089816 -163.193591) (xy 91.109393 -163.267622) (xy 91.122545 -163.34306) (xy 91.129174 -163.419348)
			(xy 91.129612 -163.457636) (xy 91.129114 -163.500412) (xy 91.120898 -163.585569) (xy 91.104536 -163.669543)
			(xy 91.080178 -163.751555) (xy 91.064588 -163.791392) (xy 91.061544 -163.799848) (xy 91.060879 -163.817795)
			(xy 91.063318 -163.826444) (xy 91.07787 -163.871922) (xy 91.098306 -163.9652) (xy 91.108623 -164.060131)
			(xy 91.109292 -164.107876) (xy 91.108825 -164.148987) (xy 91.101239 -164.230857) (xy 91.08613 -164.311679)
			(xy 91.063626 -164.390761) (xy 91.033921 -164.467428) (xy 90.997266 -164.541027) (xy 90.953976 -164.610929)
			(xy 90.904419 -164.676538) (xy 90.849019 -164.737293) (xy 90.788249 -164.792677) (xy 90.722626 -164.842215)
			(xy 90.652712 -164.885486) (xy 90.579103 -164.92212) (xy 90.502427 -164.951804) (xy 90.423339 -164.974286)
			(xy 90.342514 -164.989373) (xy 90.260641 -164.996936) (xy 90.21953 -164.997384) (xy 90.177921 -164.996892)
			(xy 90.095064 -164.989136) (xy 90.013294 -164.97368) (xy 89.933323 -164.950659) (xy 89.89441 -164.935916)
			(xy 89.88572 -164.932926) (xy 89.867362 -164.932654) (xy 89.858596 -164.935408) (xy 89.822497 -164.947854)
			(xy 89.748643 -164.967275) (xy 89.673397 -164.980297) (xy 89.597312 -164.986825) (xy 89.55913 -164.987224)
			(xy 89.520814 -164.986846) (xy 89.444461 -164.980317) (xy 89.368954 -164.967235) (xy 89.294855 -164.947698)
			(xy 89.258648 -164.935154) (xy 89.250332 -164.932568) (xy 89.232928 -164.932568) (xy 89.224612 -164.935154)
			(xy 89.188396 -164.947666) (xy 89.114296 -164.96719) (xy 89.038793 -164.980277) (xy 88.962445 -164.986828)
			(xy 88.92413 -164.987224) (xy 88.885814 -164.986846) (xy 88.809461 -164.980317) (xy 88.733954 -164.967235)
			(xy 88.659855 -164.947698) (xy 88.623648 -164.935154) (xy 88.615332 -164.932568) (xy 88.597928 -164.932568)
			(xy 88.589612 -164.935154) (xy 88.553396 -164.947666) (xy 88.479296 -164.96719) (xy 88.403793 -164.980277)
			(xy 88.327445 -164.986828) (xy 88.28913 -164.987224) (xy 88.250814 -164.986846) (xy 88.174461 -164.980317)
			(xy 88.098954 -164.967235) (xy 88.024855 -164.947698) (xy 87.988648 -164.935154) (xy 87.980332 -164.932568)
			(xy 87.962928 -164.932568) (xy 87.954612 -164.935154) (xy 87.918396 -164.947666) (xy 87.844296 -164.96719)
			(xy 87.768793 -164.980277) (xy 87.692445 -164.986828) (xy 87.65413 -164.987224) (xy 87.615814 -164.986846)
			(xy 87.539461 -164.980317) (xy 87.463954 -164.967235) (xy 87.389855 -164.947698) (xy 87.353648 -164.935154)
			(xy 87.345332 -164.932568) (xy 87.327928 -164.932568) (xy 87.319612 -164.935154) (xy 87.283487 -164.947638)
			(xy 87.209575 -164.96713) (xy 87.134265 -164.980216) (xy 87.058111 -164.9868) (xy 87.019892 -164.987224)
			(xy 87.01913 -164.987224) (xy 86.978023 -164.986759) (xy 86.896158 -164.979177) (xy 86.815342 -164.964075)
			(xy 86.736265 -164.941581) (xy 86.659599 -164.911888) (xy 86.586 -164.875249) (xy 86.516095 -164.831976)
			(xy 86.45048 -164.782438) (xy 86.389716 -164.727058) (xy 86.334319 -164.666309) (xy 86.284763 -164.600708)
			(xy 86.241471 -164.530815) (xy 86.204811 -164.457226) (xy 86.175097 -164.380569) (xy 86.152582 -164.301497)
			(xy 86.137457 -164.220686) (xy 86.129853 -164.138823) (xy 86.129368 -164.097716) (xy 2.509012 -164.097716)
			(xy 2.509012 -166.86276) (xy 61.046868 -166.86276) (xy 61.047433 -166.81799) (xy 61.056443 -166.728905)
			(xy 61.074347 -166.641174) (xy 61.100966 -166.555683) (xy 61.117988 -166.514272) (xy 61.121578 -166.504688)
			(xy 61.121563 -166.484239) (xy 61.117988 -166.474648) (xy 61.100968 -166.433235) (xy 61.074329 -166.347749)
			(xy 61.05642 -166.260018) (xy 61.047422 -166.17093) (xy 61.046868 -166.12616) (xy 61.047433 -166.08139)
			(xy 61.056443 -165.992305) (xy 61.074347 -165.904574) (xy 61.100966 -165.819083) (xy 61.117988 -165.777672)
			(xy 61.121578 -165.768088) (xy 61.121563 -165.747639) (xy 61.117988 -165.738048) (xy 61.100968 -165.696635)
			(xy 61.074329 -165.611149) (xy 61.05642 -165.523418) (xy 61.047422 -165.43433) (xy 61.046868 -165.38956)
			(xy 61.047314 -165.348449) (xy 61.054905 -165.266579) (xy 61.070019 -165.185759) (xy 61.092527 -165.106679)
			(xy 61.122236 -165.030013) (xy 61.158893 -164.956415) (xy 61.202185 -164.886514) (xy 61.251743 -164.820907)
			(xy 61.307144 -164.760153) (xy 61.367915 -164.70477) (xy 61.433537 -164.655232) (xy 61.503451 -164.611961)
			(xy 61.57706 -164.575327) (xy 61.653735 -164.545641) (xy 61.732822 -164.523157) (xy 61.813647 -164.508068)
			(xy 61.895519 -164.500502) (xy 61.93663 -164.500052) (xy 61.978234 -164.500535) (xy 62.061081 -164.508266)
			(xy 62.142846 -164.523695) (xy 62.222813 -164.546687) (xy 62.300286 -164.577041) (xy 62.374588 -164.614493)
			(xy 62.410086 -164.636196) (xy 62.419228 -164.641351) (xy 62.439942 -164.644569) (xy 62.460215 -164.639239)
			(xy 62.46876 -164.633148) (xy 62.502383 -164.607191) (xy 62.573762 -164.561136) (xy 62.649206 -164.522094)
			(xy 62.728027 -164.49042) (xy 62.809509 -164.466402) (xy 62.892908 -164.450259) (xy 62.977466 -164.442138)
			(xy 63.01994 -164.441632) (xy 63.020194 -164.441632) (xy 63.0613 -164.442118) (xy 63.143163 -164.449702)
			(xy 63.223977 -164.464805) (xy 63.303052 -164.487299) (xy 63.379716 -164.516993) (xy 63.453313 -164.553631)
			(xy 63.523217 -164.596903) (xy 63.58883 -164.64644) (xy 63.649594 -164.701818) (xy 63.70499 -164.762565)
			(xy 63.754546 -164.828164) (xy 63.797839 -164.898054) (xy 63.8345 -164.971641) (xy 63.864216 -165.048295)
			(xy 63.886734 -165.127364) (xy 63.901861 -165.208173) (xy 63.909469 -165.290034) (xy 63.909956 -165.33114)
			(xy 63.909389 -165.375909) (xy 63.900379 -165.464994) (xy 63.882475 -165.552725) (xy 63.855858 -165.638217)
			(xy 63.838836 -165.679628) (xy 63.83525 -165.689212) (xy 63.835264 -165.709661) (xy 63.838836 -165.719252)
			(xy 63.855836 -165.760605) (xy 63.882448 -165.845966) (xy 63.900356 -165.933568) (xy 63.903248 -165.962076)
			(xy 81.591411 -165.962076) (xy 81.595416 -165.856327) (xy 81.607406 -165.751184) (xy 81.627315 -165.647249)
			(xy 81.655026 -165.545117) (xy 81.690383 -165.445373) (xy 81.733181 -165.348589) (xy 81.783177 -165.255319)
			(xy 81.840084 -165.166098) (xy 81.903575 -165.081435) (xy 81.973287 -165.001817) (xy 82.048821 -164.927699)
			(xy 82.129744 -164.859506) (xy 82.215593 -164.797628) (xy 82.305876 -164.742421) (xy 82.400075 -164.694199)
			(xy 82.497652 -164.653239) (xy 82.598047 -164.619777) (xy 82.700685 -164.594003) (xy 82.804978 -164.576065)
			(xy 82.910329 -164.566066) (xy 83.016135 -164.564063) (xy 83.121789 -164.570068) (xy 83.226686 -164.584047)
			(xy 83.330226 -164.605918) (xy 83.431815 -164.635558) (xy 83.530872 -164.672796) (xy 83.626829 -164.717418)
			(xy 83.719136 -164.76917) (xy 83.807265 -164.827755) (xy 83.890711 -164.892837) (xy 83.968995 -164.964043)
			(xy 84.04167 -165.040966) (xy 84.10832 -165.123166) (xy 84.168562 -165.21017) (xy 84.222051 -165.301481)
			(xy 84.268482 -165.396576) (xy 84.307587 -165.49491) (xy 84.339144 -165.595921) (xy 84.362971 -165.699028)
			(xy 84.378932 -165.803642) (xy 84.386936 -165.909164) (xy 84.387436 -165.962076) (xy 90.989411 -165.962076)
			(xy 90.993416 -165.856327) (xy 91.005406 -165.751184) (xy 91.025315 -165.647249) (xy 91.053026 -165.545117)
			(xy 91.088383 -165.445373) (xy 91.131181 -165.348589) (xy 91.181177 -165.255319) (xy 91.238084 -165.166098)
			(xy 91.301575 -165.081435) (xy 91.371287 -165.001817) (xy 91.446821 -164.927699) (xy 91.527744 -164.859506)
			(xy 91.613593 -164.797628) (xy 91.703876 -164.742421) (xy 91.798075 -164.694199) (xy 91.895652 -164.653239)
			(xy 91.996047 -164.619777) (xy 92.098685 -164.594003) (xy 92.202978 -164.576065) (xy 92.308329 -164.566066)
			(xy 92.414135 -164.564063) (xy 92.519789 -164.570068) (xy 92.624686 -164.584047) (xy 92.728226 -164.605918)
			(xy 92.829815 -164.635558) (xy 92.928872 -164.672796) (xy 93.024829 -164.717418) (xy 93.117136 -164.76917)
			(xy 93.205265 -164.827755) (xy 93.288711 -164.892837) (xy 93.366995 -164.964043) (xy 93.43967 -165.040966)
			(xy 93.50632 -165.123166) (xy 93.566562 -165.21017) (xy 93.620051 -165.301481) (xy 93.666482 -165.396576)
			(xy 93.705587 -165.49491) (xy 93.737144 -165.595921) (xy 93.760971 -165.699028) (xy 93.776932 -165.803642)
			(xy 93.784936 -165.909164) (xy 93.785436 -165.962076) (xy 93.784936 -166.014988) (xy 93.776932 -166.12051)
			(xy 93.760971 -166.225124) (xy 93.737144 -166.328231) (xy 93.705587 -166.429242) (xy 93.666482 -166.527576)
			(xy 93.620051 -166.622671) (xy 93.566562 -166.713982) (xy 93.50632 -166.800986) (xy 93.43967 -166.883186)
			(xy 93.366995 -166.960109) (xy 93.288711 -167.031315) (xy 93.205265 -167.096397) (xy 93.117136 -167.154982)
			(xy 93.024829 -167.206734) (xy 92.928872 -167.251356) (xy 92.829815 -167.288594) (xy 92.728226 -167.318234)
			(xy 92.624686 -167.340105) (xy 92.519789 -167.354084) (xy 92.414135 -167.360089) (xy 92.308329 -167.358086)
			(xy 92.202978 -167.348087) (xy 92.098685 -167.330149) (xy 91.996047 -167.304375) (xy 91.895652 -167.270913)
			(xy 91.798075 -167.229953) (xy 91.703876 -167.181731) (xy 91.613593 -167.126524) (xy 91.527744 -167.064646)
			(xy 91.446821 -166.996453) (xy 91.371287 -166.922335) (xy 91.301575 -166.842717) (xy 91.238084 -166.758054)
			(xy 91.181177 -166.668833) (xy 91.131181 -166.575563) (xy 91.088383 -166.478779) (xy 91.053026 -166.379035)
			(xy 91.025315 -166.276903) (xy 91.005406 -166.172968) (xy 90.993416 -166.067825) (xy 90.989411 -165.962076)
			(xy 84.387436 -165.962076) (xy 84.386936 -166.014988) (xy 84.378932 -166.12051) (xy 84.362971 -166.225124)
			(xy 84.339144 -166.328231) (xy 84.307587 -166.429242) (xy 84.268482 -166.527576) (xy 84.222051 -166.622671)
			(xy 84.168562 -166.713982) (xy 84.10832 -166.800986) (xy 84.04167 -166.883186) (xy 83.968995 -166.960109)
			(xy 83.890711 -167.031315) (xy 83.807265 -167.096397) (xy 83.719136 -167.154982) (xy 83.626829 -167.206734)
			(xy 83.530872 -167.251356) (xy 83.431815 -167.288594) (xy 83.330226 -167.318234) (xy 83.226686 -167.340105)
			(xy 83.121789 -167.354084) (xy 83.016135 -167.360089) (xy 82.910329 -167.358086) (xy 82.804978 -167.348087)
			(xy 82.700685 -167.330149) (xy 82.598047 -167.304375) (xy 82.497652 -167.270913) (xy 82.400075 -167.229953)
			(xy 82.305876 -167.181731) (xy 82.215593 -167.126524) (xy 82.129744 -167.064646) (xy 82.048821 -166.996453)
			(xy 81.973287 -166.922335) (xy 81.903575 -166.842717) (xy 81.840084 -166.758054) (xy 81.783177 -166.668833)
			(xy 81.733181 -166.575563) (xy 81.690383 -166.478779) (xy 81.655026 -166.379035) (xy 81.627315 -166.276903)
			(xy 81.607406 -166.172968) (xy 81.595416 -166.067825) (xy 81.591411 -165.962076) (xy 63.903248 -165.962076)
			(xy 63.909379 -166.022525) (xy 63.909956 -166.067232) (xy 63.909956 -166.068248) (xy 63.909702 -166.079678)
			(xy 63.936181 -166.085625) (xy 63.988416 -166.100367) (xy 64.014096 -166.109142) (xy 64.022293 -166.111656)
			(xy 64.039427 -166.111656) (xy 64.047624 -166.109142) (xy 64.082842 -166.097202) (xy 64.154852 -166.078613)
			(xy 64.228174 -166.066171) (xy 64.302285 -166.059965) (xy 64.33947 -166.059612) (xy 64.376654 -166.059989)
			(xy 64.450761 -166.066209) (xy 64.524081 -166.078649) (xy 64.596093 -166.097221) (xy 64.631316 -166.109142)
			(xy 64.639513 -166.111656) (xy 64.656647 -166.111656) (xy 64.664844 -166.109142) (xy 64.699939 -166.097233)
			(xy 64.771698 -166.078689) (xy 64.844763 -166.066249) (xy 64.918616 -166.060001) (xy 64.955674 -166.059612)
			(xy 64.95669 -166.059612) (xy 64.998618 -166.060035) (xy 65.082094 -166.068005) (xy 65.164434 -166.083874)
			(xy 65.244893 -166.107498) (xy 65.322742 -166.138663) (xy 65.397276 -166.177087) (xy 65.46782 -166.222422)
			(xy 65.533735 -166.274258) (xy 65.594424 -166.332124) (xy 65.649338 -166.395498) (xy 65.69798 -166.463804)
			(xy 65.739908 -166.536425) (xy 65.774743 -166.612703) (xy 65.802169 -166.691946) (xy 65.821939 -166.773438)
			(xy 65.833873 -166.85644) (xy 65.837863 -166.9402) (xy 65.833873 -167.02396) (xy 65.821939 -167.106962)
			(xy 65.802169 -167.188454) (xy 65.774743 -167.267697) (xy 65.739908 -167.343975) (xy 65.69798 -167.416596)
			(xy 65.688295 -167.430196) (xy 351.432876 -167.430196) (xy 351.433453 -167.385427) (xy 351.442459 -167.296342)
			(xy 351.46036 -167.208611) (xy 351.486975 -167.123119) (xy 351.503996 -167.081708) (xy 351.507565 -167.072118)
			(xy 351.507564 -167.051674) (xy 351.503996 -167.042084) (xy 351.486956 -167.000679) (xy 351.460322 -166.91519)
			(xy 351.442419 -166.827456) (xy 351.433427 -166.738367) (xy 351.432876 -166.693596) (xy 351.433453 -166.648827)
			(xy 351.442459 -166.559742) (xy 351.46036 -166.472011) (xy 351.486975 -166.386519) (xy 351.503996 -166.345108)
			(xy 351.507565 -166.335518) (xy 351.507564 -166.315074) (xy 351.503996 -166.305484) (xy 351.486956 -166.264079)
			(xy 351.460322 -166.17859) (xy 351.442419 -166.090856) (xy 351.433427 -166.001767) (xy 351.432876 -165.956996)
			(xy 351.433349 -165.915886) (xy 351.440937 -165.834016) (xy 351.456047 -165.753196) (xy 351.478552 -165.674116)
			(xy 351.508259 -165.597449) (xy 351.544914 -165.523852) (xy 351.588204 -165.453951) (xy 351.63776 -165.388343)
			(xy 351.693159 -165.327588) (xy 351.753929 -165.272205) (xy 351.81955 -165.222667) (xy 351.889463 -165.179396)
			(xy 351.963071 -165.142761) (xy 352.039745 -165.113075) (xy 352.118832 -165.090592) (xy 352.199656 -165.075503)
			(xy 352.281528 -165.067937) (xy 352.322638 -165.067488) (xy 352.364242 -165.067962) (xy 352.44709 -165.075694)
			(xy 352.528855 -165.091124) (xy 352.608822 -165.114117) (xy 352.686295 -165.144474) (xy 352.760597 -165.181928)
			(xy 352.796094 -165.203632) (xy 352.805234 -165.208789) (xy 352.825949 -165.212002) (xy 352.846222 -165.206673)
			(xy 352.854768 -165.200584) (xy 352.888392 -165.174629) (xy 352.959771 -165.128573) (xy 353.035214 -165.08953)
			(xy 353.114035 -165.057855) (xy 353.195516 -165.033837) (xy 353.278916 -165.017694) (xy 353.363474 -165.009574)
			(xy 353.405948 -165.009068) (xy 353.406202 -165.009068) (xy 353.44731 -165.009511) (xy 353.529174 -165.017096)
			(xy 353.60999 -165.0322) (xy 353.689068 -165.054696) (xy 353.765733 -165.084391) (xy 353.839332 -165.121033)
			(xy 353.909237 -165.164307) (xy 353.974851 -165.213846) (xy 354.035616 -165.269227) (xy 354.091012 -165.329978)
			(xy 354.140567 -165.39558) (xy 354.183859 -165.465474) (xy 354.220519 -165.539063) (xy 354.250233 -165.615721)
			(xy 354.272749 -165.694793) (xy 354.287874 -165.775606) (xy 354.295479 -165.857468) (xy 354.295964 -165.898576)
			(xy 354.295409 -165.943346) (xy 354.286396 -166.032431) (xy 354.268489 -166.120162) (xy 354.241868 -166.205653)
			(xy 354.224844 -166.247064) (xy 354.221294 -166.256659) (xy 354.221285 -166.277097) (xy 354.224844 -166.286688)
			(xy 354.241856 -166.328036) (xy 354.268465 -166.413399) (xy 354.286369 -166.501003) (xy 354.289105 -166.527988)
			(xy 401.547076 -166.527988) (xy 401.54765 -166.483219) (xy 401.556657 -166.394134) (xy 401.574559 -166.306403)
			(xy 401.601175 -166.220911) (xy 401.618196 -166.1795) (xy 401.62177 -166.169912) (xy 401.621765 -166.149466)
			(xy 401.618196 -166.139876) (xy 401.601153 -166.098472) (xy 401.574521 -166.012983) (xy 401.556618 -165.925248)
			(xy 401.547627 -165.836159) (xy 401.547076 -165.791388) (xy 401.54765 -165.746619) (xy 401.556657 -165.657534)
			(xy 401.574559 -165.569803) (xy 401.601175 -165.484311) (xy 401.618196 -165.4429) (xy 401.62177 -165.433312)
			(xy 401.621765 -165.412866) (xy 401.618196 -165.403276) (xy 401.601153 -165.361872) (xy 401.574521 -165.276383)
			(xy 401.556618 -165.188648) (xy 401.547627 -165.099559) (xy 401.547076 -165.054788) (xy 401.547541 -165.013678)
			(xy 401.55513 -164.931808) (xy 401.570241 -164.850988) (xy 401.592747 -164.771907) (xy 401.622454 -164.695241)
			(xy 401.659109 -164.621643) (xy 401.7024 -164.551742) (xy 401.751957 -164.486134) (xy 401.807357 -164.42538)
			(xy 401.868127 -164.369997) (xy 401.933748 -164.320459) (xy 402.003662 -164.277187) (xy 402.07727 -164.240553)
			(xy 402.153944 -164.210867) (xy 402.233031 -164.188384) (xy 402.313856 -164.173295) (xy 402.395728 -164.165729)
			(xy 402.436838 -164.16528) (xy 402.478442 -164.165755) (xy 402.56129 -164.173487) (xy 402.643054 -164.188917)
			(xy 402.723022 -164.21191) (xy 402.800495 -164.242266) (xy 402.874796 -164.27972) (xy 402.910294 -164.301424)
			(xy 402.919434 -164.306582) (xy 402.940149 -164.309796) (xy 402.960422 -164.304466) (xy 402.968968 -164.298376)
			(xy 403.002591 -164.27242) (xy 403.07397 -164.226364) (xy 403.149414 -164.187321) (xy 403.228235 -164.155647)
			(xy 403.309716 -164.131629) (xy 403.393116 -164.115486) (xy 403.477674 -164.107366) (xy 403.520148 -164.10686)
			(xy 403.520402 -164.10686) (xy 403.561509 -164.107311) (xy 403.643374 -164.114895) (xy 403.724189 -164.13)
			(xy 403.803267 -164.152496) (xy 403.879931 -164.182191) (xy 403.95353 -164.218831) (xy 404.023434 -164.262106)
			(xy 404.089048 -164.311644) (xy 404.149813 -164.367025) (xy 404.205209 -164.427775) (xy 404.254764 -164.493376)
			(xy 404.298057 -164.563269) (xy 404.334716 -164.636858) (xy 404.364431 -164.713515) (xy 404.386947 -164.792587)
			(xy 404.402073 -164.873398) (xy 404.409679 -164.955261) (xy 404.410164 -164.996368) (xy 404.409606 -165.041138)
			(xy 404.400594 -165.130223) (xy 404.382688 -165.217954) (xy 404.356068 -165.303445) (xy 404.339044 -165.344856)
			(xy 404.335498 -165.354452) (xy 404.335487 -165.374889) (xy 404.339044 -165.38448) (xy 404.356053 -165.425829)
			(xy 404.382663 -165.511192) (xy 404.400568 -165.598795) (xy 404.409589 -165.687753) (xy 404.410164 -165.73246)
			(xy 404.410164 -165.733476) (xy 404.40991 -165.744906) (xy 404.436389 -165.750851) (xy 404.488624 -165.765594)
			(xy 404.514304 -165.77437) (xy 404.522501 -165.776884) (xy 404.539635 -165.776884) (xy 404.547832 -165.77437)
			(xy 404.58305 -165.762429) (xy 404.655059 -165.74384) (xy 404.728382 -165.731398) (xy 404.802492 -165.725192)
			(xy 404.839678 -165.72484) (xy 404.876862 -165.725213) (xy 404.95097 -165.731434) (xy 405.02429 -165.743875)
			(xy 405.096301 -165.762448) (xy 405.131524 -165.77437) (xy 405.139721 -165.776884) (xy 405.156855 -165.776884)
			(xy 405.165052 -165.77437) (xy 405.200146 -165.76246) (xy 405.271906 -165.743916) (xy 405.344971 -165.731476)
			(xy 405.418824 -165.725229) (xy 405.455882 -165.72484) (xy 405.456898 -165.72484) (xy 405.498822 -165.725407)
			(xy 405.582291 -165.733377) (xy 405.664623 -165.749245) (xy 405.745075 -165.772868) (xy 405.822917 -165.804031)
			(xy 405.897444 -165.842452) (xy 405.967982 -165.887784) (xy 406.033891 -165.939615) (xy 406.094575 -165.997477)
			(xy 406.149484 -166.060845) (xy 406.198121 -166.129146) (xy 406.240045 -166.20176) (xy 406.274876 -166.278031)
			(xy 406.302301 -166.357268) (xy 406.322068 -166.438752) (xy 406.334001 -166.521747) (xy 406.337991 -166.6055)
			(xy 406.334001 -166.689253) (xy 406.322068 -166.772248) (xy 406.302301 -166.853732) (xy 406.274876 -166.932969)
			(xy 406.240045 -167.00924) (xy 406.198121 -167.081854) (xy 406.149484 -167.150155) (xy 406.094575 -167.213523)
			(xy 406.033891 -167.271385) (xy 405.967982 -167.323216) (xy 405.897444 -167.368548) (xy 405.822917 -167.406969)
			(xy 405.745075 -167.438132) (xy 405.664623 -167.461755) (xy 405.582291 -167.477623) (xy 405.498822 -167.485593)
			(xy 405.456898 -167.486076) (xy 405.455882 -167.486076) (xy 405.418825 -167.485672) (xy 405.344976 -167.479407)
			(xy 405.271913 -167.466964) (xy 405.200153 -167.448432) (xy 405.165052 -167.436546) (xy 405.156855 -167.434032)
			(xy 405.139721 -167.434032) (xy 405.131524 -167.436546) (xy 405.102638 -167.446383) (xy 405.043785 -167.462529)
			(xy 405.013922 -167.468804) (xy 405.004334 -167.471159) (xy 404.987889 -167.482054) (xy 404.976796 -167.498367)
			(xy 404.974298 -167.50792) (xy 404.96417 -167.552275) (xy 404.936046 -167.638805) (xy 404.918164 -167.68064)
			(xy 404.914347 -167.690579) (xy 404.914353 -167.711846) (xy 404.918164 -167.721788) (xy 404.936394 -167.764388)
			(xy 404.964909 -167.852556) (xy 404.984099 -167.943213) (xy 404.993757 -168.035373) (xy 404.994364 -168.081706)
			(xy 404.994364 -168.082214) (xy 404.99386 -168.124562) (xy 404.985809 -168.208876) (xy 404.96978 -168.292042)
			(xy 404.945919 -168.373309) (xy 404.91444 -168.451939) (xy 404.875629 -168.52722) (xy 404.829839 -168.598472)
			(xy 404.777483 -168.665048) (xy 404.719035 -168.726346) (xy 404.655025 -168.781811) (xy 404.586033 -168.83094)
			(xy 404.512683 -168.873289) (xy 404.43564 -168.908473) (xy 404.355601 -168.936175) (xy 404.273292 -168.956143)
			(xy 404.189457 -168.968196) (xy 404.104856 -168.972227) (xy 404.020255 -168.968196) (xy 403.93642 -168.956143)
			(xy 403.854111 -168.936175) (xy 403.774072 -168.908473) (xy 403.697029 -168.873289) (xy 403.623679 -168.83094)
			(xy 403.554687 -168.781811) (xy 403.490677 -168.726346) (xy 403.432229 -168.665048) (xy 403.379873 -168.598472)
			(xy 403.334083 -168.52722) (xy 403.295272 -168.451939) (xy 403.263793 -168.373309) (xy 403.239932 -168.292042)
			(xy 403.223903 -168.208876) (xy 403.215852 -168.124562) (xy 403.215348 -168.082214) (xy 403.215348 -168.081706)
			(xy 403.215963 -168.035374) (xy 403.225632 -167.943217) (xy 403.244825 -167.852563) (xy 403.273334 -167.764394)
			(xy 403.291548 -167.721788) (xy 403.295348 -167.711844) (xy 403.295353 -167.690582) (xy 403.291548 -167.68064)
			(xy 403.273311 -167.637974) (xy 403.244764 -167.549684) (xy 403.225569 -167.458899) (xy 403.215934 -167.36661)
			(xy 403.215348 -167.320214) (xy 403.215953 -167.272404) (xy 403.226131 -167.177329) (xy 403.235668 -167.130476)
			(xy 403.23764 -167.118071) (xy 403.230727 -167.093957) (xy 403.22246 -167.084502) (xy 403.18182 -167.042338)
			(xy 403.178264 -167.0431) (xy 403.169416 -167.045411) (xy 403.154053 -167.055303) (xy 403.148292 -167.062404)
			(xy 403.123137 -167.095067) (xy 403.067717 -167.15611) (xy 403.006886 -167.211763) (xy 402.941166 -167.261548)
			(xy 402.871121 -167.305037) (xy 402.797352 -167.341858) (xy 402.720492 -167.371694) (xy 402.641201 -167.39429)
			(xy 402.560159 -167.409451) (xy 402.478062 -167.417047) (xy 402.436838 -167.417496) (xy 402.395733 -167.416951)
			(xy 402.313873 -167.409371) (xy 402.233061 -167.394271) (xy 402.153987 -167.37178) (xy 402.077325 -167.342091)
			(xy 402.003729 -167.305456) (xy 401.933826 -167.262187) (xy 401.868213 -167.212655) (xy 401.80745 -167.157281)
			(xy 401.752053 -167.096538) (xy 401.702497 -167.030943) (xy 401.659203 -166.961056) (xy 401.622541 -166.887473)
			(xy 401.592824 -166.810822) (xy 401.570304 -166.731756) (xy 401.555174 -166.65095) (xy 401.547564 -166.569093)
			(xy 401.547076 -166.527988) (xy 354.289105 -166.527988) (xy 354.295389 -166.589961) (xy 354.295964 -166.634668)
			(xy 354.295964 -166.635684) (xy 354.29571 -166.647114) (xy 354.322189 -166.653059) (xy 354.374424 -166.667802)
			(xy 354.400104 -166.676578) (xy 354.408301 -166.679092) (xy 354.425435 -166.679092) (xy 354.433632 -166.676578)
			(xy 354.468848 -166.664633) (xy 354.540859 -166.646046) (xy 354.614181 -166.633606) (xy 354.688292 -166.6274)
			(xy 354.725478 -166.627048) (xy 354.762662 -166.62742) (xy 354.83677 -166.633641) (xy 354.91009 -166.646083)
			(xy 354.982101 -166.664656) (xy 355.017324 -166.676578) (xy 355.025521 -166.679092) (xy 355.042655 -166.679092)
			(xy 355.050852 -166.676578) (xy 355.085946 -166.664669) (xy 355.157706 -166.646124) (xy 355.230771 -166.633684)
			(xy 355.304624 -166.627437) (xy 355.341682 -166.627048) (xy 355.342698 -166.627048) (xy 355.384622 -166.627599)
			(xy 355.468092 -166.635569) (xy 355.550425 -166.651437) (xy 355.630878 -166.67506) (xy 355.70872 -166.706224)
			(xy 355.783248 -166.744645) (xy 355.853787 -166.789977) (xy 355.919696 -166.841809) (xy 355.980381 -166.899671)
			(xy 356.03529 -166.96304) (xy 356.083927 -167.031341) (xy 356.125852 -167.103957) (xy 356.160684 -167.180228)
			(xy 356.188108 -167.259465) (xy 356.207876 -167.340951) (xy 356.219809 -167.423946) (xy 356.223799 -167.5077)
			(xy 356.219809 -167.591454) (xy 356.207876 -167.674449) (xy 356.188108 -167.755935) (xy 356.160684 -167.835172)
			(xy 356.125852 -167.911443) (xy 356.083927 -167.984059) (xy 356.03529 -168.05236) (xy 355.980381 -168.115729)
			(xy 355.919696 -168.173591) (xy 355.853787 -168.225423) (xy 355.783248 -168.270755) (xy 355.70872 -168.309176)
			(xy 355.630878 -168.34034) (xy 355.550425 -168.363963) (xy 355.468092 -168.379831) (xy 355.384622 -168.387801)
			(xy 355.342698 -168.388284) (xy 355.341682 -168.388284) (xy 355.304625 -168.387885) (xy 355.230776 -168.381619)
			(xy 355.157713 -168.369175) (xy 355.085953 -168.350641) (xy 355.050852 -168.338754) (xy 355.042655 -168.33624)
			(xy 355.025521 -168.33624) (xy 355.017324 -168.338754) (xy 354.989546 -168.348208) (xy 354.932984 -168.363843)
			(xy 354.904294 -168.369996) (xy 354.894532 -168.372423) (xy 354.877923 -168.383747) (xy 354.866932 -168.400579)
			(xy 354.86467 -168.410382) (xy 354.855142 -168.457509) (xy 354.827269 -168.549532) (xy 354.809044 -168.594024)
			(xy 354.805459 -168.603609) (xy 354.805473 -168.624057) (xy 354.809044 -168.633648) (xy 354.826071 -168.675024)
			(xy 354.852688 -168.760451) (xy 354.870591 -168.84812) (xy 354.879599 -168.937143) (xy 354.880164 -168.981882)
			(xy 354.880164 -168.982136) (xy 354.87966 -169.024484) (xy 354.871609 -169.108798) (xy 354.85558 -169.191964)
			(xy 354.831719 -169.273231) (xy 354.80024 -169.351861) (xy 354.761429 -169.427142) (xy 354.715639 -169.498394)
			(xy 354.663283 -169.56497) (xy 354.604835 -169.626268) (xy 354.540825 -169.681733) (xy 354.471833 -169.730862)
			(xy 354.398483 -169.773211) (xy 354.32144 -169.808395) (xy 354.241401 -169.836097) (xy 354.159092 -169.856065)
			(xy 354.075257 -169.868118) (xy 353.990656 -169.872149) (xy 353.906055 -169.868118) (xy 353.82222 -169.856065)
			(xy 353.739911 -169.836097) (xy 353.659872 -169.808395) (xy 353.582829 -169.773211) (xy 353.509479 -169.730862)
			(xy 353.440487 -169.681733) (xy 353.376477 -169.626268) (xy 353.318029 -169.56497) (xy 353.265673 -169.498394)
			(xy 353.219883 -169.427142) (xy 353.181072 -169.351861) (xy 353.149593 -169.273231) (xy 353.125732 -169.191964)
			(xy 353.109703 -169.108798) (xy 353.101652 -169.024484) (xy 353.101148 -168.982136) (xy 353.101148 -168.981882)
			(xy 353.101731 -168.937144) (xy 353.110743 -168.848123) (xy 353.128644 -168.760456) (xy 353.155252 -168.675028)
			(xy 353.172268 -168.633648) (xy 353.175811 -168.624051) (xy 353.175824 -168.603615) (xy 353.172268 -168.594024)
			(xy 353.155227 -168.55262) (xy 353.128597 -168.46713) (xy 353.110694 -168.379396) (xy 353.1017 -168.290307)
			(xy 353.101148 -168.245536) (xy 353.10149 -168.209754) (xy 353.107197 -168.138419) (xy 353.118619 -168.067773)
			(xy 353.126802 -168.032938) (xy 353.128529 -168.024629) (xy 353.126997 -168.007741) (xy 353.119979 -167.992303)
			(xy 353.114356 -167.985948) (xy 353.07397 -167.943276) (xy 353.064064 -167.945308) (xy 353.055164 -167.947623)
			(xy 353.039671 -167.957504) (xy 353.033838 -167.964612) (xy 353.008691 -167.997264) (xy 352.953283 -168.058281)
			(xy 352.892469 -168.113912) (xy 352.826771 -168.163681) (xy 352.756752 -168.207161) (xy 352.683013 -168.243979)
			(xy 352.606184 -168.273821) (xy 352.526925 -168.29643) (xy 352.445915 -168.311612) (xy 352.363848 -168.319237)
			(xy 352.322638 -168.319704) (xy 352.281533 -168.319151) (xy 352.199674 -168.311571) (xy 352.118862 -168.296471)
			(xy 352.039789 -168.273981) (xy 351.963127 -168.244292) (xy 351.889531 -168.207657) (xy 351.819629 -168.164389)
			(xy 351.754016 -168.114857) (xy 351.693252 -168.059484) (xy 351.637856 -167.998741) (xy 351.5883 -167.933147)
			(xy 351.545006 -167.863261) (xy 351.508343 -167.789678) (xy 351.478626 -167.713028) (xy 351.456106 -167.633963)
			(xy 351.440975 -167.553157) (xy 351.433364 -167.471301) (xy 351.432876 -167.430196) (xy 65.688295 -167.430196)
			(xy 65.649338 -167.484902) (xy 65.594424 -167.548276) (xy 65.533735 -167.606142) (xy 65.46782 -167.657978)
			(xy 65.397276 -167.703313) (xy 65.322742 -167.741737) (xy 65.244893 -167.772902) (xy 65.164434 -167.796526)
			(xy 65.082094 -167.812395) (xy 64.998618 -167.820365) (xy 64.95669 -167.820848) (xy 64.955674 -167.820848)
			(xy 64.918617 -167.820448) (xy 64.844768 -167.814181) (xy 64.771705 -167.801738) (xy 64.699945 -167.783204)
			(xy 64.664844 -167.771318) (xy 64.656647 -167.768804) (xy 64.639513 -167.768804) (xy 64.631316 -167.771318)
			(xy 64.597889 -167.782662) (xy 64.529607 -167.80059) (xy 64.494918 -167.807132) (xy 64.484907 -167.809437)
			(xy 64.467748 -167.820693) (xy 64.456372 -167.837772) (xy 64.454024 -167.847772) (xy 64.44452 -167.895628)
			(xy 64.416383 -167.989057) (xy 64.39789 -168.034208) (xy 64.394248 -168.043772) (xy 64.394124 -168.064219)
			(xy 64.397636 -168.073832) (xy 64.414658 -168.11521) (xy 64.441276 -168.200636) (xy 64.459181 -168.288304)
			(xy 64.46819 -168.377327) (xy 64.468756 -168.422066) (xy 64.468756 -168.42232) (xy 64.468252 -168.464668)
			(xy 64.460201 -168.548982) (xy 64.444172 -168.632148) (xy 64.420311 -168.713415) (xy 64.388832 -168.792045)
			(xy 64.350021 -168.867326) (xy 64.304231 -168.938578) (xy 64.251875 -169.005154) (xy 64.193427 -169.066452)
			(xy 64.129417 -169.121917) (xy 64.060425 -169.171046) (xy 63.987075 -169.213395) (xy 63.910032 -169.248579)
			(xy 63.829993 -169.276281) (xy 63.747684 -169.296249) (xy 63.663849 -169.308302) (xy 63.579248 -169.312333)
			(xy 63.494647 -169.308302) (xy 63.410812 -169.296249) (xy 63.328503 -169.276281) (xy 63.248464 -169.248579)
			(xy 63.171421 -169.213395) (xy 63.098071 -169.171046) (xy 63.029079 -169.121917) (xy 62.965069 -169.066452)
			(xy 62.906621 -169.005154) (xy 62.854265 -168.938578) (xy 62.808475 -168.867326) (xy 62.769664 -168.792045)
			(xy 62.738185 -168.713415) (xy 62.714324 -168.632148) (xy 62.698295 -168.548982) (xy 62.690244 -168.464668)
			(xy 62.68974 -168.42232) (xy 62.68974 -168.422066) (xy 62.690311 -168.377328) (xy 62.699325 -168.288306)
			(xy 62.71723 -168.200639) (xy 62.743842 -168.115211) (xy 62.76086 -168.073832) (xy 62.764412 -168.064238)
			(xy 62.76442 -168.043799) (xy 62.76086 -168.034208) (xy 62.743813 -167.992806) (xy 62.717185 -167.907315)
			(xy 62.699284 -167.81958) (xy 62.690292 -167.730491) (xy 62.68974 -167.68572) (xy 62.689828 -167.668048)
			(xy 62.691224 -167.632732) (xy 62.692534 -167.615108) (xy 62.692907 -167.605036) (xy 62.68662 -167.585904)
			(xy 62.673425 -167.57069) (xy 62.664594 -167.565832) (xy 62.566296 -167.516556) (xy 62.535816 -167.520366)
			(xy 62.524132 -167.53078) (xy 62.493735 -167.556935) (xy 62.428993 -167.604263) (xy 62.360251 -167.645567)
			(xy 62.288069 -167.680512) (xy 62.213032 -167.708812) (xy 62.135751 -167.730238) (xy 62.056854 -167.744617)
			(xy 61.976982 -167.75183) (xy 61.936884 -167.752268) (xy 61.93663 -167.752268) (xy 61.895524 -167.751759)
			(xy 61.813662 -167.744177) (xy 61.732849 -167.729076) (xy 61.653773 -167.706584) (xy 61.57711 -167.676893)
			(xy 61.503513 -167.640256) (xy 61.433609 -167.596985) (xy 61.367995 -167.547451) (xy 61.307231 -167.492074)
			(xy 61.251835 -167.431328) (xy 61.202279 -167.36573) (xy 61.158986 -167.295841) (xy 61.122325 -167.222256)
			(xy 61.092608 -167.145602) (xy 61.07009 -167.066534) (xy 61.054963 -166.985725) (xy 61.047355 -166.903866)
			(xy 61.046868 -166.86276) (xy 2.509012 -166.86276) (xy 2.509012 -170.29303) (xy 8.7249 -170.29303)
			(xy 8.7249 -169.42943) (xy 8.725386 -169.402179) (xy 8.733142 -169.348231) (xy 8.748497 -169.295936)
			(xy 8.771139 -169.246359) (xy 8.800605 -169.200509) (xy 8.836296 -169.159318) (xy 8.877487 -169.123627)
			(xy 8.923337 -169.094161) (xy 8.972914 -169.071519) (xy 9.025209 -169.056164) (xy 9.079157 -169.048408)
			(xy 9.133659 -169.048408) (xy 9.187607 -169.056164) (xy 9.239902 -169.071519) (xy 9.289479 -169.094161)
			(xy 9.335329 -169.123627) (xy 9.37652 -169.159318) (xy 9.412211 -169.200509) (xy 9.441677 -169.246359)
			(xy 9.464319 -169.295936) (xy 9.479674 -169.348231) (xy 9.48743 -169.402179) (xy 9.487916 -169.42943)
			(xy 9.487916 -169.857674) (xy 111.084868 -169.857674) (xy 111.085438 -169.812905) (xy 111.094447 -169.72382)
			(xy 111.112349 -169.636089) (xy 111.138966 -169.550597) (xy 111.155988 -169.509186) (xy 111.15957 -169.4996)
			(xy 111.15956 -169.479153) (xy 111.155988 -169.469562) (xy 111.13894 -169.42816) (xy 111.112309 -169.34267)
			(xy 111.094408 -169.254935) (xy 111.085418 -169.165845) (xy 111.084868 -169.121074) (xy 111.085438 -169.076305)
			(xy 111.094447 -168.98722) (xy 111.112349 -168.899489) (xy 111.138966 -168.813997) (xy 111.155988 -168.772586)
			(xy 111.15957 -168.763) (xy 111.15956 -168.742553) (xy 111.155988 -168.732962) (xy 111.13894 -168.69156)
			(xy 111.112309 -168.60607) (xy 111.094408 -168.518335) (xy 111.085418 -168.429245) (xy 111.084868 -168.384474)
			(xy 111.085274 -168.343358) (xy 111.092864 -168.261476) (xy 111.107976 -168.180645) (xy 111.130482 -168.101552)
			(xy 111.160191 -168.024873) (xy 111.196847 -167.951263) (xy 111.240139 -167.881349) (xy 111.289697 -167.815728)
			(xy 111.345099 -167.754959) (xy 111.405871 -167.699561) (xy 111.471495 -167.650007) (xy 111.541412 -167.60672)
			(xy 111.615025 -167.570068) (xy 111.691705 -167.540365) (xy 111.770799 -167.517863) (xy 111.851632 -167.502756)
			(xy 111.933514 -167.495171) (xy 111.97463 -167.494712) (xy 112.016241 -167.495173) (xy 112.099098 -167.502953)
			(xy 112.180867 -167.518431) (xy 112.260835 -167.541474) (xy 112.338303 -167.571879) (xy 112.412595 -167.609382)
			(xy 112.448086 -167.63111) (xy 112.457229 -167.636263) (xy 112.477942 -167.63948) (xy 112.498214 -167.634152)
			(xy 112.50676 -167.628062) (xy 112.540389 -167.602071) (xy 112.611783 -167.555946) (xy 112.687254 -167.516845)
			(xy 112.766112 -167.485124) (xy 112.847637 -167.461075) (xy 112.931085 -167.444915) (xy 113.015695 -167.436793)
			(xy 113.058194 -167.436292) (xy 113.099307 -167.436819) (xy 113.181182 -167.444405) (xy 113.262007 -167.459513)
			(xy 113.341094 -167.482013) (xy 113.417768 -167.511715) (xy 113.491374 -167.548365) (xy 113.561284 -167.59165)
			(xy 113.626903 -167.6412) (xy 113.68767 -167.696593) (xy 113.743067 -167.757357) (xy 113.792621 -167.822973)
			(xy 113.83591 -167.892881) (xy 113.872564 -167.966485) (xy 113.90227 -168.043156) (xy 113.924776 -168.122242)
			(xy 113.939888 -168.203067) (xy 113.947479 -168.284941) (xy 113.947956 -168.326054) (xy 113.947393 -168.370824)
			(xy 113.938383 -168.459909) (xy 113.920477 -168.54764) (xy 113.893859 -168.633131) (xy 113.876836 -168.674542)
			(xy 113.873299 -168.684141) (xy 113.873282 -168.704576) (xy 113.876836 -168.714166) (xy 113.89384 -168.755517)
			(xy 113.920451 -168.840879) (xy 113.938358 -168.928482) (xy 113.94738 -169.017439) (xy 113.947956 -169.062146)
			(xy 113.947956 -169.063162) (xy 113.947702 -169.074592) (xy 113.974181 -169.080538) (xy 114.026416 -169.095281)
			(xy 114.052096 -169.104056) (xy 114.060293 -169.10657) (xy 114.077427 -169.10657) (xy 114.085624 -169.104056)
			(xy 114.12084 -169.092095) (xy 114.192844 -169.073441) (xy 114.266165 -169.060932) (xy 114.34028 -169.054659)
			(xy 114.37747 -169.054272) (xy 114.414659 -169.054671) (xy 114.488772 -169.060958) (xy 114.562092 -169.073465)
			(xy 114.634098 -169.092103) (xy 114.669316 -169.104056) (xy 114.677513 -169.10657) (xy 114.694647 -169.10657)
			(xy 114.702844 -169.104056) (xy 114.738059 -169.092089) (xy 114.810062 -169.073437) (xy 114.883384 -169.06093)
			(xy 114.9575 -169.054658) (xy 114.99469 -169.054272) (xy 115.03663 -169.054667) (xy 115.120132 -169.062639)
			(xy 115.202497 -169.078513) (xy 115.28298 -169.102144) (xy 115.360853 -169.133319) (xy 115.43541 -169.171755)
			(xy 115.505975 -169.217104) (xy 115.57191 -169.268955) (xy 115.632618 -169.326839) (xy 115.687549 -169.390232)
			(xy 115.736205 -169.458559) (xy 115.778146 -169.531202) (xy 115.812991 -169.607503) (xy 115.840426 -169.68677)
			(xy 115.860202 -169.768287) (xy 115.87214 -169.851314) (xy 115.876131 -169.9351) (xy 115.87214 -170.018886)
			(xy 115.860202 -170.101913) (xy 115.840426 -170.18343) (xy 115.812991 -170.262697) (xy 115.778146 -170.338998)
			(xy 115.736205 -170.411641) (xy 115.687549 -170.479968) (xy 115.632618 -170.543361) (xy 115.57191 -170.601245)
			(xy 115.505975 -170.653096) (xy 115.498571 -170.657854) (xy 161.052951 -170.657854) (xy 161.052951 -170.603346)
			(xy 161.060709 -170.549393) (xy 161.076066 -170.497093) (xy 161.09871 -170.447511) (xy 161.12818 -170.401657)
			(xy 161.163876 -170.360463) (xy 161.205071 -170.324769) (xy 161.250927 -170.295301) (xy 161.30051 -170.27266)
			(xy 161.352811 -170.257305) (xy 161.406764 -170.24955) (xy 161.434018 -170.249088) (xy 162.297618 -170.249088)
			(xy 162.324868 -170.249583) (xy 162.378813 -170.257342) (xy 162.431105 -170.272698) (xy 162.48068 -170.29534)
			(xy 162.526528 -170.324806) (xy 162.567715 -170.360498) (xy 162.603404 -170.401687) (xy 162.632869 -170.447536)
			(xy 162.655508 -170.497111) (xy 162.670862 -170.549404) (xy 162.678618 -170.60335) (xy 162.678618 -170.65785)
			(xy 162.670862 -170.711796) (xy 162.655508 -170.764089) (xy 162.632869 -170.813664) (xy 162.603404 -170.859513)
			(xy 162.567715 -170.900702) (xy 162.526528 -170.936394) (xy 162.48068 -170.96586) (xy 162.431105 -170.988502)
			(xy 162.378813 -171.003858) (xy 162.324868 -171.011617) (xy 162.297618 -171.012104) (xy 161.434018 -171.012104)
			(xy 161.406764 -171.01165) (xy 161.352811 -171.003895) (xy 161.30051 -170.98854) (xy 161.250927 -170.965899)
			(xy 161.205071 -170.936431) (xy 161.163876 -170.900737) (xy 161.12818 -170.859543) (xy 161.09871 -170.813689)
			(xy 161.076066 -170.764107) (xy 161.060709 -170.711807) (xy 161.052951 -170.657854) (xy 115.498571 -170.657854)
			(xy 115.43541 -170.698445) (xy 115.360853 -170.736881) (xy 115.28298 -170.768056) (xy 115.202497 -170.791687)
			(xy 115.120132 -170.807561) (xy 115.03663 -170.815533) (xy 114.99469 -170.816016) (xy 114.9575 -170.815629)
			(xy 114.883387 -170.809339) (xy 114.810068 -170.796828) (xy 114.738062 -170.778187) (xy 114.702844 -170.766232)
			(xy 114.694647 -170.763718) (xy 114.677513 -170.763718) (xy 114.669316 -170.766232) (xy 114.625188 -170.781068)
			(xy 114.534574 -170.80245) (xy 114.488468 -170.808904) (xy 114.478735 -170.810567) (xy 114.461516 -170.820188)
			(xy 114.449244 -170.83563) (xy 114.44605 -170.844972) (xy 114.43848 -170.870441) (xy 114.420685 -170.920512)
			(xy 114.41049 -170.945048) (xy 114.406882 -170.954622) (xy 114.406736 -170.97506) (xy 114.410236 -170.984672)
			(xy 114.427271 -171.026045) (xy 114.453886 -171.111473) (xy 114.471787 -171.199143) (xy 114.480792 -171.288167)
			(xy 114.481356 -171.332906) (xy 114.481356 -171.33316) (xy 114.480852 -171.375508) (xy 114.472801 -171.459822)
			(xy 114.456772 -171.542988) (xy 114.432911 -171.624255) (xy 114.401432 -171.702885) (xy 114.362621 -171.778166)
			(xy 114.316831 -171.849418) (xy 114.264475 -171.915994) (xy 114.206027 -171.977292) (xy 114.142017 -172.032757)
			(xy 114.073025 -172.081886) (xy 113.999675 -172.124235) (xy 113.922632 -172.159419) (xy 113.842593 -172.187121)
			(xy 113.760284 -172.207089) (xy 113.676449 -172.219142) (xy 113.591848 -172.223173) (xy 113.507247 -172.219142)
			(xy 113.423412 -172.207089) (xy 113.341103 -172.187121) (xy 113.261064 -172.159419) (xy 113.184021 -172.124235)
			(xy 113.110671 -172.081886) (xy 113.041679 -172.032757) (xy 112.977669 -171.977292) (xy 112.919221 -171.915994)
			(xy 112.866865 -171.849418) (xy 112.821075 -171.778166) (xy 112.782264 -171.702885) (xy 112.750785 -171.624255)
			(xy 112.726924 -171.542988) (xy 112.710895 -171.459822) (xy 112.702844 -171.375508) (xy 112.70234 -171.33316)
			(xy 112.70234 -171.332906) (xy 112.702891 -171.288167) (xy 112.711911 -171.199145) (xy 112.729821 -171.111478)
			(xy 112.75644 -171.026051) (xy 112.77346 -170.984672) (xy 112.777047 -170.975088) (xy 112.777032 -170.954639)
			(xy 112.77346 -170.945048) (xy 112.757652 -170.906707) (xy 112.732373 -170.827716) (xy 112.714548 -170.746717)
			(xy 112.70433 -170.664411) (xy 112.702594 -170.622976) (xy 112.702594 -170.622722) (xy 112.701955 -170.613271)
			(xy 112.694549 -170.595846) (xy 112.681333 -170.582289) (xy 112.672876 -170.578018) (xy 112.589818 -170.540172)
			(xy 112.581121 -170.536666) (xy 112.562416 -170.535564) (xy 112.544562 -170.541248) (xy 112.536986 -170.546776)
			(xy 112.536986 -170.54703) (xy 112.536478 -170.54703) (xy 112.502475 -170.574102) (xy 112.430107 -170.622247)
			(xy 112.353386 -170.663099) (xy 112.273043 -170.696267) (xy 112.189846 -170.721435) (xy 112.104591 -170.738363)
			(xy 112.01809 -170.746889) (xy 111.97463 -170.747436) (xy 111.933515 -170.746973) (xy 111.851635 -170.739388)
			(xy 111.770804 -170.72428) (xy 111.691713 -170.701779) (xy 111.615035 -170.672075) (xy 111.541425 -170.635423)
			(xy 111.471511 -170.592135) (xy 111.405889 -170.542581) (xy 111.34512 -170.487183) (xy 111.289722 -170.426414)
			(xy 111.240167 -170.360793) (xy 111.196879 -170.290879) (xy 111.160226 -170.217269) (xy 111.130522 -170.140591)
			(xy 111.10802 -170.061499) (xy 111.092912 -169.980669) (xy 111.085327 -169.898789) (xy 111.084868 -169.857674)
			(xy 9.487916 -169.857674) (xy 9.487916 -170.29303) (xy 9.48743 -170.320281) (xy 9.479674 -170.374229)
			(xy 9.464319 -170.426524) (xy 9.441677 -170.476101) (xy 9.412211 -170.521951) (xy 9.37652 -170.563142)
			(xy 9.335329 -170.598833) (xy 9.289479 -170.628299) (xy 9.239902 -170.650941) (xy 9.187607 -170.666296)
			(xy 9.133659 -170.674052) (xy 9.079157 -170.674052) (xy 9.025209 -170.666296) (xy 8.972914 -170.650941)
			(xy 8.923337 -170.628299) (xy 8.877487 -170.598833) (xy 8.836296 -170.563142) (xy 8.800605 -170.521951)
			(xy 8.771139 -170.476101) (xy 8.748497 -170.426524) (xy 8.733142 -170.374229) (xy 8.725386 -170.320281)
			(xy 8.7249 -170.29303) (xy 2.509012 -170.29303) (xy 2.509012 -173.07814) (xy 8.7249 -173.07814) (xy 8.7249 -172.21454)
			(xy 8.725386 -172.187289) (xy 8.733142 -172.133341) (xy 8.748497 -172.081046) (xy 8.771139 -172.031469)
			(xy 8.800605 -171.985619) (xy 8.836296 -171.944428) (xy 8.877487 -171.908737) (xy 8.923337 -171.879271)
			(xy 8.972914 -171.856629) (xy 9.025209 -171.841274) (xy 9.079157 -171.833518) (xy 9.133659 -171.833518)
			(xy 9.187607 -171.841274) (xy 9.239902 -171.856629) (xy 9.289479 -171.879271) (xy 9.335329 -171.908737)
			(xy 9.37652 -171.944428) (xy 9.412211 -171.985619) (xy 9.441677 -172.031469) (xy 9.464319 -172.081046)
			(xy 9.479674 -172.133341) (xy 9.48743 -172.187289) (xy 9.487916 -172.21454) (xy 9.487916 -173.07814)
			(xy 9.48743 -173.105391) (xy 9.479674 -173.159339) (xy 9.464319 -173.211634) (xy 9.441677 -173.261211)
			(xy 9.412211 -173.307061) (xy 9.37652 -173.348252) (xy 9.335329 -173.383943) (xy 9.289479 -173.413409)
			(xy 9.239902 -173.436051) (xy 9.187607 -173.451406) (xy 9.133659 -173.459162) (xy 9.079157 -173.459162)
			(xy 9.025209 -173.451406) (xy 8.972914 -173.436051) (xy 8.923337 -173.413409) (xy 8.877487 -173.383943)
			(xy 8.836296 -173.348252) (xy 8.800605 -173.307061) (xy 8.771139 -173.261211) (xy 8.748497 -173.211634)
			(xy 8.733142 -173.159339) (xy 8.725386 -173.105391) (xy 8.7249 -173.07814) (xy 2.509012 -173.07814)
			(xy 2.509012 -175.848264) (xy 8.7249 -175.848264) (xy 8.7249 -174.984664) (xy 8.725386 -174.957413)
			(xy 8.733142 -174.903465) (xy 8.748497 -174.85117) (xy 8.771139 -174.801593) (xy 8.800605 -174.755743)
			(xy 8.836296 -174.714552) (xy 8.877487 -174.678861) (xy 8.923337 -174.649395) (xy 8.972914 -174.626753)
			(xy 9.025209 -174.611398) (xy 9.079157 -174.603642) (xy 9.133659 -174.603642) (xy 9.187607 -174.611398)
			(xy 9.239902 -174.626753) (xy 9.289479 -174.649395) (xy 9.335329 -174.678861) (xy 9.37652 -174.714552)
			(xy 9.412211 -174.755743) (xy 9.441677 -174.801593) (xy 9.464319 -174.85117) (xy 9.479674 -174.903465)
			(xy 9.48743 -174.957413) (xy 9.487916 -174.984664) (xy 9.487916 -175.559974) (xy 69.360288 -175.559974)
			(xy 69.360857 -175.515205) (xy 69.369865 -175.42612) (xy 69.387768 -175.338388) (xy 69.414386 -175.252897)
			(xy 69.431408 -175.211486) (xy 69.434989 -175.2019) (xy 69.43498 -175.181453) (xy 69.431408 -175.171862)
			(xy 69.414355 -175.130462) (xy 69.387726 -175.044971) (xy 69.369827 -174.957236) (xy 69.360838 -174.868145)
			(xy 69.360288 -174.823374) (xy 69.360857 -174.778605) (xy 69.369865 -174.68952) (xy 69.387768 -174.601788)
			(xy 69.414386 -174.516297) (xy 69.431408 -174.474886) (xy 69.434989 -174.4653) (xy 69.43498 -174.444853)
			(xy 69.431408 -174.435262) (xy 69.414355 -174.393862) (xy 69.387726 -174.308371) (xy 69.369827 -174.220636)
			(xy 69.360838 -174.131545) (xy 69.360288 -174.086774) (xy 69.360674 -174.045657) (xy 69.368264 -173.963775)
			(xy 69.383377 -173.882942) (xy 69.405884 -173.803848) (xy 69.435593 -173.727169) (xy 69.47225 -173.653557)
			(xy 69.515543 -173.583643) (xy 69.565103 -173.518021) (xy 69.620506 -173.457252) (xy 69.681279 -173.401854)
			(xy 69.746905 -173.3523) (xy 69.816824 -173.309013) (xy 69.890438 -173.272362) (xy 69.96712 -173.24266)
			(xy 70.046216 -173.220159) (xy 70.12705 -173.205053) (xy 70.208933 -173.19747) (xy 70.25005 -173.197012)
			(xy 70.29166 -173.197513) (xy 70.374516 -173.205285) (xy 70.456284 -173.220756) (xy 70.536252 -173.243791)
			(xy 70.613721 -173.274189) (xy 70.688014 -173.311686) (xy 70.723506 -173.33341) (xy 70.73264 -173.338581)
			(xy 70.753359 -173.341792) (xy 70.773635 -173.336456) (xy 70.78218 -173.330362) (xy 70.815836 -173.304408)
			(xy 70.887226 -173.258279) (xy 70.962691 -173.219173) (xy 71.041544 -173.187448) (xy 71.123065 -173.163392)
			(xy 71.20651 -173.147226) (xy 71.291116 -173.139097) (xy 71.333614 -173.138592) (xy 71.374727 -173.139099)
			(xy 71.456602 -173.146687) (xy 71.537428 -173.161797) (xy 71.616516 -173.1843) (xy 71.693189 -173.214003)
			(xy 71.703445 -173.21911) (xy 393.739116 -173.21911) (xy 393.739743 -173.172708) (xy 393.749432 -173.08041)
			(xy 393.768686 -172.989625) (xy 393.797294 -172.90134) (xy 393.81557 -172.858684) (xy 393.819371 -172.84874)
			(xy 393.819374 -172.827478) (xy 393.81557 -172.817536) (xy 393.797307 -172.774875) (xy 393.768715 -172.686587)
			(xy 393.749458 -172.595804) (xy 393.739745 -172.503511) (xy 393.739116 -172.45711) (xy 393.739622 -172.415997)
			(xy 393.747208 -172.33412) (xy 393.762316 -172.253293) (xy 393.784818 -172.174205) (xy 393.81452 -172.097531)
			(xy 393.851171 -172.023924) (xy 393.894457 -171.954012) (xy 393.944008 -171.888393) (xy 393.999403 -171.827626)
			(xy 394.060168 -171.772229) (xy 394.125786 -171.722675) (xy 394.195696 -171.679387) (xy 394.269301 -171.642733)
			(xy 394.345975 -171.613028) (xy 394.425062 -171.590524) (xy 394.505889 -171.575413) (xy 394.587765 -171.567824)
			(xy 394.628878 -171.567348) (xy 394.670013 -171.567796) (xy 394.75193 -171.575416) (xy 394.832794 -171.590566)
			(xy 394.911913 -171.613115) (xy 394.988614 -171.642872) (xy 395.06224 -171.679583) (xy 395.132163 -171.722933)
			(xy 395.197785 -171.772553) (xy 395.258547 -171.828019) (xy 395.313929 -171.888856) (xy 395.339062 -171.921424)
			(xy 395.345281 -171.928954) (xy 395.36201 -171.939002) (xy 395.371574 -171.940982) (xy 395.41286 -171.948033)
			(xy 395.493962 -171.968978) (xy 395.572736 -171.997455) (xy 395.648484 -172.033212) (xy 395.720535 -172.075931)
			(xy 395.78825 -172.125234) (xy 395.851031 -172.180685) (xy 395.908321 -172.241793) (xy 395.959613 -172.308015)
			(xy 396.004452 -172.378766) (xy 396.042441 -172.453419) (xy 396.073244 -172.531313) (xy 396.096588 -172.611757)
			(xy 396.112266 -172.69404) (xy 396.120139 -172.777432) (xy 396.12062 -172.819314) (xy 396.120152 -172.860082)
			(xy 396.112652 -172.941273) (xy 396.097752 -173.021436) (xy 396.075577 -173.099899) (xy 396.046313 -173.176003)
			(xy 396.028672 -173.21276) (xy 396.024359 -173.222451) (xy 396.023438 -173.243625) (xy 396.026894 -173.253654)
			(xy 396.041217 -173.292003) (xy 396.063564 -173.370761) (xy 396.07857 -173.451241) (xy 396.086111 -173.53276)
			(xy 396.086584 -173.573694) (xy 396.086007 -173.618463) (xy 396.077001 -173.707548) (xy 396.0591 -173.795279)
			(xy 396.032485 -173.880771) (xy 396.015464 -173.922182) (xy 396.011903 -173.931774) (xy 396.0119 -173.952215)
			(xy 396.015464 -173.961806) (xy 396.032477 -174.003153) (xy 396.059087 -174.088517) (xy 396.076991 -174.17612)
			(xy 396.08601 -174.265079) (xy 396.086584 -174.309786) (xy 396.086584 -174.310802) (xy 396.08633 -174.322232)
			(xy 396.112809 -174.328178) (xy 396.165044 -174.342921) (xy 396.190724 -174.351696) (xy 396.198921 -174.35421)
			(xy 396.216055 -174.35421) (xy 396.224252 -174.351696) (xy 396.259466 -174.339729) (xy 396.33147 -174.321076)
			(xy 396.404792 -174.308569) (xy 396.478908 -174.302297) (xy 396.516098 -174.301912) (xy 396.553288 -174.302301)
			(xy 396.627401 -174.30859) (xy 396.70072 -174.3211) (xy 396.772726 -174.339741) (xy 396.807944 -174.351696)
			(xy 396.816141 -174.35421) (xy 396.833275 -174.35421) (xy 396.841472 -174.351696) (xy 396.876685 -174.339723)
			(xy 396.948689 -174.321072) (xy 397.022011 -174.308567) (xy 397.096127 -174.302297) (xy 397.133318 -174.301912)
			(xy 397.175254 -174.302444) (xy 397.258746 -174.310418) (xy 397.341102 -174.326292) (xy 397.421577 -174.349923)
			(xy 397.49944 -174.381096) (xy 397.573988 -174.41953) (xy 397.644545 -174.464875) (xy 397.710473 -174.516722)
			(xy 397.771173 -174.574601) (xy 397.826097 -174.637988) (xy 397.874747 -174.706309) (xy 397.916683 -174.778944)
			(xy 397.951524 -174.855237) (xy 397.978955 -174.934497) (xy 397.998729 -175.016005) (xy 398.010665 -175.099023)
			(xy 398.014656 -175.1828) (xy 398.010665 -175.266577) (xy 397.998729 -175.349595) (xy 397.978955 -175.431103)
			(xy 397.951524 -175.510363) (xy 397.916683 -175.586656) (xy 397.874747 -175.659291) (xy 397.826097 -175.727612)
			(xy 397.771173 -175.790999) (xy 397.710473 -175.848878) (xy 397.644545 -175.900725) (xy 397.573988 -175.94607)
			(xy 397.49944 -175.984504) (xy 397.421577 -176.015677) (xy 397.341102 -176.039308) (xy 397.258746 -176.055182)
			(xy 397.175254 -176.063156) (xy 397.133318 -176.063656) (xy 397.096129 -176.063259) (xy 397.022016 -176.056971)
			(xy 396.948696 -176.044464) (xy 396.87669 -176.025825) (xy 396.841472 -176.013872) (xy 396.833275 -176.011358)
			(xy 396.816141 -176.011358) (xy 396.807944 -176.013872) (xy 396.778999 -176.023726) (xy 396.720017 -176.039869)
			(xy 396.690088 -176.04613) (xy 396.680511 -176.048515) (xy 396.664071 -176.059402) (xy 396.652972 -176.0757)
			(xy 396.650464 -176.085246) (xy 396.640294 -176.12901) (xy 396.612299 -176.21439) (xy 396.594584 -176.25568)
			(xy 396.590807 -176.265631) (xy 396.590789 -176.286886) (xy 396.594584 -176.296828) (xy 396.612789 -176.339438)
			(xy 396.641312 -176.427603) (xy 396.660509 -176.518256) (xy 396.670174 -176.610414) (xy 396.670784 -176.656746)
			(xy 396.670784 -176.657254) (xy 396.67028 -176.699602) (xy 396.662229 -176.783916) (xy 396.6462 -176.867082)
			(xy 396.622339 -176.948349) (xy 396.59086 -177.026979) (xy 396.552049 -177.10226) (xy 396.506259 -177.173512)
			(xy 396.453903 -177.240088) (xy 396.395455 -177.301386) (xy 396.331445 -177.356851) (xy 396.262453 -177.40598)
			(xy 396.189103 -177.448329) (xy 396.11206 -177.483513) (xy 396.032021 -177.511215) (xy 395.949712 -177.531183)
			(xy 395.865877 -177.543236) (xy 395.781276 -177.547267) (xy 395.696675 -177.543236) (xy 395.61284 -177.531183)
			(xy 395.530531 -177.511215) (xy 395.450492 -177.483513) (xy 395.373449 -177.448329) (xy 395.300099 -177.40598)
			(xy 395.231107 -177.356851) (xy 395.167097 -177.301386) (xy 395.108649 -177.240088) (xy 395.056293 -177.173512)
			(xy 395.010503 -177.10226) (xy 394.971692 -177.026979) (xy 394.940213 -176.948349) (xy 394.916352 -176.867082)
			(xy 394.900323 -176.783916) (xy 394.892272 -176.699602) (xy 394.891768 -176.657254) (xy 394.891768 -176.656746)
			(xy 394.892395 -176.610415) (xy 394.902061 -176.518257) (xy 394.92125 -176.427603) (xy 394.949756 -176.339434)
			(xy 394.967968 -176.296828) (xy 394.971802 -176.286894) (xy 394.971784 -176.265622) (xy 394.967968 -176.25568)
			(xy 394.949707 -176.213025) (xy 394.921167 -176.12473) (xy 394.901979 -176.033943) (xy 394.89235 -175.941651)
			(xy 394.891768 -175.895254) (xy 394.89209 -175.858508) (xy 394.898067 -175.785262) (xy 394.903706 -175.74895)
			(xy 394.905149 -175.737024) (xy 394.898112 -175.714088) (xy 394.890244 -175.705008) (xy 394.824966 -175.637698)
			(xy 394.80236 -175.629824) (xy 394.790168 -175.631602) (xy 394.748357 -175.636737) (xy 394.664175 -175.639973)
			(xy 394.580064 -175.635239) (xy 394.496776 -175.622575) (xy 394.415059 -175.602096) (xy 394.335643 -175.573985)
			(xy 394.259239 -175.538493) (xy 394.186532 -175.495939) (xy 394.118173 -175.446704) (xy 394.054773 -175.391227)
			(xy 393.996901 -175.330007) (xy 393.945075 -175.26359) (xy 393.899757 -175.192573) (xy 393.861356 -175.11759)
			(xy 393.830213 -175.039313) (xy 393.806608 -174.958443) (xy 393.790753 -174.875704) (xy 393.782789 -174.791836)
			(xy 393.782296 -174.749714) (xy 393.782793 -174.706976) (xy 393.790968 -174.621894) (xy 393.807264 -174.537986)
			(xy 393.831529 -174.456028) (xy 393.847066 -174.416212) (xy 393.850705 -174.406179) (xy 393.85003 -174.384863)
			(xy 393.845796 -174.375064) (xy 393.828734 -174.338786) (xy 393.800425 -174.263775) (xy 393.778984 -174.18652)
			(xy 393.764586 -174.107649) (xy 393.757348 -174.027801) (xy 393.756896 -173.987714) (xy 393.757452 -173.943459)
			(xy 393.766275 -173.855391) (xy 393.783795 -173.768633) (xy 393.809839 -173.684042) (xy 393.826492 -173.643036)
			(xy 393.830085 -173.632871) (xy 393.829579 -173.611348) (xy 393.825476 -173.60138) (xy 393.808875 -173.565511)
			(xy 393.781358 -173.491412) (xy 393.760529 -173.415162) (xy 393.746554 -173.337364) (xy 393.739543 -173.258632)
			(xy 393.739116 -173.21911) (xy 71.703445 -173.21911) (xy 71.766795 -173.250654) (xy 71.836706 -173.29394)
			(xy 71.902324 -173.343492) (xy 71.963091 -173.398886) (xy 72.018488 -173.459651) (xy 72.068042 -173.525268)
			(xy 72.11133 -173.595177) (xy 72.147984 -173.668781) (xy 72.17769 -173.745454) (xy 72.200196 -173.82454)
			(xy 72.215308 -173.905366) (xy 72.222899 -173.987241) (xy 72.223376 -174.028354) (xy 72.22282 -174.073124)
			(xy 72.213808 -174.162209) (xy 72.195901 -174.24994) (xy 72.16928 -174.335431) (xy 72.152256 -174.376842)
			(xy 72.148718 -174.38644) (xy 72.148701 -174.406876) (xy 72.152256 -174.416466) (xy 72.169272 -174.457846)
			(xy 72.195896 -174.543271) (xy 72.213802 -174.630939) (xy 72.222811 -174.719961) (xy 72.223376 -174.7647)
			(xy 72.223376 -174.765208) (xy 72.223122 -174.77867) (xy 72.249601 -174.784615) (xy 72.301836 -174.799358)
			(xy 72.327516 -174.808134) (xy 72.335713 -174.810648) (xy 72.352847 -174.810648) (xy 72.361044 -174.808134)
			(xy 72.39626 -174.796188) (xy 72.46827 -174.777601) (xy 72.541593 -174.765161) (xy 72.615704 -174.758956)
			(xy 72.65289 -174.758604) (xy 72.690074 -174.75897) (xy 72.764182 -174.765192) (xy 72.837502 -174.777635)
			(xy 72.909513 -174.796211) (xy 72.944736 -174.808134) (xy 72.952933 -174.810648) (xy 72.970067 -174.810648)
			(xy 72.978264 -174.808134) (xy 73.013366 -174.796247) (xy 73.085122 -174.777697) (xy 73.158185 -174.765251)
			(xy 73.232036 -174.758997) (xy 73.269094 -174.758604) (xy 73.27011 -174.758604) (xy 73.312036 -174.759059)
			(xy 73.395508 -174.767031) (xy 73.477845 -174.7829) (xy 73.5583 -174.806525) (xy 73.636145 -174.83769)
			(xy 73.710676 -174.876114) (xy 73.781216 -174.921448) (xy 73.847128 -174.973283) (xy 73.907814 -175.031148)
			(xy 73.962725 -175.094519) (xy 74.011364 -175.162823) (xy 74.053289 -175.235441) (xy 74.088123 -175.311716)
			(xy 74.115548 -175.390956) (xy 74.135316 -175.472444) (xy 74.14725 -175.555443) (xy 74.15124 -175.6392)
			(xy 74.14725 -175.722957) (xy 74.135316 -175.805956) (xy 74.115548 -175.887444) (xy 74.088123 -175.966684)
			(xy 74.053289 -176.042959) (xy 74.01685 -176.106074) (xy 102.855268 -176.106074) (xy 102.855838 -176.061305)
			(xy 102.864847 -175.97222) (xy 102.882749 -175.884489) (xy 102.909366 -175.798997) (xy 102.926388 -175.757586)
			(xy 102.92997 -175.748) (xy 102.92996 -175.727553) (xy 102.926388 -175.717962) (xy 102.90934 -175.67656)
			(xy 102.882709 -175.59107) (xy 102.864808 -175.503335) (xy 102.855818 -175.414245) (xy 102.855268 -175.369474)
			(xy 102.855838 -175.324705) (xy 102.864847 -175.23562) (xy 102.882749 -175.147889) (xy 102.909366 -175.062397)
			(xy 102.926388 -175.020986) (xy 102.92997 -175.0114) (xy 102.92996 -174.990953) (xy 102.926388 -174.981362)
			(xy 102.90934 -174.93996) (xy 102.882709 -174.85447) (xy 102.864808 -174.766735) (xy 102.855818 -174.677645)
			(xy 102.855268 -174.632874) (xy 102.855674 -174.591758) (xy 102.863264 -174.509876) (xy 102.878376 -174.429045)
			(xy 102.900882 -174.349952) (xy 102.930591 -174.273273) (xy 102.967247 -174.199663) (xy 103.010539 -174.129749)
			(xy 103.060097 -174.064128) (xy 103.115499 -174.003359) (xy 103.176271 -173.947961) (xy 103.241895 -173.898407)
			(xy 103.311812 -173.85512) (xy 103.385425 -173.818468) (xy 103.462105 -173.788765) (xy 103.541199 -173.766263)
			(xy 103.622032 -173.751156) (xy 103.703914 -173.743571) (xy 103.74503 -173.743112) (xy 103.786641 -173.743573)
			(xy 103.869498 -173.751353) (xy 103.951267 -173.766831) (xy 104.031235 -173.789874) (xy 104.108703 -173.820279)
			(xy 104.182995 -173.857782) (xy 104.218486 -173.87951) (xy 104.227629 -173.884663) (xy 104.248342 -173.88788)
			(xy 104.268614 -173.882552) (xy 104.27716 -173.876462) (xy 104.310789 -173.850471) (xy 104.382183 -173.804346)
			(xy 104.457654 -173.765245) (xy 104.536512 -173.733524) (xy 104.618037 -173.709475) (xy 104.701485 -173.693315)
			(xy 104.786095 -173.685193) (xy 104.828594 -173.684692) (xy 104.869707 -173.685219) (xy 104.951582 -173.692805)
			(xy 105.032407 -173.707913) (xy 105.111494 -173.730413) (xy 105.188168 -173.760115) (xy 105.261774 -173.796765)
			(xy 105.331684 -173.84005) (xy 105.397303 -173.8896) (xy 105.45807 -173.944993) (xy 105.513467 -174.005757)
			(xy 105.563021 -174.071373) (xy 105.60631 -174.141281) (xy 105.642964 -174.214885) (xy 105.67267 -174.291556)
			(xy 105.695176 -174.370642) (xy 105.710288 -174.451467) (xy 105.717879 -174.533341) (xy 105.718356 -174.574454)
			(xy 105.717793 -174.619224) (xy 105.708783 -174.708309) (xy 105.690877 -174.79604) (xy 105.664259 -174.881531)
			(xy 105.647236 -174.922942) (xy 105.643699 -174.932541) (xy 105.643682 -174.952976) (xy 105.647236 -174.962566)
			(xy 105.66424 -175.003917) (xy 105.690851 -175.089279) (xy 105.708758 -175.176882) (xy 105.71778 -175.265839)
			(xy 105.718356 -175.310546) (xy 105.718356 -175.311562) (xy 105.718102 -175.322992) (xy 105.744581 -175.328938)
			(xy 105.796816 -175.343681) (xy 105.822496 -175.352456) (xy 105.830693 -175.35497) (xy 105.847827 -175.35497)
			(xy 105.856024 -175.352456) (xy 105.89124 -175.340495) (xy 105.963244 -175.321841) (xy 106.036565 -175.309332)
			(xy 106.11068 -175.303059) (xy 106.14787 -175.302672) (xy 106.185059 -175.303071) (xy 106.259172 -175.309358)
			(xy 106.332492 -175.321865) (xy 106.404498 -175.340503) (xy 106.439716 -175.352456) (xy 106.447913 -175.35497)
			(xy 106.465047 -175.35497) (xy 106.473244 -175.352456) (xy 106.508459 -175.340489) (xy 106.580462 -175.321837)
			(xy 106.653784 -175.30933) (xy 106.7279 -175.303058) (xy 106.76509 -175.302672) (xy 106.80703 -175.303067)
			(xy 106.890532 -175.311039) (xy 106.972897 -175.326913) (xy 107.05338 -175.350544) (xy 107.131253 -175.381719)
			(xy 107.20581 -175.420155) (xy 107.276375 -175.465504) (xy 107.34231 -175.517355) (xy 107.403018 -175.575239)
			(xy 107.457949 -175.638632) (xy 107.505577 -175.705516) (xy 359.713276 -175.705516) (xy 359.713826 -175.660746)
			(xy 359.72284 -175.571661) (xy 359.740749 -175.48393) (xy 359.767371 -175.398439) (xy 359.784396 -175.357028)
			(xy 359.787954 -175.347435) (xy 359.78796 -175.326994) (xy 359.784396 -175.317404) (xy 359.767362 -175.275997)
			(xy 359.740727 -175.190508) (xy 359.722822 -175.102775) (xy 359.713828 -175.013687) (xy 359.713276 -174.968916)
			(xy 359.713826 -174.924146) (xy 359.72284 -174.835061) (xy 359.740749 -174.74733) (xy 359.767371 -174.661839)
			(xy 359.784396 -174.620428) (xy 359.787954 -174.610835) (xy 359.78796 -174.590394) (xy 359.784396 -174.580804)
			(xy 359.767362 -174.539397) (xy 359.740727 -174.453908) (xy 359.722822 -174.366175) (xy 359.713828 -174.277087)
			(xy 359.713276 -174.232316) (xy 359.713768 -174.191206) (xy 359.721354 -174.109337) (xy 359.736463 -174.028517)
			(xy 359.758966 -173.949437) (xy 359.788671 -173.872771) (xy 359.825324 -173.799173) (xy 359.868613 -173.729272)
			(xy 359.918168 -173.663664) (xy 359.973567 -173.602909) (xy 360.034335 -173.547526) (xy 360.099955 -173.497988)
			(xy 360.169867 -173.454716) (xy 360.243474 -173.418081) (xy 360.320148 -173.388396) (xy 360.399234 -173.365912)
			(xy 360.480057 -173.350823) (xy 360.561928 -173.343257) (xy 360.603038 -173.342808) (xy 360.644642 -173.343279)
			(xy 360.72749 -173.351011) (xy 360.809255 -173.366441) (xy 360.889223 -173.389435) (xy 360.966695 -173.419793)
			(xy 361.040997 -173.457248) (xy 361.076494 -173.478952) (xy 361.08563 -173.48412) (xy 361.106349 -173.487339)
			(xy 361.126625 -173.482001) (xy 361.135168 -173.475904) (xy 361.168794 -173.449952) (xy 361.240172 -173.403895)
			(xy 361.315615 -173.364851) (xy 361.394436 -173.333176) (xy 361.475917 -173.309157) (xy 361.559316 -173.293014)
			(xy 361.643874 -173.284894) (xy 361.686348 -173.284388) (xy 361.686602 -173.284388) (xy 361.72771 -173.284811)
			(xy 361.809576 -173.292396) (xy 361.890393 -173.307501) (xy 361.969472 -173.329998) (xy 362.046138 -173.359694)
			(xy 362.119738 -173.396336) (xy 362.189643 -173.439612) (xy 362.255258 -173.489152) (xy 362.316023 -173.544534)
			(xy 362.371419 -173.605287) (xy 362.420974 -173.67089) (xy 362.464266 -173.740786) (xy 362.500925 -173.814377)
			(xy 362.530638 -173.891036) (xy 362.553153 -173.97011) (xy 362.568276 -174.050924) (xy 362.57588 -174.132788)
			(xy 362.576364 -174.173896) (xy 362.575781 -174.218665) (xy 362.566776 -174.307749) (xy 362.548877 -174.395481)
			(xy 362.522264 -174.480972) (xy 362.505244 -174.522384) (xy 362.501683 -174.531976) (xy 362.501681 -174.552417)
			(xy 362.505244 -174.562008) (xy 362.522284 -174.603413) (xy 362.548917 -174.688902) (xy 362.56682 -174.776636)
			(xy 362.575812 -174.865725) (xy 362.576364 -174.910496) (xy 362.575094 -174.953676) (xy 362.575044 -174.965402)
			(xy 362.584373 -174.986895) (xy 362.602231 -175.002063) (xy 362.613448 -175.005492) (xy 362.632331 -175.010413)
			(xy 362.669682 -175.021721) (xy 362.688124 -175.028098) (xy 362.696321 -175.030612) (xy 362.713455 -175.030612)
			(xy 362.721652 -175.028098) (xy 362.756876 -175.016176) (xy 362.828883 -174.997583) (xy 362.902204 -174.985136)
			(xy 362.976313 -174.978924) (xy 363.013498 -174.978568) (xy 363.050682 -174.978934) (xy 363.12479 -174.985156)
			(xy 363.19811 -174.997599) (xy 363.270121 -175.016175) (xy 363.305344 -175.028098) (xy 363.313541 -175.030612)
			(xy 363.330675 -175.030612) (xy 363.338872 -175.028098) (xy 363.373974 -175.016212) (xy 363.44573 -174.997661)
			(xy 363.518793 -174.985214) (xy 363.592644 -174.978961) (xy 363.629702 -174.978568) (xy 363.630718 -174.978568)
			(xy 363.672642 -174.979095) (xy 363.75611 -174.987067) (xy 363.838443 -175.002937) (xy 363.918894 -175.026561)
			(xy 363.996736 -175.057726) (xy 364.071262 -175.096148) (xy 364.141799 -175.141481) (xy 364.207708 -175.193313)
			(xy 364.268391 -175.251175) (xy 364.323299 -175.314544) (xy 364.371935 -175.382845) (xy 364.413859 -175.45546)
			(xy 364.44869 -175.531731) (xy 364.476114 -175.610968) (xy 364.495881 -175.692452) (xy 364.507814 -175.775447)
			(xy 364.511804 -175.8592) (xy 364.507814 -175.942953) (xy 364.495881 -176.025948) (xy 364.476114 -176.107432)
			(xy 364.44869 -176.186669) (xy 364.413859 -176.26294) (xy 364.371935 -176.335555) (xy 364.323299 -176.403856)
			(xy 364.268391 -176.467225) (xy 364.207708 -176.525087) (xy 364.141799 -176.576919) (xy 364.071262 -176.622252)
			(xy 363.996736 -176.660674) (xy 363.918894 -176.691839) (xy 363.838443 -176.715463) (xy 363.75611 -176.731333)
			(xy 363.672642 -176.739305) (xy 363.630718 -176.739804) (xy 363.629702 -176.739804) (xy 363.592645 -176.739398)
			(xy 363.518796 -176.733134) (xy 363.445733 -176.720692) (xy 363.373973 -176.70216) (xy 363.338872 -176.690274)
			(xy 363.330675 -176.68776) (xy 363.313541 -176.68776) (xy 363.305344 -176.690274) (xy 363.271298 -176.701763)
			(xy 363.201741 -176.719817) (xy 363.166406 -176.726342) (xy 363.157048 -176.728326) (xy 363.140733 -176.738296)
			(xy 363.129218 -176.75356) (xy 363.126274 -176.762664) (xy 363.118487 -176.78918) (xy 363.100057 -176.841287)
			(xy 363.089444 -176.866804) (xy 363.085871 -176.876392) (xy 363.085877 -176.896837) (xy 363.089444 -176.906428)
			(xy 363.106465 -176.947806) (xy 363.133084 -177.033233) (xy 363.150988 -177.120901) (xy 363.159998 -177.209923)
			(xy 363.160564 -177.254662) (xy 363.160564 -177.254916) (xy 363.16006 -177.297264) (xy 363.152009 -177.381578)
			(xy 363.13598 -177.464744) (xy 363.112119 -177.546011) (xy 363.08064 -177.624641) (xy 363.041829 -177.699922)
			(xy 362.996039 -177.771174) (xy 362.943683 -177.83775) (xy 362.885235 -177.899048) (xy 362.821225 -177.954513)
			(xy 362.752233 -178.003642) (xy 362.678883 -178.045991) (xy 362.60184 -178.081175) (xy 362.521801 -178.108877)
			(xy 362.439492 -178.128845) (xy 362.355657 -178.140898) (xy 362.271056 -178.144929) (xy 362.186455 -178.140898)
			(xy 362.10262 -178.128845) (xy 362.020311 -178.108877) (xy 361.940272 -178.081175) (xy 361.863229 -178.045991)
			(xy 361.789879 -178.003642) (xy 361.720887 -177.954513) (xy 361.656877 -177.899048) (xy 361.598429 -177.83775)
			(xy 361.546073 -177.771174) (xy 361.500283 -177.699922) (xy 361.461472 -177.624641) (xy 361.429993 -177.546011)
			(xy 361.406132 -177.464744) (xy 361.390103 -177.381578) (xy 361.382052 -177.297264) (xy 361.381548 -177.254916)
			(xy 361.381548 -177.254662) (xy 361.382124 -177.209924) (xy 361.391138 -177.120903) (xy 361.409041 -177.033235)
			(xy 361.435651 -176.947807) (xy 361.452668 -176.906428) (xy 361.456222 -176.896834) (xy 361.456228 -176.876395)
			(xy 361.452668 -176.866804) (xy 361.435658 -176.825422) (xy 361.409036 -176.739997) (xy 361.391129 -176.65233)
			(xy 361.382115 -176.563308) (xy 361.381548 -176.51857) (xy 361.381548 -176.518316) (xy 361.38189 -176.482968)
			(xy 361.387504 -176.412495) (xy 361.39869 -176.34269) (xy 361.406694 -176.308258) (xy 361.409002 -176.295757)
			(xy 361.402463 -176.271224) (xy 361.394248 -176.261522) (xy 361.353608 -176.218596) (xy 361.34421 -176.220628)
			(xy 361.335443 -176.222892) (xy 361.32021 -176.232657) (xy 361.314492 -176.239678) (xy 361.289344 -176.272353)
			(xy 361.233931 -176.333418) (xy 361.173106 -176.389094) (xy 361.10739 -176.438902) (xy 361.037347 -176.482416)
			(xy 360.963578 -176.519263) (xy 360.886716 -176.549126) (xy 360.807421 -176.571748) (xy 360.726373 -176.586937)
			(xy 360.644268 -176.594561) (xy 360.603038 -176.595024) (xy 360.561931 -176.594551) (xy 360.480067 -176.58697)
			(xy 360.399251 -176.571868) (xy 360.320173 -176.549375) (xy 360.243508 -176.519683) (xy 360.169909 -176.483044)
			(xy 360.100004 -176.439772) (xy 360.034389 -176.390235) (xy 359.973624 -176.334856) (xy 359.918228 -176.274107)
			(xy 359.868672 -176.208506) (xy 359.825379 -176.138613) (xy 359.78872 -176.065025) (xy 359.759005 -175.988368)
			(xy 359.73649 -175.909296) (xy 359.721365 -175.828485) (xy 359.713761 -175.746623) (xy 359.713276 -175.705516)
			(xy 107.505577 -175.705516) (xy 107.506605 -175.706959) (xy 107.548546 -175.779602) (xy 107.583391 -175.855903)
			(xy 107.610826 -175.93517) (xy 107.630602 -176.016687) (xy 107.64254 -176.099714) (xy 107.646531 -176.1835)
			(xy 107.64254 -176.267286) (xy 107.630602 -176.350313) (xy 107.610826 -176.43183) (xy 107.583391 -176.511097)
			(xy 107.548546 -176.587398) (xy 107.506605 -176.660041) (xy 107.457949 -176.728368) (xy 107.403018 -176.791761)
			(xy 107.34231 -176.849645) (xy 107.276375 -176.901496) (xy 107.20581 -176.946845) (xy 107.131253 -176.985281)
			(xy 107.05338 -177.016456) (xy 106.972897 -177.040087) (xy 106.890532 -177.055961) (xy 106.80703 -177.063933)
			(xy 106.76509 -177.064416) (xy 106.7279 -177.064029) (xy 106.653787 -177.057739) (xy 106.580468 -177.045228)
			(xy 106.508462 -177.026587) (xy 106.473244 -177.014632) (xy 106.465047 -177.012118) (xy 106.447913 -177.012118)
			(xy 106.439716 -177.014632) (xy 106.394061 -177.029945) (xy 106.300252 -177.051713) (xy 106.252518 -177.058066)
			(xy 106.242041 -177.059824) (xy 106.223772 -177.070618) (xy 106.211473 -177.087908) (xy 106.20883 -177.098198)
			(xy 106.199325 -177.142161) (xy 106.1726 -177.22805) (xy 106.15549 -177.269648) (xy 106.151882 -177.279222)
			(xy 106.151736 -177.29966) (xy 106.155236 -177.309272) (xy 106.172271 -177.350645) (xy 106.198886 -177.436073)
			(xy 106.216787 -177.523743) (xy 106.225792 -177.612767) (xy 106.226356 -177.657506) (xy 106.226356 -177.65776)
			(xy 106.225852 -177.700108) (xy 106.217801 -177.784422) (xy 106.201772 -177.867588) (xy 106.177911 -177.948855)
			(xy 106.146432 -178.027485) (xy 106.107621 -178.102766) (xy 106.061831 -178.174018) (xy 106.009475 -178.240594)
			(xy 105.951027 -178.301892) (xy 105.887017 -178.357357) (xy 105.818025 -178.406486) (xy 105.744675 -178.448835)
			(xy 105.667632 -178.484019) (xy 105.587593 -178.511721) (xy 105.505284 -178.531689) (xy 105.421449 -178.543742)
			(xy 105.336848 -178.547773) (xy 105.252247 -178.543742) (xy 105.168412 -178.531689) (xy 105.086103 -178.511721)
			(xy 105.006064 -178.484019) (xy 104.929021 -178.448835) (xy 104.855671 -178.406486) (xy 104.786679 -178.357357)
			(xy 104.722669 -178.301892) (xy 104.664221 -178.240594) (xy 104.611865 -178.174018) (xy 104.566075 -178.102766)
			(xy 104.527264 -178.027485) (xy 104.495785 -177.948855) (xy 104.471924 -177.867588) (xy 104.455895 -177.784422)
			(xy 104.447844 -177.700108) (xy 104.44734 -177.65776) (xy 104.44734 -177.657506) (xy 104.447891 -177.612767)
			(xy 104.456911 -177.523745) (xy 104.474821 -177.436078) (xy 104.50144 -177.350651) (xy 104.51846 -177.309272)
			(xy 104.522047 -177.299688) (xy 104.522032 -177.279239) (xy 104.51846 -177.269648) (xy 104.501426 -177.228241)
			(xy 104.474794 -177.142752) (xy 104.456889 -177.055019) (xy 104.447894 -176.965931) (xy 104.44734 -176.92116)
			(xy 104.447594 -176.89703) (xy 104.44745 -176.887477) (xy 104.440882 -176.869548) (xy 104.428227 -176.855249)
			(xy 104.419908 -176.850548) (xy 104.33812 -176.808638) (xy 104.329507 -176.804642) (xy 104.310627 -176.802733)
			(xy 104.292347 -176.807824) (xy 104.284526 -176.81321) (xy 104.284526 -176.813464) (xy 104.284018 -176.813464)
			(xy 104.250823 -176.838169) (xy 104.180649 -176.882028) (xy 104.106709 -176.919187) (xy 104.029639 -176.949324)
			(xy 103.950105 -176.97218) (xy 103.868793 -176.987556) (xy 103.786406 -176.995321) (xy 103.74503 -176.995836)
			(xy 103.703915 -176.995373) (xy 103.622035 -176.987788) (xy 103.541204 -176.97268) (xy 103.462113 -176.950179)
			(xy 103.385435 -176.920475) (xy 103.311825 -176.883823) (xy 103.241911 -176.840535) (xy 103.176289 -176.790981)
			(xy 103.11552 -176.735583) (xy 103.060122 -176.674814) (xy 103.010567 -176.609193) (xy 102.967279 -176.539279)
			(xy 102.930626 -176.465669) (xy 102.900922 -176.388991) (xy 102.87842 -176.309899) (xy 102.863312 -176.229069)
			(xy 102.855727 -176.147189) (xy 102.855268 -176.106074) (xy 74.01685 -176.106074) (xy 74.011364 -176.115577)
			(xy 73.962725 -176.183881) (xy 73.907814 -176.247252) (xy 73.847128 -176.305117) (xy 73.781216 -176.356952)
			(xy 73.710676 -176.402286) (xy 73.636145 -176.44071) (xy 73.5583 -176.471875) (xy 73.477845 -176.4955)
			(xy 73.395508 -176.511369) (xy 73.312036 -176.519341) (xy 73.27011 -176.51984) (xy 73.269094 -176.51984)
			(xy 73.232037 -176.519434) (xy 73.158188 -176.51317) (xy 73.085125 -176.500728) (xy 73.013365 -176.482196)
			(xy 72.978264 -176.47031) (xy 72.970067 -176.467796) (xy 72.952933 -176.467796) (xy 72.944736 -176.47031)
			(xy 72.910756 -176.481853) (xy 72.841327 -176.500034) (xy 72.806052 -176.506632) (xy 72.796116 -176.508916)
			(xy 72.779041 -176.520017) (xy 72.767603 -176.536869) (xy 72.765158 -176.546764) (xy 72.755578 -176.591455)
			(xy 72.728473 -176.67875) (xy 72.711056 -176.721008) (xy 72.70748 -176.730595) (xy 72.707488 -176.751041)
			(xy 72.711056 -176.760632) (xy 72.728073 -176.802012) (xy 72.754694 -176.887437) (xy 72.7726 -176.975105)
			(xy 72.78161 -177.064127) (xy 72.782176 -177.108866) (xy 72.782176 -177.10912) (xy 72.781672 -177.151468)
			(xy 72.773621 -177.235782) (xy 72.757592 -177.318948) (xy 72.733731 -177.400215) (xy 72.702252 -177.478845)
			(xy 72.663441 -177.554126) (xy 72.617651 -177.625378) (xy 72.565295 -177.691954) (xy 72.506847 -177.753252)
			(xy 72.442837 -177.808717) (xy 72.373845 -177.857846) (xy 72.300495 -177.900195) (xy 72.223452 -177.935379)
			(xy 72.143413 -177.963081) (xy 72.061104 -177.983049) (xy 71.977269 -177.995102) (xy 71.892668 -177.999133)
			(xy 71.808067 -177.995102) (xy 71.724232 -177.983049) (xy 71.641923 -177.963081) (xy 71.561884 -177.935379)
			(xy 71.484841 -177.900195) (xy 71.411491 -177.857846) (xy 71.342499 -177.808717) (xy 71.278489 -177.753252)
			(xy 71.220041 -177.691954) (xy 71.167685 -177.625378) (xy 71.121895 -177.554126) (xy 71.083084 -177.478845)
			(xy 71.051605 -177.400215) (xy 71.027744 -177.318948) (xy 71.011715 -177.235782) (xy 71.003664 -177.151468)
			(xy 71.00316 -177.10912) (xy 71.00316 -177.108866) (xy 71.003737 -177.064128) (xy 71.01275 -176.975107)
			(xy 71.030653 -176.887439) (xy 71.057263 -176.802011) (xy 71.07428 -176.760632) (xy 71.077831 -176.751038)
			(xy 71.077839 -176.730599) (xy 71.07428 -176.721008) (xy 71.057235 -176.679605) (xy 71.030605 -176.594115)
			(xy 71.012704 -176.50638) (xy 71.003712 -176.417291) (xy 71.00316 -176.37252) (xy 71.003216 -176.357395)
			(xy 71.004231 -176.327162) (xy 71.005192 -176.312068) (xy 71.005427 -176.302019) (xy 70.999034 -176.282984)
			(xy 70.985815 -176.267867) (xy 70.976998 -176.263046) (xy 70.8787 -176.214532) (xy 70.84822 -176.218596)
			(xy 70.83679 -176.228756) (xy 70.806403 -176.254854) (xy 70.741691 -176.302073) (xy 70.672994 -176.343279)
			(xy 70.60087 -176.378141) (xy 70.525902 -176.406374) (xy 70.4487 -176.427751) (xy 70.369887 -176.442098)
			(xy 70.290104 -176.449298) (xy 70.25005 -176.449736) (xy 70.208935 -176.449254) (xy 70.127056 -176.441671)
			(xy 70.046226 -176.426565) (xy 69.967134 -176.404065) (xy 69.890456 -176.374363) (xy 69.816846 -176.337712)
			(xy 69.746932 -176.294426) (xy 69.68131 -176.244873) (xy 69.620541 -176.189476) (xy 69.565143 -176.128708)
			(xy 69.515588 -176.063088) (xy 69.472299 -175.993175) (xy 69.435647 -175.919566) (xy 69.405943 -175.842889)
			(xy 69.383441 -175.763798) (xy 69.368332 -175.682968) (xy 69.360747 -175.601089) (xy 69.360288 -175.559974)
			(xy 9.487916 -175.559974) (xy 9.487916 -175.848264) (xy 9.48743 -175.875515) (xy 9.479674 -175.929463)
			(xy 9.464319 -175.981758) (xy 9.441677 -176.031335) (xy 9.412211 -176.077185) (xy 9.37652 -176.118376)
			(xy 9.335329 -176.154067) (xy 9.289479 -176.183533) (xy 9.239902 -176.206175) (xy 9.187607 -176.22153)
			(xy 9.133659 -176.229286) (xy 9.079157 -176.229286) (xy 9.025209 -176.22153) (xy 8.972914 -176.206175)
			(xy 8.923337 -176.183533) (xy 8.877487 -176.154067) (xy 8.836296 -176.118376) (xy 8.800605 -176.077185)
			(xy 8.771139 -176.031335) (xy 8.748497 -175.981758) (xy 8.733142 -175.929463) (xy 8.725386 -175.875515)
			(xy 8.7249 -175.848264) (xy 2.509012 -175.848264) (xy 2.509012 -178.618388) (xy 8.7249 -178.618388)
			(xy 8.7249 -177.754788) (xy 8.725386 -177.727537) (xy 8.733142 -177.673589) (xy 8.748497 -177.621294)
			(xy 8.771139 -177.571717) (xy 8.800605 -177.525867) (xy 8.836296 -177.484676) (xy 8.877487 -177.448985)
			(xy 8.923337 -177.419519) (xy 8.972914 -177.396877) (xy 9.025209 -177.381522) (xy 9.079157 -177.373766)
			(xy 9.133659 -177.373766) (xy 9.187607 -177.381522) (xy 9.239902 -177.396877) (xy 9.289479 -177.419519)
			(xy 9.335329 -177.448985) (xy 9.37652 -177.484676) (xy 9.412211 -177.525867) (xy 9.441677 -177.571717)
			(xy 9.464319 -177.621294) (xy 9.479674 -177.673589) (xy 9.48743 -177.727537) (xy 9.487916 -177.754788)
			(xy 9.487916 -178.618388) (xy 9.48743 -178.645639) (xy 9.479674 -178.699587) (xy 9.464319 -178.751882)
			(xy 9.44304 -178.798474) (xy 77.963268 -178.798474) (xy 77.963886 -178.752072) (xy 77.973579 -178.659774)
			(xy 77.992835 -178.568989) (xy 78.021445 -178.480704) (xy 78.039722 -178.438048) (xy 78.043541 -178.42811)
			(xy 78.043531 -178.406843) (xy 78.039722 -178.3969) (xy 78.021451 -178.354243) (xy 77.99286 -178.265953)
			(xy 77.973605 -178.175169) (xy 77.963896 -178.082875) (xy 77.963268 -178.036474) (xy 77.963674 -177.995358)
			(xy 77.971264 -177.913476) (xy 77.986376 -177.832645) (xy 78.008882 -177.753552) (xy 78.038591 -177.676873)
			(xy 78.075247 -177.603263) (xy 78.118539 -177.533349) (xy 78.168097 -177.467728) (xy 78.223499 -177.406959)
			(xy 78.284271 -177.351561) (xy 78.349895 -177.302007) (xy 78.419812 -177.25872) (xy 78.493425 -177.222068)
			(xy 78.570105 -177.192365) (xy 78.649199 -177.169863) (xy 78.730032 -177.154756) (xy 78.811914 -177.147171)
			(xy 78.85303 -177.146712) (xy 78.893848 -177.147168) (xy 78.975141 -177.154659) (xy 79.055405 -177.169568)
			(xy 79.133966 -177.191768) (xy 79.210162 -177.221072) (xy 79.283352 -177.257234) (xy 79.352922 -177.29995)
			(xy 79.418285 -177.348861) (xy 79.478892 -177.403555) (xy 79.534233 -177.463571) (xy 79.559404 -177.495708)
			(xy 79.565179 -177.502627) (xy 79.580393 -177.512264) (xy 79.589122 -177.514504) (xy 79.631283 -177.524073)
			(xy 79.713687 -177.550242) (xy 79.793163 -177.584282) (xy 79.868962 -177.625872) (xy 79.940368 -177.67462)
			(xy 80.006708 -177.730066) (xy 80.067355 -177.791686) (xy 80.121738 -177.8589) (xy 80.169343 -177.931073)
			(xy 80.209721 -178.007525) (xy 80.242492 -178.087533) (xy 80.267345 -178.170343) (xy 80.284047 -178.255173)
			(xy 80.29244 -178.341224) (xy 80.292956 -178.384454) (xy 80.292766 -178.411062) (xy 80.289588 -178.464184)
			(xy 80.286606 -178.490626) (xy 80.285833 -178.501873) (xy 80.292962 -178.523233) (xy 80.300322 -178.531774)
			(xy 80.329261 -178.562798) (xy 80.381784 -178.629432) (xy 80.427728 -178.700761) (xy 80.466676 -178.776139)
			(xy 80.498274 -178.854881) (xy 80.522235 -178.936272) (xy 80.538342 -179.019574) (xy 80.546449 -179.104032)
			(xy 80.546956 -179.146454) (xy 80.546393 -179.191224) (xy 80.537383 -179.280309) (xy 80.519477 -179.36804)
			(xy 80.492859 -179.453531) (xy 80.475836 -179.494942) (xy 80.472299 -179.504541) (xy 80.472282 -179.524976)
			(xy 80.475836 -179.534566) (xy 80.49284 -179.575917) (xy 80.519451 -179.661279) (xy 80.537358 -179.748882)
			(xy 80.54638 -179.837839) (xy 80.546956 -179.882546) (xy 80.546956 -179.883562) (xy 80.546702 -179.894992)
			(xy 80.573181 -179.900938) (xy 80.625416 -179.915681) (xy 80.651096 -179.924456) (xy 80.659293 -179.92697)
			(xy 80.676427 -179.92697) (xy 80.684624 -179.924456) (xy 80.71984 -179.912495) (xy 80.791844 -179.893841)
			(xy 80.865165 -179.881332) (xy 80.93928 -179.875059) (xy 80.97647 -179.874672) (xy 81.013659 -179.875071)
			(xy 81.087772 -179.881358) (xy 81.161092 -179.893865) (xy 81.233098 -179.912503) (xy 81.268316 -179.924456)
			(xy 81.276513 -179.92697) (xy 81.293647 -179.92697) (xy 81.301844 -179.924456) (xy 81.337059 -179.912489)
			(xy 81.409062 -179.893837) (xy 81.482384 -179.88133) (xy 81.5565 -179.875058) (xy 81.59369 -179.874672)
			(xy 81.63563 -179.875067) (xy 81.719132 -179.883039) (xy 81.801497 -179.898913) (xy 81.88198 -179.922544)
			(xy 81.959853 -179.953719) (xy 82.03441 -179.992155) (xy 82.104975 -180.037504) (xy 82.17091 -180.089355)
			(xy 82.231618 -180.147239) (xy 82.286549 -180.210632) (xy 82.335205 -180.278959) (xy 82.377146 -180.351602)
			(xy 82.411991 -180.427903) (xy 82.439426 -180.50717) (xy 82.459202 -180.588687) (xy 82.462267 -180.610002)
			(xy 86.081108 -180.610002) (xy 86.081685 -180.565233) (xy 86.090691 -180.476148) (xy 86.108592 -180.388417)
			(xy 86.135207 -180.302925) (xy 86.152228 -180.261514) (xy 86.155792 -180.251923) (xy 86.155793 -180.231481)
			(xy 86.152228 -180.22189) (xy 86.135186 -180.180486) (xy 86.108554 -180.094996) (xy 86.090651 -180.007262)
			(xy 86.081659 -179.918173) (xy 86.081108 -179.873402) (xy 86.081685 -179.828633) (xy 86.090691 -179.739548)
			(xy 86.108592 -179.651817) (xy 86.135207 -179.566325) (xy 86.152228 -179.524914) (xy 86.155792 -179.515323)
			(xy 86.155793 -179.494881) (xy 86.152228 -179.48529) (xy 86.135186 -179.443886) (xy 86.108554 -179.358396)
			(xy 86.090651 -179.270662) (xy 86.081659 -179.181573) (xy 86.081108 -179.136802) (xy 86.081615 -179.095689)
			(xy 86.089201 -179.013813) (xy 86.10431 -178.932986) (xy 86.126812 -178.853898) (xy 86.156515 -178.777224)
			(xy 86.193165 -178.703617) (xy 86.236451 -178.633706) (xy 86.286003 -178.568087) (xy 86.341397 -178.50732)
			(xy 86.402163 -178.451923) (xy 86.46778 -178.402369) (xy 86.537689 -178.359081) (xy 86.611295 -178.322428)
			(xy 86.687968 -178.292722) (xy 86.767055 -178.270217) (xy 86.847881 -178.255106) (xy 86.929757 -178.247516)
			(xy 86.97087 -178.24704) (xy 87.01248 -178.247527) (xy 87.095336 -178.255301) (xy 87.177105 -178.270774)
			(xy 87.257073 -178.293812) (xy 87.334542 -178.324213) (xy 87.408835 -178.361712) (xy 87.444326 -178.383438)
			(xy 87.453453 -178.388623) (xy 87.474176 -178.391826) (xy 87.494454 -178.386485) (xy 87.503 -178.38039)
			(xy 87.536641 -178.354416) (xy 87.608034 -178.30829) (xy 87.683503 -178.269188) (xy 87.762359 -178.237466)
			(xy 87.843882 -178.213414) (xy 87.927328 -178.19725) (xy 88.011936 -178.189124) (xy 88.054434 -178.18862)
			(xy 88.095548 -178.18908) (xy 88.177426 -178.19667) (xy 88.258254 -178.211782) (xy 88.337343 -178.234287)
			(xy 88.414018 -178.263994) (xy 88.487625 -178.300648) (xy 88.557536 -178.343937) (xy 88.623155 -178.393491)
			(xy 88.683922 -178.448889) (xy 88.739319 -178.509657) (xy 88.788872 -178.575277) (xy 88.83216 -178.645189)
			(xy 88.868813 -178.718797) (xy 88.898518 -178.795473) (xy 88.921021 -178.874562) (xy 88.936132 -178.95539)
			(xy 88.94372 -179.037268) (xy 88.944196 -179.078382) (xy 88.943648 -179.123152) (xy 88.934633 -179.212238)
			(xy 88.916724 -179.299969) (xy 88.890101 -179.38546) (xy 88.873076 -179.42687) (xy 88.869521 -179.436464)
			(xy 88.869514 -179.456904) (xy 88.873076 -179.466494) (xy 88.890086 -179.507843) (xy 88.916696 -179.593206)
			(xy 88.934602 -179.680809) (xy 88.943621 -179.769767) (xy 88.944196 -179.814474) (xy 88.944196 -179.81549)
			(xy 88.943942 -179.82692) (xy 88.970422 -179.832862) (xy 89.022656 -179.847607) (xy 89.048336 -179.856384)
			(xy 89.056533 -179.858898) (xy 89.073667 -179.858898) (xy 89.081864 -179.856384) (xy 89.117077 -179.844413)
			(xy 89.189082 -179.825761) (xy 89.262404 -179.813256) (xy 89.33652 -179.806985) (xy 89.37371 -179.8066)
			(xy 89.4109 -179.806986) (xy 89.485013 -179.813277) (xy 89.558333 -179.825787) (xy 89.630338 -179.844429)
			(xy 89.665556 -179.856384) (xy 89.673753 -179.858898) (xy 89.690887 -179.858898) (xy 89.699084 -179.856384)
			(xy 89.734295 -179.844408) (xy 89.8063 -179.825757) (xy 89.879623 -179.813253) (xy 89.953739 -179.806984)
			(xy 89.99093 -179.8066) (xy 90.032865 -179.807156) (xy 90.116355 -179.815131) (xy 90.198709 -179.831006)
			(xy 90.279182 -179.854637) (xy 90.357043 -179.885811) (xy 90.431589 -179.924244) (xy 90.502144 -179.969589)
			(xy 90.56807 -180.021436) (xy 90.628768 -180.079314) (xy 90.683691 -180.1427) (xy 90.732339 -180.211019)
			(xy 90.774274 -180.283653) (xy 90.809114 -180.359944) (xy 90.836544 -180.439202) (xy 90.856317 -180.520708)
			(xy 90.868253 -180.603725) (xy 90.869375 -180.627274) (xy 94.473268 -180.627274) (xy 94.473838 -180.582505)
			(xy 94.482847 -180.49342) (xy 94.500749 -180.405689) (xy 94.527366 -180.320197) (xy 94.544388 -180.278786)
			(xy 94.54797 -180.2692) (xy 94.54796 -180.248753) (xy 94.544388 -180.239162) (xy 94.52734 -180.19776)
			(xy 94.500709 -180.11227) (xy 94.482808 -180.024535) (xy 94.473818 -179.935445) (xy 94.473268 -179.890674)
			(xy 94.473838 -179.845905) (xy 94.482847 -179.75682) (xy 94.500749 -179.669089) (xy 94.527366 -179.583597)
			(xy 94.544388 -179.542186) (xy 94.54797 -179.5326) (xy 94.54796 -179.512153) (xy 94.544388 -179.502562)
			(xy 94.52734 -179.46116) (xy 94.500709 -179.37567) (xy 94.482808 -179.287935) (xy 94.473818 -179.198845)
			(xy 94.473268 -179.154074) (xy 94.473674 -179.112958) (xy 94.481264 -179.031076) (xy 94.496376 -178.950245)
			(xy 94.518882 -178.871152) (xy 94.548591 -178.794473) (xy 94.585247 -178.720863) (xy 94.628539 -178.650949)
			(xy 94.678097 -178.585328) (xy 94.733499 -178.524559) (xy 94.794271 -178.469161) (xy 94.859895 -178.419607)
			(xy 94.929812 -178.37632) (xy 95.003425 -178.339668) (xy 95.080105 -178.309965) (xy 95.159199 -178.287463)
			(xy 95.240032 -178.272356) (xy 95.321914 -178.264771) (xy 95.36303 -178.264312) (xy 95.404641 -178.264773)
			(xy 95.487498 -178.272553) (xy 95.569267 -178.288031) (xy 95.649235 -178.311074) (xy 95.726703 -178.341479)
			(xy 95.800995 -178.378982) (xy 95.836486 -178.40071) (xy 95.845629 -178.405863) (xy 95.866342 -178.40908)
			(xy 95.886614 -178.403752) (xy 95.89516 -178.397662) (xy 95.928789 -178.371671) (xy 96.000183 -178.325546)
			(xy 96.075654 -178.286445) (xy 96.154512 -178.254724) (xy 96.236037 -178.230675) (xy 96.319485 -178.214515)
			(xy 96.404095 -178.206393) (xy 96.446594 -178.205892) (xy 96.487707 -178.206419) (xy 96.569582 -178.214005)
			(xy 96.650407 -178.229113) (xy 96.729494 -178.251613) (xy 96.806168 -178.281315) (xy 96.879774 -178.317965)
			(xy 96.949684 -178.36125) (xy 97.015303 -178.4108) (xy 97.07607 -178.466193) (xy 97.131467 -178.526957)
			(xy 97.181021 -178.592573) (xy 97.22431 -178.662481) (xy 97.260964 -178.736085) (xy 97.29067 -178.812756)
			(xy 97.313176 -178.891842) (xy 97.328288 -178.972667) (xy 97.335879 -179.054541) (xy 97.336356 -179.095654)
			(xy 97.335793 -179.140424) (xy 97.329275 -179.204874) (xy 368.074448 -179.204874) (xy 368.075006 -179.161932)
			(xy 368.083288 -179.076448) (xy 368.099773 -178.99216) (xy 368.124306 -178.909855) (xy 368.15666 -178.830297)
			(xy 368.196533 -178.75423) (xy 368.243554 -178.682361) (xy 368.297284 -178.615359) (xy 368.357224 -178.55385)
			(xy 368.422813 -178.498405) (xy 368.493443 -178.449542) (xy 368.568454 -178.407716) (xy 368.607594 -178.390042)
			(xy 368.615999 -178.385919) (xy 368.629281 -178.372745) (xy 368.633502 -178.364388) (xy 368.645948 -178.33721)
			(xy 368.64947 -178.328554) (xy 368.650638 -178.309919) (xy 368.648234 -178.300888) (xy 368.635415 -178.257999)
			(xy 368.617464 -178.170297) (xy 368.608423 -178.081234) (xy 368.607848 -178.036474) (xy 368.608352 -177.994113)
			(xy 368.616405 -177.909776) (xy 368.632439 -177.826586) (xy 368.656307 -177.745296) (xy 368.687795 -177.666644)
			(xy 368.726617 -177.591341) (xy 368.77242 -177.520069) (xy 368.824791 -177.453473) (xy 368.883256 -177.392158)
			(xy 368.947284 -177.336677) (xy 369.016296 -177.287534) (xy 369.089666 -177.245174) (xy 369.166731 -177.209979)
			(xy 369.246793 -177.18227) (xy 369.329126 -177.162296) (xy 369.412985 -177.150239) (xy 369.49761 -177.146208)
			(xy 369.582235 -177.150239) (xy 369.666094 -177.162296) (xy 369.748427 -177.18227) (xy 369.828489 -177.209979)
			(xy 369.905554 -177.245174) (xy 369.978924 -177.287534) (xy 370.047936 -177.336677) (xy 370.111964 -177.392158)
			(xy 370.170429 -177.453473) (xy 370.2228 -177.520069) (xy 370.268603 -177.591341) (xy 370.307425 -177.666644)
			(xy 370.338913 -177.745296) (xy 370.362781 -177.826586) (xy 370.378815 -177.909776) (xy 370.386868 -177.994113)
			(xy 370.387372 -178.036474) (xy 370.387372 -178.036728) (xy 370.386948 -178.075094) (xy 370.380306 -178.151538)
			(xy 370.367099 -178.227125) (xy 370.357654 -178.264312) (xy 370.35562 -178.273261) (xy 370.357441 -178.291512)
			(xy 370.365595 -178.307941) (xy 370.37903 -178.320427) (xy 370.387372 -178.324256) (xy 370.427603 -178.341379)
			(xy 370.50477 -178.382506) (xy 370.577528 -178.431007) (xy 370.645175 -178.486413) (xy 370.707059 -178.548191)
			(xy 370.762582 -178.615743) (xy 370.811207 -178.688417) (xy 370.852467 -178.765513) (xy 370.885962 -178.846285)
			(xy 370.911369 -178.929954) (xy 370.928442 -179.015713) (xy 370.937018 -179.102733) (xy 370.937536 -179.146454)
			(xy 370.936975 -179.191224) (xy 370.927964 -179.280309) (xy 370.910058 -179.36804) (xy 370.883439 -179.453531)
			(xy 370.866416 -179.494942) (xy 370.86288 -179.504541) (xy 370.862862 -179.524975) (xy 370.866416 -179.534566)
			(xy 370.883441 -179.575977) (xy 370.910078 -179.661464) (xy 370.927986 -179.749196) (xy 370.936982 -179.838284)
			(xy 370.937536 -179.883054) (xy 370.937282 -179.903882) (xy 370.937631 -179.91519) (xy 370.946776 -179.935848)
			(xy 370.963889 -179.950596) (xy 370.97462 -179.954174) (xy 370.989618 -179.95835) (xy 371.019344 -179.967623)
			(xy 371.034056 -179.972716) (xy 371.042253 -179.97523) (xy 371.059387 -179.97523) (xy 371.067584 -179.972716)
			(xy 371.102796 -179.960741) (xy 371.174801 -179.94209) (xy 371.248123 -179.929585) (xy 371.322239 -179.923316)
			(xy 371.35943 -179.922932) (xy 371.396619 -179.923339) (xy 371.470732 -179.929623) (xy 371.544052 -179.942128)
			(xy 371.616058 -179.960764) (xy 371.651276 -179.972716) (xy 371.659473 -179.97523) (xy 371.676607 -179.97523)
			(xy 371.684804 -179.972716) (xy 371.720023 -179.960763) (xy 371.792025 -179.942106) (xy 371.865345 -179.929595)
			(xy 371.93946 -179.923319) (xy 371.97665 -179.922932) (xy 372.01859 -179.923405) (xy 372.10209 -179.931374)
			(xy 372.184455 -179.947244) (xy 372.264938 -179.970872) (xy 372.34281 -180.002043) (xy 372.417367 -180.040476)
			(xy 372.487932 -180.085822) (xy 372.553868 -180.137671) (xy 372.614576 -180.195553) (xy 372.669507 -180.258944)
			(xy 372.718163 -180.327269) (xy 372.760105 -180.39991) (xy 372.794951 -180.476209) (xy 372.822386 -180.555475)
			(xy 372.842162 -180.63699) (xy 372.848069 -180.678074) (xy 376.477276 -180.678074) (xy 376.477846 -180.633305)
			(xy 376.486854 -180.54422) (xy 376.504757 -180.456489) (xy 376.531374 -180.370997) (xy 376.548396 -180.329586)
			(xy 376.551978 -180.32) (xy 376.551968 -180.299553) (xy 376.548396 -180.289962) (xy 376.531349 -180.24856)
			(xy 376.504717 -180.16307) (xy 376.486816 -180.075335) (xy 376.477826 -179.986245) (xy 376.477276 -179.941474)
			(xy 376.477846 -179.896705) (xy 376.486854 -179.80762) (xy 376.504757 -179.719889) (xy 376.531374 -179.634397)
			(xy 376.548396 -179.592986) (xy 376.551978 -179.5834) (xy 376.551968 -179.562953) (xy 376.548396 -179.553362)
			(xy 376.531349 -179.51196) (xy 376.504717 -179.42647) (xy 376.486816 -179.338735) (xy 376.477826 -179.249645)
			(xy 376.477276 -179.204874) (xy 376.477674 -179.163758) (xy 376.485264 -179.081876) (xy 376.500376 -179.001043)
			(xy 376.522883 -178.92195) (xy 376.552591 -178.845272) (xy 376.589248 -178.771661) (xy 376.632541 -178.701747)
			(xy 376.682099 -178.636125) (xy 376.737501 -178.575356) (xy 376.798274 -178.519958) (xy 376.863899 -178.470404)
			(xy 376.933817 -178.427117) (xy 377.00743 -178.390466) (xy 377.084111 -178.360763) (xy 377.163206 -178.338262)
			(xy 377.244039 -178.323155) (xy 377.325922 -178.315571) (xy 377.367038 -178.315112) (xy 377.408648 -178.315619)
			(xy 377.491503 -178.323389) (xy 377.573272 -178.338859) (xy 377.65324 -178.361894) (xy 377.730709 -178.392291)
			(xy 377.805002 -178.429786) (xy 377.840494 -178.45151) (xy 377.849633 -178.45667) (xy 377.870349 -178.459885)
			(xy 377.890623 -178.454554) (xy 377.899168 -178.448462) (xy 377.932829 -178.422514) (xy 378.004217 -178.376384)
			(xy 378.079682 -178.337278) (xy 378.158534 -178.305551) (xy 378.240054 -178.281495) (xy 378.323498 -178.265328)
			(xy 378.408104 -178.257198) (xy 378.450602 -178.256692) (xy 378.491715 -178.257211) (xy 378.57359 -178.264798)
			(xy 378.654416 -178.279906) (xy 378.733503 -178.302408) (xy 378.810176 -178.33211) (xy 378.883782 -178.368761)
			(xy 378.953693 -178.412046) (xy 379.019312 -178.461597) (xy 379.080078 -178.51699) (xy 379.135475 -178.577755)
			(xy 379.185029 -178.643371) (xy 379.228318 -178.713279) (xy 379.264972 -178.786883) (xy 379.294678 -178.863555)
			(xy 379.317184 -178.942641) (xy 379.332296 -179.023466) (xy 379.339887 -179.105341) (xy 379.340364 -179.146454)
			(xy 379.339801 -179.191224) (xy 379.330791 -179.280309) (xy 379.312886 -179.36804) (xy 379.286267 -179.453531)
			(xy 379.269244 -179.494942) (xy 379.265706 -179.50454) (xy 379.265689 -179.524976) (xy 379.269244 -179.534566)
			(xy 379.286249 -179.575917) (xy 379.31286 -179.661279) (xy 379.330766 -179.748882) (xy 379.339788 -179.837839)
			(xy 379.340364 -179.882546) (xy 379.340364 -179.883562) (xy 379.34011 -179.894992) (xy 379.366589 -179.900938)
			(xy 379.418824 -179.915681) (xy 379.444504 -179.924456) (xy 379.452701 -179.92697) (xy 379.469835 -179.92697)
			(xy 379.478032 -179.924456) (xy 379.513248 -179.912493) (xy 379.585251 -179.893839) (xy 379.658572 -179.881331)
			(xy 379.732688 -179.875058) (xy 379.769878 -179.874672) (xy 379.807067 -179.875069) (xy 379.88118 -179.881356)
			(xy 379.9545 -179.893864) (xy 380.026506 -179.912502) (xy 380.061724 -179.924456) (xy 380.069921 -179.92697)
			(xy 380.087055 -179.92697) (xy 380.095252 -179.924456) (xy 380.130466 -179.912487) (xy 380.20247 -179.893835)
			(xy 380.275792 -179.881329) (xy 380.349908 -179.875057) (xy 380.387098 -179.874672) (xy 380.429038 -179.875067)
			(xy 380.512539 -179.88304) (xy 380.594904 -179.898915) (xy 380.675386 -179.922546) (xy 380.753258 -179.953722)
			(xy 380.827814 -179.992158) (xy 380.898379 -180.037507) (xy 380.964314 -180.089358) (xy 381.025021 -180.147242)
			(xy 381.079951 -180.210635) (xy 381.128607 -180.278962) (xy 381.170547 -180.351604) (xy 381.205392 -180.427905)
			(xy 381.232827 -180.507172) (xy 381.252602 -180.588688) (xy 381.26454 -180.671715) (xy 381.264843 -180.678074)
			(xy 384.808476 -180.678074) (xy 384.809046 -180.633305) (xy 384.818054 -180.54422) (xy 384.835957 -180.456489)
			(xy 384.862574 -180.370997) (xy 384.879596 -180.329586) (xy 384.883178 -180.32) (xy 384.883168 -180.299553)
			(xy 384.879596 -180.289962) (xy 384.862549 -180.24856) (xy 384.835917 -180.16307) (xy 384.818016 -180.075335)
			(xy 384.809026 -179.986245) (xy 384.808476 -179.941474) (xy 384.809046 -179.896705) (xy 384.818054 -179.80762)
			(xy 384.835957 -179.719889) (xy 384.862574 -179.634397) (xy 384.879596 -179.592986) (xy 384.883178 -179.5834)
			(xy 384.883168 -179.562953) (xy 384.879596 -179.553362) (xy 384.862549 -179.51196) (xy 384.835917 -179.42647)
			(xy 384.818016 -179.338735) (xy 384.809026 -179.249645) (xy 384.808476 -179.204874) (xy 384.808874 -179.163758)
			(xy 384.816464 -179.081876) (xy 384.831576 -179.001043) (xy 384.854083 -178.92195) (xy 384.883791 -178.845272)
			(xy 384.920448 -178.771661) (xy 384.963741 -178.701747) (xy 385.013299 -178.636125) (xy 385.068701 -178.575356)
			(xy 385.129474 -178.519958) (xy 385.195099 -178.470404) (xy 385.265017 -178.427117) (xy 385.33863 -178.390466)
			(xy 385.415311 -178.360763) (xy 385.494406 -178.338262) (xy 385.575239 -178.323155) (xy 385.657122 -178.315571)
			(xy 385.698238 -178.315112) (xy 385.739848 -178.315619) (xy 385.822703 -178.323389) (xy 385.904472 -178.338859)
			(xy 385.98444 -178.361894) (xy 386.061909 -178.392291) (xy 386.136202 -178.429786) (xy 386.171694 -178.45151)
			(xy 386.180833 -178.45667) (xy 386.201549 -178.459885) (xy 386.221823 -178.454554) (xy 386.230368 -178.448462)
			(xy 386.264029 -178.422514) (xy 386.335417 -178.376384) (xy 386.410882 -178.337278) (xy 386.489734 -178.305551)
			(xy 386.571254 -178.281495) (xy 386.654698 -178.265328) (xy 386.739304 -178.257198) (xy 386.781802 -178.256692)
			(xy 386.822915 -178.257211) (xy 386.90479 -178.264798) (xy 386.985616 -178.279906) (xy 387.064703 -178.302408)
			(xy 387.141376 -178.33211) (xy 387.214982 -178.368761) (xy 387.284893 -178.412046) (xy 387.350512 -178.461597)
			(xy 387.411278 -178.51699) (xy 387.466675 -178.577755) (xy 387.516229 -178.643371) (xy 387.559518 -178.713279)
			(xy 387.596172 -178.786883) (xy 387.625878 -178.863555) (xy 387.648384 -178.942641) (xy 387.663496 -179.023466)
			(xy 387.671087 -179.105341) (xy 387.671564 -179.146454) (xy 387.671001 -179.191224) (xy 387.661991 -179.280309)
			(xy 387.644086 -179.36804) (xy 387.617467 -179.453531) (xy 387.600444 -179.494942) (xy 387.596906 -179.50454)
			(xy 387.596889 -179.524976) (xy 387.600444 -179.534566) (xy 387.617449 -179.575917) (xy 387.64406 -179.661279)
			(xy 387.661966 -179.748882) (xy 387.670988 -179.837839) (xy 387.671564 -179.882546) (xy 387.671564 -179.883562)
			(xy 387.67131 -179.894992) (xy 387.697789 -179.900938) (xy 387.750024 -179.915681) (xy 387.775704 -179.924456)
			(xy 387.783901 -179.92697) (xy 387.801035 -179.92697) (xy 387.809232 -179.924456) (xy 387.844448 -179.912493)
			(xy 387.916451 -179.893839) (xy 387.989772 -179.881331) (xy 388.063888 -179.875058) (xy 388.101078 -179.874672)
			(xy 388.138267 -179.875069) (xy 388.21238 -179.881356) (xy 388.2857 -179.893864) (xy 388.357706 -179.912502)
			(xy 388.392924 -179.924456) (xy 388.401121 -179.92697) (xy 388.418255 -179.92697) (xy 388.426452 -179.924456)
			(xy 388.461666 -179.912487) (xy 388.53367 -179.893835) (xy 388.606992 -179.881329) (xy 388.681108 -179.875057)
			(xy 388.718298 -179.874672) (xy 388.760238 -179.875067) (xy 388.843739 -179.88304) (xy 388.926104 -179.898915)
			(xy 389.006586 -179.922546) (xy 389.084458 -179.953722) (xy 389.159014 -179.992158) (xy 389.229579 -180.037507)
			(xy 389.295514 -180.089358) (xy 389.356221 -180.147242) (xy 389.411151 -180.210635) (xy 389.459807 -180.278962)
			(xy 389.501747 -180.351604) (xy 389.536592 -180.427905) (xy 389.564027 -180.507172) (xy 389.583802 -180.588688)
			(xy 389.59574 -180.671715) (xy 389.599731 -180.7555) (xy 389.59574 -180.839285) (xy 389.583802 -180.922312)
			(xy 389.564027 -181.003828) (xy 389.536592 -181.083095) (xy 389.501747 -181.159396) (xy 389.459807 -181.232038)
			(xy 389.411151 -181.300365) (xy 389.356221 -181.363758) (xy 389.295514 -181.421642) (xy 389.229579 -181.473493)
			(xy 389.159014 -181.518842) (xy 389.084458 -181.557278) (xy 389.006586 -181.588454) (xy 388.926104 -181.612085)
			(xy 388.843739 -181.62796) (xy 388.760238 -181.635933) (xy 388.718298 -181.636416) (xy 388.681108 -181.636027)
			(xy 388.606996 -181.629737) (xy 388.533676 -181.617227) (xy 388.46167 -181.598587) (xy 388.426452 -181.586632)
			(xy 388.418255 -181.584118) (xy 388.401121 -181.584118) (xy 388.392924 -181.586632) (xy 388.365208 -181.596078)
			(xy 388.308773 -181.611711) (xy 388.280148 -181.617874) (xy 388.270401 -181.620348) (xy 388.25379 -181.63165)
			(xy 388.242792 -181.648464) (xy 388.240524 -181.65826) (xy 388.231054 -181.705587) (xy 388.203179 -181.797995)
			(xy 388.184898 -181.842664) (xy 388.181281 -181.852235) (xy 388.18114 -181.872676) (xy 388.184644 -181.882288)
			(xy 388.201684 -181.923659) (xy 388.228298 -182.009088) (xy 388.246197 -182.096758) (xy 388.255201 -182.185783)
			(xy 388.255764 -182.230522) (xy 388.255764 -182.230776) (xy 388.25526 -182.273124) (xy 388.247209 -182.357438)
			(xy 388.23118 -182.440604) (xy 388.207319 -182.521871) (xy 388.17584 -182.600501) (xy 388.137029 -182.675782)
			(xy 388.091239 -182.747034) (xy 388.038883 -182.81361) (xy 387.980435 -182.874908) (xy 387.916425 -182.930373)
			(xy 387.847433 -182.979502) (xy 387.774083 -183.021851) (xy 387.69704 -183.057035) (xy 387.617001 -183.084737)
			(xy 387.534692 -183.104705) (xy 387.450857 -183.116758) (xy 387.366256 -183.120789) (xy 387.281655 -183.116758)
			(xy 387.19782 -183.104705) (xy 387.115511 -183.084737) (xy 387.035472 -183.057035) (xy 386.958429 -183.021851)
			(xy 386.885079 -182.979502) (xy 386.816087 -182.930373) (xy 386.752077 -182.874908) (xy 386.693629 -182.81361)
			(xy 386.641273 -182.747034) (xy 386.595483 -182.675782) (xy 386.556672 -182.600501) (xy 386.525193 -182.521871)
			(xy 386.501332 -182.440604) (xy 386.485303 -182.357438) (xy 386.477252 -182.273124) (xy 386.476748 -182.230776)
			(xy 386.476748 -182.230522) (xy 386.477311 -182.185784) (xy 386.486329 -182.096762) (xy 386.504235 -182.009095)
			(xy 386.53085 -181.923667) (xy 386.547868 -181.882288) (xy 386.551445 -181.872701) (xy 386.551436 -181.852255)
			(xy 386.547868 -181.842664) (xy 386.53084 -181.801254) (xy 386.504206 -181.715766) (xy 386.4863 -181.628034)
			(xy 386.477302 -181.538946) (xy 386.476748 -181.494176) (xy 386.477087 -181.458262) (xy 386.482864 -181.386666)
			(xy 386.494395 -181.315769) (xy 386.502656 -181.280816) (xy 386.504356 -181.272508) (xy 386.502799 -181.255633)
			(xy 386.495808 -181.240195) (xy 386.49021 -181.233826) (xy 386.44957 -181.1909) (xy 386.43941 -181.193186)
			(xy 386.430637 -181.195432) (xy 386.415405 -181.205208) (xy 386.409692 -181.212236) (xy 386.384552 -181.244927)
			(xy 386.329156 -181.306026) (xy 386.268343 -181.361734) (xy 386.202634 -181.411575) (xy 386.132593 -181.455119)
			(xy 386.058822 -181.491993) (xy 385.981955 -181.521881) (xy 385.902652 -181.544524) (xy 385.821593 -181.55973)
			(xy 385.739474 -181.567368) (xy 385.698238 -181.567836) (xy 385.657123 -181.567365) (xy 385.575243 -181.559781)
			(xy 385.494413 -181.544674) (xy 385.415321 -181.522173) (xy 385.338643 -181.49247) (xy 385.265033 -181.455819)
			(xy 385.195119 -181.412532) (xy 385.129497 -181.362978) (xy 385.068728 -181.30758) (xy 385.01333 -181.246812)
			(xy 384.963775 -181.181191) (xy 384.920487 -181.111277) (xy 384.883834 -181.037668) (xy 384.854131 -180.96099)
			(xy 384.831629 -180.881899) (xy 384.81652 -180.801068) (xy 384.808935 -180.719189) (xy 384.808476 -180.678074)
			(xy 381.264843 -180.678074) (xy 381.268531 -180.7555) (xy 381.26454 -180.839285) (xy 381.252602 -180.922312)
			(xy 381.232827 -181.003828) (xy 381.205392 -181.083095) (xy 381.170547 -181.159396) (xy 381.128607 -181.232038)
			(xy 381.079951 -181.300365) (xy 381.025021 -181.363758) (xy 380.964314 -181.421642) (xy 380.898379 -181.473493)
			(xy 380.827814 -181.518842) (xy 380.753258 -181.557278) (xy 380.675386 -181.588454) (xy 380.594904 -181.612085)
			(xy 380.512539 -181.62796) (xy 380.429038 -181.635933) (xy 380.387098 -181.636416) (xy 380.349908 -181.636027)
			(xy 380.275796 -181.629737) (xy 380.202476 -181.617227) (xy 380.13047 -181.598587) (xy 380.095252 -181.586632)
			(xy 380.087055 -181.584118) (xy 380.069921 -181.584118) (xy 380.061724 -181.586632) (xy 380.034008 -181.596078)
			(xy 379.977573 -181.611711) (xy 379.948948 -181.617874) (xy 379.939201 -181.620348) (xy 379.92259 -181.63165)
			(xy 379.911592 -181.648464) (xy 379.909324 -181.65826) (xy 379.899854 -181.705587) (xy 379.871979 -181.797995)
			(xy 379.853698 -181.842664) (xy 379.850081 -181.852235) (xy 379.84994 -181.872676) (xy 379.853444 -181.882288)
			(xy 379.870484 -181.923659) (xy 379.897098 -182.009088) (xy 379.914997 -182.096758) (xy 379.924001 -182.185783)
			(xy 379.924564 -182.230522) (xy 379.924564 -182.230776) (xy 379.92406 -182.273124) (xy 379.916009 -182.357438)
			(xy 379.89998 -182.440604) (xy 379.876119 -182.521871) (xy 379.84464 -182.600501) (xy 379.805829 -182.675782)
			(xy 379.760039 -182.747034) (xy 379.707683 -182.81361) (xy 379.649235 -182.874908) (xy 379.585225 -182.930373)
			(xy 379.516233 -182.979502) (xy 379.442883 -183.021851) (xy 379.36584 -183.057035) (xy 379.285801 -183.084737)
			(xy 379.203492 -183.104705) (xy 379.119657 -183.116758) (xy 379.035056 -183.120789) (xy 378.950455 -183.116758)
			(xy 378.86662 -183.104705) (xy 378.784311 -183.084737) (xy 378.704272 -183.057035) (xy 378.627229 -183.021851)
			(xy 378.553879 -182.979502) (xy 378.484887 -182.930373) (xy 378.420877 -182.874908) (xy 378.362429 -182.81361)
			(xy 378.310073 -182.747034) (xy 378.264283 -182.675782) (xy 378.225472 -182.600501) (xy 378.193993 -182.521871)
			(xy 378.170132 -182.440604) (xy 378.154103 -182.357438) (xy 378.146052 -182.273124) (xy 378.145548 -182.230776)
			(xy 378.145548 -182.230522) (xy 378.146111 -182.185784) (xy 378.155129 -182.096762) (xy 378.173035 -182.009095)
			(xy 378.19965 -181.923667) (xy 378.216668 -181.882288) (xy 378.220245 -181.872701) (xy 378.220236 -181.852255)
			(xy 378.216668 -181.842664) (xy 378.19964 -181.801254) (xy 378.173006 -181.715766) (xy 378.1551 -181.628034)
			(xy 378.146102 -181.538946) (xy 378.145548 -181.494176) (xy 378.145887 -181.458262) (xy 378.151664 -181.386666)
			(xy 378.163195 -181.315769) (xy 378.171456 -181.280816) (xy 378.173156 -181.272508) (xy 378.171599 -181.255633)
			(xy 378.164608 -181.240195) (xy 378.15901 -181.233826) (xy 378.11837 -181.1909) (xy 378.10821 -181.193186)
			(xy 378.099437 -181.195432) (xy 378.084205 -181.205208) (xy 378.078492 -181.212236) (xy 378.053352 -181.244927)
			(xy 377.997956 -181.306026) (xy 377.937143 -181.361734) (xy 377.871434 -181.411575) (xy 377.801393 -181.455119)
			(xy 377.727622 -181.491993) (xy 377.650755 -181.521881) (xy 377.571452 -181.544524) (xy 377.490393 -181.55973)
			(xy 377.408274 -181.567368) (xy 377.367038 -181.567836) (xy 377.325923 -181.567365) (xy 377.244043 -181.559781)
			(xy 377.163213 -181.544674) (xy 377.084121 -181.522173) (xy 377.007443 -181.49247) (xy 376.933833 -181.455819)
			(xy 376.863919 -181.412532) (xy 376.798297 -181.362978) (xy 376.737528 -181.30758) (xy 376.68213 -181.246812)
			(xy 376.632575 -181.181191) (xy 376.589287 -181.111277) (xy 376.552634 -181.037668) (xy 376.522931 -180.96099)
			(xy 376.500429 -180.881899) (xy 376.48532 -180.801068) (xy 376.477735 -180.719189) (xy 376.477276 -180.678074)
			(xy 372.848069 -180.678074) (xy 372.8541 -180.720015) (xy 372.858091 -180.8038) (xy 372.8541 -180.887585)
			(xy 372.842162 -180.97061) (xy 372.822386 -181.052125) (xy 372.794951 -181.131391) (xy 372.760105 -181.20769)
			(xy 372.718163 -181.280331) (xy 372.669507 -181.348656) (xy 372.614576 -181.412047) (xy 372.553868 -181.469929)
			(xy 372.487932 -181.521778) (xy 372.417367 -181.567124) (xy 372.34281 -181.605557) (xy 372.264938 -181.636728)
			(xy 372.184455 -181.660356) (xy 372.10209 -181.676226) (xy 372.01859 -181.684195) (xy 371.97665 -181.684676)
			(xy 371.939461 -181.684274) (xy 371.865348 -181.677988) (xy 371.792028 -181.665482) (xy 371.720022 -181.646845)
			(xy 371.684804 -181.634892) (xy 371.676607 -181.632378) (xy 371.659473 -181.632378) (xy 371.651276 -181.634892)
			(xy 371.611916 -181.648156) (xy 371.531285 -181.66812) (xy 371.449135 -181.680416) (xy 371.40769 -181.683152)
			(xy 371.397889 -181.684131) (xy 371.380113 -181.692579) (xy 371.36683 -181.707102) (xy 371.362986 -181.716172)
			(xy 371.348 -181.753764) (xy 371.344428 -181.763418) (xy 371.344429 -181.783987) (xy 371.348 -181.793642)
			(xy 371.365038 -181.835014) (xy 371.391656 -181.920442) (xy 371.409557 -182.008112) (xy 371.418559 -182.097137)
			(xy 371.41912 -182.141876) (xy 371.418616 -182.184237) (xy 371.410563 -182.268574) (xy 371.394529 -182.351764)
			(xy 371.370661 -182.433054) (xy 371.339173 -182.511706) (xy 371.300351 -182.587009) (xy 371.254548 -182.658281)
			(xy 371.202177 -182.724877) (xy 371.143712 -182.786192) (xy 371.079684 -182.841673) (xy 371.010672 -182.890816)
			(xy 370.937302 -182.933176) (xy 370.860237 -182.968371) (xy 370.780175 -182.99608) (xy 370.697842 -183.016054)
			(xy 370.613983 -183.028111) (xy 370.529358 -183.032143) (xy 370.444733 -183.028111) (xy 370.360874 -183.016054)
			(xy 370.278541 -182.99608) (xy 370.198479 -182.968371) (xy 370.121414 -182.933176) (xy 370.048044 -182.890816)
			(xy 369.979032 -182.841673) (xy 369.915004 -182.786192) (xy 369.856539 -182.724877) (xy 369.804168 -182.658281)
			(xy 369.758365 -182.587009) (xy 369.719543 -182.511706) (xy 369.688055 -182.433054) (xy 369.664187 -182.351764)
			(xy 369.648153 -182.268574) (xy 369.6401 -182.184237) (xy 369.639596 -182.141876) (xy 369.640165 -182.097107)
			(xy 369.649173 -182.008022) (xy 369.667076 -181.92029) (xy 369.693694 -181.834799) (xy 369.710716 -181.793388)
			(xy 369.714296 -181.783802) (xy 369.714287 -181.763355) (xy 369.710716 -181.753764) (xy 369.693665 -181.712364)
			(xy 369.667035 -181.626872) (xy 369.649135 -181.539137) (xy 369.640146 -181.450047) (xy 369.639596 -181.405276)
			(xy 369.639771 -181.384669) (xy 369.641804 -181.343504) (xy 369.64366 -181.32298) (xy 369.644023 -181.312283)
			(xy 369.63707 -181.292069) (xy 369.630198 -181.283864) (xy 369.57127 -181.22011) (xy 369.551204 -181.211728)
			(xy 369.540282 -181.211982) (xy 369.523264 -181.212236) (xy 369.522756 -181.212236) (xy 369.481649 -181.211766)
			(xy 369.399787 -181.204159) (xy 369.318976 -181.189032) (xy 369.239905 -181.166515) (xy 369.163248 -181.136799)
			(xy 369.08966 -181.100138) (xy 369.019768 -181.056844) (xy 368.954168 -181.007287) (xy 368.893419 -180.95189)
			(xy 368.83804 -180.891125) (xy 368.788503 -180.825509) (xy 368.745231 -180.755604) (xy 368.708592 -180.682005)
			(xy 368.678899 -180.605339) (xy 368.656406 -180.526261) (xy 368.641304 -180.445446) (xy 368.633721 -180.363581)
			(xy 368.633248 -180.322474) (xy 368.6337 -180.283493) (xy 368.640575 -180.205835) (xy 368.654226 -180.129077)
			(xy 368.663982 -180.091334) (xy 368.666037 -180.082278) (xy 368.664208 -180.063813) (xy 368.655908 -180.047218)
			(xy 368.642231 -180.034679) (xy 368.633756 -180.030882) (xy 368.596114 -180.015301) (xy 368.523548 -179.97826)
			(xy 368.454673 -179.934739) (xy 368.390066 -179.885102) (xy 368.330268 -179.829767) (xy 368.27578 -179.769195)
			(xy 368.227059 -179.703896) (xy 368.184512 -179.634415) (xy 368.148496 -179.561335) (xy 368.119314 -179.485268)
			(xy 368.097208 -179.406851) (xy 368.082365 -179.326741) (xy 368.074909 -179.24561) (xy 368.074448 -179.204874)
			(xy 97.329275 -179.204874) (xy 97.326783 -179.229509) (xy 97.308877 -179.31724) (xy 97.282259 -179.402731)
			(xy 97.265236 -179.444142) (xy 97.261699 -179.453741) (xy 97.261682 -179.474176) (xy 97.265236 -179.483766)
			(xy 97.28224 -179.525117) (xy 97.308851 -179.610479) (xy 97.326758 -179.698082) (xy 97.33578 -179.787039)
			(xy 97.336356 -179.831746) (xy 97.336356 -179.832762) (xy 97.336102 -179.844192) (xy 97.362581 -179.850138)
			(xy 97.414816 -179.864881) (xy 97.440496 -179.873656) (xy 97.448693 -179.87617) (xy 97.465827 -179.87617)
			(xy 97.474024 -179.873656) (xy 97.50924 -179.861695) (xy 97.581244 -179.843041) (xy 97.654565 -179.830532)
			(xy 97.72868 -179.824259) (xy 97.76587 -179.823872) (xy 97.803059 -179.824271) (xy 97.877172 -179.830558)
			(xy 97.950492 -179.843065) (xy 98.022498 -179.861703) (xy 98.057716 -179.873656) (xy 98.065913 -179.87617)
			(xy 98.083047 -179.87617) (xy 98.091244 -179.873656) (xy 98.126459 -179.861689) (xy 98.198462 -179.843037)
			(xy 98.271784 -179.83053) (xy 98.3459 -179.824258) (xy 98.38309 -179.823872) (xy 98.42503 -179.824267)
			(xy 98.508532 -179.832239) (xy 98.590897 -179.848113) (xy 98.67138 -179.871744) (xy 98.749253 -179.902919)
			(xy 98.82381 -179.941355) (xy 98.894375 -179.986704) (xy 98.96031 -180.038555) (xy 99.021018 -180.096439)
			(xy 99.075949 -180.159832) (xy 99.124605 -180.228159) (xy 99.166546 -180.300802) (xy 99.201391 -180.377103)
			(xy 99.228826 -180.45637) (xy 99.248602 -180.537887) (xy 99.26054 -180.620914) (xy 99.264531 -180.7047)
			(xy 99.26054 -180.788486) (xy 99.248602 -180.871513) (xy 99.228826 -180.95303) (xy 99.201391 -181.032297)
			(xy 99.166546 -181.108598) (xy 99.124605 -181.181241) (xy 99.075949 -181.249568) (xy 99.021018 -181.312961)
			(xy 98.96031 -181.370845) (xy 98.894375 -181.422696) (xy 98.82381 -181.468045) (xy 98.749253 -181.506481)
			(xy 98.67138 -181.537656) (xy 98.590897 -181.561287) (xy 98.508532 -181.577161) (xy 98.42503 -181.585133)
			(xy 98.38309 -181.585616) (xy 98.3459 -181.585229) (xy 98.271787 -181.578939) (xy 98.198468 -181.566428)
			(xy 98.126462 -181.547787) (xy 98.091244 -181.535832) (xy 98.083047 -181.533318) (xy 98.065913 -181.533318)
			(xy 98.057716 -181.535832) (xy 98.015534 -181.549982) (xy 97.929009 -181.570726) (xy 97.884996 -181.577234)
			(xy 97.875031 -181.57898) (xy 97.85759 -181.589205) (xy 97.845466 -181.605383) (xy 97.842578 -181.61508)
			(xy 97.833805 -181.648299) (xy 97.811813 -181.713397) (xy 97.798636 -181.745128) (xy 97.79505 -181.754712)
			(xy 97.795064 -181.775161) (xy 97.798636 -181.784752) (xy 97.815664 -181.826127) (xy 97.842281 -181.911555)
			(xy 97.860184 -181.999224) (xy 97.869191 -182.088247) (xy 97.869756 -182.132986) (xy 97.869756 -182.13324)
			(xy 97.869252 -182.175588) (xy 97.861201 -182.259902) (xy 97.845172 -182.343068) (xy 97.821311 -182.424335)
			(xy 97.789832 -182.502965) (xy 97.751021 -182.578246) (xy 97.705231 -182.649498) (xy 97.652875 -182.716074)
			(xy 97.594427 -182.777372) (xy 97.530417 -182.832837) (xy 97.461425 -182.881966) (xy 97.388075 -182.924315)
			(xy 97.311032 -182.959499) (xy 97.230993 -182.987201) (xy 97.148684 -183.007169) (xy 97.064849 -183.019222)
			(xy 96.980248 -183.023253) (xy 96.895647 -183.019222) (xy 96.811812 -183.007169) (xy 96.729503 -182.987201)
			(xy 96.649464 -182.959499) (xy 96.572421 -182.924315) (xy 96.499071 -182.881966) (xy 96.430079 -182.832837)
			(xy 96.366069 -182.777372) (xy 96.307621 -182.716074) (xy 96.255265 -182.649498) (xy 96.209475 -182.578246)
			(xy 96.170664 -182.502965) (xy 96.139185 -182.424335) (xy 96.115324 -182.343068) (xy 96.099295 -182.259902)
			(xy 96.091244 -182.175588) (xy 96.09074 -182.13324) (xy 96.09074 -182.132986) (xy 96.091318 -182.088248)
			(xy 96.10033 -181.999226) (xy 96.118232 -181.911559) (xy 96.144843 -181.826131) (xy 96.16186 -181.784752)
			(xy 96.165401 -181.775154) (xy 96.165416 -181.754718) (xy 96.16186 -181.745128) (xy 96.144825 -181.703755)
			(xy 96.11821 -181.618327) (xy 96.100309 -181.530657) (xy 96.091304 -181.441633) (xy 96.09074 -181.396894)
			(xy 96.09074 -181.395878) (xy 96.090368 -181.38632) (xy 96.083332 -181.368547) (xy 96.070254 -181.354605)
			(xy 96.061784 -181.350158) (xy 95.965264 -181.304184) (xy 95.936308 -181.30774) (xy 95.924878 -181.317138)
			(xy 95.890853 -181.344159) (xy 95.818459 -181.392213) (xy 95.741724 -181.43298) (xy 95.66138 -181.466069)
			(xy 95.578192 -181.491168) (xy 95.492953 -181.508035) (xy 95.406476 -181.51651) (xy 95.36303 -181.517036)
			(xy 95.321915 -181.516573) (xy 95.240035 -181.508988) (xy 95.159204 -181.49388) (xy 95.080113 -181.471379)
			(xy 95.003435 -181.441675) (xy 94.929825 -181.405023) (xy 94.859911 -181.361735) (xy 94.794289 -181.312181)
			(xy 94.73352 -181.256783) (xy 94.678122 -181.196014) (xy 94.628567 -181.130393) (xy 94.585279 -181.060479)
			(xy 94.548626 -180.986869) (xy 94.518922 -180.910191) (xy 94.49642 -180.831099) (xy 94.481312 -180.750269)
			(xy 94.473727 -180.668389) (xy 94.473268 -180.627274) (xy 90.869375 -180.627274) (xy 90.872244 -180.6875)
			(xy 90.868253 -180.771275) (xy 90.856317 -180.854292) (xy 90.836544 -180.935798) (xy 90.809114 -181.015056)
			(xy 90.774274 -181.091347) (xy 90.732339 -181.163981) (xy 90.683691 -181.2323) (xy 90.628768 -181.295686)
			(xy 90.56807 -181.353564) (xy 90.502144 -181.405411) (xy 90.431589 -181.450756) (xy 90.357043 -181.489189)
			(xy 90.279182 -181.520363) (xy 90.198709 -181.543994) (xy 90.116355 -181.559869) (xy 90.032865 -181.567844)
			(xy 89.99093 -181.568344) (xy 89.953741 -181.567944) (xy 89.879628 -181.561657) (xy 89.806308 -181.54915)
			(xy 89.734302 -181.530513) (xy 89.699084 -181.51856) (xy 89.690887 -181.516046) (xy 89.673753 -181.516046)
			(xy 89.665556 -181.51856) (xy 89.630433 -181.5305) (xy 89.558617 -181.54912) (xy 89.485489 -181.561626)
			(xy 89.411567 -181.56793) (xy 89.374472 -181.568344) (xy 89.372948 -181.568344) (xy 89.365328 -181.56809)
			(xy 89.355809 -181.6135) (xy 89.328579 -181.702202) (xy 89.310972 -181.745128) (xy 89.307384 -181.754712)
			(xy 89.307399 -181.775161) (xy 89.310972 -181.784752) (xy 89.327996 -181.826163) (xy 89.354632 -181.91165)
			(xy 89.37254 -181.999382) (xy 89.381538 -182.08847) (xy 89.382092 -182.13324) (xy 89.381588 -182.175601)
			(xy 89.373535 -182.259938) (xy 89.357501 -182.343128) (xy 89.333633 -182.424418) (xy 89.302145 -182.50307)
			(xy 89.263323 -182.578373) (xy 89.21752 -182.649645) (xy 89.165149 -182.716241) (xy 89.106684 -182.777556)
			(xy 89.042656 -182.833037) (xy 88.973644 -182.88218) (xy 88.900274 -182.92454) (xy 88.823209 -182.959735)
			(xy 88.743147 -182.987444) (xy 88.660814 -183.007418) (xy 88.576955 -183.019475) (xy 88.49233 -183.023507)
			(xy 88.407705 -183.019475) (xy 88.323846 -183.007418) (xy 88.241513 -182.987444) (xy 88.161451 -182.959735)
			(xy 88.084386 -182.92454) (xy 88.011016 -182.88218) (xy 87.942004 -182.833037) (xy 87.877976 -182.777556)
			(xy 87.819511 -182.716241) (xy 87.76714 -182.649645) (xy 87.721337 -182.578373) (xy 87.682515 -182.50307)
			(xy 87.651027 -182.424418) (xy 87.627159 -182.343128) (xy 87.611125 -182.259938) (xy 87.603072 -182.175601)
			(xy 87.602568 -182.13324) (xy 87.603127 -182.08847) (xy 87.612138 -181.999385) (xy 87.630045 -181.911654)
			(xy 87.656665 -181.826163) (xy 87.673688 -181.784752) (xy 87.677232 -181.775155) (xy 87.677247 -181.754718)
			(xy 87.673688 -181.745128) (xy 87.65877 -181.708939) (xy 87.634581 -181.634489) (xy 87.617023 -181.558202)
			(xy 87.606232 -181.480668) (xy 87.603838 -181.441598) (xy 87.602983 -181.432757) (xy 87.596138 -181.416387)
			(xy 87.58411 -181.403342) (xy 87.576406 -181.398926) (xy 87.486236 -181.352444) (xy 87.459312 -181.35346)
			(xy 87.447882 -181.360826) (xy 87.412209 -181.38294) (xy 87.337447 -181.421096) (xy 87.259425 -181.452047)
			(xy 87.178837 -181.475518) (xy 87.096397 -181.4913) (xy 87.012838 -181.499253) (xy 86.97087 -181.499764)
			(xy 86.929755 -181.499316) (xy 86.847877 -181.491726) (xy 86.767048 -181.476614) (xy 86.687959 -181.454109)
			(xy 86.611283 -181.424402) (xy 86.537675 -181.387748) (xy 86.467763 -181.344458) (xy 86.402144 -181.294902)
			(xy 86.341376 -181.239504) (xy 86.28598 -181.178735) (xy 86.236426 -181.113114) (xy 86.193139 -181.043201)
			(xy 86.156487 -180.969592) (xy 86.126782 -180.892915) (xy 86.10428 -180.813824) (xy 86.08917 -180.732995)
			(xy 86.081583 -180.651117) (xy 86.081108 -180.610002) (xy 82.462267 -180.610002) (xy 82.47114 -180.671714)
			(xy 82.475131 -180.7555) (xy 82.47114 -180.839286) (xy 82.459202 -180.922313) (xy 82.439426 -181.00383)
			(xy 82.411991 -181.083097) (xy 82.377146 -181.159398) (xy 82.335205 -181.232041) (xy 82.286549 -181.300368)
			(xy 82.231618 -181.363761) (xy 82.17091 -181.421645) (xy 82.104975 -181.473496) (xy 82.03441 -181.518845)
			(xy 81.959853 -181.557281) (xy 81.88198 -181.588456) (xy 81.801497 -181.612087) (xy 81.719132 -181.627961)
			(xy 81.63563 -181.635933) (xy 81.59369 -181.636416) (xy 81.5565 -181.636029) (xy 81.482387 -181.629739)
			(xy 81.409068 -181.617228) (xy 81.337062 -181.598587) (xy 81.301844 -181.586632) (xy 81.293647 -181.584118)
			(xy 81.276513 -181.584118) (xy 81.268316 -181.586632) (xy 81.24011 -181.596266) (xy 81.182657 -181.612157)
			(xy 81.153508 -181.618382) (xy 81.143879 -181.620834) (xy 81.127394 -181.631892) (xy 81.116335 -181.648377)
			(xy 81.113884 -181.658006) (xy 81.104396 -181.702491) (xy 81.07755 -181.789404) (xy 81.06029 -181.831488)
			(xy 81.056659 -181.841055) (xy 81.056528 -181.861499) (xy 81.060036 -181.871112) (xy 81.077051 -181.912492)
			(xy 81.103672 -181.997918) (xy 81.121578 -182.085585) (xy 81.130589 -182.174608) (xy 81.131156 -182.219346)
			(xy 81.131156 -182.2196) (xy 81.130652 -182.261948) (xy 81.122601 -182.346262) (xy 81.106572 -182.429428)
			(xy 81.082711 -182.510695) (xy 81.051232 -182.589325) (xy 81.012421 -182.664606) (xy 80.966631 -182.735858)
			(xy 80.914275 -182.802434) (xy 80.855827 -182.863732) (xy 80.791817 -182.919197) (xy 80.722825 -182.968326)
			(xy 80.649475 -183.010675) (xy 80.572432 -183.045859) (xy 80.492393 -183.073561) (xy 80.410084 -183.093529)
			(xy 80.326249 -183.105582) (xy 80.241648 -183.109613) (xy 80.157047 -183.105582) (xy 80.073212 -183.093529)
			(xy 79.990903 -183.073561) (xy 79.910864 -183.045859) (xy 79.833821 -183.010675) (xy 79.760471 -182.968326)
			(xy 79.691479 -182.919197) (xy 79.627469 -182.863732) (xy 79.569021 -182.802434) (xy 79.516665 -182.735858)
			(xy 79.470875 -182.664606) (xy 79.432064 -182.589325) (xy 79.400585 -182.510695) (xy 79.376724 -182.429428)
			(xy 79.360695 -182.346262) (xy 79.352644 -182.261948) (xy 79.35214 -182.2196) (xy 79.35214 -182.219346)
			(xy 79.352704 -182.174608) (xy 79.361721 -182.085586) (xy 79.379627 -181.997918) (xy 79.406242 -181.912491)
			(xy 79.42326 -181.871112) (xy 79.426824 -181.861521) (xy 79.426824 -181.841079) (xy 79.42326 -181.831488)
			(xy 79.406239 -181.790076) (xy 79.379604 -181.704589) (xy 79.361695 -181.616857) (xy 79.352696 -181.52777)
			(xy 79.35214 -181.483) (xy 79.352578 -181.44277) (xy 79.359832 -181.362636) (xy 79.366618 -181.32298)
			(xy 79.366618 -181.322726) (xy 79.368105 -181.310829) (xy 79.361202 -181.287898) (xy 79.35341 -181.278784)
			(xy 79.287878 -181.210204) (xy 79.265018 -181.202076) (xy 79.252826 -181.203854) (xy 79.222877 -181.207733)
			(xy 79.162627 -181.21193) (xy 79.13243 -181.212236) (xy 79.091315 -181.211773) (xy 79.009435 -181.204188)
			(xy 78.928604 -181.18908) (xy 78.849513 -181.166579) (xy 78.772835 -181.136875) (xy 78.699225 -181.100223)
			(xy 78.629311 -181.056935) (xy 78.563689 -181.007381) (xy 78.50292 -180.951983) (xy 78.447522 -180.891214)
			(xy 78.397967 -180.825593) (xy 78.354679 -180.755679) (xy 78.318026 -180.682069) (xy 78.288322 -180.605391)
			(xy 78.26582 -180.526299) (xy 78.250712 -180.445469) (xy 78.243127 -180.363589) (xy 78.242668 -180.322474)
			(xy 78.243154 -180.279736) (xy 78.251333 -180.194653) (xy 78.267631 -180.110746) (xy 78.2919 -180.028788)
			(xy 78.307438 -179.988972) (xy 78.311043 -179.978929) (xy 78.310391 -179.957622) (xy 78.306168 -179.947824)
			(xy 78.289089 -179.911553) (xy 78.260784 -179.836541) (xy 78.239347 -179.759284) (xy 78.224953 -179.680411)
			(xy 78.217719 -179.600562) (xy 78.217268 -179.560474) (xy 78.21746 -179.533866) (xy 78.220637 -179.480744)
			(xy 78.223618 -179.454302) (xy 78.224368 -179.443055) (xy 78.217254 -179.421697) (xy 78.209902 -179.413154)
			(xy 78.180933 -179.382157) (xy 78.128411 -179.31552) (xy 78.082469 -179.244186) (xy 78.043525 -179.168805)
			(xy 78.011931 -179.090059) (xy 77.987974 -179.008663) (xy 77.971872 -178.925358) (xy 77.963772 -178.840898)
			(xy 77.963268 -178.798474) (xy 9.44304 -178.798474) (xy 9.441677 -178.801459) (xy 9.412211 -178.847309)
			(xy 9.37652 -178.8885) (xy 9.335329 -178.924191) (xy 9.289479 -178.953657) (xy 9.239902 -178.976299)
			(xy 9.187607 -178.991654) (xy 9.133659 -178.99941) (xy 9.079157 -178.99941) (xy 9.025209 -178.991654)
			(xy 8.972914 -178.976299) (xy 8.923337 -178.953657) (xy 8.877487 -178.924191) (xy 8.836296 -178.8885)
			(xy 8.800605 -178.847309) (xy 8.771139 -178.801459) (xy 8.748497 -178.751882) (xy 8.733142 -178.699587)
			(xy 8.725386 -178.645639) (xy 8.7249 -178.618388) (xy 2.509012 -178.618388) (xy 2.509012 -190.64715)
			(xy 220.414866 -190.64715) (xy 220.414866 -190.59265) (xy 220.422621 -190.538705) (xy 220.437974 -190.486413)
			(xy 220.460612 -190.436837) (xy 220.490075 -190.390988) (xy 220.525762 -190.349798) (xy 220.566948 -190.314105)
			(xy 220.612793 -190.284636) (xy 220.662366 -190.261992) (xy 220.714656 -190.246632) (xy 220.7686 -190.238869)
			(xy 220.79585 -190.23838) (xy 221.78645 -190.23838) (xy 221.813704 -190.238864) (xy 221.867659 -190.246615)
			(xy 221.919961 -190.261966) (xy 221.969546 -190.284605) (xy 222.015404 -190.314071) (xy 222.056601 -190.349763)
			(xy 222.092299 -190.390956) (xy 222.121771 -190.43681) (xy 222.144416 -190.486392) (xy 222.159775 -190.538692)
			(xy 222.167533 -190.592646) (xy 222.167533 -190.647154) (xy 222.159775 -190.701108) (xy 222.144416 -190.753408)
			(xy 222.121771 -190.80299) (xy 222.092299 -190.848844) (xy 222.056601 -190.890037) (xy 222.015404 -190.925729)
			(xy 221.969546 -190.955195) (xy 221.919961 -190.977834) (xy 221.867659 -190.993185) (xy 221.813704 -191.000936)
			(xy 221.78645 -191.001396) (xy 220.79585 -191.001396) (xy 220.7686 -191.000931) (xy 220.714656 -190.993168)
			(xy 220.662366 -190.977808) (xy 220.612793 -190.955164) (xy 220.566948 -190.925695) (xy 220.525762 -190.890002)
			(xy 220.490075 -190.848812) (xy 220.460612 -190.802963) (xy 220.437974 -190.753387) (xy 220.422621 -190.701095)
			(xy 220.414866 -190.64715) (xy 2.509012 -190.64715) (xy 2.509012 -194.296284) (xy 255.545336 -194.296284)
			(xy 255.545336 -193.432684) (xy 255.545822 -193.405415) (xy 255.553584 -193.351431) (xy 255.568949 -193.299101)
			(xy 255.591606 -193.249491) (xy 255.621092 -193.20361) (xy 255.656807 -193.162393) (xy 255.698024 -193.126678)
			(xy 255.743905 -193.097192) (xy 255.793515 -193.074535) (xy 255.845845 -193.05917) (xy 255.899829 -193.051408)
			(xy 255.954367 -193.051408) (xy 256.008351 -193.05917) (xy 256.060681 -193.074535) (xy 256.110291 -193.097192)
			(xy 256.156172 -193.126678) (xy 256.197389 -193.162393) (xy 256.233104 -193.20361) (xy 256.26259 -193.249491)
			(xy 256.285247 -193.299101) (xy 256.300612 -193.351431) (xy 256.308374 -193.405415) (xy 256.30886 -193.432684)
			(xy 256.30886 -194.296284) (xy 256.308374 -194.323553) (xy 256.300612 -194.377537) (xy 256.285247 -194.429867)
			(xy 256.26259 -194.479477) (xy 256.25414 -194.492626) (xy 260.09346 -194.492626) (xy 260.09346 -193.502026)
			(xy 260.093946 -193.474757) (xy 260.101708 -193.420773) (xy 260.117073 -193.368443) (xy 260.13973 -193.318833)
			(xy 260.169216 -193.272952) (xy 260.204931 -193.231735) (xy 260.246148 -193.19602) (xy 260.292029 -193.166534)
			(xy 260.341639 -193.143877) (xy 260.393969 -193.128512) (xy 260.447953 -193.12075) (xy 260.502491 -193.12075)
			(xy 260.556475 -193.128512) (xy 260.608805 -193.143877) (xy 260.658415 -193.166534) (xy 260.704296 -193.19602)
			(xy 260.745513 -193.231735) (xy 260.781228 -193.272952) (xy 260.810714 -193.318833) (xy 260.833371 -193.368443)
			(xy 260.848736 -193.420773) (xy 260.856498 -193.474757) (xy 260.856984 -193.502026) (xy 260.856984 -194.492626)
			(xy 260.856498 -194.519895) (xy 260.848736 -194.573879) (xy 260.833371 -194.626209) (xy 260.810714 -194.675819)
			(xy 260.781228 -194.7217) (xy 260.745513 -194.762917) (xy 260.704296 -194.798632) (xy 260.658415 -194.828118)
			(xy 260.608805 -194.850775) (xy 260.556475 -194.86614) (xy 260.502491 -194.873902) (xy 260.447953 -194.873902)
			(xy 260.393969 -194.86614) (xy 260.341639 -194.850775) (xy 260.292029 -194.828118) (xy 260.246148 -194.798632)
			(xy 260.204931 -194.762917) (xy 260.169216 -194.7217) (xy 260.13973 -194.675819) (xy 260.117073 -194.626209)
			(xy 260.101708 -194.573879) (xy 260.093946 -194.519895) (xy 260.09346 -194.492626) (xy 256.25414 -194.492626)
			(xy 256.233104 -194.525358) (xy 256.197389 -194.566575) (xy 256.156172 -194.60229) (xy 256.110291 -194.631776)
			(xy 256.060681 -194.654433) (xy 256.008351 -194.669798) (xy 255.954367 -194.67756) (xy 255.899829 -194.67756)
			(xy 255.845845 -194.669798) (xy 255.793515 -194.654433) (xy 255.743905 -194.631776) (xy 255.698024 -194.60229)
			(xy 255.656807 -194.566575) (xy 255.621092 -194.525358) (xy 255.591606 -194.479477) (xy 255.568949 -194.429867)
			(xy 255.553584 -194.377537) (xy 255.545822 -194.323553) (xy 255.545336 -194.296284) (xy 2.509012 -194.296284)
			(xy 2.509012 -197.07352) (xy 255.545336 -197.07352) (xy 255.545336 -196.20992) (xy 255.545822 -196.182651)
			(xy 255.553584 -196.128667) (xy 255.568949 -196.076337) (xy 255.591606 -196.026727) (xy 255.621092 -195.980846)
			(xy 255.656807 -195.939629) (xy 255.698024 -195.903914) (xy 255.743905 -195.874428) (xy 255.793515 -195.851771)
			(xy 255.845845 -195.836406) (xy 255.899829 -195.828644) (xy 255.954367 -195.828644) (xy 256.008351 -195.836406)
			(xy 256.060681 -195.851771) (xy 256.110291 -195.874428) (xy 256.156172 -195.903914) (xy 256.197389 -195.939629)
			(xy 256.233104 -195.980846) (xy 256.26259 -196.026727) (xy 256.285247 -196.076337) (xy 256.300612 -196.128667)
			(xy 256.308374 -196.182651) (xy 256.30886 -196.20992) (xy 256.30886 -197.07352) (xy 256.308374 -197.100789)
			(xy 256.300612 -197.154773) (xy 256.285247 -197.207103) (xy 256.26259 -197.256713) (xy 256.233104 -197.302594)
			(xy 256.197389 -197.343811) (xy 256.156172 -197.379526) (xy 256.110291 -197.409012) (xy 256.060681 -197.431669)
			(xy 256.008351 -197.447034) (xy 255.954367 -197.454796) (xy 255.899829 -197.454796) (xy 255.845845 -197.447034)
			(xy 255.793515 -197.431669) (xy 255.743905 -197.409012) (xy 255.698024 -197.379526) (xy 255.656807 -197.343811)
			(xy 255.621092 -197.302594) (xy 255.591606 -197.256713) (xy 255.568949 -197.207103) (xy 255.553584 -197.154773)
			(xy 255.545822 -197.100789) (xy 255.545336 -197.07352) (xy 2.509012 -197.07352) (xy 2.509012 -199.868028)
			(xy 255.545336 -199.868028) (xy 255.545336 -199.004428) (xy 255.545822 -198.977159) (xy 255.553584 -198.923175)
			(xy 255.568949 -198.870845) (xy 255.591606 -198.821235) (xy 255.621092 -198.775354) (xy 255.656807 -198.734137)
			(xy 255.698024 -198.698422) (xy 255.743905 -198.668936) (xy 255.793515 -198.646279) (xy 255.845845 -198.630914)
			(xy 255.899829 -198.623152) (xy 255.954367 -198.623152) (xy 256.008351 -198.630914) (xy 256.060681 -198.646279)
			(xy 256.110291 -198.668936) (xy 256.156172 -198.698422) (xy 256.197389 -198.734137) (xy 256.233104 -198.775354)
			(xy 256.26259 -198.821235) (xy 256.285247 -198.870845) (xy 256.300612 -198.923175) (xy 256.308374 -198.977159)
			(xy 256.30886 -199.004428) (xy 256.30886 -199.868028) (xy 256.308374 -199.895297) (xy 256.300612 -199.949281)
			(xy 256.285247 -200.001611) (xy 256.26259 -200.051221) (xy 256.233104 -200.097102) (xy 256.197389 -200.138319)
			(xy 256.156172 -200.174034) (xy 256.110291 -200.20352) (xy 256.060681 -200.226177) (xy 256.008351 -200.241542)
			(xy 255.954367 -200.249304) (xy 255.899829 -200.249304) (xy 255.845845 -200.241542) (xy 255.793515 -200.226177)
			(xy 255.743905 -200.20352) (xy 255.698024 -200.174034) (xy 255.656807 -200.138319) (xy 255.621092 -200.097102)
			(xy 255.591606 -200.051221) (xy 255.568949 -200.001611) (xy 255.553584 -199.949281) (xy 255.545822 -199.895297)
			(xy 255.545336 -199.868028) (xy 2.509012 -199.868028) (xy 2.509012 -202.662536) (xy 255.545336 -202.662536)
			(xy 255.545336 -201.798936) (xy 255.545822 -201.771667) (xy 255.553584 -201.717683) (xy 255.568949 -201.665353)
			(xy 255.591606 -201.615743) (xy 255.621092 -201.569862) (xy 255.656807 -201.528645) (xy 255.698024 -201.49293)
			(xy 255.743905 -201.463444) (xy 255.793515 -201.440787) (xy 255.845845 -201.425422) (xy 255.899829 -201.41766)
			(xy 255.954367 -201.41766) (xy 256.008351 -201.425422) (xy 256.060681 -201.440787) (xy 256.110291 -201.463444)
			(xy 256.156172 -201.49293) (xy 256.197389 -201.528645) (xy 256.233104 -201.569862) (xy 256.26259 -201.615743)
			(xy 256.285247 -201.665353) (xy 256.300612 -201.717683) (xy 256.308374 -201.771667) (xy 256.30886 -201.798936)
			(xy 256.30886 -202.662536) (xy 256.308374 -202.689805) (xy 256.300612 -202.743789) (xy 256.285247 -202.796119)
			(xy 256.26259 -202.845729) (xy 256.233104 -202.89161) (xy 256.197389 -202.932827) (xy 256.156172 -202.968542)
			(xy 256.110291 -202.998028) (xy 256.060681 -203.020685) (xy 256.008351 -203.03605) (xy 255.954367 -203.043812)
			(xy 255.899829 -203.043812) (xy 255.845845 -203.03605) (xy 255.793515 -203.020685) (xy 255.743905 -202.998028)
			(xy 255.698024 -202.968542) (xy 255.656807 -202.932827) (xy 255.621092 -202.89161) (xy 255.591606 -202.845729)
			(xy 255.568949 -202.796119) (xy 255.553584 -202.743789) (xy 255.545822 -202.689805) (xy 255.545336 -202.662536)
			(xy 2.509012 -202.662536) (xy 2.509012 -205.439772) (xy 255.545336 -205.439772) (xy 255.545336 -204.576172)
			(xy 255.545822 -204.548903) (xy 255.553584 -204.494919) (xy 255.568949 -204.442589) (xy 255.591606 -204.392979)
			(xy 255.621092 -204.347098) (xy 255.656807 -204.305881) (xy 255.698024 -204.270166) (xy 255.743905 -204.24068)
			(xy 255.793515 -204.218023) (xy 255.845845 -204.202658) (xy 255.899829 -204.194896) (xy 255.954367 -204.194896)
			(xy 256.008351 -204.202658) (xy 256.060681 -204.218023) (xy 256.110291 -204.24068) (xy 256.156172 -204.270166)
			(xy 256.197389 -204.305881) (xy 256.233104 -204.347098) (xy 256.26259 -204.392979) (xy 256.285247 -204.442589)
			(xy 256.300612 -204.494919) (xy 256.308374 -204.548903) (xy 256.30886 -204.576172) (xy 256.30886 -205.439772)
			(xy 256.308374 -205.467041) (xy 256.300612 -205.521025) (xy 256.285247 -205.573355) (xy 256.26259 -205.622965)
			(xy 256.233104 -205.668846) (xy 256.197389 -205.710063) (xy 256.156172 -205.745778) (xy 256.110291 -205.775264)
			(xy 256.060681 -205.797921) (xy 256.008351 -205.813286) (xy 255.954367 -205.821048) (xy 255.899829 -205.821048)
			(xy 255.845845 -205.813286) (xy 255.793515 -205.797921) (xy 255.743905 -205.775264) (xy 255.698024 -205.745778)
			(xy 255.656807 -205.710063) (xy 255.621092 -205.668846) (xy 255.591606 -205.622965) (xy 255.568949 -205.573355)
			(xy 255.553584 -205.521025) (xy 255.545822 -205.467041) (xy 255.545336 -205.439772) (xy 2.509012 -205.439772)
			(xy 2.509012 -207.499458) (xy 97.408492 -207.499458) (xy 97.408492 -206.635858) (xy 97.408978 -206.608589)
			(xy 97.41674 -206.554605) (xy 97.432105 -206.502275) (xy 97.454762 -206.452665) (xy 97.484248 -206.406784)
			(xy 97.519963 -206.365567) (xy 97.56118 -206.329852) (xy 97.607061 -206.300366) (xy 97.656671 -206.277709)
			(xy 97.709001 -206.262344) (xy 97.762985 -206.254582) (xy 97.817523 -206.254582) (xy 97.871507 -206.262344)
			(xy 97.923837 -206.277709) (xy 97.973447 -206.300366) (xy 98.019328 -206.329852) (xy 98.060545 -206.365567)
			(xy 98.09626 -206.406784) (xy 98.125746 -206.452665) (xy 98.148403 -206.502275) (xy 98.163768 -206.554605)
			(xy 98.17153 -206.608589) (xy 98.172016 -206.635858) (xy 98.172016 -207.499458) (xy 98.17153 -207.526727)
			(xy 98.163768 -207.580711) (xy 98.148403 -207.633041) (xy 98.125746 -207.682651) (xy 98.09626 -207.728532)
			(xy 98.060545 -207.769749) (xy 98.019328 -207.805464) (xy 97.973447 -207.83495) (xy 97.923837 -207.857607)
			(xy 97.871507 -207.872972) (xy 97.817523 -207.880734) (xy 97.762985 -207.880734) (xy 97.709001 -207.872972)
			(xy 97.656671 -207.857607) (xy 97.607061 -207.83495) (xy 97.56118 -207.805464) (xy 97.519963 -207.769749)
			(xy 97.484248 -207.728532) (xy 97.454762 -207.682651) (xy 97.432105 -207.633041) (xy 97.41674 -207.580711)
			(xy 97.408978 -207.526727) (xy 97.408492 -207.499458) (xy 2.509012 -207.499458) (xy 2.509012 -209.023458)
			(xy 94.105984 -209.023458) (xy 94.105984 -208.159858) (xy 94.10647 -208.132589) (xy 94.114232 -208.078605)
			(xy 94.129597 -208.026275) (xy 94.152254 -207.976665) (xy 94.18174 -207.930784) (xy 94.217455 -207.889567)
			(xy 94.258672 -207.853852) (xy 94.304553 -207.824366) (xy 94.354163 -207.801709) (xy 94.406493 -207.786344)
			(xy 94.460477 -207.778582) (xy 94.515015 -207.778582) (xy 94.568999 -207.786344) (xy 94.621329 -207.801709)
			(xy 94.670939 -207.824366) (xy 94.71682 -207.853852) (xy 94.758037 -207.889567) (xy 94.793752 -207.930784)
			(xy 94.823238 -207.976665) (xy 94.845895 -208.026275) (xy 94.86126 -208.078605) (xy 94.869022 -208.132589)
			(xy 94.869508 -208.159858) (xy 94.869508 -208.217008) (xy 255.545336 -208.217008) (xy 255.545336 -207.353408)
			(xy 255.545822 -207.326139) (xy 255.553584 -207.272155) (xy 255.568949 -207.219825) (xy 255.591606 -207.170215)
			(xy 255.621092 -207.124334) (xy 255.656807 -207.083117) (xy 255.698024 -207.047402) (xy 255.743905 -207.017916)
			(xy 255.793515 -206.995259) (xy 255.845845 -206.979894) (xy 255.899829 -206.972132) (xy 255.954367 -206.972132)
			(xy 256.008351 -206.979894) (xy 256.060681 -206.995259) (xy 256.110291 -207.017916) (xy 256.156172 -207.047402)
			(xy 256.197389 -207.083117) (xy 256.233104 -207.124334) (xy 256.26259 -207.170215) (xy 256.285247 -207.219825)
			(xy 256.300612 -207.272155) (xy 256.308374 -207.326139) (xy 256.30886 -207.353408) (xy 256.30886 -208.217008)
			(xy 256.308374 -208.244277) (xy 256.300612 -208.298261) (xy 256.285247 -208.350591) (xy 256.26259 -208.400201)
			(xy 256.233104 -208.446082) (xy 256.197389 -208.487299) (xy 256.156172 -208.523014) (xy 256.110291 -208.5525)
			(xy 256.060681 -208.575157) (xy 256.008351 -208.590522) (xy 255.954367 -208.598284) (xy 255.899829 -208.598284)
			(xy 255.845845 -208.590522) (xy 255.793515 -208.575157) (xy 255.743905 -208.5525) (xy 255.698024 -208.523014)
			(xy 255.656807 -208.487299) (xy 255.621092 -208.446082) (xy 255.591606 -208.400201) (xy 255.568949 -208.350591)
			(xy 255.553584 -208.298261) (xy 255.545822 -208.244277) (xy 255.545336 -208.217008) (xy 94.869508 -208.217008)
			(xy 94.869508 -209.023458) (xy 94.869022 -209.050727) (xy 94.86126 -209.104711) (xy 94.845895 -209.157041)
			(xy 94.823238 -209.206651) (xy 94.793752 -209.252532) (xy 94.758037 -209.293749) (xy 94.71682 -209.329464)
			(xy 94.670939 -209.35895) (xy 94.621329 -209.381607) (xy 94.568999 -209.396972) (xy 94.515015 -209.404734)
			(xy 94.460477 -209.404734) (xy 94.406493 -209.396972) (xy 94.354163 -209.381607) (xy 94.304553 -209.35895)
			(xy 94.258672 -209.329464) (xy 94.217455 -209.293749) (xy 94.18174 -209.252532) (xy 94.152254 -209.206651)
			(xy 94.129597 -209.157041) (xy 94.114232 -209.104711) (xy 94.10647 -209.050727) (xy 94.105984 -209.023458)
			(xy 2.509012 -209.023458) (xy 2.509012 -212.98027) (xy 78.81214 -212.98027) (xy 78.81617 -212.837935)
			(xy 78.828245 -212.696055) (xy 78.848328 -212.555087) (xy 78.876355 -212.41548) (xy 78.912235 -212.277682)
			(xy 78.955853 -212.142135) (xy 79.00707 -212.009273) (xy 79.065721 -211.879521) (xy 79.131619 -211.753295)
			(xy 79.204553 -211.630999) (xy 79.28429 -211.513026) (xy 79.370572 -211.399753) (xy 79.463125 -211.291542)
			(xy 79.561652 -211.188741) (xy 79.665837 -211.091679) (xy 79.775346 -211.000667) (xy 79.889829 -210.915995)
			(xy 80.008919 -210.837937) (xy 80.132234 -210.766741) (xy 80.25938 -210.702635) (xy 80.389949 -210.645826)
			(xy 80.523523 -210.596494) (xy 80.659674 -210.554798) (xy 80.797965 -210.520872) (xy 80.937955 -210.494824)
			(xy 81.079194 -210.476738) (xy 81.22123 -210.466671) (xy 81.363608 -210.464656) (xy 81.505872 -210.470699)
			(xy 81.647566 -210.484781) (xy 81.788236 -210.506857) (xy 81.927433 -210.536857) (xy 82.064709 -210.574683)
			(xy 82.199625 -210.620215) (xy 82.331749 -210.673306) (xy 82.460658 -210.733788) (xy 82.585939 -210.801466)
			(xy 82.70719 -210.876123) (xy 82.824023 -210.957521) (xy 82.936064 -211.045398) (xy 83.042954 -211.139473)
			(xy 83.144351 -211.239445) (xy 83.239929 -211.344993) (xy 83.329383 -211.455779) (xy 83.412425 -211.571448)
			(xy 83.488791 -211.691631) (xy 83.558235 -211.815941) (xy 83.620535 -211.943982) (xy 83.675491 -212.075341)
			(xy 83.69835 -212.140038) (xy 94.106492 -212.140038) (xy 94.106492 -211.276438) (xy 94.106978 -211.249187)
			(xy 94.114734 -211.195239) (xy 94.130089 -211.142944) (xy 94.152731 -211.093367) (xy 94.182197 -211.047517)
			(xy 94.217888 -211.006326) (xy 94.259079 -210.970635) (xy 94.304929 -210.941169) (xy 94.354506 -210.918527)
			(xy 94.406801 -210.903172) (xy 94.460749 -210.895416) (xy 94.515251 -210.895416) (xy 94.569199 -210.903172)
			(xy 94.621494 -210.918527) (xy 94.671071 -210.941169) (xy 94.716921 -210.970635) (xy 94.758112 -211.006326)
			(xy 94.793803 -211.047517) (xy 94.823269 -211.093367) (xy 94.845911 -211.142944) (xy 94.861266 -211.195239)
			(xy 94.869022 -211.249187) (xy 94.869508 -211.276438) (xy 94.869508 -212.140038) (xy 94.869022 -212.167289)
			(xy 94.861266 -212.221237) (xy 94.845911 -212.273532) (xy 94.823269 -212.323109) (xy 94.793803 -212.368959)
			(xy 94.758112 -212.41015) (xy 94.716921 -212.445841) (xy 94.671071 -212.475307) (xy 94.621494 -212.497949)
			(xy 94.569199 -212.513304) (xy 94.515251 -212.52106) (xy 94.460749 -212.52106) (xy 94.406801 -212.513304)
			(xy 94.354506 -212.497949) (xy 94.304929 -212.475307) (xy 94.259079 -212.445841) (xy 94.217888 -212.41015)
			(xy 94.182197 -212.368959) (xy 94.152731 -212.323109) (xy 94.130089 -212.273532) (xy 94.114734 -212.221237)
			(xy 94.106978 -212.167289) (xy 94.106492 -212.140038) (xy 83.69835 -212.140038) (xy 83.722928 -212.2096)
			(xy 83.762692 -212.346327) (xy 83.794658 -212.485085) (xy 83.818723 -212.625429) (xy 83.834809 -212.76691)
			(xy 83.842864 -212.909074) (xy 83.843368 -212.98027) (xy 140.011408 -212.98027) (xy 140.015438 -212.837906)
			(xy 140.027516 -212.695998) (xy 140.047604 -212.555001) (xy 140.075636 -212.415366) (xy 140.111523 -212.27754)
			(xy 140.15515 -212.141966) (xy 140.206377 -212.009077) (xy 140.26504 -211.879298) (xy 140.330952 -211.753047)
			(xy 140.403901 -211.630727) (xy 140.483653 -211.51273) (xy 140.569953 -211.399434) (xy 140.662525 -211.291201)
			(xy 140.761071 -211.188379) (xy 140.865277 -211.091298) (xy 140.974809 -211.000267) (xy 141.089315 -210.915579)
			(xy 141.208429 -210.837504) (xy 141.331769 -210.766294) (xy 141.45894 -210.702175) (xy 141.589536 -210.645354)
			(xy 141.723136 -210.596013) (xy 141.859315 -210.554308) (xy 141.997634 -210.520375) (xy 142.137652 -210.494322)
			(xy 142.278919 -210.476232) (xy 142.420984 -210.466163) (xy 142.563391 -210.464148) (xy 142.705684 -210.470192)
			(xy 142.847406 -210.484278) (xy 142.988105 -210.506358) (xy 143.12733 -210.536363) (xy 143.264634 -210.574197)
			(xy 143.399577 -210.619738) (xy 143.531728 -210.672841) (xy 143.660663 -210.733335) (xy 143.785969 -210.801026)
			(xy 143.907245 -210.875699) (xy 144.024101 -210.957113) (xy 144.093464 -211.011516) (xy 255.545336 -211.011516)
			(xy 255.545336 -210.147916) (xy 255.545822 -210.120647) (xy 255.553584 -210.066663) (xy 255.568949 -210.014333)
			(xy 255.591606 -209.964723) (xy 255.621092 -209.918842) (xy 255.656807 -209.877625) (xy 255.698024 -209.84191)
			(xy 255.743905 -209.812424) (xy 255.793515 -209.789767) (xy 255.845845 -209.774402) (xy 255.899829 -209.76664)
			(xy 255.954367 -209.76664) (xy 256.008351 -209.774402) (xy 256.060681 -209.789767) (xy 256.110291 -209.812424)
			(xy 256.156172 -209.84191) (xy 256.197389 -209.877625) (xy 256.233104 -209.918842) (xy 256.26259 -209.964723)
			(xy 256.285247 -210.014333) (xy 256.300612 -210.066663) (xy 256.308374 -210.120647) (xy 256.30886 -210.147916)
			(xy 256.30886 -211.011516) (xy 256.308374 -211.038785) (xy 256.300612 -211.092769) (xy 256.285247 -211.145099)
			(xy 256.26259 -211.194709) (xy 256.233104 -211.24059) (xy 256.197389 -211.281807) (xy 256.156172 -211.317522)
			(xy 256.110291 -211.347008) (xy 256.060681 -211.369665) (xy 256.008351 -211.38503) (xy 255.954367 -211.392792)
			(xy 255.899829 -211.392792) (xy 255.845845 -211.38503) (xy 255.793515 -211.369665) (xy 255.743905 -211.347008)
			(xy 255.698024 -211.317522) (xy 255.656807 -211.281807) (xy 255.621092 -211.24059) (xy 255.591606 -211.194709)
			(xy 255.568949 -211.145099) (xy 255.553584 -211.092769) (xy 255.545822 -211.038785) (xy 255.545336 -211.011516)
			(xy 144.093464 -211.011516) (xy 144.136165 -211.045007) (xy 144.243077 -211.139101) (xy 144.344494 -211.239093)
			(xy 144.440091 -211.344662) (xy 144.529563 -211.455471) (xy 144.612622 -211.571164) (xy 144.689003 -211.691371)
			(xy 144.758461 -211.815706) (xy 144.820774 -211.943772) (xy 144.875741 -212.075159) (xy 144.923187 -212.209444)
			(xy 144.96296 -212.346199) (xy 144.994932 -212.484985) (xy 145.019002 -212.625357) (xy 145.035091 -212.766867)
			(xy 145.043148 -212.909059) (xy 145.043652 -212.98027) (xy 145.043148 -213.051481) (xy 145.035091 -213.193673)
			(xy 145.019002 -213.335183) (xy 144.994932 -213.475555) (xy 144.96296 -213.614341) (xy 144.923187 -213.751096)
			(xy 144.90378 -213.806024) (xy 255.545336 -213.806024) (xy 255.545336 -212.942424) (xy 255.545822 -212.915155)
			(xy 255.553584 -212.861171) (xy 255.568949 -212.808841) (xy 255.591606 -212.759231) (xy 255.621092 -212.71335)
			(xy 255.656807 -212.672133) (xy 255.698024 -212.636418) (xy 255.743905 -212.606932) (xy 255.793515 -212.584275)
			(xy 255.845845 -212.56891) (xy 255.899829 -212.561148) (xy 255.954367 -212.561148) (xy 256.008351 -212.56891)
			(xy 256.060681 -212.584275) (xy 256.110291 -212.606932) (xy 256.156172 -212.636418) (xy 256.197389 -212.672133)
			(xy 256.233104 -212.71335) (xy 256.26259 -212.759231) (xy 256.285247 -212.808841) (xy 256.300612 -212.861171)
			(xy 256.308374 -212.915155) (xy 256.30886 -212.942424) (xy 256.30886 -212.980016) (xy 326.752208 -212.980016)
			(xy 326.756238 -212.837681) (xy 326.768313 -212.695801) (xy 326.788396 -212.554833) (xy 326.816423 -212.415226)
			(xy 326.852303 -212.277428) (xy 326.895921 -212.141881) (xy 326.947138 -212.009019) (xy 327.005789 -211.879267)
			(xy 327.071687 -211.753041) (xy 327.144621 -211.630745) (xy 327.224358 -211.512772) (xy 327.31064 -211.399499)
			(xy 327.403193 -211.291288) (xy 327.50172 -211.188487) (xy 327.605905 -211.091425) (xy 327.715414 -211.000413)
			(xy 327.829897 -210.915741) (xy 327.948987 -210.837683) (xy 328.072302 -210.766487) (xy 328.199448 -210.702381)
			(xy 328.330017 -210.645572) (xy 328.463591 -210.59624) (xy 328.599742 -210.554544) (xy 328.738033 -210.520618)
			(xy 328.878023 -210.49457) (xy 329.019262 -210.476484) (xy 329.161298 -210.466417) (xy 329.303676 -210.464402)
			(xy 329.44594 -210.470445) (xy 329.587634 -210.484527) (xy 329.728304 -210.506603) (xy 329.867501 -210.536603)
			(xy 330.004777 -210.574429) (xy 330.139693 -210.619961) (xy 330.271817 -210.673052) (xy 330.400726 -210.733534)
			(xy 330.526007 -210.801212) (xy 330.647258 -210.875869) (xy 330.764091 -210.957267) (xy 330.876132 -211.045144)
			(xy 330.983022 -211.139219) (xy 331.084419 -211.239191) (xy 331.179997 -211.344739) (xy 331.269451 -211.455525)
			(xy 331.352493 -211.571194) (xy 331.428859 -211.691377) (xy 331.498303 -211.815687) (xy 331.560603 -211.943728)
			(xy 331.615559 -212.075087) (xy 331.662996 -212.209346) (xy 331.70276 -212.346073) (xy 331.734726 -212.484831)
			(xy 331.758791 -212.625175) (xy 331.774877 -212.766656) (xy 331.782932 -212.90882) (xy 331.783436 -212.980016)
			(xy 387.951476 -212.980016) (xy 387.955506 -212.837652) (xy 387.967584 -212.695744) (xy 387.987672 -212.554747)
			(xy 388.015704 -212.415112) (xy 388.051591 -212.277286) (xy 388.095218 -212.141712) (xy 388.146445 -212.008823)
			(xy 388.205108 -211.879044) (xy 388.27102 -211.752793) (xy 388.343969 -211.630473) (xy 388.423721 -211.512476)
			(xy 388.510021 -211.39918) (xy 388.602593 -211.290947) (xy 388.701139 -211.188125) (xy 388.805345 -211.091044)
			(xy 388.914877 -211.000013) (xy 389.029383 -210.915325) (xy 389.148497 -210.83725) (xy 389.271837 -210.76604)
			(xy 389.399008 -210.701921) (xy 389.529604 -210.6451) (xy 389.663204 -210.595759) (xy 389.799383 -210.554054)
			(xy 389.937702 -210.520121) (xy 390.07772 -210.494068) (xy 390.218987 -210.475978) (xy 390.361052 -210.465909)
			(xy 390.503459 -210.463894) (xy 390.645752 -210.469938) (xy 390.787474 -210.484024) (xy 390.928173 -210.506104)
			(xy 391.067398 -210.536109) (xy 391.204702 -210.573943) (xy 391.339645 -210.619484) (xy 391.471796 -210.672587)
			(xy 391.600731 -210.733081) (xy 391.726037 -210.800772) (xy 391.847313 -210.875445) (xy 391.964169 -210.956859)
			(xy 392.076233 -211.044753) (xy 392.183145 -211.138847) (xy 392.284562 -211.238839) (xy 392.380159 -211.344408)
			(xy 392.469631 -211.455217) (xy 392.55269 -211.57091) (xy 392.629071 -211.691117) (xy 392.698529 -211.815452)
			(xy 392.760842 -211.943518) (xy 392.815809 -212.074905) (xy 392.863255 -212.20919) (xy 392.903028 -212.345945)
			(xy 392.935 -212.484731) (xy 392.95907 -212.625103) (xy 392.975159 -212.766613) (xy 392.983216 -212.908805)
			(xy 392.98372 -212.980016) (xy 392.983216 -213.051227) (xy 392.975159 -213.193419) (xy 392.95907 -213.334929)
			(xy 392.935 -213.475301) (xy 392.903028 -213.614087) (xy 392.863255 -213.750842) (xy 392.815809 -213.885127)
			(xy 392.760842 -214.016514) (xy 392.698529 -214.14458) (xy 392.629071 -214.268915) (xy 392.55269 -214.389122)
			(xy 392.469631 -214.504815) (xy 392.380159 -214.615624) (xy 392.284562 -214.721193) (xy 392.183145 -214.821185)
			(xy 392.076233 -214.915279) (xy 391.964169 -215.003173) (xy 391.847313 -215.084587) (xy 391.726037 -215.15926)
			(xy 391.600731 -215.226951) (xy 391.471796 -215.287445) (xy 391.339645 -215.340548) (xy 391.204702 -215.386089)
			(xy 391.067398 -215.423923) (xy 390.928173 -215.453928) (xy 390.787474 -215.476008) (xy 390.645752 -215.490094)
			(xy 390.503459 -215.496138) (xy 390.361052 -215.494123) (xy 390.218987 -215.484054) (xy 390.07772 -215.465964)
			(xy 389.937702 -215.439911) (xy 389.799383 -215.405978) (xy 389.663204 -215.364273) (xy 389.529604 -215.314932)
			(xy 389.399008 -215.258111) (xy 389.271837 -215.193992) (xy 389.148497 -215.122782) (xy 389.029383 -215.044707)
			(xy 388.914877 -214.960019) (xy 388.805345 -214.868988) (xy 388.701139 -214.771907) (xy 388.602593 -214.669085)
			(xy 388.510021 -214.560852) (xy 388.423721 -214.447556) (xy 388.343969 -214.329559) (xy 388.27102 -214.207239)
			(xy 388.205108 -214.080988) (xy 388.146445 -213.951209) (xy 388.095218 -213.81832) (xy 388.051591 -213.682746)
			(xy 388.015704 -213.54492) (xy 387.987672 -213.405285) (xy 387.967584 -213.264288) (xy 387.955506 -213.12238)
			(xy 387.951476 -212.980016) (xy 331.783436 -212.980016) (xy 331.782932 -213.051212) (xy 331.774877 -213.193376)
			(xy 331.758791 -213.334857) (xy 331.734726 -213.475201) (xy 331.70276 -213.613959) (xy 331.662996 -213.750686)
			(xy 331.615559 -213.884945) (xy 331.560603 -214.016304) (xy 331.498303 -214.144345) (xy 331.428859 -214.268655)
			(xy 331.352493 -214.388838) (xy 331.269451 -214.504507) (xy 331.179997 -214.615293) (xy 331.084419 -214.720841)
			(xy 330.983022 -214.820813) (xy 330.876132 -214.914888) (xy 330.764091 -215.002765) (xy 330.647258 -215.084163)
			(xy 330.526007 -215.15882) (xy 330.400726 -215.226498) (xy 330.271817 -215.28698) (xy 330.139693 -215.340071)
			(xy 330.004777 -215.385603) (xy 329.867501 -215.423429) (xy 329.728304 -215.453429) (xy 329.587634 -215.475505)
			(xy 329.44594 -215.489587) (xy 329.303676 -215.49563) (xy 329.161298 -215.493615) (xy 329.019262 -215.483548)
			(xy 328.878023 -215.465462) (xy 328.738033 -215.439414) (xy 328.599742 -215.405488) (xy 328.463591 -215.363792)
			(xy 328.330017 -215.31446) (xy 328.199448 -215.257651) (xy 328.072302 -215.193545) (xy 327.948987 -215.122349)
			(xy 327.829897 -215.044291) (xy 327.715414 -214.959619) (xy 327.605905 -214.868607) (xy 327.50172 -214.771545)
			(xy 327.403193 -214.668744) (xy 327.31064 -214.560533) (xy 327.224358 -214.44726) (xy 327.144621 -214.329287)
			(xy 327.071687 -214.206991) (xy 327.005789 -214.080765) (xy 326.947138 -213.951013) (xy 326.895921 -213.818151)
			(xy 326.852303 -213.682604) (xy 326.816423 -213.544806) (xy 326.788396 -213.405199) (xy 326.768313 -213.264231)
			(xy 326.756238 -213.122351) (xy 326.752208 -212.980016) (xy 256.30886 -212.980016) (xy 256.30886 -213.806024)
			(xy 256.308374 -213.833293) (xy 256.300612 -213.887277) (xy 256.285247 -213.939607) (xy 256.26259 -213.989217)
			(xy 256.233104 -214.035098) (xy 256.197389 -214.076315) (xy 256.156172 -214.11203) (xy 256.110291 -214.141516)
			(xy 256.060681 -214.164173) (xy 256.008351 -214.179538) (xy 255.954367 -214.1873) (xy 255.899829 -214.1873)
			(xy 255.845845 -214.179538) (xy 255.793515 -214.164173) (xy 255.743905 -214.141516) (xy 255.698024 -214.11203)
			(xy 255.656807 -214.076315) (xy 255.621092 -214.035098) (xy 255.591606 -213.989217) (xy 255.568949 -213.939607)
			(xy 255.553584 -213.887277) (xy 255.545822 -213.833293) (xy 255.545336 -213.806024) (xy 144.90378 -213.806024)
			(xy 144.875741 -213.885381) (xy 144.820774 -214.016768) (xy 144.758461 -214.144834) (xy 144.689003 -214.269169)
			(xy 144.612622 -214.389376) (xy 144.529563 -214.505069) (xy 144.440091 -214.615878) (xy 144.344494 -214.721447)
			(xy 144.243077 -214.821439) (xy 144.136165 -214.915533) (xy 144.024101 -215.003427) (xy 143.907245 -215.084841)
			(xy 143.785969 -215.159514) (xy 143.660663 -215.227205) (xy 143.531728 -215.287699) (xy 143.399577 -215.340802)
			(xy 143.264634 -215.386343) (xy 143.12733 -215.424177) (xy 142.988105 -215.454182) (xy 142.847406 -215.476262)
			(xy 142.705684 -215.490348) (xy 142.563391 -215.496392) (xy 142.420984 -215.494377) (xy 142.278919 -215.484308)
			(xy 142.137652 -215.466218) (xy 141.997634 -215.440165) (xy 141.859315 -215.406232) (xy 141.723136 -215.364527)
			(xy 141.589536 -215.315186) (xy 141.45894 -215.258365) (xy 141.331769 -215.194246) (xy 141.208429 -215.123036)
			(xy 141.089315 -215.044961) (xy 140.974809 -214.960273) (xy 140.865277 -214.869242) (xy 140.761071 -214.772161)
			(xy 140.662525 -214.669339) (xy 140.569953 -214.561106) (xy 140.483653 -214.44781) (xy 140.403901 -214.329813)
			(xy 140.330952 -214.207493) (xy 140.26504 -214.081242) (xy 140.206377 -213.951463) (xy 140.15515 -213.818574)
			(xy 140.111523 -213.683) (xy 140.075636 -213.545174) (xy 140.047604 -213.405539) (xy 140.027516 -213.264542)
			(xy 140.015438 -213.122634) (xy 140.011408 -212.98027) (xy 83.843368 -212.98027) (xy 83.842864 -213.051466)
			(xy 83.834809 -213.19363) (xy 83.818723 -213.335111) (xy 83.794658 -213.475455) (xy 83.762692 -213.614213)
			(xy 83.722928 -213.75094) (xy 83.675491 -213.885199) (xy 83.620535 -214.016558) (xy 83.558235 -214.144599)
			(xy 83.488791 -214.268909) (xy 83.412425 -214.389092) (xy 83.329383 -214.504761) (xy 83.239929 -214.615547)
			(xy 83.144351 -214.721095) (xy 83.042954 -214.821067) (xy 82.936064 -214.915142) (xy 82.837488 -214.992458)
			(xy 94.106492 -214.992458) (xy 94.106492 -214.128858) (xy 94.106978 -214.101607) (xy 94.114734 -214.047659)
			(xy 94.130089 -213.995364) (xy 94.152731 -213.945787) (xy 94.182197 -213.899937) (xy 94.217888 -213.858746)
			(xy 94.259079 -213.823055) (xy 94.304929 -213.793589) (xy 94.354506 -213.770947) (xy 94.406801 -213.755592)
			(xy 94.460749 -213.747836) (xy 94.515251 -213.747836) (xy 94.569199 -213.755592) (xy 94.621494 -213.770947)
			(xy 94.671071 -213.793589) (xy 94.716921 -213.823055) (xy 94.758112 -213.858746) (xy 94.793803 -213.899937)
			(xy 94.823269 -213.945787) (xy 94.845911 -213.995364) (xy 94.861266 -214.047659) (xy 94.869022 -214.101607)
			(xy 94.869508 -214.128858) (xy 94.869508 -214.992458) (xy 94.869022 -215.019709) (xy 94.861266 -215.073657)
			(xy 94.845911 -215.125952) (xy 94.823269 -215.175529) (xy 94.793803 -215.221379) (xy 94.758112 -215.26257)
			(xy 94.716921 -215.298261) (xy 94.671071 -215.327727) (xy 94.621494 -215.350369) (xy 94.569199 -215.365724)
			(xy 94.515251 -215.37348) (xy 94.460749 -215.37348) (xy 94.406801 -215.365724) (xy 94.354506 -215.350369)
			(xy 94.304929 -215.327727) (xy 94.259079 -215.298261) (xy 94.217888 -215.26257) (xy 94.182197 -215.221379)
			(xy 94.152731 -215.175529) (xy 94.130089 -215.125952) (xy 94.114734 -215.073657) (xy 94.106978 -215.019709)
			(xy 94.106492 -214.992458) (xy 82.837488 -214.992458) (xy 82.824023 -215.003019) (xy 82.70719 -215.084417)
			(xy 82.585939 -215.159074) (xy 82.460658 -215.226752) (xy 82.331749 -215.287234) (xy 82.199625 -215.340325)
			(xy 82.064709 -215.385857) (xy 81.927433 -215.423683) (xy 81.788236 -215.453683) (xy 81.647566 -215.475759)
			(xy 81.505872 -215.489841) (xy 81.363608 -215.495884) (xy 81.22123 -215.493869) (xy 81.079194 -215.483802)
			(xy 80.937955 -215.465716) (xy 80.797965 -215.439668) (xy 80.659674 -215.405742) (xy 80.523523 -215.364046)
			(xy 80.389949 -215.314714) (xy 80.25938 -215.257905) (xy 80.132234 -215.193799) (xy 80.008919 -215.122603)
			(xy 79.889829 -215.044545) (xy 79.775346 -214.959873) (xy 79.665837 -214.868861) (xy 79.561652 -214.771799)
			(xy 79.463125 -214.668998) (xy 79.370572 -214.560787) (xy 79.28429 -214.447514) (xy 79.204553 -214.329541)
			(xy 79.131619 -214.207245) (xy 79.065721 -214.081019) (xy 79.00707 -213.951267) (xy 78.955853 -213.818405)
			(xy 78.912235 -213.682858) (xy 78.876355 -213.54506) (xy 78.848328 -213.405453) (xy 78.828245 -213.264485)
			(xy 78.81617 -213.122605) (xy 78.81214 -212.98027) (xy 2.509012 -212.98027) (xy 2.509012 -217.548574)
			(xy 338.152884 -217.548574) (xy 338.152884 -217.494026) (xy 338.160647 -217.440032) (xy 338.176017 -217.387693)
			(xy 338.198679 -217.338074) (xy 338.228172 -217.292186) (xy 338.263897 -217.250963) (xy 338.305125 -217.215244)
			(xy 338.351016 -217.185756) (xy 338.400638 -217.1631) (xy 338.452979 -217.147737) (xy 338.506973 -217.13998)
			(xy 338.534248 -217.13952) (xy 339.550248 -217.13952) (xy 339.577514 -217.140046) (xy 339.63149 -217.147813)
			(xy 339.683811 -217.163181) (xy 339.733413 -217.185839) (xy 339.779286 -217.215325) (xy 339.820495 -217.251039)
			(xy 339.856204 -217.292253) (xy 339.885684 -217.338129) (xy 339.908336 -217.387734) (xy 339.923698 -217.440057)
			(xy 339.931458 -217.494034) (xy 339.931458 -217.548566) (xy 339.923698 -217.602543) (xy 339.908336 -217.654866)
			(xy 339.885684 -217.704471) (xy 339.856204 -217.750347) (xy 339.820495 -217.791561) (xy 339.779286 -217.827275)
			(xy 339.733413 -217.856761) (xy 339.683811 -217.879419) (xy 339.63149 -217.894787) (xy 339.577514 -217.902554)
			(xy 339.550248 -217.903044) (xy 338.534248 -217.903044) (xy 338.506973 -217.90262) (xy 338.452979 -217.894863)
			(xy 338.400638 -217.8795) (xy 338.351016 -217.856844) (xy 338.305125 -217.827356) (xy 338.263897 -217.791637)
			(xy 338.228172 -217.750414) (xy 338.198679 -217.704526) (xy 338.176017 -217.654907) (xy 338.160647 -217.602568)
			(xy 338.152884 -217.548574) (xy 2.509012 -217.548574) (xy 2.509012 -219.820372) (xy 129.049982 -219.820372)
			(xy 129.049982 -219.765828) (xy 129.057745 -219.71184) (xy 129.073111 -219.659505) (xy 129.095769 -219.609891)
			(xy 129.125257 -219.564005) (xy 129.160975 -219.522783) (xy 129.202196 -219.487064) (xy 129.24808 -219.457575)
			(xy 129.297694 -219.434915) (xy 129.350028 -219.419547) (xy 129.404016 -219.411783) (xy 129.431288 -219.411296)
			(xy 130.447288 -219.411296) (xy 130.474557 -219.411843) (xy 130.528539 -219.419602) (xy 130.580867 -219.434966)
			(xy 130.630476 -219.45762) (xy 130.676357 -219.487104) (xy 130.717574 -219.522818) (xy 130.753288 -219.564034)
			(xy 130.782774 -219.609913) (xy 130.80543 -219.659522) (xy 130.820795 -219.711849) (xy 130.828557 -219.765831)
			(xy 130.828557 -219.820369) (xy 130.820795 -219.874351) (xy 130.80543 -219.926678) (xy 130.782774 -219.976287)
			(xy 130.753288 -220.022166) (xy 130.717574 -220.063382) (xy 130.676357 -220.099096) (xy 130.630476 -220.12858)
			(xy 130.580867 -220.151234) (xy 130.528539 -220.166598) (xy 130.474557 -220.174357) (xy 130.447288 -220.17482)
			(xy 129.431288 -220.17482) (xy 129.404016 -220.174417) (xy 129.350028 -220.166653) (xy 129.297694 -220.151285)
			(xy 129.24808 -220.128625) (xy 129.202196 -220.099136) (xy 129.160975 -220.063417) (xy 129.125257 -220.022195)
			(xy 129.095769 -219.976309) (xy 129.073111 -219.926695) (xy 129.057745 -219.87436) (xy 129.049982 -219.820372)
			(xy 2.509012 -219.820372) (xy 2.509012 -243.6744) (xy 108.185132 -243.6744) (xy 108.189304 -243.624054)
			(xy 108.201706 -243.575081) (xy 108.222 -243.528817) (xy 108.249632 -243.486525) (xy 108.283849 -243.449358)
			(xy 108.323717 -243.418331) (xy 108.368148 -243.394288) (xy 108.41593 -243.377887) (xy 108.465761 -243.369575)
			(xy 108.49102 -243.369084) (xy 109.431074 -243.369084) (xy 109.456332 -243.369591) (xy 109.506161 -243.377902)
			(xy 109.553942 -243.394301) (xy 109.598371 -243.418342) (xy 109.638238 -243.449368) (xy 109.672453 -243.486533)
			(xy 109.700085 -243.528823) (xy 109.720378 -243.575085) (xy 109.73278 -243.624056) (xy 109.736927 -243.6741)
			(xy 361.758723 -243.6741) (xy 361.762898 -243.623721) (xy 361.775308 -243.574716) (xy 361.795615 -243.528421)
			(xy 361.823265 -243.486101) (xy 361.857503 -243.448909) (xy 361.897396 -243.41786) (xy 361.941856 -243.393801)
			(xy 361.989669 -243.377388) (xy 362.039532 -243.369068) (xy 362.064808 -243.368576) (xy 363.004862 -243.368576)
			(xy 363.030146 -243.36899) (xy 363.080025 -243.377308) (xy 363.127854 -243.393722) (xy 363.172329 -243.417786)
			(xy 363.212237 -243.448843) (xy 363.246487 -243.486045) (xy 363.274147 -243.528377) (xy 363.294462 -243.574685)
			(xy 363.306876 -243.623705) (xy 363.311053 -243.6741) (xy 363.306876 -243.724495) (xy 363.294462 -243.773515)
			(xy 363.274147 -243.819823) (xy 363.246487 -243.862155) (xy 363.212237 -243.899357) (xy 363.172329 -243.930414)
			(xy 363.127854 -243.954478) (xy 363.080025 -243.970892) (xy 363.030146 -243.97921) (xy 363.004862 -243.9797)
			(xy 362.064808 -243.9797) (xy 362.039532 -243.979132) (xy 361.989669 -243.970812) (xy 361.941856 -243.954399)
			(xy 361.897396 -243.93034) (xy 361.857503 -243.899291) (xy 361.823265 -243.862099) (xy 361.795615 -243.819779)
			(xy 361.775308 -243.773484) (xy 361.762898 -243.724479) (xy 361.758723 -243.6741) (xy 109.736927 -243.6741)
			(xy 109.736952 -243.6744) (xy 109.73278 -243.724744) (xy 109.720378 -243.773715) (xy 109.700085 -243.819977)
			(xy 109.672453 -243.862267) (xy 109.638238 -243.899432) (xy 109.598371 -243.930458) (xy 109.553942 -243.954499)
			(xy 109.506161 -243.970898) (xy 109.456332 -243.979209) (xy 109.431074 -243.9797) (xy 108.49102 -243.9797)
			(xy 108.465761 -243.979225) (xy 108.41593 -243.970913) (xy 108.368148 -243.954512) (xy 108.323717 -243.930469)
			(xy 108.283849 -243.899442) (xy 108.249632 -243.862275) (xy 108.222 -243.819983) (xy 108.201706 -243.773719)
			(xy 108.189304 -243.724746) (xy 108.185132 -243.6744) (xy 2.509012 -243.6744) (xy 2.509012 -244.4844)
			(xy 97.374883 -244.4844) (xy 97.379059 -244.434011) (xy 97.391472 -244.384997) (xy 97.411784 -244.338695)
			(xy 97.43944 -244.296368) (xy 97.473686 -244.259171) (xy 97.513588 -244.228118) (xy 97.558057 -244.204057)
			(xy 97.605881 -244.187644) (xy 97.655753 -244.179326) (xy 97.681034 -244.178836) (xy 98.621088 -244.178836)
			(xy 98.646367 -244.179332) (xy 98.696236 -244.187652) (xy 98.744056 -244.204067) (xy 98.788521 -244.228129)
			(xy 98.82842 -244.259181) (xy 98.862663 -244.296378) (xy 98.890316 -244.338703) (xy 98.910626 -244.385003)
			(xy 98.923037 -244.434014) (xy 98.927213 -244.4844) (xy 100.194783 -244.4844) (xy 100.198959 -244.434011)
			(xy 100.211373 -244.384996) (xy 100.231685 -244.338693) (xy 100.259342 -244.296365) (xy 100.293589 -244.259168)
			(xy 100.333492 -244.228115) (xy 100.377963 -244.204054) (xy 100.425787 -244.187642) (xy 100.475661 -244.179326)
			(xy 100.500942 -244.178836) (xy 101.440996 -244.178836) (xy 101.466275 -244.179333) (xy 101.516143 -244.187654)
			(xy 101.563961 -244.204069) (xy 101.608426 -244.228131) (xy 101.648323 -244.259184) (xy 101.682565 -244.29638)
			(xy 101.710217 -244.338705) (xy 101.730526 -244.385005) (xy 101.742937 -244.434015) (xy 101.747113 -244.4844)
			(xy 103.014983 -244.4844) (xy 103.019159 -244.434014) (xy 103.03157 -244.385003) (xy 103.051879 -244.338704)
			(xy 103.079532 -244.296378) (xy 103.113774 -244.259181) (xy 103.153672 -244.228128) (xy 103.198137 -244.204065)
			(xy 103.245956 -244.18765) (xy 103.295825 -244.179329) (xy 103.321104 -244.178836) (xy 104.261158 -244.178836)
			(xy 104.286439 -244.17933) (xy 104.336312 -244.187646) (xy 104.384136 -244.204058) (xy 104.428605 -244.228118)
			(xy 104.468508 -244.259171) (xy 104.502755 -244.296368) (xy 104.530412 -244.338695) (xy 104.550724 -244.384997)
			(xy 104.563137 -244.434011) (xy 104.567313 -244.4844) (xy 105.834883 -244.4844) (xy 105.839059 -244.434014)
			(xy 105.851471 -244.385002) (xy 105.87178 -244.338701) (xy 105.899434 -244.296375) (xy 105.933678 -244.259178)
			(xy 105.973577 -244.228125) (xy 106.018043 -244.204063) (xy 106.065863 -244.187648) (xy 106.115732 -244.179328)
			(xy 106.141012 -244.178836) (xy 107.081066 -244.178836) (xy 107.106346 -244.17933) (xy 107.156218 -244.187647)
			(xy 107.204041 -244.20406) (xy 107.24851 -244.228121) (xy 107.288411 -244.259174) (xy 107.322657 -244.29637)
			(xy 107.350313 -244.338697) (xy 107.370624 -244.384999) (xy 107.383037 -244.434012) (xy 107.387188 -244.4841)
			(xy 364.108984 -244.4841) (xy 364.113155 -244.433763) (xy 364.125555 -244.384799) (xy 364.145845 -244.338543)
			(xy 364.173472 -244.296259) (xy 364.207683 -244.259098) (xy 364.247543 -244.228076) (xy 364.291966 -244.204037)
			(xy 364.33974 -244.187639) (xy 364.389561 -244.179327) (xy 364.414816 -244.178836) (xy 365.35487 -244.178836)
			(xy 365.380133 -244.179238) (xy 365.42997 -244.18755) (xy 365.47776 -244.203952) (xy 365.522198 -244.227997)
			(xy 365.562072 -244.259028) (xy 365.596293 -244.2962) (xy 365.62393 -244.338497) (xy 365.644227 -244.384767)
			(xy 365.656631 -244.433747) (xy 365.660804 -244.4841) (xy 366.928884 -244.4841) (xy 366.933055 -244.433762)
			(xy 366.945456 -244.384797) (xy 366.965746 -244.338541) (xy 366.993374 -244.296256) (xy 367.027586 -244.259095)
			(xy 367.067447 -244.228073) (xy 367.111871 -244.204035) (xy 367.159646 -244.187637) (xy 367.209469 -244.179327)
			(xy 367.234724 -244.178836) (xy 368.174778 -244.178836) (xy 368.200041 -244.179239) (xy 368.249877 -244.187552)
			(xy 368.297665 -244.203955) (xy 368.342102 -244.228) (xy 368.381975 -244.259031) (xy 368.416196 -244.296203)
			(xy 368.443831 -244.3385) (xy 368.464128 -244.384769) (xy 368.476531 -244.433748) (xy 368.480704 -244.4841)
			(xy 369.749113 -244.4841) (xy 369.753283 -244.433771) (xy 369.76568 -244.384814) (xy 369.785966 -244.338565)
			(xy 369.813587 -244.296286) (xy 369.847791 -244.25913) (xy 369.887643 -244.22811) (xy 369.932057 -244.204073)
			(xy 369.979822 -244.187673) (xy 370.029635 -244.179359) (xy 370.054886 -244.178836) (xy 370.99494 -244.178836)
			(xy 371.020197 -244.179272) (xy 371.070021 -244.187592) (xy 371.117796 -244.203999) (xy 371.162219 -244.228045)
			(xy 371.202079 -244.259074) (xy 371.236289 -244.296241) (xy 371.263916 -244.33853) (xy 371.284205 -244.38479)
			(xy 371.296604 -244.433759) (xy 371.300776 -244.4841) (xy 372.569013 -244.4841) (xy 372.573183 -244.43377)
			(xy 372.585581 -244.384812) (xy 372.605867 -244.338563) (xy 372.63349 -244.296284) (xy 372.667694 -244.259127)
			(xy 372.707547 -244.228107) (xy 372.751963 -244.20407) (xy 372.799729 -244.187671) (xy 372.849543 -244.179358)
			(xy 372.874794 -244.178836) (xy 373.814848 -244.178836) (xy 373.840104 -244.179273) (xy 373.889927 -244.187594)
			(xy 373.937701 -244.204002) (xy 373.982123 -244.228048) (xy 374.021982 -244.259077) (xy 374.056191 -244.296243)
			(xy 374.083817 -244.338533) (xy 374.104106 -244.384792) (xy 374.116505 -244.43376) (xy 374.120676 -244.4841)
			(xy 374.116505 -244.53444) (xy 374.104106 -244.583408) (xy 374.083817 -244.629667) (xy 374.056191 -244.671957)
			(xy 374.021982 -244.709123) (xy 373.982123 -244.740152) (xy 373.937701 -244.764198) (xy 373.889927 -244.780606)
			(xy 373.840104 -244.788927) (xy 373.814848 -244.789452) (xy 372.874794 -244.789452) (xy 372.849543 -244.788842)
			(xy 372.799729 -244.780529) (xy 372.751963 -244.76413) (xy 372.707547 -244.740093) (xy 372.667694 -244.709073)
			(xy 372.63349 -244.671916) (xy 372.605867 -244.629637) (xy 372.585581 -244.583388) (xy 372.573183 -244.53443)
			(xy 372.569013 -244.4841) (xy 371.300776 -244.4841) (xy 371.296604 -244.534441) (xy 371.284205 -244.58341)
			(xy 371.263915 -244.62967) (xy 371.236289 -244.671959) (xy 371.202079 -244.709126) (xy 371.162219 -244.740155)
			(xy 371.117796 -244.764201) (xy 371.070021 -244.780608) (xy 371.020197 -244.788928) (xy 370.99494 -244.789452)
			(xy 370.054886 -244.789452) (xy 370.029635 -244.788841) (xy 369.979822 -244.780527) (xy 369.932057 -244.764127)
			(xy 369.887643 -244.74009) (xy 369.847791 -244.70907) (xy 369.813587 -244.671914) (xy 369.785966 -244.629635)
			(xy 369.76568 -244.583386) (xy 369.753283 -244.534429) (xy 369.749113 -244.4841) (xy 368.480704 -244.4841)
			(xy 368.476531 -244.534452) (xy 368.464128 -244.583431) (xy 368.443831 -244.6297) (xy 368.416196 -244.671997)
			(xy 368.381975 -244.709169) (xy 368.342102 -244.7402) (xy 368.297665 -244.764245) (xy 368.249877 -244.780648)
			(xy 368.200041 -244.788961) (xy 368.174778 -244.789452) (xy 367.234724 -244.789452) (xy 367.209469 -244.788873)
			(xy 367.159646 -244.780563) (xy 367.111871 -244.764165) (xy 367.067447 -244.740127) (xy 367.027586 -244.709105)
			(xy 366.993374 -244.671944) (xy 366.965746 -244.629659) (xy 366.945456 -244.583403) (xy 366.933055 -244.534438)
			(xy 366.928884 -244.4841) (xy 365.660804 -244.4841) (xy 365.656631 -244.534453) (xy 365.644227 -244.583433)
			(xy 365.62393 -244.629703) (xy 365.596293 -244.672) (xy 365.562072 -244.709172) (xy 365.522198 -244.740203)
			(xy 365.47776 -244.764248) (xy 365.42997 -244.78065) (xy 365.380133 -244.788962) (xy 365.35487 -244.789452)
			(xy 364.414816 -244.789452) (xy 364.389561 -244.788873) (xy 364.33974 -244.780561) (xy 364.291966 -244.764163)
			(xy 364.247543 -244.740124) (xy 364.207683 -244.709102) (xy 364.173472 -244.671941) (xy 364.145845 -244.629657)
			(xy 364.125555 -244.583401) (xy 364.113155 -244.534437) (xy 364.108984 -244.4841) (xy 107.387188 -244.4841)
			(xy 107.387213 -244.4844) (xy 107.383037 -244.534788) (xy 107.370624 -244.583801) (xy 107.350313 -244.630103)
			(xy 107.322657 -244.67243) (xy 107.288411 -244.709626) (xy 107.24851 -244.740679) (xy 107.204041 -244.76474)
			(xy 107.156218 -244.781153) (xy 107.106346 -244.78947) (xy 107.081066 -244.78996) (xy 106.141012 -244.78996)
			(xy 106.115732 -244.789472) (xy 106.065863 -244.781152) (xy 106.018043 -244.764737) (xy 105.973577 -244.740675)
			(xy 105.933678 -244.709622) (xy 105.899434 -244.672425) (xy 105.87178 -244.630099) (xy 105.851471 -244.583798)
			(xy 105.839059 -244.534786) (xy 105.834883 -244.4844) (xy 104.567313 -244.4844) (xy 104.563137 -244.534789)
			(xy 104.550724 -244.583803) (xy 104.530412 -244.630105) (xy 104.502755 -244.672432) (xy 104.468508 -244.709629)
			(xy 104.428605 -244.740682) (xy 104.384136 -244.764742) (xy 104.336312 -244.781154) (xy 104.286439 -244.78947)
			(xy 104.261158 -244.78996) (xy 103.321104 -244.78996) (xy 103.295825 -244.789471) (xy 103.245956 -244.78115)
			(xy 103.198137 -244.764735) (xy 103.153672 -244.740672) (xy 103.113774 -244.709619) (xy 103.079532 -244.672422)
			(xy 103.051879 -244.630096) (xy 103.03157 -244.583797) (xy 103.019159 -244.534786) (xy 103.014983 -244.4844)
			(xy 101.747113 -244.4844) (xy 101.742937 -244.534785) (xy 101.730526 -244.583795) (xy 101.710217 -244.630095)
			(xy 101.682565 -244.67242) (xy 101.648323 -244.709616) (xy 101.608426 -244.740669) (xy 101.563961 -244.764731)
			(xy 101.516143 -244.781146) (xy 101.466275 -244.789467) (xy 101.440996 -244.78996) (xy 100.500942 -244.78996)
			(xy 100.475661 -244.789474) (xy 100.425787 -244.781158) (xy 100.377963 -244.764746) (xy 100.333492 -244.740685)
			(xy 100.293589 -244.709632) (xy 100.259342 -244.672435) (xy 100.231685 -244.630107) (xy 100.211373 -244.583804)
			(xy 100.198959 -244.534789) (xy 100.194783 -244.4844) (xy 98.927213 -244.4844) (xy 98.923037 -244.534786)
			(xy 98.910626 -244.583797) (xy 98.890316 -244.630097) (xy 98.862663 -244.672422) (xy 98.82842 -244.709619)
			(xy 98.788521 -244.740671) (xy 98.744056 -244.764733) (xy 98.696236 -244.781148) (xy 98.646367 -244.789468)
			(xy 98.621088 -244.78996) (xy 97.681034 -244.78996) (xy 97.655753 -244.789474) (xy 97.605881 -244.781156)
			(xy 97.558057 -244.764743) (xy 97.513588 -244.740682) (xy 97.473686 -244.709629) (xy 97.43944 -244.672432)
			(xy 97.411784 -244.630105) (xy 97.391472 -244.583803) (xy 97.379059 -244.534789) (xy 97.374883 -244.4844)
			(xy 2.509012 -244.4844) (xy 2.509012 -245.2944) (xy 108.185144 -245.2944) (xy 108.189316 -245.244056)
			(xy 108.201717 -245.195085) (xy 108.222011 -245.148823) (xy 108.249642 -245.106533) (xy 108.283857 -245.069367)
			(xy 108.323723 -245.038341) (xy 108.368153 -245.014299) (xy 108.415933 -244.997899) (xy 108.465762 -244.989587)
			(xy 108.49102 -244.989096) (xy 109.431074 -244.989096) (xy 109.456333 -244.989579) (xy 109.506164 -244.99789)
			(xy 109.553947 -245.01429) (xy 109.598378 -245.038332) (xy 109.638246 -245.069359) (xy 109.672463 -245.106526)
			(xy 109.700095 -245.148818) (xy 109.72039 -245.195081) (xy 109.732792 -245.244054) (xy 109.736939 -245.2941)
			(xy 361.758735 -245.2941) (xy 361.76291 -245.243723) (xy 361.775319 -245.194719) (xy 361.795626 -245.148427)
			(xy 361.823274 -245.106109) (xy 361.857511 -245.068918) (xy 361.897403 -245.03787) (xy 361.941861 -245.013812)
			(xy 361.989672 -244.997399) (xy 362.039533 -244.98908) (xy 362.064808 -244.988588) (xy 363.004862 -244.988588)
			(xy 363.030147 -244.988978) (xy 363.080028 -244.997296) (xy 363.127859 -245.013711) (xy 363.172336 -245.037776)
			(xy 363.212245 -245.068834) (xy 363.246497 -245.106037) (xy 363.274158 -245.148371) (xy 363.294473 -245.194681)
			(xy 363.306888 -245.243703) (xy 363.311065 -245.2941) (xy 363.306888 -245.344497) (xy 363.294473 -245.393519)
			(xy 363.274158 -245.439829) (xy 363.246497 -245.482163) (xy 363.212245 -245.519366) (xy 363.172336 -245.550424)
			(xy 363.127859 -245.574489) (xy 363.080028 -245.590904) (xy 363.030147 -245.599222) (xy 363.004862 -245.599712)
			(xy 362.064808 -245.599712) (xy 362.039533 -245.59912) (xy 361.989672 -245.590801) (xy 361.941861 -245.574388)
			(xy 361.897403 -245.55033) (xy 361.857511 -245.519282) (xy 361.823274 -245.482091) (xy 361.795626 -245.439773)
			(xy 361.775319 -245.393481) (xy 361.76291 -245.344477) (xy 361.758735 -245.2941) (xy 109.736939 -245.2941)
			(xy 109.736964 -245.2944) (xy 109.732792 -245.344746) (xy 109.72039 -245.393719) (xy 109.700095 -245.439982)
			(xy 109.672463 -245.482274) (xy 109.638246 -245.519441) (xy 109.598378 -245.550468) (xy 109.553947 -245.57451)
			(xy 109.506164 -245.59091) (xy 109.456333 -245.599221) (xy 109.431074 -245.599712) (xy 108.49102 -245.599712)
			(xy 108.465762 -245.599213) (xy 108.415933 -245.590901) (xy 108.368153 -245.574501) (xy 108.323723 -245.550459)
			(xy 108.283857 -245.519433) (xy 108.249642 -245.482267) (xy 108.222011 -245.439977) (xy 108.201717 -245.393715)
			(xy 108.189316 -245.344744) (xy 108.185144 -245.2944) (xy 2.509012 -245.2944) (xy 2.509012 -246.1044)
			(xy 97.374895 -246.1044) (xy 97.379071 -246.054013) (xy 97.391483 -246.005001) (xy 97.411794 -245.958701)
			(xy 97.439449 -245.916375) (xy 97.473694 -245.879179) (xy 97.513595 -245.848128) (xy 97.558062 -245.824068)
			(xy 97.605884 -245.807655) (xy 97.655754 -245.799338) (xy 97.681034 -245.798848) (xy 98.621088 -245.798848)
			(xy 98.646368 -245.79932) (xy 98.696239 -245.80764) (xy 98.744061 -245.824056) (xy 98.788528 -245.848119)
			(xy 98.828428 -245.879173) (xy 98.862672 -245.91637) (xy 98.890327 -245.958698) (xy 98.910637 -246.004999)
			(xy 98.923049 -246.054012) (xy 98.927225 -246.1044) (xy 100.194795 -246.1044) (xy 100.198971 -246.054012)
			(xy 100.211384 -246.005) (xy 100.231695 -245.958699) (xy 100.259351 -245.916373) (xy 100.293597 -245.879177)
			(xy 100.333499 -245.848125) (xy 100.377968 -245.824065) (xy 100.42579 -245.807654) (xy 100.475662 -245.799338)
			(xy 100.500942 -245.798848) (xy 101.440996 -245.798848) (xy 101.466276 -245.799321) (xy 101.516146 -245.807642)
			(xy 101.563966 -245.824058) (xy 101.608432 -245.848121) (xy 101.648331 -245.879175) (xy 101.682574 -245.916373)
			(xy 101.710228 -245.9587) (xy 101.730538 -246.005001) (xy 101.742949 -246.054013) (xy 101.747125 -246.1044)
			(xy 103.014995 -246.1044) (xy 103.01917 -246.054016) (xy 103.031581 -246.005007) (xy 103.05189 -245.958709)
			(xy 103.079542 -245.916385) (xy 103.113783 -245.87919) (xy 103.153679 -245.848138) (xy 103.198142 -245.824076)
			(xy 103.245959 -245.807661) (xy 103.295826 -245.799341) (xy 103.321104 -245.798848) (xy 104.261158 -245.798848)
			(xy 104.28644 -245.799318) (xy 104.336315 -245.807634) (xy 104.38414 -245.824047) (xy 104.428612 -245.848108)
			(xy 104.468516 -245.879162) (xy 104.502764 -245.91636) (xy 104.530422 -245.958689) (xy 104.550735 -246.004993)
			(xy 104.563149 -246.054009) (xy 104.567325 -246.1044) (xy 105.834895 -246.1044) (xy 105.839071 -246.054016)
			(xy 105.851482 -246.005006) (xy 105.871791 -245.958707) (xy 105.899444 -245.916383) (xy 105.933686 -245.879187)
			(xy 105.973583 -245.848135) (xy 106.018047 -245.824074) (xy 106.065866 -245.80766) (xy 106.115733 -245.79934)
			(xy 106.141012 -245.798848) (xy 107.081066 -245.798848) (xy 107.106347 -245.799318) (xy 107.156221 -245.807636)
			(xy 107.204046 -245.824049) (xy 107.248516 -245.848111) (xy 107.288419 -245.879165) (xy 107.322666 -245.916363)
			(xy 107.350323 -245.958691) (xy 107.370636 -246.004995) (xy 107.383049 -246.05401) (xy 107.387208 -246.1042)
			(xy 364.108896 -246.1042) (xy 364.113068 -246.053848) (xy 364.125472 -246.00487) (xy 364.145768 -245.958601)
			(xy 364.173403 -245.916305) (xy 364.207623 -245.879133) (xy 364.247495 -245.848102) (xy 364.291931 -245.824057)
			(xy 364.339718 -245.807653) (xy 364.389554 -245.79934) (xy 364.414816 -245.798848) (xy 365.35487 -245.798848)
			(xy 365.380126 -245.799426) (xy 365.429949 -245.807736) (xy 365.477725 -245.824133) (xy 365.52215 -245.848171)
			(xy 365.562012 -245.879193) (xy 365.596224 -245.916354) (xy 365.623853 -245.958639) (xy 365.644144 -246.004896)
			(xy 365.656545 -246.053861) (xy 365.660716 -246.1042) (xy 366.928796 -246.1042) (xy 366.932969 -246.053847)
			(xy 366.945372 -246.004868) (xy 366.965669 -245.958599) (xy 366.993305 -245.916302) (xy 367.027526 -245.879131)
			(xy 367.067399 -245.848099) (xy 367.111836 -245.824054) (xy 367.159625 -245.807652) (xy 367.209461 -245.799339)
			(xy 367.234724 -245.798848) (xy 368.174778 -245.798848) (xy 368.200033 -245.799427) (xy 368.249855 -245.807737)
			(xy 368.29763 -245.824135) (xy 368.342054 -245.848173) (xy 368.381915 -245.879196) (xy 368.416126 -245.916357)
			(xy 368.443754 -245.958642) (xy 368.464045 -246.004897) (xy 368.476445 -246.053862) (xy 368.480616 -246.1042)
			(xy 369.749024 -246.1042) (xy 369.753196 -246.053856) (xy 369.765597 -246.004885) (xy 369.785888 -245.958623)
			(xy 369.813518 -245.916332) (xy 369.847731 -245.879165) (xy 369.887595 -245.848136) (xy 369.932022 -245.824092)
			(xy 369.979801 -245.807687) (xy 370.029628 -245.79937) (xy 370.054886 -245.798848) (xy 370.99494 -245.798848)
			(xy 371.02019 -245.799461) (xy 371.069999 -245.807778) (xy 371.11776 -245.82418) (xy 371.162171 -245.848219)
			(xy 371.202019 -245.879239) (xy 371.236219 -245.916395) (xy 371.263838 -245.958673) (xy 371.284121 -246.004919)
			(xy 371.296517 -246.053873) (xy 371.300687 -246.1042) (xy 372.568924 -246.1042) (xy 372.573096 -246.053855)
			(xy 372.585497 -246.004884) (xy 372.60579 -245.958621) (xy 372.63342 -245.916329) (xy 372.667634 -245.879162)
			(xy 372.707499 -245.848133) (xy 372.751927 -245.824089) (xy 372.799707 -245.807685) (xy 372.849535 -245.79937)
			(xy 372.874794 -245.798848) (xy 373.814848 -245.798848) (xy 373.840097 -245.799461) (xy 373.889906 -245.80778)
			(xy 373.937666 -245.824183) (xy 373.982075 -245.848222) (xy 374.021923 -245.879242) (xy 374.056121 -245.916398)
			(xy 374.083739 -245.958675) (xy 374.104022 -246.004921) (xy 374.116417 -246.053874) (xy 374.120587 -246.1042)
			(xy 374.116417 -246.154526) (xy 374.104022 -246.203479) (xy 374.083739 -246.249725) (xy 374.056121 -246.292002)
			(xy 374.021923 -246.329158) (xy 373.982075 -246.360178) (xy 373.937666 -246.384217) (xy 373.889906 -246.40062)
			(xy 373.840097 -246.408939) (xy 373.814848 -246.409464) (xy 372.874794 -246.409464) (xy 372.849535 -246.40903)
			(xy 372.799707 -246.400715) (xy 372.751927 -246.384311) (xy 372.707499 -246.360267) (xy 372.667634 -246.329238)
			(xy 372.63342 -246.292071) (xy 372.60579 -246.249779) (xy 372.585497 -246.203516) (xy 372.573096 -246.154545)
			(xy 372.568924 -246.1042) (xy 371.300687 -246.1042) (xy 371.296517 -246.154527) (xy 371.284121 -246.203481)
			(xy 371.263838 -246.249727) (xy 371.236219 -246.292005) (xy 371.202019 -246.329161) (xy 371.162171 -246.360181)
			(xy 371.11776 -246.38422) (xy 371.069999 -246.400622) (xy 371.02019 -246.408939) (xy 370.99494 -246.409464)
			(xy 370.054886 -246.409464) (xy 370.029628 -246.40903) (xy 369.979801 -246.400713) (xy 369.932022 -246.384308)
			(xy 369.887595 -246.360264) (xy 369.847731 -246.329235) (xy 369.813518 -246.292068) (xy 369.785888 -246.249777)
			(xy 369.765597 -246.203515) (xy 369.753196 -246.154544) (xy 369.749024 -246.1042) (xy 368.480616 -246.1042)
			(xy 368.476445 -246.154538) (xy 368.464045 -246.203503) (xy 368.443754 -246.249758) (xy 368.416126 -246.292043)
			(xy 368.381915 -246.329204) (xy 368.342054 -246.360227) (xy 368.29763 -246.384265) (xy 368.249855 -246.400663)
			(xy 368.200033 -246.408973) (xy 368.174778 -246.409464) (xy 367.234724 -246.409464) (xy 367.209461 -246.409061)
			(xy 367.159625 -246.400748) (xy 367.111836 -246.384346) (xy 367.067399 -246.360301) (xy 367.027526 -246.329269)
			(xy 366.993305 -246.292098) (xy 366.965669 -246.249801) (xy 366.945372 -246.203532) (xy 366.932969 -246.154553)
			(xy 366.928796 -246.1042) (xy 365.660716 -246.1042) (xy 365.656545 -246.154539) (xy 365.644144 -246.203504)
			(xy 365.623853 -246.249761) (xy 365.596224 -246.292046) (xy 365.562012 -246.329207) (xy 365.52215 -246.360229)
			(xy 365.477725 -246.384267) (xy 365.429949 -246.400664) (xy 365.380126 -246.408974) (xy 365.35487 -246.409464)
			(xy 364.414816 -246.409464) (xy 364.389554 -246.40906) (xy 364.339718 -246.400747) (xy 364.291931 -246.384343)
			(xy 364.247495 -246.360298) (xy 364.207623 -246.329267) (xy 364.173403 -246.292095) (xy 364.145768 -246.249799)
			(xy 364.125472 -246.20353) (xy 364.113068 -246.154552) (xy 364.108896 -246.1042) (xy 107.387208 -246.1042)
			(xy 107.387225 -246.1044) (xy 107.383049 -246.15479) (xy 107.370636 -246.203805) (xy 107.350323 -246.250109)
			(xy 107.322666 -246.292437) (xy 107.288419 -246.329635) (xy 107.248516 -246.360689) (xy 107.204046 -246.384751)
			(xy 107.156221 -246.401164) (xy 107.106347 -246.409482) (xy 107.081066 -246.409972) (xy 106.141012 -246.409972)
			(xy 106.115733 -246.40946) (xy 106.065866 -246.40114) (xy 106.018047 -246.384726) (xy 105.973583 -246.360665)
			(xy 105.933686 -246.329613) (xy 105.899444 -246.292417) (xy 105.871791 -246.250093) (xy 105.851482 -246.203794)
			(xy 105.839071 -246.154784) (xy 105.834895 -246.1044) (xy 104.567325 -246.1044) (xy 104.563149 -246.154791)
			(xy 104.550735 -246.203807) (xy 104.530422 -246.250111) (xy 104.502764 -246.29244) (xy 104.468516 -246.329638)
			(xy 104.428612 -246.360692) (xy 104.38414 -246.384753) (xy 104.336315 -246.401166) (xy 104.28644 -246.409482)
			(xy 104.261158 -246.409972) (xy 103.321104 -246.409972) (xy 103.295826 -246.409459) (xy 103.245959 -246.401139)
			(xy 103.198142 -246.384724) (xy 103.153679 -246.360662) (xy 103.113783 -246.32961) (xy 103.079542 -246.292415)
			(xy 103.05189 -246.250091) (xy 103.031581 -246.203793) (xy 103.01917 -246.154784) (xy 103.014995 -246.1044)
			(xy 101.747125 -246.1044) (xy 101.742949 -246.154787) (xy 101.730538 -246.203799) (xy 101.710228 -246.2501)
			(xy 101.682574 -246.292427) (xy 101.648331 -246.329625) (xy 101.608432 -246.360679) (xy 101.563966 -246.384742)
			(xy 101.516146 -246.401158) (xy 101.466276 -246.409479) (xy 101.440996 -246.409972) (xy 100.500942 -246.409972)
			(xy 100.475662 -246.409462) (xy 100.42579 -246.401146) (xy 100.377968 -246.384735) (xy 100.333499 -246.360675)
			(xy 100.293597 -246.329623) (xy 100.259351 -246.292427) (xy 100.231695 -246.250101) (xy 100.211384 -246.2038)
			(xy 100.198971 -246.154788) (xy 100.194795 -246.1044) (xy 98.927225 -246.1044) (xy 98.923049 -246.154788)
			(xy 98.910637 -246.203801) (xy 98.890327 -246.250102) (xy 98.862672 -246.29243) (xy 98.828428 -246.329627)
			(xy 98.788528 -246.360681) (xy 98.744061 -246.384744) (xy 98.696239 -246.40116) (xy 98.646368 -246.40948)
			(xy 98.621088 -246.409972) (xy 97.681034 -246.409972) (xy 97.655754 -246.409462) (xy 97.605884 -246.401145)
			(xy 97.558062 -246.384732) (xy 97.513595 -246.360672) (xy 97.473694 -246.329621) (xy 97.439449 -246.292425)
			(xy 97.411794 -246.250099) (xy 97.391483 -246.203799) (xy 97.379071 -246.154787) (xy 97.374895 -246.1044)
			(xy 2.509012 -246.1044) (xy 2.509012 -246.9144) (xy 108.185156 -246.9144) (xy 108.189328 -246.864058)
			(xy 108.201729 -246.815089) (xy 108.222021 -246.768829) (xy 108.249651 -246.72654) (xy 108.283865 -246.689376)
			(xy 108.32373 -246.658351) (xy 108.368157 -246.63431) (xy 108.415936 -246.617911) (xy 108.465763 -246.609599)
			(xy 108.49102 -246.609108) (xy 109.431074 -246.609108) (xy 109.456334 -246.609567) (xy 109.506167 -246.617878)
			(xy 109.553951 -246.634279) (xy 109.598385 -246.658322) (xy 109.638254 -246.68935) (xy 109.672472 -246.726518)
			(xy 109.700106 -246.768812) (xy 109.720401 -246.815077) (xy 109.732804 -246.864052) (xy 109.736959 -246.9142)
			(xy 361.758647 -246.9142) (xy 361.762823 -246.863808) (xy 361.775236 -246.814791) (xy 361.795548 -246.768485)
			(xy 361.823205 -246.726155) (xy 361.857452 -246.688953) (xy 361.897355 -246.657897) (xy 361.941825 -246.633831)
			(xy 361.989651 -246.617414) (xy 362.039526 -246.609093) (xy 362.064808 -246.6086) (xy 363.004862 -246.6086)
			(xy 363.03014 -246.609166) (xy 363.080006 -246.617481) (xy 363.127824 -246.633892) (xy 363.172288 -246.65795)
			(xy 363.212185 -246.688999) (xy 363.246428 -246.726191) (xy 363.274081 -246.768513) (xy 363.29439 -246.81481)
			(xy 363.306801 -246.863818) (xy 363.310977 -246.9142) (xy 363.306801 -246.964582) (xy 363.29439 -247.01359)
			(xy 363.274081 -247.059887) (xy 363.246428 -247.102209) (xy 363.212185 -247.139401) (xy 363.172288 -247.17045)
			(xy 363.127824 -247.194508) (xy 363.080006 -247.210919) (xy 363.03014 -247.219234) (xy 363.004862 -247.219724)
			(xy 362.064808 -247.219724) (xy 362.039526 -247.219307) (xy 361.989651 -247.210986) (xy 361.941825 -247.194569)
			(xy 361.897355 -247.170503) (xy 361.857452 -247.139447) (xy 361.823205 -247.102245) (xy 361.795548 -247.059915)
			(xy 361.775236 -247.013609) (xy 361.762823 -246.964592) (xy 361.758647 -246.9142) (xy 109.736959 -246.9142)
			(xy 109.736976 -246.9144) (xy 109.732804 -246.964748) (xy 109.720401 -247.013723) (xy 109.700106 -247.059988)
			(xy 109.672472 -247.102282) (xy 109.638254 -247.13945) (xy 109.598385 -247.170478) (xy 109.553951 -247.194521)
			(xy 109.506167 -247.210922) (xy 109.456334 -247.219233) (xy 109.431074 -247.219724) (xy 108.49102 -247.219724)
			(xy 108.465763 -247.219201) (xy 108.415936 -247.210889) (xy 108.368157 -247.19449) (xy 108.32373 -247.170449)
			(xy 108.283865 -247.139424) (xy 108.249651 -247.10226) (xy 108.222021 -247.059971) (xy 108.201729 -247.013711)
			(xy 108.189328 -246.964742) (xy 108.185156 -246.9144) (xy 2.509012 -246.9144) (xy 2.509012 -247.7244)
			(xy 97.374907 -247.7244) (xy 97.379083 -247.674015) (xy 97.391495 -247.625005) (xy 97.411805 -247.578707)
			(xy 97.439459 -247.536383) (xy 97.473702 -247.499188) (xy 97.513601 -247.468138) (xy 97.558067 -247.444079)
			(xy 97.605887 -247.427667) (xy 97.655755 -247.41935) (xy 97.681034 -247.41886) (xy 98.621088 -247.41886)
			(xy 98.646369 -247.419308) (xy 98.696242 -247.427629) (xy 98.744066 -247.444045) (xy 98.788534 -247.468109)
			(xy 98.828436 -247.499164) (xy 98.862682 -247.536363) (xy 98.890337 -247.578692) (xy 98.910648 -247.624995)
			(xy 98.923061 -247.67401) (xy 98.927237 -247.7244) (xy 100.194807 -247.7244) (xy 100.198983 -247.674014)
			(xy 100.211395 -247.625004) (xy 100.231706 -247.578704) (xy 100.259361 -247.53638) (xy 100.293605 -247.499185)
			(xy 100.333506 -247.468135) (xy 100.377972 -247.444076) (xy 100.425793 -247.427665) (xy 100.475663 -247.41935)
			(xy 100.500942 -247.41886) (xy 101.440996 -247.41886) (xy 101.466277 -247.419309) (xy 101.516149 -247.42763)
			(xy 101.563971 -247.444047) (xy 101.608439 -247.468111) (xy 101.648339 -247.499167) (xy 101.682584 -247.536366)
			(xy 101.710238 -247.578694) (xy 101.730549 -247.624997) (xy 101.742961 -247.674011) (xy 101.747137 -247.7244)
			(xy 103.015007 -247.7244) (xy 103.019182 -247.674018) (xy 103.031593 -247.625011) (xy 103.0519 -247.578715)
			(xy 103.079551 -247.536393) (xy 103.113791 -247.499199) (xy 103.153685 -247.468148) (xy 103.198147 -247.444087)
			(xy 103.245962 -247.427673) (xy 103.295827 -247.419353) (xy 103.321104 -247.41886) (xy 104.261158 -247.41886)
			(xy 104.286441 -247.419306) (xy 104.336318 -247.427622) (xy 104.384145 -247.444036) (xy 104.428619 -247.468098)
			(xy 104.468524 -247.499153) (xy 104.502774 -247.536353) (xy 104.530433 -247.578683) (xy 104.550746 -247.624989)
			(xy 104.56316 -247.674007) (xy 104.567337 -247.7244) (xy 105.834907 -247.7244) (xy 105.839082 -247.674018)
			(xy 105.851493 -247.62501) (xy 105.871801 -247.578713) (xy 105.899453 -247.53639) (xy 105.933694 -247.499196)
			(xy 105.97359 -247.468145) (xy 106.018052 -247.444085) (xy 106.065869 -247.427671) (xy 106.115734 -247.419352)
			(xy 106.141012 -247.41886) (xy 107.081066 -247.41886) (xy 107.106348 -247.419306) (xy 107.156224 -247.427624)
			(xy 107.204051 -247.444038) (xy 107.248523 -247.468101) (xy 107.288427 -247.499156) (xy 107.322676 -247.536356)
			(xy 107.350334 -247.578686) (xy 107.370647 -247.624991) (xy 107.383061 -247.674008) (xy 107.38722 -247.7242)
			(xy 364.108908 -247.7242) (xy 364.11308 -247.67385) (xy 364.125483 -247.624874) (xy 364.145778 -247.578607)
			(xy 364.173412 -247.536312) (xy 364.207631 -247.499142) (xy 364.247501 -247.468112) (xy 364.291935 -247.444068)
			(xy 364.339721 -247.427665) (xy 364.389555 -247.419352) (xy 364.414816 -247.41886) (xy 365.35487 -247.41886)
			(xy 365.380127 -247.419414) (xy 365.429952 -247.427724) (xy 365.477729 -247.444122) (xy 365.522156 -247.468161)
			(xy 365.56202 -247.499184) (xy 365.596233 -247.536347) (xy 365.623863 -247.578634) (xy 365.644155 -247.624892)
			(xy 365.656556 -247.673859) (xy 365.660728 -247.7242) (xy 366.928808 -247.7242) (xy 366.93298 -247.673849)
			(xy 366.945384 -247.624872) (xy 366.96568 -247.578605) (xy 366.993314 -247.536309) (xy 367.027534 -247.499139)
			(xy 367.067406 -247.468109) (xy 367.111841 -247.444065) (xy 367.159628 -247.427663) (xy 367.209462 -247.419351)
			(xy 367.234724 -247.41886) (xy 368.174778 -247.41886) (xy 368.200034 -247.419415) (xy 368.249858 -247.427726)
			(xy 368.297635 -247.444124) (xy 368.34206 -247.468163) (xy 368.381923 -247.499187) (xy 368.416136 -247.536349)
			(xy 368.443764 -247.578636) (xy 368.464056 -247.624893) (xy 368.476457 -247.67386) (xy 368.480628 -247.7242)
			(xy 369.749037 -247.7242) (xy 369.753208 -247.673858) (xy 369.765609 -247.624889) (xy 369.785899 -247.578629)
			(xy 369.813527 -247.53634) (xy 369.847739 -247.499174) (xy 369.887601 -247.468147) (xy 369.932027 -247.444103)
			(xy 369.979804 -247.427699) (xy 370.029629 -247.419383) (xy 370.054886 -247.41886) (xy 370.99494 -247.41886)
			(xy 371.020191 -247.419449) (xy 371.070002 -247.427767) (xy 371.117765 -247.444169) (xy 371.162177 -247.468209)
			(xy 371.202028 -247.499231) (xy 371.236229 -247.536388) (xy 371.263848 -247.578667) (xy 371.284133 -247.624915)
			(xy 371.296529 -247.673871) (xy 371.300699 -247.7242) (xy 372.568937 -247.7242) (xy 372.573108 -247.673857)
			(xy 372.585509 -247.624888) (xy 372.605801 -247.578627) (xy 372.63343 -247.536337) (xy 372.667642 -247.499171)
			(xy 372.707506 -247.468144) (xy 372.751932 -247.444101) (xy 372.79971 -247.427698) (xy 372.849536 -247.419382)
			(xy 372.874794 -247.41886) (xy 373.814848 -247.41886) (xy 373.840098 -247.419449) (xy 373.889908 -247.427768)
			(xy 373.93767 -247.444172) (xy 373.982082 -247.468212) (xy 374.021931 -247.499233) (xy 374.056131 -247.53639)
			(xy 374.083749 -247.578669) (xy 374.104033 -247.624917) (xy 374.116429 -247.673872) (xy 374.120599 -247.7242)
			(xy 374.116429 -247.774528) (xy 374.104033 -247.823483) (xy 374.083749 -247.869731) (xy 374.056131 -247.91201)
			(xy 374.021931 -247.949166) (xy 373.982082 -247.980188) (xy 373.937671 -248.004228) (xy 373.889908 -248.020632)
			(xy 373.840098 -248.028951) (xy 373.814848 -248.029476) (xy 372.874794 -248.029476) (xy 372.849536 -248.029018)
			(xy 372.79971 -248.020702) (xy 372.751932 -248.004299) (xy 372.707506 -247.980256) (xy 372.667642 -247.949229)
			(xy 372.63343 -247.912063) (xy 372.605801 -247.869773) (xy 372.585509 -247.823512) (xy 372.573108 -247.774543)
			(xy 372.568937 -247.7242) (xy 371.300699 -247.7242) (xy 371.296529 -247.774529) (xy 371.284133 -247.823485)
			(xy 371.263848 -247.869733) (xy 371.236229 -247.912012) (xy 371.202028 -247.949169) (xy 371.162177 -247.980191)
			(xy 371.117765 -248.004231) (xy 371.070002 -248.020633) (xy 371.020191 -248.028951) (xy 370.99494 -248.029476)
			(xy 370.054886 -248.029476) (xy 370.029629 -248.029017) (xy 369.979804 -248.020701) (xy 369.932027 -248.004297)
			(xy 369.887601 -247.980253) (xy 369.847739 -247.949226) (xy 369.813527 -247.91206) (xy 369.785899 -247.869771)
			(xy 369.765609 -247.823511) (xy 369.753208 -247.774542) (xy 369.749037 -247.7242) (xy 368.480628 -247.7242)
			(xy 368.476457 -247.77454) (xy 368.464056 -247.823507) (xy 368.443764 -247.869764) (xy 368.416136 -247.912051)
			(xy 368.381923 -247.949213) (xy 368.34206 -247.980237) (xy 368.297635 -248.004276) (xy 368.249858 -248.020674)
			(xy 368.200034 -248.028985) (xy 368.174778 -248.029476) (xy 367.234724 -248.029476) (xy 367.209462 -248.029049)
			(xy 367.159628 -248.020737) (xy 367.111841 -248.004335) (xy 367.067406 -247.980291) (xy 367.027534 -247.949261)
			(xy 366.993314 -247.912091) (xy 366.96568 -247.869795) (xy 366.945384 -247.823528) (xy 366.93298 -247.774551)
			(xy 366.928808 -247.7242) (xy 365.660728 -247.7242) (xy 365.656556 -247.774541) (xy 365.644155 -247.823508)
			(xy 365.623863 -247.869766) (xy 365.596233 -247.912053) (xy 365.56202 -247.949216) (xy 365.522156 -247.980239)
			(xy 365.477729 -248.004278) (xy 365.429952 -248.020676) (xy 365.380127 -248.028986) (xy 365.35487 -248.029476)
			(xy 364.414816 -248.029476) (xy 364.389555 -248.029048) (xy 364.339721 -248.020735) (xy 364.291935 -248.004332)
			(xy 364.247501 -247.980288) (xy 364.207631 -247.949258) (xy 364.173412 -247.912088) (xy 364.145778 -247.869793)
			(xy 364.125483 -247.823526) (xy 364.11308 -247.77455) (xy 364.108908 -247.7242) (xy 107.38722 -247.7242)
			(xy 107.387237 -247.7244) (xy 107.383061 -247.774792) (xy 107.370647 -247.823809) (xy 107.350334 -247.870114)
			(xy 107.322676 -247.912444) (xy 107.288427 -247.949644) (xy 107.248523 -247.980699) (xy 107.204051 -248.004762)
			(xy 107.156224 -248.021176) (xy 107.106348 -248.029494) (xy 107.081066 -248.029984) (xy 106.141012 -248.029984)
			(xy 106.115734 -248.029448) (xy 106.065869 -248.021129) (xy 106.018052 -248.004715) (xy 105.97359 -247.980655)
			(xy 105.933694 -247.949604) (xy 105.899453 -247.91241) (xy 105.871801 -247.870087) (xy 105.851493 -247.82379)
			(xy 105.839082 -247.774782) (xy 105.834907 -247.7244) (xy 104.567337 -247.7244) (xy 104.56316 -247.774793)
			(xy 104.550746 -247.823811) (xy 104.530433 -247.870117) (xy 104.502774 -247.912447) (xy 104.468524 -247.949647)
			(xy 104.428619 -247.980702) (xy 104.384145 -248.004764) (xy 104.336318 -248.021178) (xy 104.286441 -248.029494)
			(xy 104.261158 -248.029984) (xy 103.321104 -248.029984) (xy 103.295827 -248.029447) (xy 103.245962 -248.021127)
			(xy 103.198147 -248.004713) (xy 103.153685 -247.980652) (xy 103.113791 -247.949601) (xy 103.079551 -247.912407)
			(xy 103.0519 -247.870085) (xy 103.031593 -247.823789) (xy 103.019182 -247.774782) (xy 103.015007 -247.7244)
			(xy 101.747137 -247.7244) (xy 101.742961 -247.774789) (xy 101.730549 -247.823803) (xy 101.710238 -247.870106)
			(xy 101.682584 -247.912434) (xy 101.648339 -247.949633) (xy 101.608439 -247.980689) (xy 101.563971 -248.004753)
			(xy 101.516149 -248.02117) (xy 101.466277 -248.029491) (xy 101.440996 -248.029984) (xy 100.500942 -248.029984)
			(xy 100.475663 -248.02945) (xy 100.425793 -248.021135) (xy 100.377972 -248.004724) (xy 100.333506 -247.980665)
			(xy 100.293605 -247.949615) (xy 100.259361 -247.91242) (xy 100.231706 -247.870096) (xy 100.211395 -247.823796)
			(xy 100.198983 -247.774786) (xy 100.194807 -247.7244) (xy 98.927237 -247.7244) (xy 98.923061 -247.77479)
			(xy 98.910648 -247.823805) (xy 98.890337 -247.870108) (xy 98.862682 -247.912437) (xy 98.828436 -247.949636)
			(xy 98.788534 -247.980691) (xy 98.744066 -248.004755) (xy 98.696242 -248.021171) (xy 98.646369 -248.029492)
			(xy 98.621088 -248.029984) (xy 97.681034 -248.029984) (xy 97.655755 -248.02945) (xy 97.605887 -248.021133)
			(xy 97.558067 -248.004721) (xy 97.513601 -247.980662) (xy 97.473702 -247.949612) (xy 97.439459 -247.912417)
			(xy 97.411805 -247.870093) (xy 97.391495 -247.823795) (xy 97.379083 -247.774785) (xy 97.374907 -247.7244)
			(xy 2.509012 -247.7244) (xy 2.509012 -248.5344) (xy 108.185168 -248.5344) (xy 108.189339 -248.48406)
			(xy 108.20174 -248.435093) (xy 108.222032 -248.388834) (xy 108.249661 -248.346547) (xy 108.283873 -248.309385)
			(xy 108.323736 -248.278361) (xy 108.368162 -248.254321) (xy 108.415939 -248.237922) (xy 108.465764 -248.229611)
			(xy 108.49102 -248.22912) (xy 109.431074 -248.22912) (xy 109.456335 -248.229555) (xy 109.50617 -248.237867)
			(xy 109.553956 -248.254268) (xy 109.598391 -248.278312) (xy 109.638262 -248.309342) (xy 109.672482 -248.346511)
			(xy 109.700117 -248.388806) (xy 109.720412 -248.435073) (xy 109.732816 -248.48405) (xy 109.736971 -248.5342)
			(xy 361.758659 -248.5342) (xy 361.762835 -248.48381) (xy 361.775248 -248.434795) (xy 361.795559 -248.388491)
			(xy 361.823214 -248.346162) (xy 361.85746 -248.308962) (xy 361.897361 -248.277907) (xy 361.94183 -248.253842)
			(xy 361.989653 -248.237426) (xy 362.039527 -248.229104) (xy 362.064808 -248.228612) (xy 363.004862 -248.228612)
			(xy 363.030141 -248.229154) (xy 363.080009 -248.23747) (xy 363.127829 -248.253881) (xy 363.172294 -248.27794)
			(xy 363.212193 -248.30899) (xy 363.246437 -248.346184) (xy 363.274091 -248.388507) (xy 363.294401 -248.434806)
			(xy 363.306813 -248.483816) (xy 363.310989 -248.5342) (xy 363.306813 -248.584584) (xy 363.294401 -248.633594)
			(xy 363.274091 -248.679893) (xy 363.246437 -248.722216) (xy 363.212193 -248.75941) (xy 363.172294 -248.79046)
			(xy 363.127829 -248.814519) (xy 363.080009 -248.83093) (xy 363.030141 -248.839246) (xy 363.004862 -248.839736)
			(xy 362.064808 -248.839736) (xy 362.039527 -248.839296) (xy 361.989653 -248.830974) (xy 361.94183 -248.814558)
			(xy 361.897361 -248.790493) (xy 361.85746 -248.759438) (xy 361.823214 -248.722238) (xy 361.795559 -248.679909)
			(xy 361.775248 -248.633605) (xy 361.762835 -248.58459) (xy 361.758659 -248.5342) (xy 109.736971 -248.5342)
			(xy 109.736988 -248.5344) (xy 109.732816 -248.58475) (xy 109.720412 -248.633727) (xy 109.700117 -248.679994)
			(xy 109.672482 -248.722289) (xy 109.638262 -248.759458) (xy 109.598391 -248.790488) (xy 109.553956 -248.814532)
			(xy 109.50617 -248.830933) (xy 109.456335 -248.839245) (xy 109.431074 -248.839736) (xy 108.49102 -248.839736)
			(xy 108.465764 -248.839189) (xy 108.415939 -248.830878) (xy 108.368162 -248.814479) (xy 108.323736 -248.790439)
			(xy 108.283873 -248.759415) (xy 108.249661 -248.722253) (xy 108.222032 -248.679966) (xy 108.20174 -248.633707)
			(xy 108.189339 -248.58474) (xy 108.185168 -248.5344) (xy 2.509012 -248.5344) (xy 2.509012 -258.880356)
			(xy 67.312036 -258.880356) (xy 67.316066 -258.738021) (xy 67.328141 -258.596141) (xy 67.348224 -258.455173)
			(xy 67.376251 -258.315566) (xy 67.412131 -258.177768) (xy 67.455749 -258.042221) (xy 67.506966 -257.909359)
			(xy 67.565617 -257.779607) (xy 67.631515 -257.653381) (xy 67.704449 -257.531085) (xy 67.784186 -257.413112)
			(xy 67.870468 -257.299839) (xy 67.963021 -257.191628) (xy 68.061548 -257.088827) (xy 68.165733 -256.991765)
			(xy 68.275242 -256.900753) (xy 68.389725 -256.816081) (xy 68.508815 -256.738023) (xy 68.63213 -256.666827)
			(xy 68.759276 -256.602721) (xy 68.889845 -256.545912) (xy 69.023419 -256.49658) (xy 69.15957 -256.454884)
			(xy 69.297861 -256.420958) (xy 69.437851 -256.39491) (xy 69.57909 -256.376824) (xy 69.721126 -256.366757)
			(xy 69.863504 -256.364742) (xy 70.005768 -256.370785) (xy 70.147462 -256.384867) (xy 70.288132 -256.406943)
			(xy 70.427329 -256.436943) (xy 70.564605 -256.474769) (xy 70.699521 -256.520301) (xy 70.831645 -256.573392)
			(xy 70.960554 -256.633874) (xy 71.085835 -256.701552) (xy 71.207086 -256.776209) (xy 71.323919 -256.857607)
			(xy 71.43596 -256.945484) (xy 71.54285 -257.039559) (xy 71.644247 -257.139531) (xy 71.739825 -257.245079)
			(xy 71.829279 -257.355865) (xy 71.912321 -257.471534) (xy 71.988687 -257.591717) (xy 72.058131 -257.716027)
			(xy 72.120431 -257.844068) (xy 72.175387 -257.975427) (xy 72.222824 -258.109686) (xy 72.262588 -258.246413)
			(xy 72.294554 -258.385171) (xy 72.318619 -258.525515) (xy 72.334705 -258.666996) (xy 72.34276 -258.80916)
			(xy 72.343264 -258.880356) (xy 151.51202 -258.880356) (xy 151.51605 -258.738021) (xy 151.528125 -258.596141)
			(xy 151.548208 -258.455173) (xy 151.576235 -258.315566) (xy 151.612115 -258.177768) (xy 151.655733 -258.042221)
			(xy 151.70695 -257.909359) (xy 151.765601 -257.779607) (xy 151.831499 -257.653381) (xy 151.904433 -257.531085)
			(xy 151.98417 -257.413112) (xy 152.070452 -257.299839) (xy 152.163005 -257.191628) (xy 152.261532 -257.088827)
			(xy 152.365717 -256.991765) (xy 152.475226 -256.900753) (xy 152.589709 -256.816081) (xy 152.708799 -256.738023)
			(xy 152.832114 -256.666827) (xy 152.95926 -256.602721) (xy 153.089829 -256.545912) (xy 153.223403 -256.49658)
			(xy 153.359554 -256.454884) (xy 153.497845 -256.420958) (xy 153.637835 -256.39491) (xy 153.779074 -256.376824)
			(xy 153.92111 -256.366757) (xy 154.063488 -256.364742) (xy 154.205752 -256.370785) (xy 154.347446 -256.384867)
			(xy 154.488116 -256.406943) (xy 154.627313 -256.436943) (xy 154.764589 -256.474769) (xy 154.899505 -256.520301)
			(xy 155.031629 -256.573392) (xy 155.160538 -256.633874) (xy 155.285819 -256.701552) (xy 155.40707 -256.776209)
			(xy 155.523903 -256.857607) (xy 155.635944 -256.945484) (xy 155.742834 -257.039559) (xy 155.844231 -257.139531)
			(xy 155.939809 -257.245079) (xy 156.029263 -257.355865) (xy 156.112305 -257.471534) (xy 156.188671 -257.591717)
			(xy 156.258115 -257.716027) (xy 156.320415 -257.844068) (xy 156.375371 -257.975427) (xy 156.422808 -258.109686)
			(xy 156.462572 -258.246413) (xy 156.494538 -258.385171) (xy 156.518603 -258.525515) (xy 156.534689 -258.666996)
			(xy 156.542744 -258.80916) (xy 156.543246 -258.880102) (xy 315.252104 -258.880102) (xy 315.256134 -258.737767)
			(xy 315.268209 -258.595887) (xy 315.288292 -258.454919) (xy 315.316319 -258.315312) (xy 315.352199 -258.177514)
			(xy 315.395817 -258.041967) (xy 315.447034 -257.909105) (xy 315.505685 -257.779353) (xy 315.571583 -257.653127)
			(xy 315.644517 -257.530831) (xy 315.724254 -257.412858) (xy 315.810536 -257.299585) (xy 315.903089 -257.191374)
			(xy 316.001616 -257.088573) (xy 316.105801 -256.991511) (xy 316.21531 -256.900499) (xy 316.329793 -256.815827)
			(xy 316.448883 -256.737769) (xy 316.572198 -256.666573) (xy 316.699344 -256.602467) (xy 316.829913 -256.545658)
			(xy 316.963487 -256.496326) (xy 317.099638 -256.45463) (xy 317.237929 -256.420704) (xy 317.377919 -256.394656)
			(xy 317.519158 -256.37657) (xy 317.661194 -256.366503) (xy 317.803572 -256.364488) (xy 317.945836 -256.370531)
			(xy 318.08753 -256.384613) (xy 318.2282 -256.406689) (xy 318.367397 -256.436689) (xy 318.504673 -256.474515)
			(xy 318.639589 -256.520047) (xy 318.771713 -256.573138) (xy 318.900622 -256.63362) (xy 319.025903 -256.701298)
			(xy 319.147154 -256.775955) (xy 319.263987 -256.857353) (xy 319.376028 -256.94523) (xy 319.482918 -257.039305)
			(xy 319.584315 -257.139277) (xy 319.679893 -257.244825) (xy 319.769347 -257.355611) (xy 319.852389 -257.47128)
			(xy 319.928755 -257.591463) (xy 319.998199 -257.715773) (xy 320.060499 -257.843814) (xy 320.115455 -257.975173)
			(xy 320.162892 -258.109432) (xy 320.202656 -258.246159) (xy 320.234622 -258.384917) (xy 320.258687 -258.525261)
			(xy 320.274773 -258.666742) (xy 320.282828 -258.808906) (xy 320.283332 -258.880102) (xy 399.452088 -258.880102)
			(xy 399.456118 -258.737767) (xy 399.468193 -258.595887) (xy 399.488276 -258.454919) (xy 399.516303 -258.315312)
			(xy 399.552183 -258.177514) (xy 399.595801 -258.041967) (xy 399.647018 -257.909105) (xy 399.705669 -257.779353)
			(xy 399.771567 -257.653127) (xy 399.844501 -257.530831) (xy 399.924238 -257.412858) (xy 400.01052 -257.299585)
			(xy 400.103073 -257.191374) (xy 400.2016 -257.088573) (xy 400.305785 -256.991511) (xy 400.415294 -256.900499)
			(xy 400.529777 -256.815827) (xy 400.648867 -256.737769) (xy 400.772182 -256.666573) (xy 400.899328 -256.602467)
			(xy 401.029897 -256.545658) (xy 401.163471 -256.496326) (xy 401.299622 -256.45463) (xy 401.437913 -256.420704)
			(xy 401.577903 -256.394656) (xy 401.719142 -256.37657) (xy 401.861178 -256.366503) (xy 402.003556 -256.364488)
			(xy 402.14582 -256.370531) (xy 402.287514 -256.384613) (xy 402.428184 -256.406689) (xy 402.567381 -256.436689)
			(xy 402.704657 -256.474515) (xy 402.839573 -256.520047) (xy 402.971697 -256.573138) (xy 403.100606 -256.63362)
			(xy 403.225887 -256.701298) (xy 403.347138 -256.775955) (xy 403.463971 -256.857353) (xy 403.576012 -256.94523)
			(xy 403.682902 -257.039305) (xy 403.784299 -257.139277) (xy 403.879877 -257.244825) (xy 403.969331 -257.355611)
			(xy 404.052373 -257.47128) (xy 404.128739 -257.591463) (xy 404.198183 -257.715773) (xy 404.260483 -257.843814)
			(xy 404.315439 -257.975173) (xy 404.362876 -258.109432) (xy 404.40264 -258.246159) (xy 404.434606 -258.384917)
			(xy 404.458671 -258.525261) (xy 404.474757 -258.666742) (xy 404.482812 -258.808906) (xy 404.483316 -258.880102)
			(xy 404.482812 -258.951298) (xy 404.474757 -259.093462) (xy 404.458671 -259.234943) (xy 404.434606 -259.375287)
			(xy 404.40264 -259.514045) (xy 404.362876 -259.650772) (xy 404.315439 -259.785031) (xy 404.260483 -259.91639)
			(xy 404.198183 -260.044431) (xy 404.128739 -260.168741) (xy 404.052373 -260.288924) (xy 403.969331 -260.404593)
			(xy 403.879877 -260.515379) (xy 403.784299 -260.620927) (xy 403.682902 -260.720899) (xy 403.576012 -260.814974)
			(xy 403.463971 -260.902851) (xy 403.347138 -260.984249) (xy 403.225887 -261.058906) (xy 403.100606 -261.126584)
			(xy 402.971697 -261.187066) (xy 402.839573 -261.240157) (xy 402.704657 -261.285689) (xy 402.567381 -261.323515)
			(xy 402.428184 -261.353515) (xy 402.287514 -261.375591) (xy 402.14582 -261.389673) (xy 402.003556 -261.395716)
			(xy 401.861178 -261.393701) (xy 401.719142 -261.383634) (xy 401.577903 -261.365548) (xy 401.437913 -261.3395)
			(xy 401.299622 -261.305574) (xy 401.163471 -261.263878) (xy 401.029897 -261.214546) (xy 400.899328 -261.157737)
			(xy 400.772182 -261.093631) (xy 400.648867 -261.022435) (xy 400.529777 -260.944377) (xy 400.415294 -260.859705)
			(xy 400.305785 -260.768693) (xy 400.2016 -260.671631) (xy 400.103073 -260.56883) (xy 400.01052 -260.460619)
			(xy 399.924238 -260.347346) (xy 399.844501 -260.229373) (xy 399.771567 -260.107077) (xy 399.705669 -259.980851)
			(xy 399.647018 -259.851099) (xy 399.595801 -259.718237) (xy 399.552183 -259.58269) (xy 399.516303 -259.444892)
			(xy 399.488276 -259.305285) (xy 399.468193 -259.164317) (xy 399.456118 -259.022437) (xy 399.452088 -258.880102)
			(xy 320.283332 -258.880102) (xy 320.282828 -258.951298) (xy 320.274773 -259.093462) (xy 320.258687 -259.234943)
			(xy 320.234622 -259.375287) (xy 320.202656 -259.514045) (xy 320.162892 -259.650772) (xy 320.115455 -259.785031)
			(xy 320.060499 -259.91639) (xy 319.998199 -260.044431) (xy 319.928755 -260.168741) (xy 319.852389 -260.288924)
			(xy 319.769347 -260.404593) (xy 319.679893 -260.515379) (xy 319.584315 -260.620927) (xy 319.482918 -260.720899)
			(xy 319.376028 -260.814974) (xy 319.263987 -260.902851) (xy 319.147154 -260.984249) (xy 319.025903 -261.058906)
			(xy 318.900622 -261.126584) (xy 318.771713 -261.187066) (xy 318.639589 -261.240157) (xy 318.504673 -261.285689)
			(xy 318.367397 -261.323515) (xy 318.2282 -261.353515) (xy 318.08753 -261.375591) (xy 317.945836 -261.389673)
			(xy 317.803572 -261.395716) (xy 317.661194 -261.393701) (xy 317.519158 -261.383634) (xy 317.377919 -261.365548)
			(xy 317.237929 -261.3395) (xy 317.099638 -261.305574) (xy 316.963487 -261.263878) (xy 316.829913 -261.214546)
			(xy 316.699344 -261.157737) (xy 316.572198 -261.093631) (xy 316.448883 -261.022435) (xy 316.329793 -260.944377)
			(xy 316.21531 -260.859705) (xy 316.105801 -260.768693) (xy 316.001616 -260.671631) (xy 315.903089 -260.56883)
			(xy 315.810536 -260.460619) (xy 315.724254 -260.347346) (xy 315.644517 -260.229373) (xy 315.571583 -260.107077)
			(xy 315.505685 -259.980851) (xy 315.447034 -259.851099) (xy 315.395817 -259.718237) (xy 315.352199 -259.58269)
			(xy 315.316319 -259.444892) (xy 315.288292 -259.305285) (xy 315.268209 -259.164317) (xy 315.256134 -259.022437)
			(xy 315.252104 -258.880102) (xy 156.543246 -258.880102) (xy 156.543248 -258.880356) (xy 156.542744 -258.951552)
			(xy 156.534689 -259.093716) (xy 156.518603 -259.235197) (xy 156.494538 -259.375541) (xy 156.462572 -259.514299)
			(xy 156.422808 -259.651026) (xy 156.375371 -259.785285) (xy 156.320415 -259.916644) (xy 156.258115 -260.044685)
			(xy 156.188671 -260.168995) (xy 156.112305 -260.289178) (xy 156.029263 -260.404847) (xy 155.939809 -260.515633)
			(xy 155.844231 -260.621181) (xy 155.742834 -260.721153) (xy 155.635944 -260.815228) (xy 155.523903 -260.903105)
			(xy 155.40707 -260.984503) (xy 155.285819 -261.05916) (xy 155.160538 -261.126838) (xy 155.031629 -261.18732)
			(xy 154.899505 -261.240411) (xy 154.764589 -261.285943) (xy 154.627313 -261.323769) (xy 154.488116 -261.353769)
			(xy 154.347446 -261.375845) (xy 154.205752 -261.389927) (xy 154.063488 -261.39597) (xy 153.92111 -261.393955)
			(xy 153.779074 -261.383888) (xy 153.637835 -261.365802) (xy 153.497845 -261.339754) (xy 153.359554 -261.305828)
			(xy 153.223403 -261.264132) (xy 153.089829 -261.2148) (xy 152.95926 -261.157991) (xy 152.832114 -261.093885)
			(xy 152.708799 -261.022689) (xy 152.589709 -260.944631) (xy 152.475226 -260.859959) (xy 152.365717 -260.768947)
			(xy 152.261532 -260.671885) (xy 152.163005 -260.569084) (xy 152.070452 -260.460873) (xy 151.98417 -260.3476)
			(xy 151.904433 -260.229627) (xy 151.831499 -260.107331) (xy 151.765601 -259.981105) (xy 151.70695 -259.851353)
			(xy 151.655733 -259.718491) (xy 151.612115 -259.582944) (xy 151.576235 -259.445146) (xy 151.548208 -259.305539)
			(xy 151.528125 -259.164571) (xy 151.51605 -259.022691) (xy 151.51202 -258.880356) (xy 72.343264 -258.880356)
			(xy 72.34276 -258.951552) (xy 72.334705 -259.093716) (xy 72.318619 -259.235197) (xy 72.294554 -259.375541)
			(xy 72.262588 -259.514299) (xy 72.222824 -259.651026) (xy 72.175387 -259.785285) (xy 72.120431 -259.916644)
			(xy 72.058131 -260.044685) (xy 71.988687 -260.168995) (xy 71.912321 -260.289178) (xy 71.829279 -260.404847)
			(xy 71.739825 -260.515633) (xy 71.644247 -260.621181) (xy 71.54285 -260.721153) (xy 71.43596 -260.815228)
			(xy 71.323919 -260.903105) (xy 71.207086 -260.984503) (xy 71.085835 -261.05916) (xy 70.960554 -261.126838)
			(xy 70.831645 -261.18732) (xy 70.699521 -261.240411) (xy 70.564605 -261.285943) (xy 70.427329 -261.323769)
			(xy 70.288132 -261.353769) (xy 70.147462 -261.375845) (xy 70.005768 -261.389927) (xy 69.863504 -261.39597)
			(xy 69.721126 -261.393955) (xy 69.57909 -261.383888) (xy 69.437851 -261.365802) (xy 69.297861 -261.339754)
			(xy 69.15957 -261.305828) (xy 69.023419 -261.264132) (xy 68.889845 -261.2148) (xy 68.759276 -261.157991)
			(xy 68.63213 -261.093885) (xy 68.508815 -261.022689) (xy 68.389725 -260.944631) (xy 68.275242 -260.859959)
			(xy 68.165733 -260.768947) (xy 68.061548 -260.671885) (xy 67.963021 -260.569084) (xy 67.870468 -260.460873)
			(xy 67.784186 -260.3476) (xy 67.704449 -260.229627) (xy 67.631515 -260.107331) (xy 67.565617 -259.981105)
			(xy 67.506966 -259.851353) (xy 67.455749 -259.718491) (xy 67.412131 -259.582944) (xy 67.376251 -259.445146)
			(xy 67.348224 -259.305539) (xy 67.328141 -259.164571) (xy 67.316066 -259.022691) (xy 67.312036 -258.880356)
			(xy 2.509012 -258.880356) (xy 2.509012 -281.3764) (xy 97.674859 -281.3764) (xy 97.679035 -281.32601)
			(xy 97.691448 -281.276995) (xy 97.711759 -281.230691) (xy 97.739414 -281.188362) (xy 97.77366 -281.151162)
			(xy 97.813561 -281.120107) (xy 97.85803 -281.096042) (xy 97.905853 -281.079626) (xy 97.955727 -281.071304)
			(xy 97.981008 -281.070812) (xy 98.921062 -281.070812) (xy 98.946341 -281.071354) (xy 98.996209 -281.07967)
			(xy 99.044029 -281.096081) (xy 99.088494 -281.12014) (xy 99.128393 -281.15119) (xy 99.162637 -281.188384)
			(xy 99.190291 -281.230707) (xy 99.210601 -281.277006) (xy 99.223013 -281.326016) (xy 99.227189 -281.3764)
			(xy 100.495088 -281.3764) (xy 100.499263 -281.326019) (xy 100.511672 -281.277012) (xy 100.531978 -281.230715)
			(xy 100.559627 -281.188392) (xy 100.593865 -281.151197) (xy 100.633757 -281.120144) (xy 100.678216 -281.09608)
			(xy 100.72603 -281.079662) (xy 100.775893 -281.071336) (xy 100.80117 -281.070812) (xy 101.741224 -281.070812)
			(xy 101.766497 -281.071388) (xy 101.816353 -281.079711) (xy 101.864159 -281.096126) (xy 101.908611 -281.120186)
			(xy 101.948498 -281.151233) (xy 101.98273 -281.188422) (xy 102.010375 -281.230738) (xy 102.030678 -281.277027)
			(xy 102.043086 -281.326027) (xy 102.04726 -281.3764) (xy 122.108688 -281.3764) (xy 122.112863 -281.326017)
			(xy 122.125274 -281.277007) (xy 122.145582 -281.230709) (xy 122.173233 -281.188385) (xy 122.207473 -281.151189)
			(xy 122.247369 -281.120136) (xy 122.291831 -281.096074) (xy 122.339648 -281.079657) (xy 122.389514 -281.071335)
			(xy 122.414792 -281.070812) (xy 123.354846 -281.070812) (xy 123.380118 -281.071389) (xy 123.429971 -281.079715)
			(xy 123.477774 -281.096133) (xy 123.522223 -281.120193) (xy 123.562106 -281.151241) (xy 123.596336 -281.18843)
			(xy 123.623978 -281.230745) (xy 123.64428 -281.277032) (xy 123.656686 -281.326029) (xy 123.66086 -281.3764)
			(xy 124.928589 -281.3764) (xy 124.932763 -281.326016) (xy 124.945174 -281.277006) (xy 124.965483 -281.230707)
			(xy 124.993135 -281.188382) (xy 125.027376 -281.151186) (xy 125.067273 -281.120134) (xy 125.111736 -281.096071)
			(xy 125.159554 -281.079655) (xy 125.209422 -281.071334) (xy 125.2347 -281.070812) (xy 126.174754 -281.070812)
			(xy 126.200033 -281.071353) (xy 126.249903 -281.079668) (xy 126.297723 -281.096079) (xy 126.34219 -281.120137)
			(xy 126.38209 -281.151187) (xy 126.416335 -281.188381) (xy 126.44399 -281.230705) (xy 126.464301 -281.277004)
			(xy 126.476713 -281.326015) (xy 126.480864 -281.3761) (xy 345.615289 -281.3761) (xy 345.619459 -281.325768)
			(xy 345.631857 -281.276808) (xy 345.652144 -281.230557) (xy 345.679766 -281.188275) (xy 345.713971 -281.151116)
			(xy 345.753825 -281.120094) (xy 345.798241 -281.096054) (xy 345.846008 -281.079652) (xy 345.895824 -281.071335)
			(xy 345.921076 -281.070812) (xy 346.86113 -281.070812) (xy 346.886385 -281.071296) (xy 346.936207 -281.079614)
			(xy 346.983979 -281.096019) (xy 347.028401 -281.120062) (xy 347.068259 -281.151089) (xy 347.102467 -281.188252)
			(xy 347.130092 -281.230539) (xy 347.150381 -281.276796) (xy 347.16278 -281.325762) (xy 347.166951 -281.3761)
			(xy 348.43536 -281.3761) (xy 348.439532 -281.325756) (xy 348.451934 -281.276786) (xy 348.472227 -281.230526)
			(xy 348.499859 -281.188237) (xy 348.534075 -281.151073) (xy 348.573942 -281.120048) (xy 348.618371 -281.096009)
			(xy 348.666152 -281.079611) (xy 348.71598 -281.071302) (xy 348.741238 -281.070812) (xy 349.681292 -281.070812)
			(xy 349.706552 -281.071264) (xy 349.756383 -281.079578) (xy 349.804165 -281.095981) (xy 349.848596 -281.120025)
			(xy 349.888464 -281.151054) (xy 349.92268 -281.188222) (xy 349.950312 -281.230515) (xy 349.970606 -281.276779)
			(xy 349.983008 -281.325753) (xy 349.98718 -281.3761) (xy 370.049089 -281.3761) (xy 370.053259 -281.325769)
			(xy 370.065656 -281.276811) (xy 370.085941 -281.230561) (xy 370.113562 -281.18828) (xy 370.147764 -281.151122)
			(xy 370.187616 -281.120099) (xy 370.23203 -281.096058) (xy 370.279795 -281.079655) (xy 370.329608 -281.071337)
			(xy 370.35486 -281.070812) (xy 371.294914 -281.070812) (xy 371.32017 -281.071295) (xy 371.369993 -281.079611)
			(xy 371.417768 -281.096014) (xy 371.462192 -281.120057) (xy 371.502053 -281.151083) (xy 371.536263 -281.188247)
			(xy 371.56389 -281.230535) (xy 371.58418 -281.276793) (xy 371.59658 -281.32576) (xy 371.600751 -281.3761)
			(xy 372.868989 -281.3761) (xy 372.873159 -281.325768) (xy 372.885556 -281.27681) (xy 372.905842 -281.230559)
			(xy 372.933464 -281.188278) (xy 372.967667 -281.151119) (xy 373.00752 -281.120096) (xy 373.051935 -281.096056)
			(xy 373.099702 -281.079653) (xy 373.149516 -281.071336) (xy 373.174768 -281.070812) (xy 374.114822 -281.070812)
			(xy 374.140078 -281.071295) (xy 374.1899 -281.079613) (xy 374.237674 -281.096016) (xy 374.282096 -281.120059)
			(xy 374.321956 -281.151086) (xy 374.356165 -281.18825) (xy 374.383791 -281.230537) (xy 374.404081 -281.276795)
			(xy 374.41648 -281.325761) (xy 374.420651 -281.3761) (xy 374.41648 -281.426439) (xy 374.404081 -281.475405)
			(xy 374.383791 -281.521663) (xy 374.356165 -281.56395) (xy 374.321956 -281.601114) (xy 374.282096 -281.632141)
			(xy 374.237674 -281.656184) (xy 374.1899 -281.672587) (xy 374.140078 -281.680905) (xy 374.114822 -281.681428)
			(xy 373.174768 -281.681428) (xy 373.149516 -281.680864) (xy 373.099702 -281.672547) (xy 373.051935 -281.656144)
			(xy 373.00752 -281.632104) (xy 372.967667 -281.601081) (xy 372.933464 -281.563922) (xy 372.905842 -281.521641)
			(xy 372.885556 -281.47539) (xy 372.873159 -281.426432) (xy 372.868989 -281.3761) (xy 371.600751 -281.3761)
			(xy 371.59658 -281.42644) (xy 371.58418 -281.475407) (xy 371.56389 -281.521665) (xy 371.536263 -281.563953)
			(xy 371.502053 -281.601117) (xy 371.462192 -281.632143) (xy 371.417768 -281.656186) (xy 371.369993 -281.672589)
			(xy 371.32017 -281.680905) (xy 371.294914 -281.681428) (xy 370.35486 -281.681428) (xy 370.329609 -281.680863)
			(xy 370.279795 -281.672545) (xy 370.23203 -281.656142) (xy 370.187616 -281.632101) (xy 370.147764 -281.601078)
			(xy 370.113562 -281.56392) (xy 370.085941 -281.521639) (xy 370.065656 -281.475389) (xy 370.053259 -281.426431)
			(xy 370.049089 -281.3761) (xy 349.98718 -281.3761) (xy 349.983008 -281.426447) (xy 349.970606 -281.475421)
			(xy 349.950312 -281.521685) (xy 349.92268 -281.563978) (xy 349.888464 -281.601146) (xy 349.848596 -281.632175)
			(xy 349.804165 -281.656219) (xy 349.756383 -281.672622) (xy 349.706552 -281.680936) (xy 349.681292 -281.681428)
			(xy 348.741238 -281.681428) (xy 348.71598 -281.680898) (xy 348.666152 -281.672589) (xy 348.618371 -281.656191)
			(xy 348.573941 -281.632152) (xy 348.534075 -281.601127) (xy 348.499859 -281.563963) (xy 348.472227 -281.521674)
			(xy 348.451934 -281.475414) (xy 348.439532 -281.426444) (xy 348.43536 -281.3761) (xy 347.166951 -281.3761)
			(xy 347.16278 -281.426438) (xy 347.150381 -281.475404) (xy 347.130092 -281.521661) (xy 347.102467 -281.563948)
			(xy 347.068259 -281.601111) (xy 347.028401 -281.632138) (xy 346.983979 -281.656181) (xy 346.936207 -281.672586)
			(xy 346.886385 -281.680904) (xy 346.86113 -281.681428) (xy 345.921076 -281.681428) (xy 345.895824 -281.680865)
			(xy 345.846008 -281.672548) (xy 345.798241 -281.656146) (xy 345.753825 -281.632106) (xy 345.713971 -281.601084)
			(xy 345.679766 -281.563925) (xy 345.652144 -281.521643) (xy 345.631857 -281.475392) (xy 345.619459 -281.426432)
			(xy 345.615289 -281.3761) (xy 126.480864 -281.3761) (xy 126.480889 -281.3764) (xy 126.476713 -281.426785)
			(xy 126.464301 -281.475796) (xy 126.44399 -281.522095) (xy 126.416335 -281.564419) (xy 126.38209 -281.601613)
			(xy 126.34219 -281.632663) (xy 126.297723 -281.656721) (xy 126.249903 -281.673132) (xy 126.200033 -281.681447)
			(xy 126.174754 -281.681936) (xy 125.2347 -281.681936) (xy 125.209422 -281.681466) (xy 125.159554 -281.673145)
			(xy 125.111736 -281.656729) (xy 125.067273 -281.632666) (xy 125.027376 -281.601614) (xy 124.993135 -281.564418)
			(xy 124.965483 -281.522093) (xy 124.945174 -281.475794) (xy 124.932763 -281.426784) (xy 124.928589 -281.3764)
			(xy 123.66086 -281.3764) (xy 123.656686 -281.426771) (xy 123.64428 -281.475768) (xy 123.623978 -281.522055)
			(xy 123.596336 -281.56437) (xy 123.562106 -281.601559) (xy 123.522223 -281.632607) (xy 123.477774 -281.656667)
			(xy 123.429971 -281.673085) (xy 123.380118 -281.681411) (xy 123.354846 -281.681936) (xy 122.414792 -281.681936)
			(xy 122.389514 -281.681465) (xy 122.339648 -281.673143) (xy 122.291831 -281.656726) (xy 122.247369 -281.632664)
			(xy 122.207473 -281.601611) (xy 122.173233 -281.564415) (xy 122.145582 -281.522091) (xy 122.125274 -281.475793)
			(xy 122.112863 -281.426783) (xy 122.108688 -281.3764) (xy 102.04726 -281.3764) (xy 102.043086 -281.426773)
			(xy 102.030678 -281.475773) (xy 102.010375 -281.522062) (xy 101.98273 -281.564378) (xy 101.948498 -281.601567)
			(xy 101.908611 -281.632614) (xy 101.864159 -281.656674) (xy 101.816353 -281.673089) (xy 101.766497 -281.681412)
			(xy 101.741224 -281.681936) (xy 100.80117 -281.681936) (xy 100.775893 -281.681464) (xy 100.72603 -281.673138)
			(xy 100.678216 -281.65672) (xy 100.633757 -281.632656) (xy 100.593865 -281.601603) (xy 100.559627 -281.564408)
			(xy 100.531978 -281.522085) (xy 100.511672 -281.475788) (xy 100.499263 -281.426781) (xy 100.495088 -281.3764)
			(xy 99.227189 -281.3764) (xy 99.223013 -281.426784) (xy 99.210601 -281.475794) (xy 99.190291 -281.522093)
			(xy 99.162637 -281.564416) (xy 99.128393 -281.60161) (xy 99.088494 -281.63266) (xy 99.044029 -281.656719)
			(xy 98.996209 -281.67313) (xy 98.946341 -281.681446) (xy 98.921062 -281.681936) (xy 97.981008 -281.681936)
			(xy 97.955727 -281.681496) (xy 97.905853 -281.673174) (xy 97.85803 -281.656758) (xy 97.813561 -281.632693)
			(xy 97.77366 -281.601638) (xy 97.739414 -281.564438) (xy 97.711759 -281.522109) (xy 97.691448 -281.475805)
			(xy 97.679035 -281.42679) (xy 97.674859 -281.3764) (xy 2.509012 -281.3764) (xy 2.509012 -282.1864)
			(xy 108.485149 -282.1864) (xy 108.48932 -282.136059) (xy 108.50172 -282.087092) (xy 108.522011 -282.040833)
			(xy 108.549639 -281.998544) (xy 108.58385 -281.96138) (xy 108.623712 -281.930354) (xy 108.668137 -281.906312)
			(xy 108.715913 -281.889909) (xy 108.765737 -281.881594) (xy 108.790994 -281.881072) (xy 109.731048 -281.881072)
			(xy 109.756299 -281.881637) (xy 109.806111 -281.889957) (xy 109.853875 -281.906361) (xy 109.898288 -281.930402)
			(xy 109.938139 -281.961425) (xy 109.97234 -281.998583) (xy 109.99996 -282.040863) (xy 110.020245 -282.087113)
			(xy 110.032641 -282.13607) (xy 110.036811 -282.1864) (xy 114.11882 -282.1864) (xy 114.122992 -282.136052)
			(xy 114.135394 -282.087078) (xy 114.155689 -282.040813) (xy 114.183321 -281.99852) (xy 114.217539 -281.961352)
			(xy 114.257407 -281.930323) (xy 114.301839 -281.906279) (xy 114.349622 -281.889877) (xy 114.399454 -281.881564)
			(xy 114.424714 -281.881072) (xy 115.364768 -281.881072) (xy 115.390026 -281.881602) (xy 115.439853 -281.889912)
			(xy 115.487633 -281.90631) (xy 115.532062 -281.93035) (xy 115.571927 -281.961375) (xy 115.606142 -281.998539)
			(xy 115.633773 -282.040827) (xy 115.654067 -282.087088) (xy 115.666468 -282.136057) (xy 115.670615 -282.1861)
			(xy 356.42504 -282.1861) (xy 356.429214 -282.135728) (xy 356.441621 -282.08673) (xy 356.461923 -282.040442)
			(xy 356.489566 -281.998127) (xy 356.523797 -281.960938) (xy 356.563681 -281.92989) (xy 356.608132 -281.90583)
			(xy 356.655936 -281.889414) (xy 356.70579 -281.881089) (xy 356.731062 -281.880564) (xy 357.671116 -281.880564)
			(xy 357.696394 -281.881035) (xy 357.746259 -281.889359) (xy 357.794074 -281.905776) (xy 357.838536 -281.929839)
			(xy 357.87843 -281.960892) (xy 357.912669 -281.998088) (xy 357.940319 -282.040411) (xy 357.960627 -282.086709)
			(xy 357.973037 -282.135717) (xy 357.977212 -282.1861) (xy 362.05874 -282.1861) (xy 362.062914 -282.135726)
			(xy 362.075322 -282.086726) (xy 362.095626 -282.040437) (xy 362.123271 -281.99812) (xy 362.157505 -281.960931)
			(xy 362.197392 -281.929883) (xy 362.241845 -281.905824) (xy 362.289652 -281.88941) (xy 362.339509 -281.881087)
			(xy 362.364782 -281.880564) (xy 363.304836 -281.880564) (xy 363.330113 -281.881037) (xy 363.379975 -281.889363)
			(xy 363.427788 -281.905782) (xy 363.472246 -281.929846) (xy 363.512138 -281.960899) (xy 363.546374 -281.998094)
			(xy 363.574022 -282.040417) (xy 363.594328 -282.086713) (xy 363.606737 -282.135719) (xy 363.610912 -282.1861)
			(xy 363.606737 -282.236481) (xy 363.594328 -282.285487) (xy 363.574022 -282.331783) (xy 363.546374 -282.374106)
			(xy 363.512138 -282.411301) (xy 363.472246 -282.442354) (xy 363.427788 -282.466418) (xy 363.379975 -282.482837)
			(xy 363.330113 -282.491163) (xy 363.304836 -282.491688) (xy 362.364782 -282.491688) (xy 362.339509 -282.491113)
			(xy 362.289652 -282.48279) (xy 362.241845 -282.466376) (xy 362.197392 -282.442317) (xy 362.157505 -282.411269)
			(xy 362.123271 -282.37408) (xy 362.095626 -282.331763) (xy 362.075322 -282.285474) (xy 362.062914 -282.236474)
			(xy 362.05874 -282.1861) (xy 357.977212 -282.1861) (xy 357.973037 -282.236483) (xy 357.960627 -282.285491)
			(xy 357.940319 -282.331789) (xy 357.912669 -282.374112) (xy 357.87843 -282.411308) (xy 357.838536 -282.442361)
			(xy 357.794074 -282.466424) (xy 357.746259 -282.482841) (xy 357.696394 -282.491165) (xy 357.671116 -282.491688)
			(xy 356.731062 -282.491688) (xy 356.70579 -282.491111) (xy 356.655936 -282.482786) (xy 356.608132 -282.46637)
			(xy 356.563681 -282.44231) (xy 356.523797 -282.411262) (xy 356.489566 -282.374073) (xy 356.461923 -282.331758)
			(xy 356.441621 -282.28547) (xy 356.429214 -282.236472) (xy 356.42504 -282.1861) (xy 115.670615 -282.1861)
			(xy 115.67064 -282.1864) (xy 115.666468 -282.236743) (xy 115.654067 -282.285712) (xy 115.633773 -282.331973)
			(xy 115.606142 -282.374261) (xy 115.571927 -282.411425) (xy 115.532062 -282.44245) (xy 115.487633 -282.46649)
			(xy 115.439853 -282.482888) (xy 115.390026 -282.491198) (xy 115.364768 -282.491688) (xy 114.424714 -282.491688)
			(xy 114.399454 -282.491236) (xy 114.349622 -282.482923) (xy 114.301839 -282.466521) (xy 114.257407 -282.442477)
			(xy 114.217539 -282.411448) (xy 114.183321 -282.37428) (xy 114.155689 -282.331987) (xy 114.135394 -282.285722)
			(xy 114.122992 -282.236748) (xy 114.11882 -282.1864) (xy 110.036811 -282.1864) (xy 110.032641 -282.23673)
			(xy 110.020245 -282.285687) (xy 109.99996 -282.331937) (xy 109.97234 -282.374217) (xy 109.938139 -282.411375)
			(xy 109.898288 -282.442398) (xy 109.853875 -282.466439) (xy 109.806111 -282.482843) (xy 109.756299 -282.491163)
			(xy 109.731048 -282.491688) (xy 108.790994 -282.491688) (xy 108.765737 -282.491206) (xy 108.715913 -282.482891)
			(xy 108.668137 -282.466488) (xy 108.623712 -282.442446) (xy 108.58385 -282.41142) (xy 108.549639 -282.374256)
			(xy 108.522011 -282.331967) (xy 108.50172 -282.285708) (xy 108.48932 -282.236741) (xy 108.485149 -282.1864)
			(xy 2.509012 -282.1864) (xy 2.509012 -282.9964) (xy 97.674871 -282.9964) (xy 97.679047 -282.946012)
			(xy 97.691459 -282.896999) (xy 97.711769 -282.850697) (xy 97.739424 -282.808369) (xy 97.773668 -282.771171)
			(xy 97.813568 -282.740117) (xy 97.858035 -282.716053) (xy 97.905856 -282.699637) (xy 97.955728 -282.691316)
			(xy 97.981008 -282.690824) (xy 98.921062 -282.690824) (xy 98.946342 -282.691342) (xy 98.996212 -282.699658)
			(xy 99.044033 -282.71607) (xy 99.088501 -282.74013) (xy 99.128401 -282.771181) (xy 99.162646 -282.808377)
			(xy 99.190302 -282.850702) (xy 99.210613 -282.897002) (xy 99.223025 -282.946014) (xy 99.227201 -282.9964)
			(xy 100.4951 -282.9964) (xy 100.499275 -282.946021) (xy 100.511684 -282.897016) (xy 100.531989 -282.850721)
			(xy 100.559637 -282.8084) (xy 100.593873 -282.771206) (xy 100.633764 -282.740154) (xy 100.678221 -282.716091)
			(xy 100.726032 -282.699673) (xy 100.775894 -282.691348) (xy 100.80117 -282.690824) (xy 101.741224 -282.690824)
			(xy 101.766498 -282.691376) (xy 101.816356 -282.699699) (xy 101.864164 -282.716115) (xy 101.908618 -282.740176)
			(xy 101.948506 -282.771224) (xy 101.98274 -282.808415) (xy 102.010385 -282.850733) (xy 102.030689 -282.897024)
			(xy 102.043098 -282.946025) (xy 102.047272 -282.9964) (xy 103.315 -282.9964) (xy 103.319175 -282.94602)
			(xy 103.331584 -282.897014) (xy 103.35189 -282.850719) (xy 103.379539 -282.808397) (xy 103.413776 -282.771203)
			(xy 103.453668 -282.740151) (xy 103.498126 -282.716089) (xy 103.545939 -282.699672) (xy 103.595802 -282.691348)
			(xy 103.621078 -282.690824) (xy 104.561132 -282.690824) (xy 104.586405 -282.691376) (xy 104.636262 -282.699701)
			(xy 104.684069 -282.716117) (xy 104.728522 -282.740178) (xy 104.768409 -282.771227) (xy 104.802642 -282.808418)
			(xy 104.830287 -282.850735) (xy 104.85059 -282.897025) (xy 104.862998 -282.946026) (xy 104.867172 -282.9964)
			(xy 106.1349 -282.9964) (xy 106.139075 -282.946019) (xy 106.151485 -282.897012) (xy 106.171791 -282.850717)
			(xy 106.199441 -282.808394) (xy 106.233679 -282.7712) (xy 106.273572 -282.740149) (xy 106.318032 -282.716086)
			(xy 106.365846 -282.69967) (xy 106.415709 -282.691347) (xy 106.440986 -282.690824) (xy 107.38104 -282.690824)
			(xy 107.406313 -282.691377) (xy 107.456169 -282.699702) (xy 107.503975 -282.71612) (xy 107.548426 -282.740181)
			(xy 107.588312 -282.77123) (xy 107.622544 -282.80842) (xy 107.650188 -282.850737) (xy 107.67049 -282.897027)
			(xy 107.682898 -282.946026) (xy 107.687072 -282.9964) (xy 116.468571 -282.9964) (xy 116.472747 -282.946011)
			(xy 116.48516 -282.896996) (xy 116.505471 -282.850693) (xy 116.533127 -282.808365) (xy 116.567373 -282.771166)
			(xy 116.607275 -282.740112) (xy 116.651744 -282.716049) (xy 116.699568 -282.699634) (xy 116.749441 -282.691315)
			(xy 116.774722 -282.690824) (xy 117.714776 -282.690824) (xy 117.740055 -282.691343) (xy 117.789924 -282.699661)
			(xy 117.837743 -282.716074) (xy 117.882208 -282.740135) (xy 117.922107 -282.771186) (xy 117.95635 -282.808381)
			(xy 117.984004 -282.850706) (xy 118.004313 -282.897005) (xy 118.016725 -282.946015) (xy 118.020901 -282.9964)
			(xy 119.288471 -282.9964) (xy 119.292647 -282.94601) (xy 119.30506 -282.896994) (xy 119.325373 -282.850691)
			(xy 119.353029 -282.808362) (xy 119.387276 -282.771163) (xy 119.427179 -282.740109) (xy 119.47165 -282.716047)
			(xy 119.519474 -282.699633) (xy 119.569348 -282.691315) (xy 119.59463 -282.690824) (xy 120.534684 -282.690824)
			(xy 120.559962 -282.691344) (xy 120.60983 -282.699663) (xy 120.657648 -282.716077) (xy 120.702113 -282.740137)
			(xy 120.74201 -282.771189) (xy 120.776252 -282.808384) (xy 120.803905 -282.850708) (xy 120.824214 -282.897006)
			(xy 120.836625 -282.946016) (xy 120.840801 -282.9964) (xy 122.1087 -282.9964) (xy 122.112875 -282.946019)
			(xy 122.125285 -282.897011) (xy 122.145592 -282.850715) (xy 122.173242 -282.808392) (xy 122.207481 -282.771198)
			(xy 122.247375 -282.740147) (xy 122.291836 -282.716085) (xy 122.33965 -282.699669) (xy 122.389515 -282.691347)
			(xy 122.414792 -282.690824) (xy 123.354846 -282.690824) (xy 123.380119 -282.691377) (xy 123.429974 -282.699704)
			(xy 123.477779 -282.716122) (xy 123.52223 -282.740183) (xy 123.562114 -282.771232) (xy 123.596345 -282.808422)
			(xy 123.623989 -282.850739) (xy 123.644291 -282.897028) (xy 123.656698 -282.946027) (xy 123.660872 -282.9964)
			(xy 124.928601 -282.9964) (xy 124.932775 -282.946018) (xy 124.945186 -282.89701) (xy 124.965494 -282.850713)
			(xy 124.993144 -282.80839) (xy 125.027384 -282.771195) (xy 125.067279 -282.740144) (xy 125.111741 -282.716082)
			(xy 125.159557 -282.699667) (xy 125.209423 -282.691346) (xy 125.2347 -282.690824) (xy 126.174754 -282.690824)
			(xy 126.200034 -282.691341) (xy 126.249906 -282.699657) (xy 126.297728 -282.716068) (xy 126.342197 -282.740127)
			(xy 126.382098 -282.771178) (xy 126.416344 -282.808374) (xy 126.444 -282.850699) (xy 126.464312 -282.897)
			(xy 126.476725 -282.946013) (xy 126.480876 -282.9961) (xy 345.615301 -282.9961) (xy 345.619471 -282.94577)
			(xy 345.631868 -282.896812) (xy 345.652154 -282.850562) (xy 345.679775 -282.808282) (xy 345.713979 -282.771125)
			(xy 345.753831 -282.740104) (xy 345.798246 -282.716065) (xy 345.846011 -282.699663) (xy 345.895825 -282.691347)
			(xy 345.921076 -282.690824) (xy 346.86113 -282.690824) (xy 346.886386 -282.691284) (xy 346.936209 -282.699603)
			(xy 346.983984 -282.716008) (xy 347.028407 -282.740052) (xy 347.068267 -282.77108) (xy 347.102477 -282.808245)
			(xy 347.130103 -282.850534) (xy 347.150393 -282.896792) (xy 347.162792 -282.94576) (xy 347.166963 -282.9961)
			(xy 348.435372 -282.9961) (xy 348.439544 -282.945758) (xy 348.451945 -282.89679) (xy 348.472238 -282.850531)
			(xy 348.499869 -282.808244) (xy 348.534083 -282.771081) (xy 348.573948 -282.740058) (xy 348.618376 -282.71602)
			(xy 348.666155 -282.699622) (xy 348.715981 -282.691314) (xy 348.741238 -282.690824) (xy 349.681292 -282.690824)
			(xy 349.706553 -282.691252) (xy 349.756386 -282.699567) (xy 349.80417 -282.71597) (xy 349.848603 -282.740015)
			(xy 349.888472 -282.771045) (xy 349.92269 -282.808215) (xy 349.950323 -282.850509) (xy 349.970617 -282.896775)
			(xy 349.98302 -282.945751) (xy 349.987192 -282.9961) (xy 351.255272 -282.9961) (xy 351.259444 -282.945758)
			(xy 351.271846 -282.896789) (xy 351.292139 -282.850529) (xy 351.319771 -282.808241) (xy 351.353986 -282.771079)
			(xy 351.393852 -282.740055) (xy 351.438281 -282.716017) (xy 351.486061 -282.699621) (xy 351.535888 -282.691313)
			(xy 351.561146 -282.690824) (xy 352.5012 -282.690824) (xy 352.526458 -282.691282) (xy 352.576285 -282.699596)
			(xy 352.624064 -282.715999) (xy 352.668491 -282.740042) (xy 352.708355 -282.771069) (xy 352.742569 -282.808235)
			(xy 352.770198 -282.850525) (xy 352.79049 -282.896786) (xy 352.802891 -282.945757) (xy 352.807063 -282.9961)
			(xy 354.075301 -282.9961) (xy 354.079471 -282.945772) (xy 354.091867 -282.896816) (xy 354.112151 -282.850569)
			(xy 354.13977 -282.80829) (xy 354.17397 -282.771133) (xy 354.213819 -282.740111) (xy 354.258231 -282.716071)
			(xy 354.305993 -282.699668) (xy 354.355804 -282.691349) (xy 354.381054 -282.690824) (xy 355.321108 -282.690824)
			(xy 355.346366 -282.691282) (xy 355.396191 -282.699598) (xy 355.443969 -282.716001) (xy 355.488395 -282.740045)
			(xy 355.528258 -282.771072) (xy 355.562471 -282.808238) (xy 355.5901 -282.850528) (xy 355.610391 -282.896788)
			(xy 355.622792 -282.945757) (xy 355.626963 -282.9961) (xy 364.409001 -282.9961) (xy 364.413172 -282.945768)
			(xy 364.425569 -282.896809) (xy 364.445856 -282.850559) (xy 364.473479 -282.808278) (xy 364.507684 -282.77112)
			(xy 364.547539 -282.740099) (xy 364.591955 -282.71606) (xy 364.639723 -282.69966) (xy 364.689538 -282.691346)
			(xy 364.71479 -282.690824) (xy 365.654844 -282.690824) (xy 365.6801 -282.691285) (xy 365.729921 -282.699605)
			(xy 365.777694 -282.716012) (xy 365.822115 -282.740057) (xy 365.861972 -282.771085) (xy 365.89618 -282.80825)
			(xy 365.923805 -282.850538) (xy 365.944094 -282.896795) (xy 365.956492 -282.945761) (xy 365.960663 -282.9961)
			(xy 367.228901 -282.9961) (xy 367.233072 -282.945767) (xy 367.24547 -282.896808) (xy 367.265758 -282.850556)
			(xy 367.293381 -282.808275) (xy 367.327587 -282.771117) (xy 367.367443 -282.740096) (xy 367.411861 -282.716058)
			(xy 367.459629 -282.699659) (xy 367.509445 -282.691346) (xy 367.534698 -282.690824) (xy 368.474752 -282.690824)
			(xy 368.500015 -282.691249) (xy 368.549853 -282.699558) (xy 368.597643 -282.715958) (xy 368.642082 -282.740001)
			(xy 368.681956 -282.771031) (xy 368.716179 -282.808201) (xy 368.743817 -282.850498) (xy 368.764115 -282.896767)
			(xy 368.776519 -282.945747) (xy 368.780692 -282.9961) (xy 370.049101 -282.9961) (xy 370.053271 -282.945771)
			(xy 370.065667 -282.896815) (xy 370.085952 -282.850567) (xy 370.113571 -282.808288) (xy 370.147772 -282.771131)
			(xy 370.187623 -282.740109) (xy 370.232035 -282.716069) (xy 370.279798 -282.699667) (xy 370.329609 -282.691349)
			(xy 370.35486 -282.690824) (xy 371.294914 -282.690824) (xy 371.320171 -282.691283) (xy 371.369996 -282.699599)
			(xy 371.417773 -282.716003) (xy 371.462199 -282.740047) (xy 371.502061 -282.771074) (xy 371.536273 -282.80824)
			(xy 371.563901 -282.850529) (xy 371.584191 -282.896789) (xy 371.596592 -282.945758) (xy 371.600763 -282.9961)
			(xy 372.869001 -282.9961) (xy 372.873171 -282.94577) (xy 372.885568 -282.896814) (xy 372.905853 -282.850565)
			(xy 372.933473 -282.808285) (xy 372.967676 -282.771128) (xy 373.007527 -282.740106) (xy 373.05194 -282.716067)
			(xy 373.099705 -282.699665) (xy 373.149517 -282.691348) (xy 373.174768 -282.690824) (xy 374.114822 -282.690824)
			(xy 374.140079 -282.691283) (xy 374.189903 -282.699601) (xy 374.237679 -282.716005) (xy 374.282103 -282.740049)
			(xy 374.321964 -282.771077) (xy 374.356175 -282.808242) (xy 374.383802 -282.850531) (xy 374.404092 -282.896791)
			(xy 374.416492 -282.945759) (xy 374.420663 -282.9961) (xy 374.416492 -283.046441) (xy 374.404092 -283.095409)
			(xy 374.383802 -283.141669) (xy 374.356175 -283.183958) (xy 374.321964 -283.221123) (xy 374.282103 -283.252151)
			(xy 374.237679 -283.276195) (xy 374.189903 -283.292599) (xy 374.140079 -283.300917) (xy 374.114822 -283.30144)
			(xy 373.174768 -283.30144) (xy 373.149517 -283.300852) (xy 373.099705 -283.292535) (xy 373.05194 -283.276133)
			(xy 373.007527 -283.252094) (xy 372.967676 -283.221072) (xy 372.933473 -283.183915) (xy 372.905853 -283.141635)
			(xy 372.885568 -283.095386) (xy 372.873171 -283.04643) (xy 372.869001 -282.9961) (xy 371.600763 -282.9961)
			(xy 371.596592 -283.046442) (xy 371.584191 -283.095411) (xy 371.563901 -283.141671) (xy 371.536273 -283.18396)
			(xy 371.502061 -283.221126) (xy 371.462199 -283.252153) (xy 371.417773 -283.276197) (xy 371.369996 -283.292601)
			(xy 371.320171 -283.300917) (xy 371.294914 -283.30144) (xy 370.35486 -283.30144) (xy 370.329609 -283.300851)
			(xy 370.279798 -283.292533) (xy 370.232035 -283.276131) (xy 370.187623 -283.252091) (xy 370.147772 -283.221069)
			(xy 370.113571 -283.183912) (xy 370.085952 -283.141633) (xy 370.065667 -283.095385) (xy 370.053271 -283.046429)
			(xy 370.049101 -282.9961) (xy 368.780692 -282.9961) (xy 368.776519 -283.046453) (xy 368.764115 -283.095433)
			(xy 368.743817 -283.141702) (xy 368.716179 -283.183999) (xy 368.681956 -283.221169) (xy 368.642082 -283.252199)
			(xy 368.597643 -283.276242) (xy 368.549853 -283.292642) (xy 368.500015 -283.300951) (xy 368.474752 -283.30144)
			(xy 367.534698 -283.30144) (xy 367.509445 -283.300854) (xy 367.459629 -283.292541) (xy 367.411861 -283.276142)
			(xy 367.367443 -283.252104) (xy 367.327587 -283.221083) (xy 367.293381 -283.183925) (xy 367.265758 -283.141644)
			(xy 367.24547 -283.095392) (xy 367.233072 -283.046433) (xy 367.228901 -282.9961) (xy 365.960663 -282.9961)
			(xy 365.956492 -283.046439) (xy 365.944094 -283.095405) (xy 365.923805 -283.141662) (xy 365.89618 -283.18395)
			(xy 365.861972 -283.221115) (xy 365.822115 -283.252143) (xy 365.777694 -283.276188) (xy 365.729921 -283.292595)
			(xy 365.6801 -283.300915) (xy 365.654844 -283.30144) (xy 364.71479 -283.30144) (xy 364.689538 -283.300854)
			(xy 364.639723 -283.29254) (xy 364.591955 -283.27614) (xy 364.547539 -283.252101) (xy 364.507684 -283.22108)
			(xy 364.473479 -283.183922) (xy 364.445856 -283.141641) (xy 364.425569 -283.095391) (xy 364.413172 -283.046432)
			(xy 364.409001 -282.9961) (xy 355.626963 -282.9961) (xy 355.622792 -283.046443) (xy 355.610391 -283.095412)
			(xy 355.5901 -283.141672) (xy 355.562471 -283.183962) (xy 355.528258 -283.221128) (xy 355.488395 -283.252155)
			(xy 355.443969 -283.276199) (xy 355.396191 -283.292602) (xy 355.346366 -283.300918) (xy 355.321108 -283.30144)
			(xy 354.381054 -283.30144) (xy 354.355804 -283.300851) (xy 354.305993 -283.292532) (xy 354.258231 -283.276129)
			(xy 354.213819 -283.252089) (xy 354.17397 -283.221067) (xy 354.13977 -283.18391) (xy 354.112151 -283.141631)
			(xy 354.091867 -283.095384) (xy 354.079471 -283.046428) (xy 354.075301 -282.9961) (xy 352.807063 -282.9961)
			(xy 352.802891 -283.046443) (xy 352.79049 -283.095414) (xy 352.770198 -283.141675) (xy 352.742569 -283.183965)
			(xy 352.708355 -283.221131) (xy 352.668491 -283.252158) (xy 352.624064 -283.276201) (xy 352.576285 -283.292604)
			(xy 352.526458 -283.300918) (xy 352.5012 -283.30144) (xy 351.561146 -283.30144) (xy 351.535888 -283.300887)
			(xy 351.486061 -283.292579) (xy 351.438281 -283.276183) (xy 351.393852 -283.252145) (xy 351.353986 -283.221121)
			(xy 351.319771 -283.183959) (xy 351.292139 -283.141671) (xy 351.271846 -283.095411) (xy 351.259444 -283.046442)
			(xy 351.255272 -282.9961) (xy 349.987192 -282.9961) (xy 349.98302 -283.046449) (xy 349.970617 -283.095425)
			(xy 349.950323 -283.141691) (xy 349.92269 -283.183985) (xy 349.888472 -283.221155) (xy 349.848603 -283.252185)
			(xy 349.80417 -283.27623) (xy 349.756386 -283.292633) (xy 349.706553 -283.300948) (xy 349.681292 -283.30144)
			(xy 348.741238 -283.30144) (xy 348.715981 -283.300886) (xy 348.666155 -283.292578) (xy 348.618376 -283.27618)
			(xy 348.573948 -283.252142) (xy 348.534083 -283.221119) (xy 348.499869 -283.183956) (xy 348.472238 -283.141669)
			(xy 348.451945 -283.09541) (xy 348.439544 -283.046442) (xy 348.435372 -282.9961) (xy 347.166963 -282.9961)
			(xy 347.162792 -283.04644) (xy 347.150393 -283.095408) (xy 347.130103 -283.141666) (xy 347.102477 -283.183955)
			(xy 347.068267 -283.22112) (xy 347.028407 -283.252148) (xy 346.983984 -283.276192) (xy 346.936209 -283.292597)
			(xy 346.886386 -283.300916) (xy 346.86113 -283.30144) (xy 345.921076 -283.30144) (xy 345.895825 -283.300853)
			(xy 345.846011 -283.292537) (xy 345.798246 -283.276135) (xy 345.753831 -283.252096) (xy 345.713979 -283.221075)
			(xy 345.679775 -283.183918) (xy 345.652154 -283.141638) (xy 345.631868 -283.095388) (xy 345.619471 -283.04643)
			(xy 345.615301 -282.9961) (xy 126.480876 -282.9961) (xy 126.480901 -282.9964) (xy 126.476725 -283.046787)
			(xy 126.464312 -283.0958) (xy 126.444 -283.142101) (xy 126.416344 -283.184426) (xy 126.382098 -283.221622)
			(xy 126.342197 -283.252673) (xy 126.297728 -283.276732) (xy 126.249906 -283.293143) (xy 126.200034 -283.301459)
			(xy 126.174754 -283.301948) (xy 125.2347 -283.301948) (xy 125.209423 -283.301454) (xy 125.159557 -283.293133)
			(xy 125.111741 -283.276718) (xy 125.067279 -283.252656) (xy 125.027384 -283.221605) (xy 124.993144 -283.18441)
			(xy 124.965494 -283.142087) (xy 124.945186 -283.09579) (xy 124.932775 -283.046782) (xy 124.928601 -282.9964)
			(xy 123.660872 -282.9964) (xy 123.656698 -283.046773) (xy 123.644291 -283.095772) (xy 123.623989 -283.142061)
			(xy 123.596345 -283.184378) (xy 123.562114 -283.221568) (xy 123.52223 -283.252617) (xy 123.477779 -283.276678)
			(xy 123.429974 -283.293096) (xy 123.380119 -283.301423) (xy 123.354846 -283.301948) (xy 122.414792 -283.301948)
			(xy 122.389515 -283.301453) (xy 122.33965 -283.293131) (xy 122.291836 -283.276715) (xy 122.247375 -283.252653)
			(xy 122.207481 -283.221602) (xy 122.173242 -283.184408) (xy 122.145592 -283.142085) (xy 122.125285 -283.095789)
			(xy 122.112875 -283.046781) (xy 122.1087 -282.9964) (xy 120.840801 -282.9964) (xy 120.836625 -283.046784)
			(xy 120.824214 -283.095794) (xy 120.803905 -283.142092) (xy 120.776252 -283.184416) (xy 120.74201 -283.221611)
			(xy 120.702113 -283.252663) (xy 120.657648 -283.276723) (xy 120.60983 -283.293137) (xy 120.559962 -283.301456)
			(xy 120.534684 -283.301948) (xy 119.59463 -283.301948) (xy 119.569348 -283.301485) (xy 119.519474 -283.293167)
			(xy 119.47165 -283.276753) (xy 119.427179 -283.252691) (xy 119.387276 -283.221637) (xy 119.353029 -283.184438)
			(xy 119.325373 -283.142109) (xy 119.30506 -283.095806) (xy 119.292647 -283.04679) (xy 119.288471 -282.9964)
			(xy 118.020901 -282.9964) (xy 118.016725 -283.046785) (xy 118.004313 -283.095795) (xy 117.984004 -283.142094)
			(xy 117.95635 -283.184419) (xy 117.922107 -283.221614) (xy 117.882208 -283.252665) (xy 117.837743 -283.276726)
			(xy 117.789924 -283.293139) (xy 117.740055 -283.301457) (xy 117.714776 -283.301948) (xy 116.774722 -283.301948)
			(xy 116.749441 -283.301485) (xy 116.699568 -283.293166) (xy 116.651744 -283.276751) (xy 116.607275 -283.252688)
			(xy 116.567373 -283.221634) (xy 116.533127 -283.184435) (xy 116.505471 -283.142107) (xy 116.48516 -283.095804)
			(xy 116.472747 -283.046789) (xy 116.468571 -282.9964) (xy 107.687072 -282.9964) (xy 107.682898 -283.046774)
			(xy 107.67049 -283.095773) (xy 107.650188 -283.142063) (xy 107.622544 -283.18438) (xy 107.588312 -283.22157)
			(xy 107.548426 -283.252619) (xy 107.503975 -283.27668) (xy 107.456169 -283.293098) (xy 107.406313 -283.301423)
			(xy 107.38104 -283.301948) (xy 106.440986 -283.301948) (xy 106.415709 -283.301453) (xy 106.365846 -283.29313)
			(xy 106.318032 -283.276714) (xy 106.273572 -283.252651) (xy 106.233679 -283.2216) (xy 106.199441 -283.184406)
			(xy 106.171791 -283.142083) (xy 106.151485 -283.095788) (xy 106.139075 -283.046781) (xy 106.1349 -282.9964)
			(xy 104.867172 -282.9964) (xy 104.862998 -283.046774) (xy 104.85059 -283.095775) (xy 104.830287 -283.142065)
			(xy 104.802642 -283.184382) (xy 104.768409 -283.221573) (xy 104.728522 -283.252622) (xy 104.684069 -283.276683)
			(xy 104.636262 -283.293099) (xy 104.586405 -283.301424) (xy 104.561132 -283.301948) (xy 103.621078 -283.301948)
			(xy 103.595802 -283.301452) (xy 103.545939 -283.293128) (xy 103.498126 -283.276711) (xy 103.453668 -283.252649)
			(xy 103.413776 -283.221597) (xy 103.379539 -283.184403) (xy 103.35189 -283.142081) (xy 103.331584 -283.095786)
			(xy 103.319175 -283.04678) (xy 103.315 -282.9964) (xy 102.047272 -282.9964) (xy 102.043098 -283.046775)
			(xy 102.030689 -283.095776) (xy 102.010385 -283.142067) (xy 101.98274 -283.184385) (xy 101.948506 -283.221576)
			(xy 101.908618 -283.252624) (xy 101.864164 -283.276685) (xy 101.816356 -283.293101) (xy 101.766498 -283.301424)
			(xy 101.741224 -283.301948) (xy 100.80117 -283.301948) (xy 100.775894 -283.301452) (xy 100.726032 -283.293127)
			(xy 100.678221 -283.276709) (xy 100.633764 -283.252646) (xy 100.593873 -283.221594) (xy 100.559637 -283.1844)
			(xy 100.531989 -283.142079) (xy 100.511684 -283.095784) (xy 100.499275 -283.046779) (xy 100.4951 -282.9964)
			(xy 99.227201 -282.9964) (xy 99.223025 -283.046786) (xy 99.210613 -283.095798) (xy 99.190302 -283.142098)
			(xy 99.162646 -283.184423) (xy 99.128401 -283.221619) (xy 99.088501 -283.25267) (xy 99.044033 -283.27673)
			(xy 98.996212 -283.293142) (xy 98.946342 -283.301458) (xy 98.921062 -283.301948) (xy 97.981008 -283.301948)
			(xy 97.955728 -283.301484) (xy 97.905856 -283.293163) (xy 97.858035 -283.276747) (xy 97.813568 -283.252683)
			(xy 97.773668 -283.221629) (xy 97.739424 -283.184431) (xy 97.711769 -283.142103) (xy 97.691459 -283.095801)
			(xy 97.679047 -283.046788) (xy 97.674871 -282.9964) (xy 2.509012 -282.9964) (xy 2.509012 -283.8064)
			(xy 108.485161 -283.8064) (xy 108.489332 -283.756061) (xy 108.501732 -283.707095) (xy 108.522022 -283.660838)
			(xy 108.549649 -283.618552) (xy 108.583859 -283.581389) (xy 108.623719 -283.550364) (xy 108.668142 -283.526323)
			(xy 108.715916 -283.509921) (xy 108.765738 -283.501606) (xy 108.790994 -283.501084) (xy 109.731048 -283.501084)
			(xy 109.7563 -283.501625) (xy 109.806114 -283.509945) (xy 109.85388 -283.52635) (xy 109.898295 -283.550392)
			(xy 109.938147 -283.581416) (xy 109.97235 -283.618576) (xy 109.999971 -283.660858) (xy 110.020256 -283.707109)
			(xy 110.032653 -283.756068) (xy 110.036823 -283.8064) (xy 114.118832 -283.8064) (xy 114.123004 -283.756054)
			(xy 114.135406 -283.707082) (xy 114.155699 -283.660819) (xy 114.183331 -283.618527) (xy 114.217547 -283.581361)
			(xy 114.257413 -283.550333) (xy 114.301844 -283.52629) (xy 114.349625 -283.509889) (xy 114.399455 -283.501576)
			(xy 114.424714 -283.501084) (xy 115.364768 -283.501084) (xy 115.390027 -283.50159) (xy 115.439856 -283.5099)
			(xy 115.487638 -283.526299) (xy 115.532068 -283.55034) (xy 115.571936 -283.581366) (xy 115.606152 -283.618531)
			(xy 115.633784 -283.660822) (xy 115.654078 -283.707084) (xy 115.66648 -283.756055) (xy 115.670627 -283.8061)
			(xy 356.425052 -283.8061) (xy 356.429226 -283.75573) (xy 356.441632 -283.706734) (xy 356.461934 -283.660448)
			(xy 356.489576 -283.618134) (xy 356.523805 -283.580947) (xy 356.563688 -283.5499) (xy 356.608136 -283.525841)
			(xy 356.655939 -283.509425) (xy 356.705791 -283.501101) (xy 356.731062 -283.500576) (xy 357.671116 -283.500576)
			(xy 357.696395 -283.501023) (xy 357.746262 -283.509347) (xy 357.794079 -283.525765) (xy 357.838542 -283.549829)
			(xy 357.878438 -283.580883) (xy 357.912679 -283.61808) (xy 357.94033 -283.660406) (xy 357.960638 -283.706705)
			(xy 357.973049 -283.755715) (xy 357.977224 -283.8061) (xy 362.058752 -283.8061) (xy 362.062926 -283.755728)
			(xy 362.075334 -283.70673) (xy 362.095637 -283.660442) (xy 362.123281 -283.618128) (xy 362.157513 -283.58094)
			(xy 362.197398 -283.549894) (xy 362.24185 -283.525835) (xy 362.289655 -283.509421) (xy 362.33951 -283.501099)
			(xy 362.364782 -283.500576) (xy 363.304836 -283.500576) (xy 363.330114 -283.501025) (xy 363.379978 -283.509351)
			(xy 363.427793 -283.525771) (xy 363.472253 -283.549836) (xy 363.512146 -283.58089) (xy 363.546384 -283.618087)
			(xy 363.574033 -283.660411) (xy 363.594339 -283.706709) (xy 363.606749 -283.755717) (xy 363.610924 -283.8061)
			(xy 363.606749 -283.856483) (xy 363.594339 -283.905491) (xy 363.574033 -283.951789) (xy 363.546384 -283.994113)
			(xy 363.512146 -284.03131) (xy 363.472253 -284.062364) (xy 363.427793 -284.086429) (xy 363.379978 -284.102849)
			(xy 363.330114 -284.111175) (xy 363.304836 -284.1117) (xy 362.364782 -284.1117) (xy 362.33951 -284.111101)
			(xy 362.289655 -284.102779) (xy 362.24185 -284.086365) (xy 362.197398 -284.062306) (xy 362.157513 -284.03126)
			(xy 362.123281 -283.994072) (xy 362.095637 -283.951758) (xy 362.075334 -283.90547) (xy 362.062926 -283.856472)
			(xy 362.058752 -283.8061) (xy 357.977224 -283.8061) (xy 357.973049 -283.856485) (xy 357.960638 -283.905495)
			(xy 357.94033 -283.951794) (xy 357.912679 -283.99412) (xy 357.878438 -284.031317) (xy 357.838542 -284.062371)
			(xy 357.794079 -284.086435) (xy 357.746262 -284.102853) (xy 357.696395 -284.111177) (xy 357.671116 -284.1117)
			(xy 356.731062 -284.1117) (xy 356.705791 -284.111099) (xy 356.655939 -284.102775) (xy 356.608136 -284.086359)
			(xy 356.563688 -284.0623) (xy 356.523805 -284.031253) (xy 356.489576 -283.994066) (xy 356.461934 -283.951752)
			(xy 356.441632 -283.905466) (xy 356.429226 -283.85647) (xy 356.425052 -283.8061) (xy 115.670627 -283.8061)
			(xy 115.670652 -283.8064) (xy 115.66648 -283.856745) (xy 115.654078 -283.905716) (xy 115.633784 -283.951978)
			(xy 115.606152 -283.994269) (xy 115.571936 -284.031434) (xy 115.532068 -284.06246) (xy 115.487638 -284.086501)
			(xy 115.439856 -284.1029) (xy 115.390027 -284.11121) (xy 115.364768 -284.1117) (xy 114.424714 -284.1117)
			(xy 114.399455 -284.111224) (xy 114.349625 -284.102911) (xy 114.301844 -284.08651) (xy 114.257413 -284.062467)
			(xy 114.217547 -284.031439) (xy 114.183331 -283.994273) (xy 114.155699 -283.951981) (xy 114.135406 -283.905718)
			(xy 114.123004 -283.856746) (xy 114.118832 -283.8064) (xy 110.036823 -283.8064) (xy 110.032653 -283.856732)
			(xy 110.020256 -283.905691) (xy 109.999971 -283.951942) (xy 109.97235 -283.994224) (xy 109.938147 -284.031384)
			(xy 109.898295 -284.062408) (xy 109.85388 -284.08645) (xy 109.806114 -284.102855) (xy 109.7563 -284.111175)
			(xy 109.731048 -284.1117) (xy 108.790994 -284.1117) (xy 108.765738 -284.111194) (xy 108.715916 -284.102879)
			(xy 108.668142 -284.086477) (xy 108.623719 -284.062436) (xy 108.583859 -284.031411) (xy 108.549649 -283.994248)
			(xy 108.522022 -283.951962) (xy 108.501732 -283.905705) (xy 108.489332 -283.856739) (xy 108.485161 -283.8064)
			(xy 2.509012 -283.8064) (xy 2.509012 -284.6164) (xy 97.674883 -284.6164) (xy 97.679059 -284.566014)
			(xy 97.69147 -284.517003) (xy 97.71178 -284.470702) (xy 97.739433 -284.428377) (xy 97.773676 -284.39118)
			(xy 97.813574 -284.360127) (xy 97.85804 -284.336064) (xy 97.905859 -284.319649) (xy 97.955729 -284.311328)
			(xy 97.981008 -284.310836) (xy 98.921062 -284.310836) (xy 98.946343 -284.31133) (xy 98.996215 -284.319647)
			(xy 99.044038 -284.336059) (xy 99.088508 -284.36012) (xy 99.12841 -284.391172) (xy 99.162656 -284.428369)
			(xy 99.190312 -284.470696) (xy 99.210624 -284.516998) (xy 99.223037 -284.566012) (xy 99.227213 -284.6164)
			(xy 100.495112 -284.6164) (xy 100.499287 -284.566023) (xy 100.511695 -284.51702) (xy 100.532 -284.470727)
			(xy 100.559646 -284.428407) (xy 100.593881 -284.391215) (xy 100.63377 -284.360164) (xy 100.678226 -284.336102)
			(xy 100.726035 -284.319685) (xy 100.775895 -284.31136) (xy 100.80117 -284.310836) (xy 101.741224 -284.310836)
			(xy 101.766499 -284.311364) (xy 101.816359 -284.319688) (xy 101.864169 -284.336104) (xy 101.908625 -284.360165)
			(xy 101.948514 -284.391216) (xy 101.982749 -284.428408) (xy 102.010396 -284.470727) (xy 102.030701 -284.51702)
			(xy 102.043109 -284.566023) (xy 102.047284 -284.6164) (xy 103.315012 -284.6164) (xy 103.319187 -284.566022)
			(xy 103.331596 -284.517018) (xy 103.351901 -284.470725) (xy 103.379548 -284.428404) (xy 103.413784 -284.391212)
			(xy 103.453674 -284.360161) (xy 103.498131 -284.3361) (xy 103.545942 -284.319683) (xy 103.595803 -284.31136)
			(xy 103.621078 -284.310836) (xy 104.561132 -284.310836) (xy 104.586406 -284.311364) (xy 104.636265 -284.319689)
			(xy 104.684074 -284.336106) (xy 104.728529 -284.360168) (xy 104.768417 -284.391218) (xy 104.802651 -284.42841)
			(xy 104.830297 -284.470729) (xy 104.850601 -284.517021) (xy 104.863009 -284.566024) (xy 104.867184 -284.6164)
			(xy 106.134912 -284.6164) (xy 106.139087 -284.566021) (xy 106.151496 -284.517016) (xy 106.171802 -284.470722)
			(xy 106.19945 -284.428402) (xy 106.233687 -284.391209) (xy 106.273579 -284.360159) (xy 106.318037 -284.336097)
			(xy 106.365849 -284.319682) (xy 106.41571 -284.311359) (xy 106.440986 -284.310836) (xy 107.38104 -284.310836)
			(xy 107.406314 -284.311365) (xy 107.456172 -284.319691) (xy 107.503979 -284.336109) (xy 107.548433 -284.360171)
			(xy 107.58832 -284.391221) (xy 107.622553 -284.428413) (xy 107.650198 -284.470731) (xy 107.670502 -284.517023)
			(xy 107.68291 -284.566024) (xy 107.687084 -284.6164) (xy 116.468583 -284.6164) (xy 116.472759 -284.566013)
			(xy 116.485171 -284.517) (xy 116.505482 -284.470699) (xy 116.533137 -284.428372) (xy 116.567381 -284.391175)
			(xy 116.607282 -284.360122) (xy 116.651749 -284.33606) (xy 116.699571 -284.319646) (xy 116.749442 -284.311327)
			(xy 116.774722 -284.310836) (xy 117.714776 -284.310836) (xy 117.740056 -284.311331) (xy 117.789927 -284.319649)
			(xy 117.837748 -284.336063) (xy 117.882215 -284.360125) (xy 117.922115 -284.391177) (xy 117.95636 -284.428374)
			(xy 117.984014 -284.4707) (xy 118.004325 -284.517001) (xy 118.016737 -284.566013) (xy 118.020913 -284.6164)
			(xy 119.288483 -284.6164) (xy 119.292659 -284.566012) (xy 119.305072 -284.516998) (xy 119.325383 -284.470696)
			(xy 119.353039 -284.428369) (xy 119.387285 -284.391172) (xy 119.427186 -284.360119) (xy 119.471655 -284.336058)
			(xy 119.519477 -284.319644) (xy 119.569349 -284.311327) (xy 119.59463 -284.310836) (xy 120.534684 -284.310836)
			(xy 120.559963 -284.311332) (xy 120.609833 -284.319651) (xy 120.657653 -284.336066) (xy 120.702119 -284.360127)
			(xy 120.742018 -284.39118) (xy 120.776262 -284.428376) (xy 120.803915 -284.470702) (xy 120.824225 -284.517002)
			(xy 120.836637 -284.566014) (xy 120.840813 -284.6164) (xy 122.108712 -284.6164) (xy 122.112887 -284.56602)
			(xy 122.125297 -284.517015) (xy 122.145603 -284.470721) (xy 122.173252 -284.4284) (xy 122.207489 -284.391207)
			(xy 122.247382 -284.360157) (xy 122.291841 -284.336096) (xy 122.339653 -284.31968) (xy 122.389516 -284.311359)
			(xy 122.414792 -284.310836) (xy 123.354846 -284.310836) (xy 123.38012 -284.311366) (xy 123.429977 -284.319692)
			(xy 123.477783 -284.336111) (xy 123.522236 -284.360173) (xy 123.562123 -284.391223) (xy 123.596355 -284.428415)
			(xy 123.623999 -284.470733) (xy 123.644302 -284.517024) (xy 123.65671 -284.566025) (xy 123.660884 -284.6164)
			(xy 124.928613 -284.6164) (xy 124.932787 -284.56602) (xy 124.945197 -284.517014) (xy 124.965504 -284.470718)
			(xy 124.993154 -284.428397) (xy 125.027393 -284.391204) (xy 125.067286 -284.360154) (xy 125.111746 -284.336093)
			(xy 125.15956 -284.319679) (xy 125.209423 -284.311358) (xy 125.2347 -284.310836) (xy 126.174754 -284.310836)
			(xy 126.200035 -284.311329) (xy 126.249909 -284.319645) (xy 126.297733 -284.336057) (xy 126.342203 -284.360117)
			(xy 126.382107 -284.391169) (xy 126.416354 -284.428366) (xy 126.444011 -284.470694) (xy 126.464323 -284.516996)
			(xy 126.476737 -284.566011) (xy 126.480888 -284.6161) (xy 345.615313 -284.6161) (xy 345.619483 -284.565772)
			(xy 345.63188 -284.516816) (xy 345.652165 -284.470568) (xy 345.679785 -284.42829) (xy 345.713987 -284.391134)
			(xy 345.753838 -284.360114) (xy 345.798251 -284.336076) (xy 345.846014 -284.319675) (xy 345.895826 -284.311359)
			(xy 345.921076 -284.310836) (xy 346.86113 -284.310836) (xy 346.886387 -284.311272) (xy 346.936213 -284.31959)
			(xy 346.983989 -284.335996) (xy 347.028414 -284.360042) (xy 347.068275 -284.391071) (xy 347.102487 -284.428237)
			(xy 347.130114 -284.470528) (xy 347.150404 -284.516788) (xy 347.162804 -284.565758) (xy 347.166976 -284.6161)
			(xy 348.435384 -284.6161) (xy 348.439556 -284.56576) (xy 348.451957 -284.516794) (xy 348.472249 -284.470537)
			(xy 348.499878 -284.428251) (xy 348.534091 -284.39109) (xy 348.573955 -284.360068) (xy 348.618381 -284.336031)
			(xy 348.666158 -284.319634) (xy 348.715982 -284.311326) (xy 348.741238 -284.310836) (xy 349.681292 -284.310836)
			(xy 349.706554 -284.31124) (xy 349.756388 -284.319555) (xy 349.804175 -284.335959) (xy 349.848609 -284.360005)
			(xy 349.88848 -284.391036) (xy 349.922699 -284.428207) (xy 349.950333 -284.470504) (xy 349.970629 -284.516772)
			(xy 349.983032 -284.565749) (xy 349.987204 -284.6161) (xy 351.255284 -284.6161) (xy 351.259456 -284.56576)
			(xy 351.271857 -284.516793) (xy 351.29215 -284.470535) (xy 351.31978 -284.428249) (xy 351.353994 -284.391087)
			(xy 351.393859 -284.360065) (xy 351.438286 -284.336028) (xy 351.486064 -284.319632) (xy 351.535889 -284.311325)
			(xy 351.561146 -284.310836) (xy 352.5012 -284.310836) (xy 352.526459 -284.311269) (xy 352.576288 -284.319584)
			(xy 352.624069 -284.335987) (xy 352.668498 -284.360031) (xy 352.708364 -284.39106) (xy 352.742579 -284.428227)
			(xy 352.770209 -284.470519) (xy 352.790502 -284.516782) (xy 352.802904 -284.565755) (xy 352.807076 -284.6161)
			(xy 354.075313 -284.6161) (xy 354.079483 -284.565774) (xy 354.091878 -284.51682) (xy 354.112161 -284.470574)
			(xy 354.139779 -284.428297) (xy 354.173978 -284.391142) (xy 354.213826 -284.360121) (xy 354.258236 -284.336082)
			(xy 354.305996 -284.31968) (xy 354.355805 -284.311361) (xy 354.381054 -284.310836) (xy 355.321108 -284.310836)
			(xy 355.346367 -284.31127) (xy 355.396195 -284.319586) (xy 355.443974 -284.33599) (xy 355.488402 -284.360034)
			(xy 355.528267 -284.391063) (xy 355.562481 -284.42823) (xy 355.590111 -284.470522) (xy 355.610403 -284.516784)
			(xy 355.622804 -284.565755) (xy 355.626976 -284.6161) (xy 364.409013 -284.6161) (xy 364.413183 -284.56577)
			(xy 364.425581 -284.516813) (xy 364.445867 -284.470564) (xy 364.473488 -284.428285) (xy 364.507692 -284.391129)
			(xy 364.547545 -284.360109) (xy 364.59196 -284.336071) (xy 364.639726 -284.319672) (xy 364.689539 -284.311358)
			(xy 364.71479 -284.310836) (xy 365.654844 -284.310836) (xy 365.680101 -284.311273) (xy 365.729924 -284.319593)
			(xy 365.777699 -284.336) (xy 365.822121 -284.360047) (xy 365.861981 -284.391076) (xy 365.89619 -284.428242)
			(xy 365.923816 -284.470532) (xy 365.944105 -284.516791) (xy 365.956505 -284.565759) (xy 365.960676 -284.6161)
			(xy 367.228913 -284.6161) (xy 367.233084 -284.565769) (xy 367.245481 -284.516812) (xy 367.265768 -284.470562)
			(xy 367.293391 -284.428282) (xy 367.327595 -284.391126) (xy 367.367449 -284.360106) (xy 367.411865 -284.336069)
			(xy 367.459632 -284.31967) (xy 367.509446 -284.311358) (xy 367.534698 -284.310836) (xy 368.474752 -284.310836)
			(xy 368.500016 -284.311237) (xy 368.549856 -284.319547) (xy 368.597648 -284.335947) (xy 368.642088 -284.359991)
			(xy 368.681965 -284.391022) (xy 368.716189 -284.428194) (xy 368.743827 -284.470492) (xy 368.764126 -284.516764)
			(xy 368.776531 -284.565745) (xy 368.780704 -284.6161) (xy 370.049113 -284.6161) (xy 370.053283 -284.565773)
			(xy 370.065679 -284.516819) (xy 370.085962 -284.470573) (xy 370.113581 -284.428295) (xy 370.147781 -284.391139)
			(xy 370.187629 -284.360119) (xy 370.23204 -284.33608) (xy 370.279801 -284.319678) (xy 370.32961 -284.311361)
			(xy 370.35486 -284.310836) (xy 371.294914 -284.310836) (xy 371.320172 -284.31127) (xy 371.369999 -284.319587)
			(xy 371.417778 -284.335992) (xy 371.462205 -284.360036) (xy 371.502069 -284.391065) (xy 371.536282 -284.428232)
			(xy 371.563912 -284.470523) (xy 371.584203 -284.516785) (xy 371.596604 -284.565756) (xy 371.600776 -284.6161)
			(xy 372.869013 -284.6161) (xy 372.873183 -284.565772) (xy 372.885579 -284.516818) (xy 372.905864 -284.47057)
			(xy 372.933483 -284.428292) (xy 372.967684 -284.391137) (xy 373.007533 -284.360116) (xy 373.051945 -284.336078)
			(xy 373.099708 -284.319677) (xy 373.149518 -284.31136) (xy 373.174768 -284.310836) (xy 374.114822 -284.310836)
			(xy 374.14008 -284.311271) (xy 374.189906 -284.319589) (xy 374.237684 -284.335994) (xy 374.28211 -284.360039)
			(xy 374.321972 -284.391068) (xy 374.356184 -284.428235) (xy 374.383813 -284.470525) (xy 374.404104 -284.516787)
			(xy 374.416504 -284.565757) (xy 374.420676 -284.6161) (xy 374.416504 -284.666443) (xy 374.404104 -284.715413)
			(xy 374.383813 -284.761675) (xy 374.356184 -284.803965) (xy 374.321972 -284.841132) (xy 374.28211 -284.872161)
			(xy 374.237684 -284.896206) (xy 374.189906 -284.912611) (xy 374.14008 -284.920929) (xy 374.114822 -284.921452)
			(xy 373.174768 -284.921452) (xy 373.149518 -284.92084) (xy 373.099708 -284.912523) (xy 373.051945 -284.896122)
			(xy 373.007533 -284.872084) (xy 372.967684 -284.841063) (xy 372.933483 -284.803908) (xy 372.905864 -284.76163)
			(xy 372.885579 -284.715382) (xy 372.873183 -284.666428) (xy 372.869013 -284.6161) (xy 371.600776 -284.6161)
			(xy 371.596604 -284.666444) (xy 371.584203 -284.715415) (xy 371.563912 -284.761677) (xy 371.536282 -284.803968)
			(xy 371.502069 -284.841135) (xy 371.462205 -284.872164) (xy 371.417778 -284.896208) (xy 371.369999 -284.912613)
			(xy 371.320172 -284.92093) (xy 371.294914 -284.921452) (xy 370.35486 -284.921452) (xy 370.32961 -284.920839)
			(xy 370.279801 -284.912522) (xy 370.23204 -284.89612) (xy 370.187629 -284.872081) (xy 370.147781 -284.841061)
			(xy 370.113581 -284.803905) (xy 370.085962 -284.761627) (xy 370.065679 -284.715381) (xy 370.053283 -284.666427)
			(xy 370.049113 -284.6161) (xy 368.780704 -284.6161) (xy 368.776531 -284.666455) (xy 368.764126 -284.715436)
			(xy 368.743827 -284.761708) (xy 368.716189 -284.804006) (xy 368.681965 -284.841178) (xy 368.642088 -284.872209)
			(xy 368.597648 -284.896253) (xy 368.549856 -284.912653) (xy 368.500016 -284.920963) (xy 368.474752 -284.921452)
			(xy 367.534698 -284.921452) (xy 367.509446 -284.920842) (xy 367.459632 -284.91253) (xy 367.411865 -284.896131)
			(xy 367.367449 -284.872094) (xy 367.327595 -284.841074) (xy 367.293391 -284.803918) (xy 367.265768 -284.761638)
			(xy 367.245481 -284.715388) (xy 367.233084 -284.666431) (xy 367.228913 -284.6161) (xy 365.960676 -284.6161)
			(xy 365.956505 -284.666441) (xy 365.944105 -284.715409) (xy 365.923816 -284.761668) (xy 365.89619 -284.803958)
			(xy 365.861981 -284.841124) (xy 365.822121 -284.872153) (xy 365.777699 -284.8962) (xy 365.729924 -284.912607)
			(xy 365.680101 -284.920927) (xy 365.654844 -284.921452) (xy 364.71479 -284.921452) (xy 364.689539 -284.920842)
			(xy 364.639726 -284.912528) (xy 364.59196 -284.896129) (xy 364.547545 -284.872091) (xy 364.507692 -284.841071)
			(xy 364.473489 -284.803915) (xy 364.445867 -284.761636) (xy 364.425581 -284.715387) (xy 364.413183 -284.66643)
			(xy 364.409013 -284.6161) (xy 355.626976 -284.6161) (xy 355.622804 -284.666445) (xy 355.610403 -284.715416)
			(xy 355.590111 -284.761678) (xy 355.562481 -284.80397) (xy 355.528267 -284.841137) (xy 355.488402 -284.872166)
			(xy 355.443974 -284.89621) (xy 355.396195 -284.912614) (xy 355.346367 -284.92093) (xy 355.321108 -284.921452)
			(xy 354.381054 -284.921452) (xy 354.355805 -284.920839) (xy 354.305996 -284.91252) (xy 354.258236 -284.896118)
			(xy 354.213826 -284.872079) (xy 354.173978 -284.841058) (xy 354.139779 -284.803903) (xy 354.112161 -284.761626)
			(xy 354.091878 -284.71538) (xy 354.079483 -284.666426) (xy 354.075313 -284.6161) (xy 352.807076 -284.6161)
			(xy 352.802904 -284.666445) (xy 352.790502 -284.715418) (xy 352.770209 -284.761681) (xy 352.742579 -284.803973)
			(xy 352.708364 -284.84114) (xy 352.668498 -284.872169) (xy 352.624069 -284.896213) (xy 352.576288 -284.912616)
			(xy 352.526459 -284.920931) (xy 352.5012 -284.921452) (xy 351.561146 -284.921452) (xy 351.535889 -284.920875)
			(xy 351.486064 -284.912568) (xy 351.438286 -284.896172) (xy 351.393859 -284.872135) (xy 351.353994 -284.841113)
			(xy 351.31978 -284.803951) (xy 351.29215 -284.761665) (xy 351.271857 -284.715407) (xy 351.259456 -284.66644)
			(xy 351.255284 -284.6161) (xy 349.987204 -284.6161) (xy 349.983032 -284.666451) (xy 349.970629 -284.715428)
			(xy 349.950333 -284.761696) (xy 349.922699 -284.803993) (xy 349.88848 -284.841164) (xy 349.848609 -284.872195)
			(xy 349.804175 -284.896241) (xy 349.756388 -284.912645) (xy 349.706554 -284.92096) (xy 349.681292 -284.921452)
			(xy 348.741238 -284.921452) (xy 348.715982 -284.920874) (xy 348.666158 -284.912566) (xy 348.618381 -284.896169)
			(xy 348.573955 -284.872132) (xy 348.534091 -284.84111) (xy 348.499878 -284.803949) (xy 348.472249 -284.761663)
			(xy 348.451957 -284.715406) (xy 348.439556 -284.66644) (xy 348.435384 -284.6161) (xy 347.166976 -284.6161)
			(xy 347.162804 -284.666442) (xy 347.150404 -284.715412) (xy 347.130114 -284.761672) (xy 347.102487 -284.803963)
			(xy 347.068275 -284.841129) (xy 347.028414 -284.872158) (xy 346.983989 -284.896204) (xy 346.936213 -284.91261)
			(xy 346.886387 -284.920928) (xy 346.86113 -284.921452) (xy 345.921076 -284.921452) (xy 345.895826 -284.920841)
			(xy 345.846014 -284.912525) (xy 345.798251 -284.896124) (xy 345.753838 -284.872086) (xy 345.713987 -284.841066)
			(xy 345.679785 -284.80391) (xy 345.652165 -284.761632) (xy 345.63188 -284.715384) (xy 345.619483 -284.666428)
			(xy 345.615313 -284.6161) (xy 126.480888 -284.6161) (xy 126.480913 -284.6164) (xy 126.476737 -284.666789)
			(xy 126.464323 -284.715804) (xy 126.444011 -284.762106) (xy 126.416354 -284.804434) (xy 126.382107 -284.841631)
			(xy 126.342203 -284.872683) (xy 126.297733 -284.896743) (xy 126.249909 -284.913155) (xy 126.200035 -284.921471)
			(xy 126.174754 -284.92196) (xy 125.2347 -284.92196) (xy 125.209423 -284.921442) (xy 125.15956 -284.913121)
			(xy 125.111746 -284.896707) (xy 125.067286 -284.872646) (xy 125.027393 -284.841596) (xy 124.993154 -284.804403)
			(xy 124.965504 -284.762082) (xy 124.945197 -284.715786) (xy 124.932787 -284.66678) (xy 124.928613 -284.6164)
			(xy 123.660884 -284.6164) (xy 123.65671 -284.666775) (xy 123.644302 -284.715776) (xy 123.623999 -284.762067)
			(xy 123.596355 -284.804385) (xy 123.562123 -284.841577) (xy 123.522236 -284.872627) (xy 123.477783 -284.896689)
			(xy 123.429977 -284.913108) (xy 123.38012 -284.921434) (xy 123.354846 -284.92196) (xy 122.414792 -284.92196)
			(xy 122.389516 -284.921441) (xy 122.339653 -284.91312) (xy 122.291841 -284.896704) (xy 122.247382 -284.872643)
			(xy 122.207489 -284.841593) (xy 122.173252 -284.8044) (xy 122.145603 -284.762079) (xy 122.125297 -284.715785)
			(xy 122.112887 -284.66678) (xy 122.108712 -284.6164) (xy 120.840813 -284.6164) (xy 120.836637 -284.666786)
			(xy 120.824225 -284.715798) (xy 120.803915 -284.762098) (xy 120.776262 -284.804424) (xy 120.742018 -284.84162)
			(xy 120.702119 -284.872673) (xy 120.657653 -284.896734) (xy 120.609833 -284.913149) (xy 120.559963 -284.921468)
			(xy 120.534684 -284.92196) (xy 119.59463 -284.92196) (xy 119.569349 -284.921473) (xy 119.519477 -284.913156)
			(xy 119.471655 -284.896742) (xy 119.427186 -284.872681) (xy 119.387285 -284.841628) (xy 119.353039 -284.804431)
			(xy 119.325383 -284.762104) (xy 119.305072 -284.715802) (xy 119.292659 -284.666788) (xy 119.288483 -284.6164)
			(xy 118.020913 -284.6164) (xy 118.016737 -284.666787) (xy 118.004325 -284.715799) (xy 117.984014 -284.7621)
			(xy 117.95636 -284.804426) (xy 117.922115 -284.841623) (xy 117.882215 -284.872675) (xy 117.837748 -284.896737)
			(xy 117.789927 -284.913151) (xy 117.740056 -284.921469) (xy 117.714776 -284.92196) (xy 116.774722 -284.92196)
			(xy 116.749442 -284.921473) (xy 116.699571 -284.913154) (xy 116.651749 -284.89674) (xy 116.607282 -284.872678)
			(xy 116.567381 -284.841625) (xy 116.533137 -284.804428) (xy 116.505482 -284.762101) (xy 116.485171 -284.7158)
			(xy 116.472759 -284.666787) (xy 116.468583 -284.6164) (xy 107.687084 -284.6164) (xy 107.68291 -284.666776)
			(xy 107.670502 -284.715777) (xy 107.650198 -284.762069) (xy 107.622553 -284.804387) (xy 107.58832 -284.841579)
			(xy 107.548433 -284.872629) (xy 107.503979 -284.896691) (xy 107.456172 -284.913109) (xy 107.406314 -284.921435)
			(xy 107.38104 -284.92196) (xy 106.440986 -284.92196) (xy 106.41571 -284.921441) (xy 106.365849 -284.913118)
			(xy 106.318037 -284.896703) (xy 106.273579 -284.872641) (xy 106.233687 -284.841591) (xy 106.19945 -284.804398)
			(xy 106.171802 -284.762078) (xy 106.151496 -284.715784) (xy 106.139087 -284.666779) (xy 106.134912 -284.6164)
			(xy 104.867184 -284.6164) (xy 104.863009 -284.666776) (xy 104.850601 -284.715779) (xy 104.830297 -284.762071)
			(xy 104.802651 -284.80439) (xy 104.768417 -284.841582) (xy 104.728529 -284.872632) (xy 104.684074 -284.896694)
			(xy 104.636265 -284.913111) (xy 104.586406 -284.921436) (xy 104.561132 -284.92196) (xy 103.621078 -284.92196)
			(xy 103.595803 -284.92144) (xy 103.545942 -284.913117) (xy 103.498131 -284.8967) (xy 103.453674 -284.872639)
			(xy 103.413784 -284.841588) (xy 103.379548 -284.804396) (xy 103.351901 -284.762075) (xy 103.331596 -284.715782)
			(xy 103.319187 -284.666778) (xy 103.315012 -284.6164) (xy 102.047284 -284.6164) (xy 102.043109 -284.666777)
			(xy 102.030701 -284.71578) (xy 102.010396 -284.762073) (xy 101.982749 -284.804392) (xy 101.948514 -284.841584)
			(xy 101.908625 -284.872635) (xy 101.864169 -284.896696) (xy 101.816359 -284.913112) (xy 101.766499 -284.921436)
			(xy 101.741224 -284.92196) (xy 100.80117 -284.92196) (xy 100.775895 -284.92144) (xy 100.726035 -284.913115)
			(xy 100.678226 -284.896698) (xy 100.63377 -284.872636) (xy 100.593881 -284.841585) (xy 100.559646 -284.804393)
			(xy 100.532 -284.762073) (xy 100.511695 -284.71578) (xy 100.499287 -284.666777) (xy 100.495112 -284.6164)
			(xy 99.227213 -284.6164) (xy 99.223037 -284.666788) (xy 99.210624 -284.715802) (xy 99.190312 -284.762104)
			(xy 99.162656 -284.804431) (xy 99.12841 -284.841628) (xy 99.088508 -284.87268) (xy 99.044038 -284.896741)
			(xy 98.996215 -284.913153) (xy 98.946343 -284.92147) (xy 98.921062 -284.92196) (xy 97.981008 -284.92196)
			(xy 97.955729 -284.921472) (xy 97.905859 -284.913151) (xy 97.85804 -284.896736) (xy 97.813574 -284.872673)
			(xy 97.773676 -284.84162) (xy 97.739433 -284.804423) (xy 97.71178 -284.762098) (xy 97.69147 -284.715797)
			(xy 97.679059 -284.666786) (xy 97.674883 -284.6164) (xy 2.509012 -284.6164) (xy 2.509012 -285.4264)
			(xy 108.485173 -285.4264) (xy 108.489344 -285.376063) (xy 108.501743 -285.327099) (xy 108.522032 -285.280844)
			(xy 108.549658 -285.238559) (xy 108.583867 -285.201398) (xy 108.623725 -285.170374) (xy 108.668147 -285.146334)
			(xy 108.715919 -285.129932) (xy 108.765739 -285.121618) (xy 108.790994 -285.121096) (xy 109.731048 -285.121096)
			(xy 109.756301 -285.121613) (xy 109.806117 -285.129933) (xy 109.853885 -285.146339) (xy 109.898301 -285.170382)
			(xy 109.938155 -285.201407) (xy 109.972359 -285.238568) (xy 109.999981 -285.280852) (xy 110.020267 -285.327105)
			(xy 110.032665 -285.376066) (xy 110.036835 -285.4264) (xy 114.118844 -285.4264) (xy 114.123016 -285.376056)
			(xy 114.135417 -285.327086) (xy 114.15571 -285.280825) (xy 114.18334 -285.238535) (xy 114.217555 -285.201369)
			(xy 114.25742 -285.170343) (xy 114.301849 -285.146301) (xy 114.349628 -285.1299) (xy 114.399456 -285.121588)
			(xy 114.424714 -285.121096) (xy 115.364768 -285.121096) (xy 115.390028 -285.121578) (xy 115.439859 -285.129889)
			(xy 115.487643 -285.146288) (xy 115.532075 -285.17033) (xy 115.571944 -285.201357) (xy 115.606161 -285.238524)
			(xy 115.633795 -285.280816) (xy 115.654089 -285.32708) (xy 115.666492 -285.376053) (xy 115.670639 -285.4261)
			(xy 356.425064 -285.4261) (xy 356.429238 -285.375732) (xy 356.441644 -285.326738) (xy 356.461944 -285.280454)
			(xy 356.489585 -285.238142) (xy 356.523813 -285.200956) (xy 356.563694 -285.16991) (xy 356.608141 -285.145852)
			(xy 356.655942 -285.129437) (xy 356.705792 -285.121113) (xy 356.731062 -285.120588) (xy 357.671116 -285.120588)
			(xy 357.696396 -285.121011) (xy 357.746265 -285.129335) (xy 357.794084 -285.145754) (xy 357.838549 -285.169819)
			(xy 357.878446 -285.200875) (xy 357.912688 -285.238073) (xy 357.940341 -285.2804) (xy 357.960649 -285.326701)
			(xy 357.97306 -285.375713) (xy 357.977236 -285.4261) (xy 362.058764 -285.4261) (xy 362.062938 -285.37573)
			(xy 362.075345 -285.326734) (xy 362.095647 -285.280448) (xy 362.12329 -285.238135) (xy 362.157521 -285.200949)
			(xy 362.197405 -285.169904) (xy 362.241855 -285.145846) (xy 362.289658 -285.129433) (xy 362.339511 -285.121111)
			(xy 362.364782 -285.120588) (xy 363.304836 -285.120588) (xy 363.330115 -285.121013) (xy 363.379981 -285.12934)
			(xy 363.427798 -285.14576) (xy 363.472259 -285.169826) (xy 363.512154 -285.200882) (xy 363.546393 -285.23808)
			(xy 363.574044 -285.280406) (xy 363.594351 -285.326705) (xy 363.606761 -285.375716) (xy 363.610936 -285.4261)
			(xy 363.606761 -285.476485) (xy 363.594351 -285.525495) (xy 363.574044 -285.571794) (xy 363.546393 -285.61412)
			(xy 363.512154 -285.651318) (xy 363.472259 -285.682374) (xy 363.427798 -285.70644) (xy 363.379981 -285.72286)
			(xy 363.330115 -285.731187) (xy 363.304836 -285.731712) (xy 362.364782 -285.731712) (xy 362.339511 -285.731089)
			(xy 362.289658 -285.722767) (xy 362.241855 -285.706354) (xy 362.197405 -285.682296) (xy 362.157521 -285.651251)
			(xy 362.12329 -285.614065) (xy 362.095647 -285.571752) (xy 362.075345 -285.525466) (xy 362.062938 -285.47647)
			(xy 362.058764 -285.4261) (xy 357.977236 -285.4261) (xy 357.97306 -285.476487) (xy 357.960649 -285.525499)
			(xy 357.940341 -285.5718) (xy 357.912688 -285.614127) (xy 357.878446 -285.651325) (xy 357.838549 -285.682381)
			(xy 357.794084 -285.706446) (xy 357.746265 -285.722865) (xy 357.696396 -285.731189) (xy 357.671116 -285.731712)
			(xy 356.731062 -285.731712) (xy 356.705792 -285.731087) (xy 356.655942 -285.722763) (xy 356.608141 -285.706348)
			(xy 356.563694 -285.68229) (xy 356.523813 -285.651244) (xy 356.489585 -285.614058) (xy 356.461944 -285.571746)
			(xy 356.441644 -285.525462) (xy 356.429238 -285.476468) (xy 356.425064 -285.4261) (xy 115.670639 -285.4261)
			(xy 115.670664 -285.4264) (xy 115.666492 -285.476747) (xy 115.654089 -285.52572) (xy 115.633795 -285.571984)
			(xy 115.606161 -285.614276) (xy 115.571944 -285.651443) (xy 115.532075 -285.68247) (xy 115.487643 -285.706512)
			(xy 115.439859 -285.722911) (xy 115.390028 -285.731222) (xy 115.364768 -285.731712) (xy 114.424714 -285.731712)
			(xy 114.399456 -285.731212) (xy 114.349628 -285.7229) (xy 114.301849 -285.706499) (xy 114.25742 -285.682457)
			(xy 114.217555 -285.651431) (xy 114.18334 -285.614265) (xy 114.15571 -285.571975) (xy 114.135417 -285.525714)
			(xy 114.123016 -285.476744) (xy 114.118844 -285.4264) (xy 110.036835 -285.4264) (xy 110.032665 -285.476734)
			(xy 110.020267 -285.525695) (xy 109.999981 -285.571948) (xy 109.972359 -285.614232) (xy 109.938155 -285.651393)
			(xy 109.898301 -285.682418) (xy 109.853885 -285.706461) (xy 109.806117 -285.722867) (xy 109.756301 -285.731187)
			(xy 109.731048 -285.731712) (xy 108.790994 -285.731712) (xy 108.765739 -285.731182) (xy 108.715919 -285.722868)
			(xy 108.668147 -285.706466) (xy 108.623725 -285.682426) (xy 108.583867 -285.651402) (xy 108.549658 -285.614241)
			(xy 108.522032 -285.571956) (xy 108.501743 -285.525701) (xy 108.489344 -285.476737) (xy 108.485173 -285.4264)
			(xy 2.509012 -285.4264) (xy 2.509012 -286.2364) (xy 100.495124 -286.2364) (xy 100.499298 -286.186025)
			(xy 100.511706 -286.137023) (xy 100.53201 -286.090733) (xy 100.559656 -286.048415) (xy 100.593889 -286.011224)
			(xy 100.633777 -285.980174) (xy 100.678231 -285.956113) (xy 100.726038 -285.939697) (xy 100.775896 -285.931372)
			(xy 100.80117 -285.930848) (xy 101.741224 -285.930848) (xy 101.7665 -285.931352) (xy 101.816362 -285.939676)
			(xy 101.864173 -285.956093) (xy 101.908631 -285.980155) (xy 101.948522 -286.011207) (xy 101.982759 -286.0484)
			(xy 102.010407 -286.090721) (xy 102.030712 -286.137016) (xy 102.043121 -286.186021) (xy 102.047296 -286.2364)
			(xy 103.315024 -286.2364) (xy 103.319199 -286.186024) (xy 103.331607 -286.137022) (xy 103.351911 -286.09073)
			(xy 103.379558 -286.048412) (xy 103.413792 -286.011221) (xy 103.453681 -285.980171) (xy 103.498136 -285.956111)
			(xy 103.545945 -285.939695) (xy 103.595804 -285.931372) (xy 103.621078 -285.930848) (xy 104.561132 -285.930848)
			(xy 104.586407 -285.931352) (xy 104.636268 -285.939678) (xy 104.684079 -285.956095) (xy 104.728535 -285.980158)
			(xy 104.768425 -286.01121) (xy 104.802661 -286.048403) (xy 104.830308 -286.090724) (xy 104.850613 -286.137017)
			(xy 104.863021 -286.186022) (xy 104.867196 -286.2364) (xy 106.134924 -286.2364) (xy 106.139099 -286.186023)
			(xy 106.151508 -286.13702) (xy 106.171813 -286.090728) (xy 106.19946 -286.048409) (xy 106.233695 -286.011218)
			(xy 106.273585 -285.980169) (xy 106.318041 -285.956108) (xy 106.365851 -285.939693) (xy 106.415711 -285.931371)
			(xy 106.440986 -285.930848) (xy 107.38104 -285.930848) (xy 107.406315 -285.931353) (xy 107.456175 -285.939679)
			(xy 107.503984 -285.956098) (xy 107.54844 -285.980161) (xy 107.588328 -286.011213) (xy 107.622563 -286.048406)
			(xy 107.650209 -286.090726) (xy 107.670513 -286.137019) (xy 107.682921 -286.186022) (xy 107.687096 -286.2364)
			(xy 116.468595 -286.2364) (xy 116.472771 -286.186015) (xy 116.485183 -286.137004) (xy 116.505492 -286.090704)
			(xy 116.533146 -286.048379) (xy 116.56739 -286.011184) (xy 116.607288 -285.980132) (xy 116.651754 -285.956071)
			(xy 116.699574 -285.939658) (xy 116.749443 -285.931339) (xy 116.774722 -285.930848) (xy 117.714776 -285.930848)
			(xy 117.740057 -285.931319) (xy 117.789929 -285.939638) (xy 117.837753 -285.956052) (xy 117.882222 -285.980115)
			(xy 117.922123 -286.011168) (xy 117.956369 -286.048366) (xy 117.984025 -286.090694) (xy 118.004336 -286.136997)
			(xy 118.016749 -286.186011) (xy 118.020925 -286.2364) (xy 119.288495 -286.2364) (xy 119.292671 -286.186014)
			(xy 119.305083 -286.137002) (xy 119.325394 -286.090702) (xy 119.353048 -286.048377) (xy 119.387293 -286.011181)
			(xy 119.427193 -285.980129) (xy 119.47166 -285.956069) (xy 119.51948 -285.939656) (xy 119.56935 -285.931339)
			(xy 119.59463 -285.930848) (xy 120.534684 -285.930848) (xy 120.559964 -285.93132) (xy 120.609836 -285.93964)
			(xy 120.657658 -285.956055) (xy 120.702126 -285.980117) (xy 120.742026 -286.011171) (xy 120.776271 -286.048369)
			(xy 120.803926 -286.090696) (xy 120.824237 -286.136998) (xy 120.836649 -286.186012) (xy 120.840825 -286.2364)
			(xy 122.108724 -286.2364) (xy 122.112899 -286.186022) (xy 122.125308 -286.137019) (xy 122.145613 -286.090726)
			(xy 122.173261 -286.048407) (xy 122.207498 -286.011216) (xy 122.247388 -285.980167) (xy 122.291845 -285.956107)
			(xy 122.339656 -285.939692) (xy 122.389517 -285.931371) (xy 122.414792 -285.930848) (xy 123.354846 -285.930848)
			(xy 123.380121 -285.931354) (xy 123.42998 -285.93968) (xy 123.477788 -285.9561) (xy 123.522243 -285.980163)
			(xy 123.562131 -286.011215) (xy 123.596364 -286.048408) (xy 123.62401 -286.090727) (xy 123.644314 -286.13702)
			(xy 123.656722 -286.186023) (xy 123.660879 -286.2362) (xy 348.435296 -286.2362) (xy 348.439469 -286.185846)
			(xy 348.451873 -286.136866) (xy 348.472171 -286.090595) (xy 348.499809 -286.048297) (xy 348.534032 -286.011126)
			(xy 348.573906 -285.980094) (xy 348.618345 -285.95605) (xy 348.666136 -285.939649) (xy 348.715975 -285.931338)
			(xy 348.741238 -285.930848) (xy 349.681292 -285.930848) (xy 349.706547 -285.931428) (xy 349.756367 -285.93974)
			(xy 349.804139 -285.956139) (xy 349.848561 -285.980178) (xy 349.88842 -286.011201) (xy 349.92263 -286.048361)
			(xy 349.950256 -286.090645) (xy 349.970545 -286.1369) (xy 349.982945 -286.185864) (xy 349.987116 -286.2362)
			(xy 351.255196 -286.2362) (xy 351.259369 -286.185845) (xy 351.271774 -286.136864) (xy 351.292072 -286.090593)
			(xy 351.319711 -286.048295) (xy 351.353935 -286.011123) (xy 351.393811 -285.980092) (xy 351.438251 -285.956048)
			(xy 351.486043 -285.939647) (xy 351.535882 -285.931337) (xy 351.561146 -285.930848) (xy 352.5012 -285.930848)
			(xy 352.526452 -285.931457) (xy 352.576266 -285.93977) (xy 352.624033 -285.956168) (xy 352.66845 -285.980205)
			(xy 352.708304 -286.011225) (xy 352.742509 -286.048382) (xy 352.770132 -286.090661) (xy 352.790419 -286.136911)
			(xy 352.802816 -286.185869) (xy 352.806987 -286.2362) (xy 354.075224 -286.2362) (xy 354.079395 -286.185859)
			(xy 354.091795 -286.136892) (xy 354.112084 -286.090632) (xy 354.139709 -286.048343) (xy 354.173918 -286.011177)
			(xy 354.213778 -285.980147) (xy 354.2582 -285.956101) (xy 354.305974 -285.939694) (xy 354.355797 -285.931373)
			(xy 354.381054 -285.930848) (xy 355.321108 -285.930848) (xy 355.346359 -285.931458) (xy 355.396173 -285.939772)
			(xy 355.443939 -285.956171) (xy 355.488354 -285.980208) (xy 355.528207 -286.011228) (xy 355.562411 -286.048384)
			(xy 355.590033 -286.090664) (xy 355.610319 -286.136913) (xy 355.622717 -286.18587) (xy 355.626887 -286.2362)
			(xy 364.408924 -286.2362) (xy 364.413096 -286.185856) (xy 364.425497 -286.136884) (xy 364.445789 -286.090622)
			(xy 364.473419 -286.048331) (xy 364.507632 -286.011164) (xy 364.547497 -285.980135) (xy 364.591924 -285.95609)
			(xy 364.639704 -285.939686) (xy 364.689532 -285.93137) (xy 364.71479 -285.930848) (xy 365.654844 -285.930848)
			(xy 365.680093 -285.931461) (xy 365.729902 -285.939779) (xy 365.777663 -285.956181) (xy 365.822073 -285.980221)
			(xy 365.861921 -286.011241) (xy 365.89612 -286.048396) (xy 365.923738 -286.090674) (xy 365.944022 -286.13692)
			(xy 365.956417 -286.185874) (xy 365.960587 -286.2362) (xy 367.228824 -286.2362) (xy 367.232996 -286.185855)
			(xy 367.245398 -286.136883) (xy 367.26569 -286.09062) (xy 367.293321 -286.048328) (xy 367.327535 -286.011161)
			(xy 367.367401 -285.980132) (xy 367.41183 -285.956088) (xy 367.45961 -285.939685) (xy 367.509439 -285.931369)
			(xy 367.534698 -285.930848) (xy 368.474752 -285.930848) (xy 368.500009 -285.931425) (xy 368.549834 -285.939732)
			(xy 368.597612 -285.956128) (xy 368.64204 -285.980164) (xy 368.681905 -286.011187) (xy 368.716119 -286.048348)
			(xy 368.74375 -286.090634) (xy 368.764043 -286.136892) (xy 368.776444 -286.185859) (xy 368.780616 -286.2362)
			(xy 370.049024 -286.2362) (xy 370.053196 -286.185859) (xy 370.065595 -286.13689) (xy 370.085885 -286.09063)
			(xy 370.113511 -286.048341) (xy 370.147721 -286.011174) (xy 370.187581 -285.980145) (xy 370.232004 -285.956099)
			(xy 370.279779 -285.939692) (xy 370.329603 -285.931372) (xy 370.35486 -285.930848) (xy 371.294914 -285.930848)
			(xy 371.320165 -285.931459) (xy 371.369978 -285.939773) (xy 371.417743 -285.956173) (xy 371.462157 -285.98021)
			(xy 371.502009 -286.01123) (xy 371.536213 -286.048386) (xy 371.563834 -286.090665) (xy 371.58412 -286.136914)
			(xy 371.596517 -286.185871) (xy 371.600687 -286.2362) (xy 371.596517 -286.286529) (xy 371.58412 -286.335486)
			(xy 371.563834 -286.381735) (xy 371.536213 -286.424014) (xy 371.502009 -286.46117) (xy 371.462157 -286.49219)
			(xy 371.417743 -286.516227) (xy 371.369978 -286.532627) (xy 371.320165 -286.540941) (xy 371.294914 -286.541464)
			(xy 370.35486 -286.541464) (xy 370.329603 -286.541028) (xy 370.279779 -286.532708) (xy 370.232004 -286.516301)
			(xy 370.187581 -286.492255) (xy 370.147721 -286.461226) (xy 370.113511 -286.424059) (xy 370.085884 -286.38177)
			(xy 370.065595 -286.33551) (xy 370.053196 -286.286541) (xy 370.049024 -286.2362) (xy 368.780616 -286.2362)
			(xy 368.776444 -286.286541) (xy 368.764043 -286.335508) (xy 368.74375 -286.381766) (xy 368.716119 -286.424052)
			(xy 368.681905 -286.461213) (xy 368.64204 -286.492236) (xy 368.597612 -286.516272) (xy 368.549834 -286.532668)
			(xy 368.500009 -286.540975) (xy 368.474752 -286.541464) (xy 367.534698 -286.541464) (xy 367.509439 -286.541031)
			(xy 367.45961 -286.532715) (xy 367.41183 -286.516312) (xy 367.367401 -286.492268) (xy 367.327535 -286.461239)
			(xy 367.293321 -286.424072) (xy 367.26569 -286.38178) (xy 367.245398 -286.335517) (xy 367.232996 -286.286545)
			(xy 367.228824 -286.2362) (xy 365.960587 -286.2362) (xy 365.956417 -286.286526) (xy 365.944022 -286.33548)
			(xy 365.923738 -286.381726) (xy 365.89612 -286.424004) (xy 365.861921 -286.461159) (xy 365.822073 -286.492179)
			(xy 365.777663 -286.516219) (xy 365.729902 -286.532621) (xy 365.680093 -286.540939) (xy 365.654844 -286.541464)
			(xy 364.71479 -286.541464) (xy 364.689532 -286.54103) (xy 364.639704 -286.532714) (xy 364.591924 -286.51631)
			(xy 364.547497 -286.492265) (xy 364.507632 -286.461236) (xy 364.473419 -286.424069) (xy 364.445789 -286.381778)
			(xy 364.425497 -286.335516) (xy 364.413096 -286.286544) (xy 364.408924 -286.2362) (xy 355.626887 -286.2362)
			(xy 355.622717 -286.28653) (xy 355.610319 -286.335487) (xy 355.590033 -286.381736) (xy 355.562411 -286.424016)
			(xy 355.528207 -286.461172) (xy 355.488354 -286.492192) (xy 355.443939 -286.516229) (xy 355.396173 -286.532628)
			(xy 355.346359 -286.540942) (xy 355.321108 -286.541464) (xy 354.381054 -286.541464) (xy 354.355797 -286.541027)
			(xy 354.305974 -286.532706) (xy 354.2582 -286.516299) (xy 354.213778 -286.492253) (xy 354.173918 -286.461223)
			(xy 354.139709 -286.424057) (xy 354.112084 -286.381768) (xy 354.091795 -286.335508) (xy 354.079395 -286.286541)
			(xy 354.075224 -286.2362) (xy 352.806987 -286.2362) (xy 352.802816 -286.286531) (xy 352.790419 -286.335489)
			(xy 352.770132 -286.381739) (xy 352.742509 -286.424018) (xy 352.708304 -286.461175) (xy 352.66845 -286.492195)
			(xy 352.624033 -286.516232) (xy 352.576266 -286.53263) (xy 352.526452 -286.540943) (xy 352.5012 -286.541464)
			(xy 351.561146 -286.541464) (xy 351.535882 -286.541063) (xy 351.486043 -286.532753) (xy 351.438251 -286.516352)
			(xy 351.393811 -286.492309) (xy 351.353935 -286.461277) (xy 351.319711 -286.424105) (xy 351.292072 -286.381807)
			(xy 351.271774 -286.335536) (xy 351.259369 -286.286555) (xy 351.255196 -286.2362) (xy 349.987116 -286.2362)
			(xy 349.982945 -286.286536) (xy 349.970545 -286.3355) (xy 349.950256 -286.381755) (xy 349.92263 -286.424039)
			(xy 349.88842 -286.461199) (xy 349.848561 -286.492222) (xy 349.804139 -286.516261) (xy 349.756367 -286.53266)
			(xy 349.706547 -286.540972) (xy 349.681292 -286.541464) (xy 348.741238 -286.541464) (xy 348.715975 -286.541062)
			(xy 348.666136 -286.532751) (xy 348.618345 -286.51635) (xy 348.573907 -286.492306) (xy 348.534032 -286.461274)
			(xy 348.499809 -286.424103) (xy 348.472171 -286.381805) (xy 348.451873 -286.335534) (xy 348.439469 -286.286554)
			(xy 348.435296 -286.2362) (xy 123.660879 -286.2362) (xy 123.660896 -286.2364) (xy 123.656722 -286.286777)
			(xy 123.644314 -286.33578) (xy 123.62401 -286.382073) (xy 123.596364 -286.424392) (xy 123.562131 -286.461585)
			(xy 123.522243 -286.492637) (xy 123.477788 -286.5167) (xy 123.42998 -286.53312) (xy 123.380121 -286.541446)
			(xy 123.354846 -286.541972) (xy 122.414792 -286.541972) (xy 122.389517 -286.541429) (xy 122.339656 -286.533108)
			(xy 122.291845 -286.516693) (xy 122.247388 -286.492633) (xy 122.207498 -286.461584) (xy 122.173261 -286.424393)
			(xy 122.145613 -286.382074) (xy 122.125308 -286.335781) (xy 122.112899 -286.286778) (xy 122.108724 -286.2364)
			(xy 120.840825 -286.2364) (xy 120.836649 -286.286788) (xy 120.824237 -286.335802) (xy 120.803926 -286.382104)
			(xy 120.776271 -286.424431) (xy 120.742026 -286.461629) (xy 120.702126 -286.492683) (xy 120.657658 -286.516745)
			(xy 120.609836 -286.53316) (xy 120.559964 -286.54148) (xy 120.534684 -286.541972) (xy 119.59463 -286.541972)
			(xy 119.56935 -286.541461) (xy 119.51948 -286.533144) (xy 119.47166 -286.516731) (xy 119.427193 -286.492671)
			(xy 119.387293 -286.461619) (xy 119.353048 -286.424423) (xy 119.325394 -286.382098) (xy 119.305083 -286.335798)
			(xy 119.292671 -286.286786) (xy 119.288495 -286.2364) (xy 118.020925 -286.2364) (xy 118.016749 -286.286789)
			(xy 118.004336 -286.335803) (xy 117.984025 -286.382106) (xy 117.956369 -286.424434) (xy 117.922123 -286.461632)
			(xy 117.882222 -286.492685) (xy 117.837753 -286.516748) (xy 117.789929 -286.533162) (xy 117.740057 -286.541481)
			(xy 117.714776 -286.541972) (xy 116.774722 -286.541972) (xy 116.749443 -286.541461) (xy 116.699574 -286.533142)
			(xy 116.651754 -286.516729) (xy 116.607288 -286.492668) (xy 116.56739 -286.461616) (xy 116.533146 -286.424421)
			(xy 116.505492 -286.382096) (xy 116.485183 -286.335796) (xy 116.472771 -286.286785) (xy 116.468595 -286.2364)
			(xy 107.687096 -286.2364) (xy 107.682921 -286.286778) (xy 107.670513 -286.335781) (xy 107.650209 -286.382074)
			(xy 107.622563 -286.424394) (xy 107.588328 -286.461587) (xy 107.54844 -286.492639) (xy 107.503984 -286.516702)
			(xy 107.456175 -286.533121) (xy 107.406315 -286.541447) (xy 107.38104 -286.541972) (xy 106.440986 -286.541972)
			(xy 106.415711 -286.541429) (xy 106.365851 -286.533107) (xy 106.318041 -286.516692) (xy 106.273585 -286.492631)
			(xy 106.233695 -286.461582) (xy 106.19946 -286.424391) (xy 106.171813 -286.382072) (xy 106.151508 -286.33578)
			(xy 106.139099 -286.286777) (xy 106.134924 -286.2364) (xy 104.867196 -286.2364) (xy 104.863021 -286.286778)
			(xy 104.850613 -286.335783) (xy 104.830308 -286.382076) (xy 104.802661 -286.424397) (xy 104.768425 -286.46159)
			(xy 104.728535 -286.492642) (xy 104.684079 -286.516705) (xy 104.636268 -286.533122) (xy 104.586407 -286.541448)
			(xy 104.561132 -286.541972) (xy 103.621078 -286.541972) (xy 103.595804 -286.541428) (xy 103.545945 -286.533105)
			(xy 103.498136 -286.516689) (xy 103.453681 -286.492629) (xy 103.413792 -286.461579) (xy 103.379558 -286.424388)
			(xy 103.351911 -286.38207) (xy 103.331607 -286.335778) (xy 103.319199 -286.286776) (xy 103.315024 -286.2364)
			(xy 102.047296 -286.2364) (xy 102.043121 -286.286779) (xy 102.030712 -286.335784) (xy 102.010407 -286.382079)
			(xy 101.982759 -286.4244) (xy 101.948522 -286.461593) (xy 101.908631 -286.492645) (xy 101.864173 -286.516707)
			(xy 101.816362 -286.533124) (xy 101.7665 -286.541448) (xy 101.741224 -286.541972) (xy 100.80117 -286.541972)
			(xy 100.775896 -286.541428) (xy 100.726038 -286.533103) (xy 100.678231 -286.516687) (xy 100.633777 -286.492626)
			(xy 100.593889 -286.461576) (xy 100.559656 -286.424385) (xy 100.53201 -286.382067) (xy 100.511706 -286.335777)
			(xy 100.499298 -286.286775) (xy 100.495124 -286.2364) (xy 2.509012 -286.2364) (xy 2.509012 -300.146974)
			(xy 340.219284 -300.146974) (xy 340.219284 -299.130974) (xy 340.21977 -299.103723) (xy 340.227526 -299.049775)
			(xy 340.242881 -298.99748) (xy 340.265523 -298.947903) (xy 340.294989 -298.902053) (xy 340.33068 -298.860862)
			(xy 340.371871 -298.825171) (xy 340.417721 -298.795705) (xy 340.467298 -298.773063) (xy 340.519593 -298.757708)
			(xy 340.573541 -298.749952) (xy 340.628043 -298.749952) (xy 340.681991 -298.757708) (xy 340.734286 -298.773063)
			(xy 340.783863 -298.795705) (xy 340.829713 -298.825171) (xy 340.870904 -298.860862) (xy 340.906595 -298.902053)
			(xy 340.936061 -298.947903) (xy 340.958703 -298.99748) (xy 340.974058 -299.049775) (xy 340.981814 -299.103723)
			(xy 340.9823 -299.130974) (xy 340.9823 -300.146974) (xy 340.981814 -300.174225) (xy 340.974058 -300.228173)
			(xy 340.958703 -300.280468) (xy 340.936061 -300.330045) (xy 340.906595 -300.375895) (xy 340.870904 -300.417086)
			(xy 340.829713 -300.452777) (xy 340.783863 -300.482243) (xy 340.734286 -300.504885) (xy 340.681991 -300.52024)
			(xy 340.628043 -300.527996) (xy 340.573541 -300.527996) (xy 340.519593 -300.52024) (xy 340.467298 -300.504885)
			(xy 340.417721 -300.482243) (xy 340.371871 -300.452777) (xy 340.33068 -300.417086) (xy 340.294989 -300.375895)
			(xy 340.265523 -300.330045) (xy 340.242881 -300.280468) (xy 340.227526 -300.228173) (xy 340.21977 -300.174225)
			(xy 340.219284 -300.146974) (xy 2.509012 -300.146974) (xy 2.509012 -304.780442) (xy 78.811886 -304.780442)
			(xy 78.815916 -304.638092) (xy 78.827993 -304.496199) (xy 78.848078 -304.355216) (xy 78.876107 -304.215595)
			(xy 78.911991 -304.077783) (xy 78.955613 -303.942222) (xy 79.006835 -303.809347) (xy 79.065493 -303.679582)
			(xy 79.131398 -303.553343) (xy 79.204339 -303.431035) (xy 79.284083 -303.31305) (xy 79.370375 -303.199765)
			(xy 79.462937 -303.091544) (xy 79.561474 -302.988732) (xy 79.665669 -302.89166) (xy 79.77519 -302.800639)
			(xy 79.889684 -302.715959) (xy 80.008786 -302.637893) (xy 80.132114 -302.566689) (xy 80.259272 -302.502577)
			(xy 80.389854 -302.445762) (xy 80.523442 -302.396425) (xy 80.659606 -302.354725) (xy 80.797912 -302.320796)
			(xy 80.937915 -302.294745) (xy 81.079169 -302.276657) (xy 81.221219 -302.266589) (xy 81.363611 -302.264574)
			(xy 81.50589 -302.270618) (xy 81.647598 -302.284701) (xy 81.788283 -302.30678) (xy 81.927493 -302.336782)
			(xy 82.064783 -302.374612) (xy 82.199713 -302.420148) (xy 82.331851 -302.473246) (xy 82.460773 -302.533733)
			(xy 82.586066 -302.601418) (xy 82.707329 -302.676083) (xy 82.824174 -302.757489) (xy 82.936227 -302.845375)
			(xy 83.043127 -302.939459) (xy 83.144534 -303.039441) (xy 83.240122 -303.144999) (xy 83.329585 -303.255797)
			(xy 83.412636 -303.371478) (xy 83.489009 -303.491673) (xy 83.55846 -303.615996) (xy 83.620766 -303.744049)
			(xy 83.675728 -303.875422) (xy 83.723169 -304.009694) (xy 83.762938 -304.146435) (xy 83.794907 -304.285207)
			(xy 83.818974 -304.425565) (xy 83.835062 -304.56706) (xy 83.843118 -304.709239) (xy 83.843622 -304.780442)
			(xy 140.011408 -304.780442) (xy 140.015438 -304.638078) (xy 140.027516 -304.49617) (xy 140.047604 -304.355173)
			(xy 140.075636 -304.215538) (xy 140.111523 -304.077712) (xy 140.15515 -303.942138) (xy 140.206377 -303.809249)
			(xy 140.26504 -303.67947) (xy 140.330952 -303.553219) (xy 140.403901 -303.430899) (xy 140.483653 -303.312902)
			(xy 140.569953 -303.199606) (xy 140.662525 -303.091373) (xy 140.761071 -302.988551) (xy 140.865277 -302.89147)
			(xy 140.974809 -302.800439) (xy 141.089315 -302.715751) (xy 141.208429 -302.637676) (xy 141.331769 -302.566466)
			(xy 141.45894 -302.502347) (xy 141.589536 -302.445526) (xy 141.723136 -302.396185) (xy 141.859315 -302.35448)
			(xy 141.997634 -302.320547) (xy 142.137652 -302.294494) (xy 142.278919 -302.276404) (xy 142.420984 -302.266335)
			(xy 142.563391 -302.26432) (xy 142.705684 -302.270364) (xy 142.847406 -302.28445) (xy 142.988105 -302.30653)
			(xy 143.12733 -302.336535) (xy 143.264634 -302.374369) (xy 143.399577 -302.41991) (xy 143.531728 -302.473013)
			(xy 143.660663 -302.533507) (xy 143.785969 -302.601198) (xy 143.907245 -302.675871) (xy 144.024101 -302.757285)
			(xy 144.136165 -302.845179) (xy 144.243077 -302.939273) (xy 144.344494 -303.039265) (xy 144.440091 -303.144834)
			(xy 144.529563 -303.255643) (xy 144.612622 -303.371336) (xy 144.689003 -303.491543) (xy 144.758461 -303.615878)
			(xy 144.820774 -303.743944) (xy 144.875741 -303.875331) (xy 144.923187 -304.009616) (xy 144.96296 -304.146371)
			(xy 144.994932 -304.285157) (xy 145.019002 -304.425529) (xy 145.035091 -304.567039) (xy 145.043148 -304.709231)
			(xy 145.04365 -304.780188) (xy 326.751954 -304.780188) (xy 326.755984 -304.637838) (xy 326.768061 -304.495945)
			(xy 326.788146 -304.354962) (xy 326.816175 -304.215341) (xy 326.852059 -304.077529) (xy 326.895681 -303.941968)
			(xy 326.946903 -303.809093) (xy 327.005561 -303.679328) (xy 327.071466 -303.553089) (xy 327.144407 -303.430781)
			(xy 327.224151 -303.312796) (xy 327.310443 -303.199511) (xy 327.403005 -303.09129) (xy 327.501542 -302.988478)
			(xy 327.605737 -302.891406) (xy 327.715258 -302.800385) (xy 327.829752 -302.715705) (xy 327.948854 -302.637639)
			(xy 328.072182 -302.566435) (xy 328.19934 -302.502323) (xy 328.329922 -302.445508) (xy 328.46351 -302.396171)
			(xy 328.599674 -302.354471) (xy 328.73798 -302.320542) (xy 328.877983 -302.294491) (xy 329.019237 -302.276403)
			(xy 329.161287 -302.266335) (xy 329.303679 -302.26432) (xy 329.445958 -302.270364) (xy 329.587666 -302.284447)
			(xy 329.728351 -302.306526) (xy 329.867561 -302.336528) (xy 330.004851 -302.374358) (xy 330.139781 -302.419894)
			(xy 330.271919 -302.472992) (xy 330.400841 -302.533479) (xy 330.526134 -302.601164) (xy 330.647397 -302.675829)
			(xy 330.764242 -302.757235) (xy 330.876295 -302.845121) (xy 330.983195 -302.939205) (xy 331.084602 -303.039187)
			(xy 331.18019 -303.144745) (xy 331.269653 -303.255543) (xy 331.352704 -303.371224) (xy 331.429077 -303.491419)
			(xy 331.498528 -303.615742) (xy 331.560834 -303.743795) (xy 331.615796 -303.875168) (xy 331.663237 -304.00944)
			(xy 331.703006 -304.146181) (xy 331.734975 -304.284953) (xy 331.759042 -304.425311) (xy 331.77513 -304.566806)
			(xy 331.781608 -304.681128) (xy 333.795116 -304.681128) (xy 333.795116 -303.817528) (xy 333.795602 -303.790259)
			(xy 333.803364 -303.736275) (xy 333.818729 -303.683945) (xy 333.841386 -303.634335) (xy 333.870872 -303.588454)
			(xy 333.906587 -303.547237) (xy 333.947804 -303.511522) (xy 333.993685 -303.482036) (xy 334.043295 -303.459379)
			(xy 334.095625 -303.444014) (xy 334.149609 -303.436252) (xy 334.204147 -303.436252) (xy 334.258131 -303.444014)
			(xy 334.310461 -303.459379) (xy 334.360071 -303.482036) (xy 334.405952 -303.511522) (xy 334.447169 -303.547237)
			(xy 334.482884 -303.588454) (xy 334.51237 -303.634335) (xy 334.535027 -303.683945) (xy 334.550392 -303.736275)
			(xy 334.558154 -303.790259) (xy 334.55864 -303.817528) (xy 334.55864 -304.681128) (xy 334.558154 -304.708397)
			(xy 334.550392 -304.762381) (xy 334.545164 -304.780188) (xy 387.951476 -304.780188) (xy 387.955506 -304.637824)
			(xy 387.967584 -304.495916) (xy 387.987672 -304.354919) (xy 388.015704 -304.215284) (xy 388.051591 -304.077458)
			(xy 388.095218 -303.941884) (xy 388.146445 -303.808995) (xy 388.205108 -303.679216) (xy 388.27102 -303.552965)
			(xy 388.343969 -303.430645) (xy 388.423721 -303.312648) (xy 388.510021 -303.199352) (xy 388.602593 -303.091119)
			(xy 388.701139 -302.988297) (xy 388.805345 -302.891216) (xy 388.914877 -302.800185) (xy 389.029383 -302.715497)
			(xy 389.148497 -302.637422) (xy 389.271837 -302.566212) (xy 389.399008 -302.502093) (xy 389.529604 -302.445272)
			(xy 389.663204 -302.395931) (xy 389.799383 -302.354226) (xy 389.937702 -302.320293) (xy 390.07772 -302.29424)
			(xy 390.218987 -302.27615) (xy 390.361052 -302.266081) (xy 390.503459 -302.264066) (xy 390.645752 -302.27011)
			(xy 390.787474 -302.284196) (xy 390.928173 -302.306276) (xy 391.067398 -302.336281) (xy 391.204702 -302.374115)
			(xy 391.339645 -302.419656) (xy 391.471796 -302.472759) (xy 391.600731 -302.533253) (xy 391.726037 -302.600944)
			(xy 391.847313 -302.675617) (xy 391.964169 -302.757031) (xy 392.076233 -302.844925) (xy 392.183145 -302.939019)
			(xy 392.284562 -303.039011) (xy 392.380159 -303.14458) (xy 392.469631 -303.255389) (xy 392.55269 -303.371082)
			(xy 392.629071 -303.491289) (xy 392.698529 -303.615624) (xy 392.760842 -303.74369) (xy 392.815809 -303.875077)
			(xy 392.863255 -304.009362) (xy 392.903028 -304.146117) (xy 392.935 -304.284903) (xy 392.95907 -304.425275)
			(xy 392.975159 -304.566785) (xy 392.983216 -304.708977) (xy 392.98372 -304.780188) (xy 392.983216 -304.851399)
			(xy 392.975159 -304.993591) (xy 392.95907 -305.135101) (xy 392.935 -305.275473) (xy 392.903028 -305.414259)
			(xy 392.863255 -305.551014) (xy 392.815809 -305.685299) (xy 392.760842 -305.816686) (xy 392.698529 -305.944752)
			(xy 392.629071 -306.069087) (xy 392.55269 -306.189294) (xy 392.469631 -306.304987) (xy 392.380159 -306.415796)
			(xy 392.284562 -306.521365) (xy 392.183145 -306.621357) (xy 392.076233 -306.715451) (xy 391.964169 -306.803345)
			(xy 391.847313 -306.884759) (xy 391.726037 -306.959432) (xy 391.600731 -307.027123) (xy 391.471796 -307.087617)
			(xy 391.339645 -307.14072) (xy 391.204702 -307.186261) (xy 391.067398 -307.224095) (xy 390.928173 -307.2541)
			(xy 390.787474 -307.27618) (xy 390.645752 -307.290266) (xy 390.503459 -307.29631) (xy 390.361052 -307.294295)
			(xy 390.218987 -307.284226) (xy 390.07772 -307.266136) (xy 389.937702 -307.240083) (xy 389.799383 -307.20615)
			(xy 389.663204 -307.164445) (xy 389.529604 -307.115104) (xy 389.399008 -307.058283) (xy 389.271837 -306.994164)
			(xy 389.148497 -306.922954) (xy 389.029383 -306.844879) (xy 388.914877 -306.760191) (xy 388.805345 -306.66916)
			(xy 388.701139 -306.572079) (xy 388.602593 -306.469257) (xy 388.510021 -306.361024) (xy 388.423721 -306.247728)
			(xy 388.343969 -306.129731) (xy 388.27102 -306.007411) (xy 388.205108 -305.88116) (xy 388.146445 -305.751381)
			(xy 388.095218 -305.618492) (xy 388.051591 -305.482918) (xy 388.015704 -305.345092) (xy 387.987672 -305.205457)
			(xy 387.967584 -305.06446) (xy 387.955506 -304.922552) (xy 387.951476 -304.780188) (xy 334.545164 -304.780188)
			(xy 334.535027 -304.814711) (xy 334.51237 -304.864321) (xy 334.482884 -304.910202) (xy 334.447169 -304.951419)
			(xy 334.405952 -304.987134) (xy 334.360071 -305.01662) (xy 334.310461 -305.039277) (xy 334.258131 -305.054642)
			(xy 334.204147 -305.062404) (xy 334.149609 -305.062404) (xy 334.095625 -305.054642) (xy 334.043295 -305.039277)
			(xy 333.993685 -305.01662) (xy 333.947804 -304.987134) (xy 333.906587 -304.951419) (xy 333.870872 -304.910202)
			(xy 333.841386 -304.864321) (xy 333.818729 -304.814711) (xy 333.803364 -304.762381) (xy 333.795602 -304.708397)
			(xy 333.795116 -304.681128) (xy 331.781608 -304.681128) (xy 331.783186 -304.708985) (xy 331.78369 -304.780188)
			(xy 331.783186 -304.851391) (xy 331.77513 -304.99357) (xy 331.759042 -305.135065) (xy 331.734975 -305.275423)
			(xy 331.703006 -305.414195) (xy 331.663237 -305.550936) (xy 331.615796 -305.685208) (xy 331.560834 -305.816581)
			(xy 331.498528 -305.944634) (xy 331.429077 -306.068957) (xy 331.352704 -306.189152) (xy 331.269653 -306.304833)
			(xy 331.18019 -306.415631) (xy 331.164492 -306.432966) (xy 340.495636 -306.432966) (xy 340.495636 -305.569366)
			(xy 340.496122 -305.542115) (xy 340.503878 -305.488167) (xy 340.519233 -305.435872) (xy 340.541875 -305.386295)
			(xy 340.571341 -305.340445) (xy 340.607032 -305.299254) (xy 340.648223 -305.263563) (xy 340.694073 -305.234097)
			(xy 340.74365 -305.211455) (xy 340.795945 -305.1961) (xy 340.849893 -305.188344) (xy 340.904395 -305.188344)
			(xy 340.958343 -305.1961) (xy 341.010638 -305.211455) (xy 341.060215 -305.234097) (xy 341.106065 -305.263563)
			(xy 341.147256 -305.299254) (xy 341.182947 -305.340445) (xy 341.212413 -305.386295) (xy 341.235055 -305.435872)
			(xy 341.25041 -305.488167) (xy 341.258166 -305.542115) (xy 341.258652 -305.569366) (xy 341.258652 -306.432966)
			(xy 341.258166 -306.460217) (xy 341.25041 -306.514165) (xy 341.235055 -306.56646) (xy 341.212413 -306.616037)
			(xy 341.182947 -306.661887) (xy 341.147256 -306.703078) (xy 341.106065 -306.738769) (xy 341.060215 -306.768235)
			(xy 341.010638 -306.790877) (xy 340.958343 -306.806232) (xy 340.904395 -306.813988) (xy 340.849893 -306.813988)
			(xy 340.795945 -306.806232) (xy 340.74365 -306.790877) (xy 340.694073 -306.768235) (xy 340.648223 -306.738769)
			(xy 340.607032 -306.703078) (xy 340.571341 -306.661887) (xy 340.541875 -306.616037) (xy 340.519233 -306.56646)
			(xy 340.503878 -306.514165) (xy 340.496122 -306.460217) (xy 340.495636 -306.432966) (xy 331.164492 -306.432966)
			(xy 331.084602 -306.521189) (xy 330.983195 -306.621171) (xy 330.876295 -306.715255) (xy 330.764242 -306.803141)
			(xy 330.647397 -306.884547) (xy 330.526134 -306.959212) (xy 330.400841 -307.026897) (xy 330.271919 -307.087384)
			(xy 330.139781 -307.140482) (xy 330.004851 -307.186018) (xy 329.867561 -307.223848) (xy 329.728351 -307.25385)
			(xy 329.587666 -307.275929) (xy 329.445958 -307.290012) (xy 329.303679 -307.296056) (xy 329.161287 -307.294041)
			(xy 329.019237 -307.283973) (xy 328.877983 -307.265885) (xy 328.73798 -307.239834) (xy 328.599674 -307.205905)
			(xy 328.46351 -307.164205) (xy 328.329922 -307.114868) (xy 328.19934 -307.058053) (xy 328.072182 -306.993941)
			(xy 327.948854 -306.922737) (xy 327.829752 -306.844671) (xy 327.715258 -306.759991) (xy 327.605737 -306.66897)
			(xy 327.501542 -306.571898) (xy 327.403005 -306.469086) (xy 327.310443 -306.360865) (xy 327.224151 -306.24758)
			(xy 327.144407 -306.129595) (xy 327.071466 -306.007287) (xy 327.005561 -305.881048) (xy 326.946903 -305.751283)
			(xy 326.895681 -305.618408) (xy 326.852059 -305.482847) (xy 326.816175 -305.345035) (xy 326.788146 -305.205414)
			(xy 326.768061 -305.064431) (xy 326.755984 -304.922538) (xy 326.751954 -304.780188) (xy 145.04365 -304.780188)
			(xy 145.043652 -304.780442) (xy 145.043148 -304.851653) (xy 145.035091 -304.993845) (xy 145.019002 -305.135355)
			(xy 144.994932 -305.275727) (xy 144.96296 -305.414513) (xy 144.923187 -305.551268) (xy 144.875741 -305.685553)
			(xy 144.820774 -305.81694) (xy 144.758461 -305.945006) (xy 144.689003 -306.069341) (xy 144.612622 -306.189548)
			(xy 144.529563 -306.305241) (xy 144.440091 -306.41605) (xy 144.344494 -306.521619) (xy 144.243077 -306.621611)
			(xy 144.136165 -306.715705) (xy 144.024101 -306.803599) (xy 143.907245 -306.885013) (xy 143.785969 -306.959686)
			(xy 143.660663 -307.027377) (xy 143.531728 -307.087871) (xy 143.399577 -307.140974) (xy 143.264634 -307.186515)
			(xy 143.12733 -307.224349) (xy 142.988105 -307.254354) (xy 142.847406 -307.276434) (xy 142.705684 -307.29052)
			(xy 142.563391 -307.296564) (xy 142.420984 -307.294549) (xy 142.278919 -307.28448) (xy 142.137652 -307.26639)
			(xy 141.997634 -307.240337) (xy 141.859315 -307.206404) (xy 141.723136 -307.164699) (xy 141.589536 -307.115358)
			(xy 141.45894 -307.058537) (xy 141.331769 -306.994418) (xy 141.208429 -306.923208) (xy 141.089315 -306.845133)
			(xy 140.974809 -306.760445) (xy 140.865277 -306.669414) (xy 140.761071 -306.572333) (xy 140.662525 -306.469511)
			(xy 140.569953 -306.361278) (xy 140.483653 -306.247982) (xy 140.403901 -306.129985) (xy 140.330952 -306.007665)
			(xy 140.26504 -305.881414) (xy 140.206377 -305.751635) (xy 140.15515 -305.618746) (xy 140.111523 -305.483172)
			(xy 140.075636 -305.345346) (xy 140.047604 -305.205711) (xy 140.027516 -305.064714) (xy 140.015438 -304.922806)
			(xy 140.011408 -304.780442) (xy 83.843622 -304.780442) (xy 83.843118 -304.851645) (xy 83.835062 -304.993824)
			(xy 83.818974 -305.135319) (xy 83.794907 -305.275677) (xy 83.762938 -305.414449) (xy 83.723169 -305.55119)
			(xy 83.675728 -305.685462) (xy 83.620766 -305.816835) (xy 83.55846 -305.944888) (xy 83.489009 -306.069211)
			(xy 83.412636 -306.189406) (xy 83.329585 -306.305087) (xy 83.240122 -306.415885) (xy 83.144534 -306.521443)
			(xy 83.043127 -306.621425) (xy 82.936227 -306.715509) (xy 82.824174 -306.803395) (xy 82.707329 -306.884801)
			(xy 82.586066 -306.959466) (xy 82.460773 -307.027151) (xy 82.331851 -307.087638) (xy 82.199713 -307.140736)
			(xy 82.064783 -307.186272) (xy 81.927493 -307.224102) (xy 81.788283 -307.254104) (xy 81.647598 -307.276183)
			(xy 81.50589 -307.290266) (xy 81.363611 -307.29631) (xy 81.221219 -307.294295) (xy 81.079169 -307.284227)
			(xy 80.937915 -307.266139) (xy 80.797912 -307.240088) (xy 80.659606 -307.206159) (xy 80.523442 -307.164459)
			(xy 80.389854 -307.115122) (xy 80.259272 -307.058307) (xy 80.132114 -306.994195) (xy 80.008786 -306.922991)
			(xy 79.889684 -306.844925) (xy 79.77519 -306.760245) (xy 79.665669 -306.669224) (xy 79.561474 -306.572152)
			(xy 79.462937 -306.46934) (xy 79.370375 -306.361119) (xy 79.284083 -306.247834) (xy 79.204339 -306.129849)
			(xy 79.131398 -306.007541) (xy 79.065493 -305.881302) (xy 79.006835 -305.751537) (xy 78.955613 -305.618662)
			(xy 78.911991 -305.483101) (xy 78.876107 -305.345289) (xy 78.848078 -305.205668) (xy 78.827993 -305.064685)
			(xy 78.815916 -304.922792) (xy 78.811886 -304.780442) (xy 2.509012 -304.780442) (xy 2.509012 -309.504588)
			(xy 79.192628 -309.504588) (xy 79.192628 -308.640988) (xy 79.193114 -308.613737) (xy 79.20087 -308.559789)
			(xy 79.216225 -308.507494) (xy 79.238867 -308.457917) (xy 79.268333 -308.412067) (xy 79.304024 -308.370876)
			(xy 79.345215 -308.335185) (xy 79.391065 -308.305719) (xy 79.440642 -308.283077) (xy 79.492937 -308.267722)
			(xy 79.546885 -308.259966) (xy 79.601387 -308.259966) (xy 79.655335 -308.267722) (xy 79.70763 -308.283077)
			(xy 79.757207 -308.305719) (xy 79.803057 -308.335185) (xy 79.844248 -308.370876) (xy 79.879939 -308.412067)
			(xy 79.909405 -308.457917) (xy 79.92811 -308.498873) (xy 93.275072 -308.498873) (xy 93.275072 -308.444327)
			(xy 93.282834 -308.390335) (xy 93.298202 -308.337998) (xy 93.320862 -308.288381) (xy 93.350352 -308.242493)
			(xy 93.386073 -308.20127) (xy 93.427297 -308.16555) (xy 93.473184 -308.13606) (xy 93.522802 -308.113401)
			(xy 93.575139 -308.098034) (xy 93.629131 -308.090271) (xy 93.656404 -308.089808) (xy 94.520004 -308.089808)
			(xy 94.547271 -308.090355) (xy 94.60125 -308.098116) (xy 94.653575 -308.113481) (xy 94.703181 -308.136135)
			(xy 94.749058 -308.165619) (xy 94.790271 -308.201331) (xy 94.825983 -308.242546) (xy 94.855467 -308.288423)
			(xy 94.878121 -308.338029) (xy 94.893485 -308.390354) (xy 94.901246 -308.444333) (xy 94.901246 -308.498867)
			(xy 94.893485 -308.552846) (xy 94.878121 -308.605171) (xy 94.855467 -308.654777) (xy 94.825983 -308.700654)
			(xy 94.790271 -308.741869) (xy 94.749058 -308.777581) (xy 94.703181 -308.807065) (xy 94.653575 -308.829719)
			(xy 94.60125 -308.845084) (xy 94.547271 -308.852845) (xy 94.520004 -308.853332) (xy 93.656404 -308.853332)
			(xy 93.629131 -308.852929) (xy 93.575139 -308.845166) (xy 93.522802 -308.829799) (xy 93.473184 -308.80714)
			(xy 93.427297 -308.77765) (xy 93.386073 -308.74193) (xy 93.350352 -308.700707) (xy 93.320862 -308.654819)
			(xy 93.298202 -308.605202) (xy 93.282834 -308.552865) (xy 93.275072 -308.498873) (xy 79.92811 -308.498873)
			(xy 79.932047 -308.507494) (xy 79.947402 -308.559789) (xy 79.955158 -308.613737) (xy 79.955644 -308.640988)
			(xy 79.955644 -309.303166) (xy 341.51824 -309.303166) (xy 341.51824 -308.439566) (xy 341.518726 -308.412297)
			(xy 341.526488 -308.358313) (xy 341.541853 -308.305983) (xy 341.56451 -308.256373) (xy 341.593996 -308.210492)
			(xy 341.629711 -308.169275) (xy 341.670928 -308.13356) (xy 341.716809 -308.104074) (xy 341.766419 -308.081417)
			(xy 341.818749 -308.066052) (xy 341.872733 -308.05829) (xy 341.927271 -308.05829) (xy 341.981255 -308.066052)
			(xy 342.033585 -308.081417) (xy 342.083195 -308.104074) (xy 342.129076 -308.13356) (xy 342.170293 -308.169275)
			(xy 342.206008 -308.210492) (xy 342.235494 -308.256373) (xy 342.258151 -308.305983) (xy 342.273516 -308.358313)
			(xy 342.281278 -308.412297) (xy 342.281764 -308.439566) (xy 342.281764 -309.303166) (xy 342.281278 -309.330435)
			(xy 342.273516 -309.384419) (xy 342.258151 -309.436749) (xy 342.235494 -309.486359) (xy 342.206008 -309.53224)
			(xy 342.170293 -309.573457) (xy 342.129076 -309.609172) (xy 342.083195 -309.638658) (xy 342.033585 -309.661315)
			(xy 341.981255 -309.67668) (xy 341.927271 -309.684442) (xy 341.872733 -309.684442) (xy 341.818749 -309.67668)
			(xy 341.766419 -309.661315) (xy 341.716809 -309.638658) (xy 341.670928 -309.609172) (xy 341.629711 -309.573457)
			(xy 341.593996 -309.53224) (xy 341.56451 -309.486359) (xy 341.541853 -309.436749) (xy 341.526488 -309.384419)
			(xy 341.518726 -309.330435) (xy 341.51824 -309.303166) (xy 79.955644 -309.303166) (xy 79.955644 -309.504588)
			(xy 79.955158 -309.531839) (xy 79.947402 -309.585787) (xy 79.932047 -309.638082) (xy 79.909405 -309.687659)
			(xy 79.879939 -309.733509) (xy 79.844248 -309.7747) (xy 79.803057 -309.810391) (xy 79.757207 -309.839857)
			(xy 79.70763 -309.862499) (xy 79.655335 -309.877854) (xy 79.601387 -309.88561) (xy 79.546885 -309.88561)
			(xy 79.492937 -309.877854) (xy 79.440642 -309.862499) (xy 79.391065 -309.839857) (xy 79.345215 -309.810391)
			(xy 79.304024 -309.7747) (xy 79.268333 -309.733509) (xy 79.238867 -309.687659) (xy 79.216225 -309.638082)
			(xy 79.20087 -309.585787) (xy 79.193114 -309.531839) (xy 79.192628 -309.504588) (xy 2.509012 -309.504588)
			(xy 2.509012 -310.603646) (xy 98.925888 -310.603646) (xy 98.925888 -309.740046) (xy 98.926374 -309.712795)
			(xy 98.93413 -309.658847) (xy 98.949485 -309.606552) (xy 98.972127 -309.556975) (xy 99.001593 -309.511125)
			(xy 99.037284 -309.469934) (xy 99.078475 -309.434243) (xy 99.124325 -309.404777) (xy 99.173902 -309.382135)
			(xy 99.226197 -309.36678) (xy 99.280145 -309.359024) (xy 99.334647 -309.359024) (xy 99.388595 -309.36678)
			(xy 99.44089 -309.382135) (xy 99.490467 -309.404777) (xy 99.536317 -309.434243) (xy 99.577508 -309.469934)
			(xy 99.613199 -309.511125) (xy 99.642665 -309.556975) (xy 99.665307 -309.606552) (xy 99.680662 -309.658847)
			(xy 99.688418 -309.712795) (xy 99.688904 -309.740046) (xy 99.688904 -310.603646) (xy 99.688418 -310.630897)
			(xy 99.680662 -310.684845) (xy 99.665307 -310.73714) (xy 99.642665 -310.786717) (xy 99.613199 -310.832567)
			(xy 99.577508 -310.873758) (xy 99.536317 -310.909449) (xy 99.490467 -310.938915) (xy 99.44089 -310.961557)
			(xy 99.388595 -310.976912) (xy 99.334647 -310.984668) (xy 99.280145 -310.984668) (xy 99.226197 -310.976912)
			(xy 99.173902 -310.961557) (xy 99.124325 -310.938915) (xy 99.078475 -310.909449) (xy 99.037284 -310.873758)
			(xy 99.001593 -310.832567) (xy 98.972127 -310.786717) (xy 98.949485 -310.73714) (xy 98.93413 -310.684845)
			(xy 98.926374 -310.630897) (xy 98.925888 -310.603646) (xy 2.509012 -310.603646) (xy 2.509012 -311.513728)
			(xy 347.772228 -311.513728) (xy 347.772228 -310.650128) (xy 347.772714 -310.622859) (xy 347.780476 -310.568875)
			(xy 347.795841 -310.516545) (xy 347.818498 -310.466935) (xy 347.847984 -310.421054) (xy 347.883699 -310.379837)
			(xy 347.924916 -310.344122) (xy 347.970797 -310.314636) (xy 348.020407 -310.291979) (xy 348.072737 -310.276614)
			(xy 348.126721 -310.268852) (xy 348.181259 -310.268852) (xy 348.235243 -310.276614) (xy 348.287573 -310.291979)
			(xy 348.337183 -310.314636) (xy 348.383064 -310.344122) (xy 348.424281 -310.379837) (xy 348.459996 -310.421054)
			(xy 348.489482 -310.466935) (xy 348.512139 -310.516545) (xy 348.527504 -310.568875) (xy 348.535266 -310.622859)
			(xy 348.535752 -310.650128) (xy 348.535752 -311.513728) (xy 348.535266 -311.540997) (xy 348.527504 -311.594981)
			(xy 348.512139 -311.647311) (xy 348.489482 -311.696921) (xy 348.459996 -311.742802) (xy 348.424281 -311.784019)
			(xy 348.383064 -311.819734) (xy 348.337183 -311.84922) (xy 348.287573 -311.871877) (xy 348.235243 -311.887242)
			(xy 348.181259 -311.895004) (xy 348.126721 -311.895004) (xy 348.072737 -311.887242) (xy 348.020407 -311.871877)
			(xy 347.970797 -311.84922) (xy 347.924916 -311.819734) (xy 347.883699 -311.784019) (xy 347.847984 -311.742802)
			(xy 347.818498 -311.696921) (xy 347.795841 -311.647311) (xy 347.780476 -311.594981) (xy 347.772714 -311.540997)
			(xy 347.772228 -311.513728) (xy 2.509012 -311.513728) (xy 2.509012 -314.997338) (xy 98.330512 -314.997338)
			(xy 98.330512 -314.133738) (xy 98.330998 -314.106487) (xy 98.338754 -314.052539) (xy 98.354109 -314.000244)
			(xy 98.376751 -313.950667) (xy 98.406217 -313.904817) (xy 98.441908 -313.863626) (xy 98.483099 -313.827935)
			(xy 98.528949 -313.798469) (xy 98.578526 -313.775827) (xy 98.630821 -313.760472) (xy 98.684769 -313.752716)
			(xy 98.739271 -313.752716) (xy 98.793219 -313.760472) (xy 98.845514 -313.775827) (xy 98.895091 -313.798469)
			(xy 98.940941 -313.827935) (xy 98.982132 -313.863626) (xy 99.017823 -313.904817) (xy 99.047289 -313.950667)
			(xy 99.069931 -314.000244) (xy 99.085286 -314.052539) (xy 99.093042 -314.106487) (xy 99.093528 -314.133738)
			(xy 99.093528 -314.997338) (xy 99.093042 -315.024589) (xy 99.085286 -315.078537) (xy 99.069931 -315.130832)
			(xy 99.047289 -315.180409) (xy 99.017823 -315.226259) (xy 98.982132 -315.26745) (xy 98.940941 -315.303141)
			(xy 98.895091 -315.332607) (xy 98.845514 -315.355249) (xy 98.793219 -315.370604) (xy 98.739271 -315.37836)
			(xy 98.684769 -315.37836) (xy 98.630821 -315.370604) (xy 98.578526 -315.355249) (xy 98.528949 -315.332607)
			(xy 98.483099 -315.303141) (xy 98.441908 -315.26745) (xy 98.406217 -315.226259) (xy 98.376751 -315.180409)
			(xy 98.354109 -315.130832) (xy 98.338754 -315.078537) (xy 98.330998 -315.024589) (xy 98.330512 -314.997338)
			(xy 2.509012 -314.997338) (xy 2.509012 -336.9884) (xy 70.218517 -336.9884) (xy 70.222508 -336.904617)
			(xy 70.234446 -336.821593) (xy 70.254221 -336.74008) (xy 70.281655 -336.660815) (xy 70.3165 -336.584518)
			(xy 70.35844 -336.511878) (xy 70.407095 -336.443554) (xy 70.462025 -336.380164) (xy 70.522731 -336.322283)
			(xy 70.588664 -336.270435) (xy 70.659228 -336.225089) (xy 70.733783 -336.186656) (xy 70.811653 -336.155484)
			(xy 70.892134 -336.131855) (xy 70.974497 -336.115984) (xy 71.057995 -336.108014) (xy 71.099934 -336.107532)
			(xy 71.137123 -336.107938) (xy 71.211236 -336.114223) (xy 71.284556 -336.126727) (xy 71.356562 -336.145363)
			(xy 71.39178 -336.157316) (xy 71.399977 -336.15983) (xy 71.417111 -336.15983) (xy 71.425308 -336.157316)
			(xy 71.460496 -336.145371) (xy 71.532436 -336.126725) (xy 71.605692 -336.114215) (xy 71.679742 -336.107929)
			(xy 71.7169 -336.107532) (xy 71.717408 -336.107532) (xy 71.748142 -336.108294) (xy 71.757646 -336.056715)
			(xy 71.787316 -335.956115) (xy 71.807324 -335.907634) (xy 71.810983 -335.897931) (xy 71.810971 -335.877211)
			(xy 71.807324 -335.867502) (xy 71.790219 -335.826242) (xy 71.763427 -335.741032) (xy 71.74539 -335.653549)
			(xy 71.736293 -335.564691) (xy 71.735696 -335.52003) (xy 71.735696 -335.519268) (xy 71.736195 -335.477343)
			(xy 71.744165 -335.393872) (xy 71.760034 -335.311537) (xy 71.783657 -335.231083) (xy 71.814821 -335.153239)
			(xy 71.853244 -335.078709) (xy 71.898577 -335.00817) (xy 71.95041 -334.942259) (xy 72.008273 -334.881573)
			(xy 72.071643 -334.826663) (xy 72.139946 -334.778025) (xy 72.212563 -334.7361) (xy 72.288836 -334.701267)
			(xy 72.368075 -334.673842) (xy 72.449561 -334.654073) (xy 72.532558 -334.64214) (xy 72.616314 -334.638151)
			(xy 72.70007 -334.64214) (xy 72.783067 -334.654073) (xy 72.864553 -334.673842) (xy 72.943792 -334.701267)
			(xy 73.020065 -334.7361) (xy 73.092682 -334.778025) (xy 73.160985 -334.826663) (xy 73.224355 -334.881573)
			(xy 73.282218 -334.942259) (xy 73.334051 -335.00817) (xy 73.379384 -335.078709) (xy 73.417807 -335.153239)
			(xy 73.448971 -335.231083) (xy 73.472594 -335.311537) (xy 73.488463 -335.393872) (xy 73.496433 -335.477343)
			(xy 73.496932 -335.519268) (xy 73.496932 -335.52003) (xy 73.496371 -335.564694) (xy 73.487295 -335.653559)
			(xy 73.46926 -335.741047) (xy 73.442452 -335.826257) (xy 73.425304 -335.867502) (xy 73.421681 -335.877216)
			(xy 73.421669 -335.897926) (xy 73.425304 -335.907634) (xy 73.441139 -335.945575) (xy 73.466487 -336.02379)
			(xy 73.484436 -336.104027) (xy 73.494829 -336.185587) (xy 73.496678 -336.226658) (xy 73.496932 -336.24012)
			(xy 73.51141 -336.263234) (xy 73.61301 -336.31759) (xy 73.639934 -336.316828) (xy 73.651618 -336.309462)
			(xy 73.686811 -336.288202) (xy 73.76042 -336.251553) (xy 73.837094 -336.221845) (xy 73.91618 -336.199333)
			(xy 73.997005 -336.184209) (xy 74.07888 -336.1766) (xy 74.119994 -336.176112) (xy 74.161107 -336.176619)
			(xy 74.242983 -336.184205) (xy 74.32381 -336.199313) (xy 74.402898 -336.221815) (xy 74.479573 -336.251518)
			(xy 74.553179 -336.288168) (xy 74.623091 -336.331454) (xy 74.68871 -336.381006) (xy 74.749477 -336.4364)
			(xy 74.804874 -336.497166) (xy 74.854428 -336.562783) (xy 74.897716 -336.632693) (xy 74.934369 -336.706298)
			(xy 74.964075 -336.782971) (xy 74.986579 -336.862059) (xy 75.001691 -336.942885) (xy 75.005252 -336.9813)
			(xy 78.574105 -336.9813) (xy 78.578096 -336.897517) (xy 78.590033 -336.814493) (xy 78.609809 -336.732979)
			(xy 78.637243 -336.653715) (xy 78.672087 -336.577417) (xy 78.714027 -336.504776) (xy 78.762681 -336.436452)
			(xy 78.81761 -336.373061) (xy 78.878316 -336.31518) (xy 78.94425 -336.26333) (xy 79.014813 -336.217984)
			(xy 79.089367 -336.179549) (xy 79.167237 -336.148376) (xy 79.247718 -336.124747) (xy 79.330081 -336.108874)
			(xy 79.413579 -336.100902) (xy 79.455518 -336.10042) (xy 79.492708 -336.100802) (xy 79.566821 -336.107094)
			(xy 79.640141 -336.119606) (xy 79.712146 -336.138248) (xy 79.747364 -336.150204) (xy 79.755561 -336.152718)
			(xy 79.772695 -336.152718) (xy 79.780892 -336.150204) (xy 79.816103 -336.138226) (xy 79.888108 -336.119576)
			(xy 79.961431 -336.107072) (xy 80.035547 -336.100804) (xy 80.072738 -336.10042) (xy 80.10906 -336.101182)
			(xy 80.115245 -336.066241) (xy 80.132513 -335.997409) (xy 80.155273 -335.930194) (xy 80.169004 -335.897474)
			(xy 80.172641 -335.887764) (xy 80.172644 -335.86705) (xy 80.169004 -335.857342) (xy 80.151879 -335.81609)
			(xy 80.125092 -335.730877) (xy 80.107061 -335.643392) (xy 80.09797 -335.554532) (xy 80.097376 -335.50987)
			(xy 80.097376 -335.509108) (xy 80.097875 -335.467183) (xy 80.105845 -335.383712) (xy 80.121714 -335.301377)
			(xy 80.145337 -335.220923) (xy 80.176501 -335.143079) (xy 80.214924 -335.068549) (xy 80.260257 -334.99801)
			(xy 80.31209 -334.932099) (xy 80.369953 -334.871413) (xy 80.433323 -334.816503) (xy 80.501626 -334.767865)
			(xy 80.574243 -334.72594) (xy 80.650516 -334.691107) (xy 80.729755 -334.663682) (xy 80.811241 -334.643913)
			(xy 80.894238 -334.63198) (xy 80.977994 -334.627991) (xy 81.06175 -334.63198) (xy 81.144747 -334.643913)
			(xy 81.226233 -334.663682) (xy 81.305472 -334.691107) (xy 81.381745 -334.72594) (xy 81.454362 -334.767865)
			(xy 81.522665 -334.816503) (xy 81.586035 -334.871413) (xy 81.643898 -334.932099) (xy 81.695731 -334.99801)
			(xy 81.741064 -335.068549) (xy 81.779487 -335.143079) (xy 81.810651 -335.220923) (xy 81.834274 -335.301377)
			(xy 81.850143 -335.383712) (xy 81.858113 -335.467183) (xy 81.858612 -335.509108) (xy 81.858612 -335.50987)
			(xy 81.858066 -335.554534) (xy 81.848986 -335.6434) (xy 81.830947 -335.730888) (xy 81.804134 -335.816098)
			(xy 81.786984 -335.857342) (xy 81.783338 -335.867049) (xy 81.783341 -335.887765) (xy 81.786984 -335.897474)
			(xy 81.802748 -335.935334) (xy 81.827987 -336.013369) (xy 81.845871 -336.093411) (xy 81.856247 -336.174768)
			(xy 81.858104 -336.215736) (xy 81.858828 -336.22455) (xy 81.865419 -336.240944) (xy 81.877182 -336.254128)
			(xy 81.884774 -336.258662) (xy 81.973928 -336.306922) (xy 82.000852 -336.30616) (xy 82.012536 -336.299048)
			(xy 82.047432 -336.278305) (xy 82.120306 -336.242523) (xy 82.19614 -336.213534) (xy 82.2743 -336.191579)
			(xy 82.354137 -336.176843) (xy 82.434985 -336.169448) (xy 82.475578 -336.169) (xy 82.516691 -336.169534)
			(xy 82.598566 -336.177119) (xy 82.679391 -336.192225) (xy 82.758479 -336.214725) (xy 82.835153 -336.244426)
			(xy 82.908759 -336.281075) (xy 82.97867 -336.324359) (xy 83.044289 -336.373909) (xy 83.105056 -336.429302)
			(xy 83.160453 -336.490065) (xy 83.210007 -336.555681) (xy 83.253296 -336.625589) (xy 83.28995 -336.699193)
			(xy 83.319656 -336.775864) (xy 83.342161 -336.85495) (xy 83.357273 -336.935775) (xy 83.360149 -336.9668)
			(xy 86.931981 -336.9668) (xy 86.935971 -336.883042) (xy 86.947905 -336.800043) (xy 86.967674 -336.718554)
			(xy 86.9951 -336.639313) (xy 87.029935 -336.563039) (xy 87.071862 -336.490421) (xy 87.120503 -336.422117)
			(xy 87.175416 -336.358746) (xy 87.236104 -336.300883) (xy 87.302018 -336.24905) (xy 87.37256 -336.203717)
			(xy 87.447092 -336.165296) (xy 87.52494 -336.134133) (xy 87.605396 -336.110512) (xy 87.687734 -336.094645)
			(xy 87.771208 -336.086677) (xy 87.813134 -336.086196) (xy 87.81415 -336.086196) (xy 87.851207 -336.086587)
			(xy 87.925057 -336.092856) (xy 87.998119 -336.105302) (xy 88.069879 -336.123838) (xy 88.10498 -336.135726)
			(xy 88.113177 -336.13824) (xy 88.130311 -336.13824) (xy 88.138508 -336.135726) (xy 88.173727 -336.123789)
			(xy 88.245736 -336.1052) (xy 88.319058 -336.092757) (xy 88.393169 -336.086549) (xy 88.430354 -336.086196)
			(xy 88.454992 -336.08645) (xy 88.464629 -336.040549) (xy 88.49238 -335.950951) (xy 88.510364 -335.907634)
			(xy 88.514021 -335.89793) (xy 88.514009 -335.877211) (xy 88.510364 -335.867502) (xy 88.493256 -335.826243)
			(xy 88.466465 -335.741033) (xy 88.448429 -335.65355) (xy 88.439333 -335.564691) (xy 88.438736 -335.52003)
			(xy 88.438736 -335.519268) (xy 88.439235 -335.477343) (xy 88.447205 -335.393872) (xy 88.463074 -335.311537)
			(xy 88.486697 -335.231083) (xy 88.517861 -335.153239) (xy 88.556284 -335.078709) (xy 88.601617 -335.00817)
			(xy 88.65345 -334.942259) (xy 88.711313 -334.881573) (xy 88.774683 -334.826663) (xy 88.842986 -334.778025)
			(xy 88.915603 -334.7361) (xy 88.991876 -334.701267) (xy 89.071115 -334.673842) (xy 89.152601 -334.654073)
			(xy 89.235598 -334.64214) (xy 89.319354 -334.638151) (xy 89.40311 -334.64214) (xy 89.486107 -334.654073)
			(xy 89.567593 -334.673842) (xy 89.646832 -334.701267) (xy 89.723105 -334.7361) (xy 89.795722 -334.778025)
			(xy 89.864025 -334.826663) (xy 89.927395 -334.881573) (xy 89.985258 -334.942259) (xy 90.037091 -335.00817)
			(xy 90.082424 -335.078709) (xy 90.120847 -335.153239) (xy 90.152011 -335.231083) (xy 90.175634 -335.311537)
			(xy 90.191503 -335.393872) (xy 90.199473 -335.477343) (xy 90.199972 -335.519268) (xy 90.199972 -335.52003)
			(xy 90.199408 -335.564694) (xy 90.190332 -335.653559) (xy 90.172298 -335.741047) (xy 90.145491 -335.826257)
			(xy 90.128344 -335.867502) (xy 90.124724 -335.877216) (xy 90.124712 -335.897925) (xy 90.128344 -335.907634)
			(xy 90.14352 -335.944017) (xy 90.168055 -336.018939) (xy 90.185802 -336.095753) (xy 90.196619 -336.173844)
			(xy 90.198956 -336.213196) (xy 90.198956 -336.21345) (xy 90.199799 -336.222253) (xy 90.206694 -336.238523)
			(xy 90.218709 -336.251482) (xy 90.226388 -336.255868) (xy 90.316812 -336.302604) (xy 90.343482 -336.301334)
			(xy 90.355166 -336.293968) (xy 90.390883 -336.271832) (xy 90.465707 -336.233583) (xy 90.543804 -336.20256)
			(xy 90.624479 -336.17904) (xy 90.707013 -336.163233) (xy 90.790669 -336.155279) (xy 90.832686 -336.154776)
			(xy 90.833194 -336.154776) (xy 90.874302 -336.155218) (xy 90.956167 -336.162803) (xy 91.036983 -336.177907)
			(xy 91.116061 -336.200402) (xy 91.192727 -336.230097) (xy 91.266326 -336.266738) (xy 91.336231 -336.310013)
			(xy 91.401845 -336.359552) (xy 91.46261 -336.414933) (xy 91.518006 -336.475684) (xy 91.567562 -336.541286)
			(xy 91.610854 -336.61118) (xy 91.647513 -336.68477) (xy 91.677227 -336.761428) (xy 91.699742 -336.840501)
			(xy 91.714867 -336.921313) (xy 91.722471 -337.003176) (xy 91.722641 -337.0176) (xy 95.263181 -337.0176)
			(xy 95.267171 -336.933842) (xy 95.279105 -336.850843) (xy 95.298874 -336.769354) (xy 95.3263 -336.690113)
			(xy 95.361135 -336.613839) (xy 95.403062 -336.541221) (xy 95.451703 -336.472917) (xy 95.506616 -336.409546)
			(xy 95.567304 -336.351683) (xy 95.633218 -336.29985) (xy 95.70376 -336.254517) (xy 95.778292 -336.216096)
			(xy 95.85614 -336.184933) (xy 95.936596 -336.161312) (xy 96.018934 -336.145445) (xy 96.102408 -336.137477)
			(xy 96.144334 -336.136996) (xy 96.14535 -336.136996) (xy 96.182407 -336.137387) (xy 96.256257 -336.143656)
			(xy 96.329319 -336.156102) (xy 96.401079 -336.174638) (xy 96.43618 -336.186526) (xy 96.444377 -336.18904)
			(xy 96.461511 -336.18904) (xy 96.469708 -336.186526) (xy 96.504897 -336.174599) (xy 96.576843 -336.15602)
			(xy 96.650101 -336.143577) (xy 96.724146 -336.137359) (xy 96.7613 -336.136996) (xy 96.761808 -336.136996)
			(xy 96.796352 -336.137504) (xy 96.805918 -336.09484) (xy 96.832381 -336.0115) (xy 96.849184 -335.971134)
			(xy 96.852845 -335.961431) (xy 96.852833 -335.940711) (xy 96.849184 -335.931002) (xy 96.832077 -335.889743)
			(xy 96.805286 -335.804532) (xy 96.78725 -335.717049) (xy 96.778153 -335.628191) (xy 96.777556 -335.58353)
			(xy 96.777556 -335.582768) (xy 96.778055 -335.540843) (xy 96.786025 -335.457372) (xy 96.801894 -335.375037)
			(xy 96.825517 -335.294583) (xy 96.856681 -335.216739) (xy 96.895104 -335.142209) (xy 96.940437 -335.07167)
			(xy 96.99227 -335.005759) (xy 97.050133 -334.945073) (xy 97.113503 -334.890163) (xy 97.181806 -334.841525)
			(xy 97.254423 -334.7996) (xy 97.330696 -334.764767) (xy 97.409935 -334.737342) (xy 97.491421 -334.717573)
			(xy 97.574418 -334.70564) (xy 97.658174 -334.701651) (xy 97.74193 -334.70564) (xy 97.824927 -334.717573)
			(xy 97.906413 -334.737342) (xy 97.985652 -334.764767) (xy 98.061925 -334.7996) (xy 98.134542 -334.841525)
			(xy 98.202845 -334.890163) (xy 98.266215 -334.945073) (xy 98.324078 -335.005759) (xy 98.375911 -335.07167)
			(xy 98.421244 -335.142209) (xy 98.459667 -335.216739) (xy 98.490831 -335.294583) (xy 98.514454 -335.375037)
			(xy 98.530323 -335.457372) (xy 98.538293 -335.540843) (xy 98.538792 -335.582768) (xy 98.538792 -335.58353)
			(xy 98.538226 -335.628194) (xy 98.529151 -335.717059) (xy 98.511117 -335.804547) (xy 98.484311 -335.889757)
			(xy 98.467164 -335.931002) (xy 98.463542 -335.940716) (xy 98.463531 -335.961426) (xy 98.467164 -335.971134)
			(xy 98.48433 -336.012473) (xy 98.511159 -336.097874) (xy 98.529194 -336.185554) (xy 98.538249 -336.27461)
			(xy 98.538792 -336.319368) (xy 98.538552 -336.350973) (xy 98.534101 -336.414026) (xy 98.529902 -336.445352)
			(xy 98.528378 -336.45602) (xy 98.53422 -336.477102) (xy 98.590608 -336.543396) (xy 98.597904 -336.55118)
			(xy 98.617064 -336.560504) (xy 98.627692 -336.56143) (xy 98.6282 -336.56143) (xy 98.671147 -336.563026)
			(xy 98.756458 -336.573467) (xy 98.840365 -336.592088) (xy 98.922084 -336.618714) (xy 99.000854 -336.653099)
			(xy 99.07594 -336.69492) (xy 99.146643 -336.743788) (xy 99.212303 -336.799248) (xy 99.272307 -336.860782)
			(xy 99.326097 -336.927817) (xy 99.362614 -336.9836) (xy 318.155561 -336.9836) (xy 318.15955 -336.899842)
			(xy 318.171484 -336.816843) (xy 318.191253 -336.735354) (xy 318.218678 -336.656114) (xy 318.253512 -336.579839)
			(xy 318.295438 -336.50722) (xy 318.344078 -336.438916) (xy 318.398989 -336.375544) (xy 318.459676 -336.317679)
			(xy 318.525589 -336.265845) (xy 318.59613 -336.220511) (xy 318.670661 -336.182087) (xy 318.748507 -336.150922)
			(xy 318.828963 -336.127298) (xy 318.911301 -336.111429) (xy 318.994774 -336.103459) (xy 319.0367 -336.10296)
			(xy 319.037716 -336.10296) (xy 319.074773 -336.103363) (xy 319.148622 -336.109628) (xy 319.221685 -336.122071)
			(xy 319.293445 -336.140604) (xy 319.328546 -336.15249) (xy 319.336743 -336.155004) (xy 319.353877 -336.155004)
			(xy 319.362074 -336.15249) (xy 319.397267 -336.140575) (xy 319.469212 -336.121992) (xy 319.542468 -336.109546)
			(xy 319.616513 -336.103324) (xy 319.653666 -336.10296) (xy 319.654174 -336.10296) (xy 319.681606 -336.103214)
			(xy 319.687655 -336.066844) (xy 319.704988 -335.995173) (xy 319.728195 -335.925184) (xy 319.742312 -335.891124)
			(xy 319.745871 -335.881532) (xy 319.745875 -335.86109) (xy 319.742312 -335.8515) (xy 319.725303 -335.810117)
			(xy 319.698681 -335.724692) (xy 319.680772 -335.637026) (xy 319.671759 -335.548004) (xy 319.671192 -335.503266)
			(xy 319.671192 -335.503012) (xy 319.671696 -335.460664) (xy 319.679747 -335.37635) (xy 319.695776 -335.293184)
			(xy 319.719637 -335.211917) (xy 319.751116 -335.133287) (xy 319.789927 -335.058006) (xy 319.835717 -334.986754)
			(xy 319.888073 -334.920178) (xy 319.946521 -334.85888) (xy 320.010531 -334.803415) (xy 320.079523 -334.754286)
			(xy 320.152873 -334.711937) (xy 320.229916 -334.676753) (xy 320.309955 -334.649051) (xy 320.392264 -334.629083)
			(xy 320.476099 -334.61703) (xy 320.5607 -334.613) (xy 320.645301 -334.61703) (xy 320.729136 -334.629083)
			(xy 320.811445 -334.649051) (xy 320.891484 -334.676753) (xy 320.968527 -334.711937) (xy 321.041877 -334.754286)
			(xy 321.110869 -334.803415) (xy 321.174879 -334.85888) (xy 321.233327 -334.920178) (xy 321.285683 -334.986754)
			(xy 321.331473 -335.058006) (xy 321.370284 -335.133287) (xy 321.401763 -335.211917) (xy 321.425624 -335.293184)
			(xy 321.441653 -335.37635) (xy 321.449704 -335.460664) (xy 321.450208 -335.503012) (xy 321.450208 -335.503266)
			(xy 321.449645 -335.548004) (xy 321.440627 -335.637026) (xy 321.422721 -335.724694) (xy 321.396107 -335.810121)
			(xy 321.379088 -335.8515) (xy 321.375596 -335.861115) (xy 321.37573 -335.881553) (xy 321.379342 -335.891124)
			(xy 321.395061 -335.929255) (xy 321.42019 -336.007817) (xy 321.437947 -336.088366) (xy 321.448179 -336.170212)
			(xy 321.449954 -336.211418) (xy 321.450208 -336.22488) (xy 321.464178 -336.24774) (xy 321.564762 -336.303112)
			(xy 321.591432 -336.302604) (xy 321.603116 -336.295746) (xy 321.637431 -336.275914) (xy 321.708951 -336.241747)
			(xy 321.783227 -336.214078) (xy 321.859671 -336.193127) (xy 321.937675 -336.179058) (xy 322.016621 -336.171985)
			(xy 322.056252 -336.17154) (xy 322.05676 -336.17154) (xy 322.097864 -336.17199) (xy 322.179721 -336.179572)
			(xy 322.26053 -336.194675) (xy 322.3396 -336.21717) (xy 322.416257 -336.246866) (xy 322.489847 -336.283508)
			(xy 322.559742 -336.326784) (xy 322.625346 -336.376325) (xy 322.686098 -336.431708) (xy 322.74148 -336.492461)
			(xy 322.791021 -336.558064) (xy 322.834296 -336.62796) (xy 322.870938 -336.70155) (xy 322.900632 -336.778207)
			(xy 322.923127 -336.857278) (xy 322.938229 -336.938087) (xy 322.941787 -336.9765) (xy 326.511148 -336.9765)
			(xy 326.515138 -336.892742) (xy 326.527072 -336.809743) (xy 326.546841 -336.728254) (xy 326.574266 -336.649013)
			(xy 326.609099 -336.572737) (xy 326.651025 -336.500118) (xy 326.699664 -336.431814) (xy 326.754575 -336.368441)
			(xy 326.815262 -336.310576) (xy 326.881174 -336.258741) (xy 326.951715 -336.213406) (xy 327.026246 -336.174981)
			(xy 327.104092 -336.143815) (xy 327.184547 -336.12019) (xy 327.266885 -336.104319) (xy 327.350358 -336.096347)
			(xy 327.392284 -336.095848) (xy 327.3933 -336.095848) (xy 327.430357 -336.096256) (xy 327.504206 -336.10252)
			(xy 327.577268 -336.114961) (xy 327.649028 -336.133493) (xy 327.68413 -336.145378) (xy 327.692327 -336.147892)
			(xy 327.709461 -336.147892) (xy 327.717658 -336.145378) (xy 327.752881 -336.133453) (xy 327.824889 -336.114861)
			(xy 327.898209 -336.102415) (xy 327.972319 -336.096203) (xy 328.009504 -336.095848) (xy 328.043286 -336.096356)
			(xy 328.05281 -336.047304) (xy 328.081456 -335.951571) (xy 328.100436 -335.905348) (xy 328.10398 -335.895751)
			(xy 328.103994 -335.875314) (xy 328.100436 -335.865724) (xy 328.083404 -335.82435) (xy 328.056787 -335.738922)
			(xy 328.038886 -335.651253) (xy 328.02988 -335.562229) (xy 328.029316 -335.51749) (xy 328.029316 -335.517236)
			(xy 328.02982 -335.474888) (xy 328.037871 -335.390574) (xy 328.0539 -335.307408) (xy 328.077761 -335.226141)
			(xy 328.10924 -335.147511) (xy 328.148051 -335.07223) (xy 328.193841 -335.000978) (xy 328.246197 -334.934402)
			(xy 328.304645 -334.873104) (xy 328.368655 -334.817639) (xy 328.437647 -334.76851) (xy 328.510997 -334.726161)
			(xy 328.58804 -334.690977) (xy 328.668079 -334.663275) (xy 328.750388 -334.643307) (xy 328.834223 -334.631254)
			(xy 328.918824 -334.627224) (xy 329.003425 -334.631254) (xy 329.08726 -334.643307) (xy 329.169569 -334.663275)
			(xy 329.249608 -334.690977) (xy 329.326651 -334.726161) (xy 329.400001 -334.76851) (xy 329.468993 -334.817639)
			(xy 329.533003 -334.873104) (xy 329.591451 -334.934402) (xy 329.643807 -335.000978) (xy 329.689597 -335.07223)
			(xy 329.728408 -335.147511) (xy 329.759887 -335.226141) (xy 329.783748 -335.307408) (xy 329.799777 -335.390574)
			(xy 329.807828 -335.474888) (xy 329.808332 -335.517236) (xy 329.808332 -335.51749) (xy 329.807775 -335.562229)
			(xy 329.798756 -335.651251) (xy 329.780848 -335.738918) (xy 329.754231 -335.824345) (xy 329.737212 -335.865724)
			(xy 329.733624 -335.875308) (xy 329.733638 -335.895757) (xy 329.737212 -335.905348) (xy 329.752022 -335.941175)
			(xy 329.776095 -336.014872) (xy 329.793653 -336.090386) (xy 329.804563 -336.167144) (xy 329.807062 -336.20583)
			(xy 329.807824 -336.219038) (xy 329.822048 -336.24139) (xy 329.91044 -336.288888) (xy 329.918254 -336.292745)
			(xy 329.93547 -336.295369) (xy 329.95256 -336.292022) (xy 329.960224 -336.287872) (xy 329.994483 -336.268147)
			(xy 330.065868 -336.23417) (xy 330.139986 -336.206662) (xy 330.216254 -336.18584) (xy 330.294068 -336.171868)
			(xy 330.372815 -336.164856) (xy 330.412344 -336.164428) (xy 330.453448 -336.164825) (xy 330.535306 -336.172414)
			(xy 330.616114 -336.187524) (xy 330.695183 -336.210025) (xy 330.771839 -336.239726) (xy 330.845427 -336.276373)
			(xy 330.91532 -336.319653) (xy 330.980922 -336.369198) (xy 331.041672 -336.424584) (xy 331.097053 -336.48534)
			(xy 331.146592 -336.550946) (xy 331.189866 -336.620843) (xy 331.226507 -336.694434) (xy 331.256201 -336.771093)
			(xy 331.278695 -336.850164) (xy 331.293797 -336.930973) (xy 331.296671 -336.962) (xy 334.868517 -336.962)
			(xy 334.872507 -336.878219) (xy 334.884444 -336.795197) (xy 334.904219 -336.713686) (xy 334.931652 -336.634423)
			(xy 334.966495 -336.558127) (xy 335.008433 -336.485488) (xy 335.057086 -336.417165) (xy 335.112013 -336.353776)
			(xy 335.172717 -336.295895) (xy 335.238647 -336.244046) (xy 335.309208 -336.198699) (xy 335.38376 -336.160265)
			(xy 335.461628 -336.129092) (xy 335.542106 -336.105461) (xy 335.624466 -336.089588) (xy 335.707962 -336.081615)
			(xy 335.7499 -336.081116) (xy 335.78709 -336.081504) (xy 335.861203 -336.087794) (xy 335.934522 -336.100304)
			(xy 336.006528 -336.118945) (xy 336.041746 -336.1309) (xy 336.049943 -336.133414) (xy 336.067077 -336.133414)
			(xy 336.075274 -336.1309) (xy 336.110487 -336.118927) (xy 336.182491 -336.100276) (xy 336.255813 -336.08777)
			(xy 336.329929 -336.0815) (xy 336.36712 -336.081116) (xy 336.407506 -336.082132) (xy 336.417036 -336.036786)
			(xy 336.444265 -335.948213) (xy 336.461862 -335.905348) (xy 336.465474 -335.895775) (xy 336.465619 -335.875336)
			(xy 336.462116 -335.865724) (xy 336.445083 -335.824351) (xy 336.418467 -335.738922) (xy 336.400565 -335.651253)
			(xy 336.39156 -335.562229) (xy 336.390996 -335.51749) (xy 336.390996 -335.517236) (xy 336.3915 -335.474888)
			(xy 336.399551 -335.390574) (xy 336.41558 -335.307408) (xy 336.439441 -335.226141) (xy 336.47092 -335.147511)
			(xy 336.509731 -335.07223) (xy 336.555521 -335.000978) (xy 336.607877 -334.934402) (xy 336.666325 -334.873104)
			(xy 336.730335 -334.817639) (xy 336.799327 -334.76851) (xy 336.872677 -334.726161) (xy 336.94972 -334.690977)
			(xy 337.029759 -334.663275) (xy 337.112068 -334.643307) (xy 337.195903 -334.631254) (xy 337.280504 -334.627224)
			(xy 337.365105 -334.631254) (xy 337.44894 -334.643307) (xy 337.531249 -334.663275) (xy 337.611288 -334.690977)
			(xy 337.688331 -334.726161) (xy 337.761681 -334.76851) (xy 337.830673 -334.817639) (xy 337.894683 -334.873104)
			(xy 337.953131 -334.934402) (xy 338.005487 -335.000978) (xy 338.051277 -335.07223) (xy 338.090088 -335.147511)
			(xy 338.121567 -335.226141) (xy 338.145428 -335.307408) (xy 338.161457 -335.390574) (xy 338.169508 -335.474888)
			(xy 338.170012 -335.517236) (xy 338.170012 -335.51749) (xy 338.169456 -335.562229) (xy 338.160437 -335.651251)
			(xy 338.142528 -335.738918) (xy 338.115912 -335.824345) (xy 338.098892 -335.865724) (xy 338.095386 -335.875335)
			(xy 338.09553 -335.895777) (xy 338.099146 -335.905348) (xy 338.117792 -335.95091) (xy 338.146101 -336.045203)
			(xy 338.163844 -336.142042) (xy 338.16798 -336.191098) (xy 338.168919 -336.199672) (xy 338.175759 -336.215494)
			(xy 338.187449 -336.228161) (xy 338.194904 -336.2325) (xy 338.283042 -336.278728) (xy 338.309204 -336.27822)
			(xy 338.320634 -336.271616) (xy 338.354723 -336.252133) (xy 338.425722 -336.218592) (xy 338.499399 -336.191437)
			(xy 338.575183 -336.170878) (xy 338.652483 -336.157075) (xy 338.730699 -336.150137) (xy 338.76996 -336.149696)
			(xy 338.81107 -336.150191) (xy 338.89294 -336.157775) (xy 338.97376 -336.172882) (xy 339.052841 -336.195384)
			(xy 339.129508 -336.225088) (xy 339.203107 -336.261741) (xy 339.273008 -336.305029) (xy 339.338617 -336.354584)
			(xy 339.399372 -336.409982) (xy 339.454755 -336.470751) (xy 339.504294 -336.536372) (xy 339.547565 -336.606284)
			(xy 339.5842 -336.679891) (xy 339.613885 -336.756566) (xy 339.636368 -336.835652) (xy 339.651455 -336.916476)
			(xy 339.659019 -336.998348) (xy 339.659177 -337.0128) (xy 343.199717 -337.0128) (xy 343.203707 -336.929019)
			(xy 343.215644 -336.845997) (xy 343.235419 -336.764486) (xy 343.262852 -336.685223) (xy 343.297695 -336.608927)
			(xy 343.339633 -336.536288) (xy 343.388286 -336.467965) (xy 343.443213 -336.404576) (xy 343.503917 -336.346695)
			(xy 343.569847 -336.294846) (xy 343.640408 -336.249499) (xy 343.71496 -336.211065) (xy 343.792828 -336.179892)
			(xy 343.873306 -336.156261) (xy 343.955666 -336.140388) (xy 344.039162 -336.132415) (xy 344.0811 -336.131916)
			(xy 344.11829 -336.132304) (xy 344.192403 -336.138594) (xy 344.265722 -336.151104) (xy 344.337728 -336.169745)
			(xy 344.372946 -336.1817) (xy 344.381143 -336.184214) (xy 344.398277 -336.184214) (xy 344.406474 -336.1817)
			(xy 344.441687 -336.169727) (xy 344.513691 -336.151076) (xy 344.587013 -336.13857) (xy 344.661129 -336.1323)
			(xy 344.69832 -336.131916) (xy 344.712798 -336.13217) (xy 344.724169 -336.131792) (xy 344.744841 -336.122355)
			(xy 344.759419 -336.104924) (xy 344.762836 -336.09407) (xy 344.771457 -336.062103) (xy 344.792812 -335.999426)
			(xy 344.805508 -335.968848) (xy 344.809054 -335.959252) (xy 344.809067 -335.938814) (xy 344.805508 -335.929224)
			(xy 344.788475 -335.887851) (xy 344.761859 -335.802423) (xy 344.743957 -335.714753) (xy 344.734952 -335.625729)
			(xy 344.734388 -335.58099) (xy 344.734388 -335.580736) (xy 344.734892 -335.538388) (xy 344.742943 -335.454074)
			(xy 344.758972 -335.370908) (xy 344.782833 -335.289641) (xy 344.814312 -335.211011) (xy 344.853123 -335.13573)
			(xy 344.898913 -335.064478) (xy 344.951269 -334.997902) (xy 345.009717 -334.936604) (xy 345.073727 -334.881139)
			(xy 345.142719 -334.83201) (xy 345.216069 -334.789661) (xy 345.293112 -334.754477) (xy 345.373151 -334.726775)
			(xy 345.45546 -334.706807) (xy 345.539295 -334.694754) (xy 345.623896 -334.690724) (xy 345.708497 -334.694754)
			(xy 345.792332 -334.706807) (xy 345.874641 -334.726775) (xy 345.95468 -334.754477) (xy 346.031723 -334.789661)
			(xy 346.105073 -334.83201) (xy 346.174065 -334.881139) (xy 346.238075 -334.936604) (xy 346.296523 -334.997902)
			(xy 346.348879 -335.064478) (xy 346.394669 -335.13573) (xy 346.43348 -335.211011) (xy 346.464959 -335.289641)
			(xy 346.48882 -335.370908) (xy 346.504849 -335.454074) (xy 346.5129 -335.538388) (xy 346.513404 -335.580736)
			(xy 346.513404 -335.58099) (xy 346.512849 -335.625729) (xy 346.50383 -335.714751) (xy 346.485921 -335.802418)
			(xy 346.459304 -335.887845) (xy 346.442284 -335.929224) (xy 346.438698 -335.938808) (xy 346.438711 -335.959257)
			(xy 346.442284 -335.968848) (xy 346.459319 -336.010255) (xy 346.48595 -336.095744) (xy 346.503854 -336.183477)
			(xy 346.51285 -336.272565) (xy 346.513404 -336.317336) (xy 346.513182 -336.348682) (xy 346.508857 -336.411225)
			(xy 346.504768 -336.442304) (xy 346.503244 -336.452972) (xy 346.508832 -336.473546) (xy 346.56268 -336.539586)
			(xy 346.569651 -336.547336) (xy 346.588142 -336.55691) (xy 346.598494 -336.558128) (xy 346.599002 -336.558128)
			(xy 346.640786 -336.561293) (xy 346.723543 -336.574476) (xy 346.804694 -336.595383) (xy 346.883519 -336.62383)
			(xy 346.959319 -336.659564) (xy 347.031422 -336.702268) (xy 347.09919 -336.751564) (xy 347.162022 -336.807015)
			(xy 347.21936 -336.868129) (xy 347.270696 -336.934365) (xy 347.315576 -337.005135) (xy 347.353601 -337.079812)
			(xy 347.384434 -337.157734) (xy 347.407802 -337.238211) (xy 347.423499 -337.320529) (xy 347.431384 -337.403958)
			(xy 347.431868 -337.445858) (xy 347.431868 -337.446874) (xy 347.431339 -337.489485) (xy 347.423121 -337.57431)
			(xy 347.406824 -337.657959) (xy 347.382599 -337.739665) (xy 347.367098 -337.77936) (xy 347.363634 -337.789438)
			(xy 347.36443 -337.810709) (xy 347.368622 -337.820508) (xy 347.385666 -337.856788) (xy 347.413917 -337.931808)
			(xy 347.435302 -338.009067) (xy 347.449648 -338.087936) (xy 347.456838 -338.167776) (xy 347.457268 -338.207858)
			(xy 347.456674 -338.254253) (xy 347.447033 -338.346541) (xy 347.42784 -338.437325) (xy 347.399305 -338.525619)
			(xy 347.381068 -338.568284) (xy 347.377284 -338.578233) (xy 347.377268 -338.599491) (xy 347.381068 -338.609432)
			(xy 347.399296 -338.652101) (xy 347.427845 -338.740391) (xy 347.447043 -338.831174) (xy 347.456681 -338.923462)
			(xy 347.457268 -338.969858) (xy 347.456674 -339.016253) (xy 347.447033 -339.108541) (xy 347.42784 -339.199325)
			(xy 347.399305 -339.287619) (xy 347.381068 -339.330284) (xy 347.377284 -339.340233) (xy 347.377268 -339.361491)
			(xy 347.381068 -339.371432) (xy 347.39928 -339.414039) (xy 347.427799 -339.502205) (xy 347.446995 -339.592859)
			(xy 347.456658 -339.685018) (xy 347.457268 -339.73135) (xy 347.457268 -339.731858) (xy 347.456747 -339.772964)
			(xy 347.449167 -339.854825) (xy 347.434067 -339.935639) (xy 347.411576 -340.014714) (xy 347.381885 -340.091377)
			(xy 347.345249 -340.164975) (xy 347.30198 -340.234878) (xy 347.252446 -340.300492) (xy 347.19707 -340.361256)
			(xy 347.136324 -340.416653) (xy 347.070727 -340.466209) (xy 347.000838 -340.509502) (xy 346.927254 -340.546163)
			(xy 346.8506 -340.575879) (xy 346.771533 -340.598397) (xy 346.690725 -340.613525) (xy 346.608866 -340.621133)
			(xy 346.56776 -340.62162) (xy 346.525159 -340.621134) (xy 346.440349 -340.612975) (xy 346.356708 -340.596745)
			(xy 346.275001 -340.572593) (xy 346.195978 -340.540739) (xy 346.120362 -340.501477) (xy 346.048846 -340.455165)
			(xy 345.982085 -340.402229) (xy 345.920691 -340.343152) (xy 345.865226 -340.278476) (xy 345.840304 -340.243922)
			(xy 345.834713 -340.236567) (xy 345.819465 -340.226159) (xy 345.810586 -340.223602) (xy 345.769427 -340.213207)
			(xy 345.689122 -340.185668) (xy 345.611806 -340.150603) (xy 345.538183 -340.108332) (xy 345.468921 -340.05924)
			(xy 345.40465 -340.003772) (xy 345.345957 -339.942434) (xy 345.293373 -339.875784) (xy 345.247379 -339.804427)
			(xy 345.208391 -339.729013) (xy 345.176765 -339.650228) (xy 345.152789 -339.568788) (xy 345.136679 -339.485435)
			(xy 345.128584 -339.400926) (xy 345.128088 -339.358478) (xy 345.128088 -339.358224) (xy 345.128648 -339.313485)
			(xy 345.137666 -339.224464) (xy 345.155574 -339.136796) (xy 345.182189 -339.051369) (xy 345.199208 -339.00999)
			(xy 345.202787 -339.000403) (xy 345.202779 -338.979957) (xy 345.199208 -338.970366) (xy 345.182177 -338.928958)
			(xy 345.155545 -338.843469) (xy 345.13764 -338.755736) (xy 345.128642 -338.666649) (xy 345.128088 -338.621878)
			(xy 345.128637 -338.577108) (xy 345.137642 -338.488021) (xy 345.15555 -338.400289) (xy 345.182178 -338.314799)
			(xy 345.199208 -338.27339) (xy 345.202787 -338.263803) (xy 345.202779 -338.243357) (xy 345.199208 -338.233766)
			(xy 345.182177 -338.192358) (xy 345.155545 -338.106869) (xy 345.13764 -338.019136) (xy 345.128642 -337.930049)
			(xy 345.128088 -337.885278) (xy 345.128088 -337.87334) (xy 345.101609 -337.867394) (xy 345.049374 -337.852651)
			(xy 345.023694 -337.843876) (xy 345.015497 -337.841362) (xy 344.998363 -337.841362) (xy 344.990166 -337.843876)
			(xy 344.95495 -337.855837) (xy 344.882946 -337.874492) (xy 344.809626 -337.887) (xy 344.73551 -337.893274)
			(xy 344.69832 -337.89366) (xy 344.661131 -337.893262) (xy 344.587018 -337.886974) (xy 344.513698 -337.874467)
			(xy 344.441692 -337.855829) (xy 344.406474 -337.843876) (xy 344.398277 -337.841362) (xy 344.381143 -337.841362)
			(xy 344.372946 -337.843876) (xy 344.337731 -337.855842) (xy 344.265728 -337.874496) (xy 344.192406 -337.887003)
			(xy 344.11829 -337.893275) (xy 344.0811 -337.89366) (xy 344.039162 -337.893185) (xy 343.955666 -337.885212)
			(xy 343.873306 -337.869339) (xy 343.792828 -337.845708) (xy 343.71496 -337.814535) (xy 343.640408 -337.776101)
			(xy 343.569847 -337.730754) (xy 343.503917 -337.678905) (xy 343.443213 -337.621024) (xy 343.388286 -337.557635)
			(xy 343.339633 -337.489312) (xy 343.297695 -337.416673) (xy 343.262852 -337.340377) (xy 343.235419 -337.261114)
			(xy 343.215644 -337.179603) (xy 343.203707 -337.096581) (xy 343.199717 -337.0128) (xy 339.659177 -337.0128)
			(xy 339.659468 -337.039458) (xy 339.6589 -337.084228) (xy 339.649901 -337.173314) (xy 339.631999 -337.261046)
			(xy 339.605375 -337.346537) (xy 339.588348 -337.387946) (xy 339.584808 -337.397544) (xy 339.584792 -337.41798)
			(xy 339.588348 -337.42757) (xy 339.605388 -337.468975) (xy 339.632018 -337.554465) (xy 339.649921 -337.642198)
			(xy 339.658915 -337.731287) (xy 339.659468 -337.776058) (xy 339.6589 -337.820828) (xy 339.649901 -337.909914)
			(xy 339.631999 -337.997646) (xy 339.605375 -338.083137) (xy 339.588348 -338.124546) (xy 339.584808 -338.134144)
			(xy 339.584792 -338.15458) (xy 339.588348 -338.16417) (xy 339.605377 -338.205545) (xy 339.631995 -338.290972)
			(xy 339.649897 -338.378641) (xy 339.658904 -338.467665) (xy 339.659468 -338.512404) (xy 339.659468 -338.512658)
			(xy 339.658947 -338.553764) (xy 339.651367 -338.635625) (xy 339.636267 -338.716439) (xy 339.613776 -338.795514)
			(xy 339.584085 -338.872177) (xy 339.547449 -338.945775) (xy 339.50418 -339.015678) (xy 339.454646 -339.081292)
			(xy 339.39927 -339.142056) (xy 339.338524 -339.197453) (xy 339.272927 -339.247009) (xy 339.203038 -339.290302)
			(xy 339.129454 -339.326963) (xy 339.0528 -339.356679) (xy 338.973733 -339.379197) (xy 338.892925 -339.394325)
			(xy 338.811066 -339.401933) (xy 338.76996 -339.40242) (xy 338.728351 -339.40191) (xy 338.645495 -339.394139)
			(xy 338.563727 -339.378669) (xy 338.483759 -339.355636) (xy 338.40629 -339.325239) (xy 338.331996 -339.287745)
			(xy 338.296504 -339.266022) (xy 338.287367 -339.260856) (xy 338.26665 -339.257639) (xy 338.246374 -339.262975)
			(xy 338.23783 -339.26907) (xy 338.204174 -339.295024) (xy 338.132784 -339.341153) (xy 338.057318 -339.380258)
			(xy 337.978465 -339.411983) (xy 337.896945 -339.436039) (xy 337.8135 -339.452205) (xy 337.728894 -339.460335)
			(xy 337.686396 -339.46084) (xy 337.645286 -339.460351) (xy 337.563418 -339.452764) (xy 337.482599 -339.437653)
			(xy 337.403519 -339.415149) (xy 337.326853 -339.385443) (xy 337.253256 -339.348789) (xy 337.183356 -339.3055)
			(xy 337.117748 -339.255944) (xy 337.056994 -339.200546) (xy 337.001611 -339.139778) (xy 336.952073 -339.074158)
			(xy 336.908801 -339.004246) (xy 336.872166 -338.93064) (xy 336.842479 -338.853967) (xy 336.819995 -338.774881)
			(xy 336.804905 -338.694058) (xy 336.797338 -338.612188) (xy 336.796888 -338.571078) (xy 336.797437 -338.526308)
			(xy 336.806442 -338.437221) (xy 336.82435 -338.349489) (xy 336.850978 -338.263999) (xy 336.868008 -338.22259)
			(xy 336.871587 -338.213003) (xy 336.871579 -338.192557) (xy 336.868008 -338.182966) (xy 336.850977 -338.141558)
			(xy 336.824345 -338.056069) (xy 336.80644 -337.968336) (xy 336.797442 -337.879249) (xy 336.796888 -337.834478)
			(xy 336.796888 -337.82254) (xy 336.770409 -337.816594) (xy 336.718174 -337.801851) (xy 336.692494 -337.793076)
			(xy 336.684297 -337.790562) (xy 336.667163 -337.790562) (xy 336.658966 -337.793076) (xy 336.62375 -337.805037)
			(xy 336.551746 -337.823692) (xy 336.478426 -337.8362) (xy 336.40431 -337.842474) (xy 336.36712 -337.84286)
			(xy 336.329931 -337.842462) (xy 336.255818 -337.836174) (xy 336.182498 -337.823667) (xy 336.110492 -337.805029)
			(xy 336.075274 -337.793076) (xy 336.067077 -337.790562) (xy 336.049943 -337.790562) (xy 336.041746 -337.793076)
			(xy 336.006531 -337.805042) (xy 335.934528 -337.823696) (xy 335.861206 -337.836203) (xy 335.78709 -337.842475)
			(xy 335.7499 -337.84286) (xy 335.707962 -337.842385) (xy 335.624466 -337.834412) (xy 335.542106 -337.818539)
			(xy 335.461628 -337.794908) (xy 335.38376 -337.763735) (xy 335.309208 -337.725301) (xy 335.238647 -337.679954)
			(xy 335.172717 -337.628105) (xy 335.112013 -337.570224) (xy 335.057086 -337.506835) (xy 335.008433 -337.438512)
			(xy 334.966495 -337.365873) (xy 334.931652 -337.289577) (xy 334.904219 -337.210314) (xy 334.884444 -337.128803)
			(xy 334.872507 -337.045781) (xy 334.868517 -336.962) (xy 331.296671 -336.962) (xy 331.301379 -337.012832)
			(xy 331.301852 -337.053936) (xy 331.301852 -337.05419) (xy 331.301293 -337.098929) (xy 331.292274 -337.18795)
			(xy 331.274367 -337.275618) (xy 331.247751 -337.361045) (xy 331.230732 -337.402424) (xy 331.227148 -337.412009)
			(xy 331.227161 -337.432457) (xy 331.230732 -337.442048) (xy 331.247764 -337.483456) (xy 331.274397 -337.568945)
			(xy 331.292302 -337.656677) (xy 331.301298 -337.745765) (xy 331.301852 -337.790536) (xy 331.301312 -337.835307)
			(xy 331.292305 -337.924394) (xy 331.274395 -338.012126) (xy 331.247763 -338.097615) (xy 331.230732 -338.139024)
			(xy 331.227148 -338.148609) (xy 331.227161 -338.169057) (xy 331.230732 -338.178648) (xy 331.247759 -338.220024)
			(xy 331.274376 -338.305451) (xy 331.292279 -338.39312) (xy 331.301287 -338.482143) (xy 331.301852 -338.526882)
			(xy 331.301852 -338.527136) (xy 331.301368 -338.568238) (xy 331.29378 -338.65009) (xy 331.278673 -338.730894)
			(xy 331.256175 -338.809959) (xy 331.226478 -338.886611) (xy 331.189836 -338.960196) (xy 331.14656 -339.030087)
			(xy 331.097021 -339.095686) (xy 331.041641 -339.156436) (xy 330.980892 -339.211816) (xy 330.915293 -339.261356)
			(xy 330.845403 -339.304632) (xy 330.771818 -339.341275) (xy 330.695167 -339.370972) (xy 330.616102 -339.393471)
			(xy 330.535298 -339.408579) (xy 330.453446 -339.416167) (xy 330.412344 -339.416644) (xy 330.411582 -339.416644)
			(xy 330.370042 -339.416142) (xy 330.287326 -339.408361) (xy 330.205695 -339.392907) (xy 330.125859 -339.369913)
			(xy 330.048513 -339.339581) (xy 329.97433 -339.302172) (xy 329.938888 -339.2805) (xy 329.929757 -339.275322)
			(xy 329.909036 -339.272112) (xy 329.888759 -339.277452) (xy 329.880214 -339.283548) (xy 329.846565 -339.30947)
			(xy 329.775191 -339.355528) (xy 329.699752 -339.394575) (xy 329.620935 -339.426254) (xy 329.539458 -339.450278)
			(xy 329.456062 -339.466427) (xy 329.371506 -339.474554) (xy 329.329034 -339.475064) (xy 329.32878 -339.475064)
			(xy 329.287675 -339.474667) (xy 329.205817 -339.46708) (xy 329.125007 -339.451972) (xy 329.045936 -339.429472)
			(xy 328.969279 -339.399772) (xy 328.895689 -339.363126) (xy 328.825795 -339.319846) (xy 328.760192 -339.270301)
			(xy 328.69944 -339.214915) (xy 328.644058 -339.154159) (xy 328.594518 -339.088553) (xy 328.551243 -339.018655)
			(xy 328.514602 -338.945062) (xy 328.484908 -338.868403) (xy 328.462414 -338.789331) (xy 328.447312 -338.70852)
			(xy 328.43973 -338.626661) (xy 328.439272 -338.585556) (xy 328.439272 -338.585302) (xy 328.43986 -338.540564)
			(xy 328.44887 -338.451543) (xy 328.466769 -338.363876) (xy 328.493377 -338.278448) (xy 328.510392 -338.237068)
			(xy 328.513984 -338.227485) (xy 328.513968 -338.207035) (xy 328.510392 -338.197444) (xy 328.493353 -338.156039)
			(xy 328.466723 -338.070549) (xy 328.44882 -337.982815) (xy 328.439825 -337.893727) (xy 328.439272 -337.848956)
			(xy 328.439272 -337.837018) (xy 328.412793 -337.831074) (xy 328.360558 -337.81633) (xy 328.334878 -337.807554)
			(xy 328.326681 -337.80504) (xy 328.309547 -337.80504) (xy 328.30135 -337.807554) (xy 328.266125 -337.819474)
			(xy 328.194118 -337.838068) (xy 328.120798 -337.850516) (xy 328.046689 -337.856728) (xy 328.009504 -337.857084)
			(xy 327.97232 -337.856715) (xy 327.898212 -337.850493) (xy 327.824892 -337.838051) (xy 327.752881 -337.819476)
			(xy 327.717658 -337.807554) (xy 327.709461 -337.80504) (xy 327.692327 -337.80504) (xy 327.68413 -337.807554)
			(xy 327.649029 -337.819442) (xy 327.577272 -337.837992) (xy 327.504209 -337.850438) (xy 327.430358 -337.856691)
			(xy 327.3933 -337.857084) (xy 327.392284 -337.857084) (xy 327.350358 -337.856653) (xy 327.266885 -337.848681)
			(xy 327.184547 -337.83281) (xy 327.104092 -337.809185) (xy 327.026246 -337.778019) (xy 326.951715 -337.739594)
			(xy 326.881174 -337.694259) (xy 326.815262 -337.642424) (xy 326.754575 -337.584559) (xy 326.699664 -337.521186)
			(xy 326.651025 -337.452882) (xy 326.609099 -337.380263) (xy 326.574266 -337.303987) (xy 326.546841 -337.224746)
			(xy 326.527072 -337.143257) (xy 326.515138 -337.060258) (xy 326.511148 -336.9765) (xy 322.941787 -336.9765)
			(xy 322.94581 -337.019944) (xy 322.946268 -337.061048) (xy 322.946268 -337.061302) (xy 322.945685 -337.10604)
			(xy 322.936674 -337.195061) (xy 322.918774 -337.282729) (xy 322.892164 -337.368156) (xy 322.875148 -337.409536)
			(xy 322.871556 -337.419119) (xy 322.871574 -337.439569) (xy 322.875148 -337.44916) (xy 322.892185 -337.490566)
			(xy 322.918816 -337.576056) (xy 322.93672 -337.663789) (xy 322.945715 -337.752877) (xy 322.946268 -337.797648)
			(xy 322.945697 -337.842418) (xy 322.936698 -337.931504) (xy 322.918797 -338.019236) (xy 322.892175 -338.104727)
			(xy 322.875148 -338.146136) (xy 322.871556 -338.155719) (xy 322.871574 -338.176169) (xy 322.875148 -338.18576)
			(xy 322.892174 -338.227136) (xy 322.918792 -338.312563) (xy 322.936696 -338.400232) (xy 322.945704 -338.489255)
			(xy 322.946268 -338.533994) (xy 322.946268 -338.534248) (xy 322.945879 -338.575352) (xy 322.938289 -338.65721)
			(xy 322.923179 -338.738019) (xy 322.900678 -338.817088) (xy 322.870976 -338.893744) (xy 322.834329 -338.967333)
			(xy 322.791048 -339.037226) (xy 322.741503 -339.102828) (xy 322.686116 -339.163578) (xy 322.62536 -339.218959)
			(xy 322.559753 -339.268498) (xy 322.489856 -339.311772) (xy 322.416264 -339.348412) (xy 322.339605 -339.378106)
			(xy 322.260533 -339.400599) (xy 322.179723 -339.415702) (xy 322.097864 -339.423283) (xy 322.05676 -339.423756)
			(xy 322.055998 -339.423756) (xy 322.014458 -339.423244) (xy 321.931742 -339.415465) (xy 321.850112 -339.400013)
			(xy 321.770276 -339.377021) (xy 321.69293 -339.34669) (xy 321.618746 -339.309284) (xy 321.583304 -339.287612)
			(xy 321.574167 -339.282447) (xy 321.55345 -339.279232) (xy 321.533175 -339.284566) (xy 321.52463 -339.29066)
			(xy 321.491012 -339.316622) (xy 321.419631 -339.362677) (xy 321.344187 -339.401718) (xy 321.265365 -339.433392)
			(xy 321.183883 -339.457409) (xy 321.100483 -339.47355) (xy 321.015924 -339.48167) (xy 320.97345 -339.482176)
			(xy 320.973196 -339.482176) (xy 320.932092 -339.481752) (xy 320.850234 -339.474166) (xy 320.769426 -339.459059)
			(xy 320.690356 -339.436561) (xy 320.613699 -339.406863) (xy 320.54011 -339.370219) (xy 320.470216 -339.326941)
			(xy 320.404613 -339.277398) (xy 320.343861 -339.222013) (xy 320.288479 -339.161259) (xy 320.238939 -339.095655)
			(xy 320.195664 -339.025759) (xy 320.159022 -338.952168) (xy 320.129327 -338.87551) (xy 320.106832 -338.796439)
			(xy 320.091729 -338.71563) (xy 320.084147 -338.633772) (xy 320.083688 -338.592668) (xy 320.083688 -338.592414)
			(xy 320.084245 -338.547675) (xy 320.093264 -338.458653) (xy 320.111172 -338.370986) (xy 320.137789 -338.285559)
			(xy 320.154808 -338.24418) (xy 320.158393 -338.234595) (xy 320.158381 -338.214147) (xy 320.154808 -338.204556)
			(xy 320.137774 -338.163149) (xy 320.111142 -338.07766) (xy 320.093238 -337.989927) (xy 320.084242 -337.900839)
			(xy 320.083688 -337.856068) (xy 320.083688 -337.84413) (xy 320.057209 -337.838184) (xy 320.004974 -337.823441)
			(xy 319.979294 -337.814666) (xy 319.971097 -337.812152) (xy 319.953963 -337.812152) (xy 319.945766 -337.814666)
			(xy 319.910549 -337.82661) (xy 319.838539 -337.845197) (xy 319.765217 -337.857638) (xy 319.691106 -337.863844)
			(xy 319.65392 -337.864196) (xy 319.616736 -337.863827) (xy 319.542628 -337.857606) (xy 319.469308 -337.845164)
			(xy 319.397297 -337.826589) (xy 319.362074 -337.814666) (xy 319.353877 -337.812152) (xy 319.336743 -337.812152)
			(xy 319.328546 -337.814666) (xy 319.293452 -337.826578) (xy 319.221693 -337.845121) (xy 319.148627 -337.85756)
			(xy 319.074774 -337.863807) (xy 319.037716 -337.864196) (xy 319.0367 -337.864196) (xy 318.994774 -337.863741)
			(xy 318.911301 -337.855771) (xy 318.828963 -337.839902) (xy 318.748507 -337.816278) (xy 318.670661 -337.785113)
			(xy 318.59613 -337.746689) (xy 318.525589 -337.701355) (xy 318.459676 -337.649521) (xy 318.398989 -337.591656)
			(xy 318.344078 -337.528284) (xy 318.295438 -337.45998) (xy 318.253512 -337.387361) (xy 318.218678 -337.311086)
			(xy 318.191253 -337.231846) (xy 318.171484 -337.150357) (xy 318.15955 -337.067358) (xy 318.155561 -336.9836)
			(xy 99.362614 -336.9836) (xy 99.373171 -336.999727) (xy 99.41309 -337.075842) (xy 99.445481 -337.155452)
			(xy 99.470043 -337.237815) (xy 99.486546 -337.322163) (xy 99.494837 -337.40771) (xy 99.495356 -337.450684)
			(xy 99.494854 -337.493421) (xy 99.48668 -337.578504) (xy 99.470386 -337.662411) (xy 99.446122 -337.744369)
			(xy 99.430586 -337.784186) (xy 99.426944 -337.794219) (xy 99.427619 -337.815536) (xy 99.431856 -337.825334)
			(xy 99.448914 -337.861614) (xy 99.477225 -337.936624) (xy 99.498666 -338.013878) (xy 99.513065 -338.092749)
			(xy 99.520304 -338.172597) (xy 99.520756 -338.212684) (xy 99.520272 -338.252763) (xy 99.512982 -338.33259)
			(xy 99.498549 -338.411439) (xy 99.488244 -338.450174) (xy 99.485843 -338.460698) (xy 99.489132 -338.482012)
			(xy 99.494594 -338.491322) (xy 99.517345 -338.52734) (xy 99.556637 -338.602937) (xy 99.588514 -338.681946)
			(xy 99.612684 -338.763644) (xy 99.628925 -338.847279) (xy 99.637089 -338.932085) (xy 99.637596 -338.974684)
			(xy 99.637001 -339.021087) (xy 99.627302 -339.113385) (xy 99.608039 -339.204171) (xy 99.579422 -339.292455)
			(xy 99.561142 -339.33511) (xy 99.557344 -339.345055) (xy 99.557338 -339.366316) (xy 99.561142 -339.376258)
			(xy 99.579397 -339.418922) (xy 99.607993 -339.507209) (xy 99.627252 -339.597991) (xy 99.636966 -339.690283)
			(xy 99.637596 -339.736684) (xy 99.637118 -339.777779) (xy 99.629538 -339.859619) (xy 99.614439 -339.94041)
			(xy 99.591952 -340.019465) (xy 99.562267 -340.096107) (xy 99.525639 -340.169684) (xy 99.482378 -340.239568)
			(xy 99.432856 -340.305164) (xy 99.377493 -340.36591) (xy 99.316762 -340.421291) (xy 99.251181 -340.470833)
			(xy 99.18131 -340.514113) (xy 99.107743 -340.550763) (xy 99.031109 -340.58047) (xy 98.952062 -340.60298)
			(xy 98.871275 -340.618102) (xy 98.789437 -340.625707) (xy 98.748342 -340.626192) (xy 98.747834 -340.626192)
			(xy 98.704859 -340.625663) (xy 98.619309 -340.617375) (xy 98.534957 -340.600874) (xy 98.45259 -340.576313)
			(xy 98.372977 -340.543922) (xy 98.296859 -340.504001) (xy 98.224947 -340.456925) (xy 98.157912 -340.403131)
			(xy 98.096378 -340.343122) (xy 98.040919 -340.277458) (xy 98.01606 -340.242398) (xy 98.010455 -340.235056)
			(xy 97.995216 -340.224641) (xy 97.986342 -340.222078) (xy 97.94544 -340.211492) (xy 97.865683 -340.183605)
			(xy 97.788928 -340.148281) (xy 97.715869 -340.105839) (xy 97.647164 -340.05666) (xy 97.583432 -340.001188)
			(xy 97.525246 -339.939922) (xy 97.473132 -339.873416) (xy 97.427559 -339.802268) (xy 97.388937 -339.727119)
			(xy 97.357615 -339.648646) (xy 97.333875 -339.567557) (xy 97.317931 -339.484583) (xy 97.309927 -339.40047)
			(xy 97.309432 -339.358224) (xy 97.309829 -339.321956) (xy 97.315809 -339.249667) (xy 97.327648 -339.178103)
			(xy 97.336102 -339.142832) (xy 97.338115 -339.132729) (xy 97.334853 -339.112411) (xy 97.329752 -339.103462)
			(xy 97.30766 -339.067807) (xy 97.269551 -338.993079) (xy 97.238646 -338.915096) (xy 97.215218 -338.83455)
			(xy 97.199477 -338.752156) (xy 97.191562 -338.668646) (xy 97.191068 -338.626704) (xy 97.191648 -338.581935)
			(xy 97.200654 -338.49285) (xy 97.218554 -338.405119) (xy 97.245168 -338.319627) (xy 97.262188 -338.278216)
			(xy 97.265753 -338.268625) (xy 97.265754 -338.248182) (xy 97.262188 -338.238592) (xy 97.245172 -338.197246)
			(xy 97.218563 -338.111882) (xy 97.20066 -338.024278) (xy 97.191642 -337.935319) (xy 97.191068 -337.890612)
			(xy 97.191068 -337.889596) (xy 97.191322 -337.878166) (xy 97.164844 -337.872216) (xy 97.112609 -337.857476)
			(xy 97.086928 -337.848702) (xy 97.078731 -337.846188) (xy 97.061597 -337.846188) (xy 97.0534 -337.848702)
			(xy 97.01818 -337.860638) (xy 96.946171 -337.879227) (xy 96.87285 -337.89167) (xy 96.798739 -337.897878)
			(xy 96.761554 -337.898232) (xy 96.724369 -337.89788) (xy 96.650261 -337.891654) (xy 96.576941 -337.879206)
			(xy 96.504931 -337.860627) (xy 96.469708 -337.848702) (xy 96.461511 -337.846188) (xy 96.444377 -337.846188)
			(xy 96.43618 -337.848702) (xy 96.401082 -337.860602) (xy 96.329324 -337.879149) (xy 96.25626 -337.891592)
			(xy 96.182408 -337.897841) (xy 96.14535 -337.898232) (xy 96.144334 -337.898232) (xy 96.102408 -337.897723)
			(xy 96.018934 -337.889755) (xy 95.936596 -337.873888) (xy 95.85614 -337.850267) (xy 95.778292 -337.819104)
			(xy 95.70376 -337.780683) (xy 95.633218 -337.73535) (xy 95.567304 -337.683517) (xy 95.506616 -337.625654)
			(xy 95.451703 -337.562283) (xy 95.403062 -337.493979) (xy 95.361135 -337.421361) (xy 95.3263 -337.345087)
			(xy 95.298874 -337.265846) (xy 95.279105 -337.184357) (xy 95.267171 -337.101358) (xy 95.263181 -337.0176)
			(xy 91.722641 -337.0176) (xy 91.722956 -337.044284) (xy 91.722404 -337.089054) (xy 91.71339 -337.178139)
			(xy 91.695482 -337.26587) (xy 91.668861 -337.351361) (xy 91.651836 -337.392772) (xy 91.648282 -337.402366)
			(xy 91.648276 -337.422805) (xy 91.651836 -337.432396) (xy 91.668872 -337.473803) (xy 91.695506 -337.559291)
			(xy 91.71341 -337.647024) (xy 91.722404 -337.736113) (xy 91.722956 -337.780884) (xy 91.722404 -337.825654)
			(xy 91.71339 -337.914739) (xy 91.695482 -338.00247) (xy 91.668861 -338.087961) (xy 91.651836 -338.129372)
			(xy 91.648282 -338.138966) (xy 91.648276 -338.159405) (xy 91.651836 -338.168996) (xy 91.668872 -338.210403)
			(xy 91.695506 -338.295891) (xy 91.71341 -338.383624) (xy 91.722404 -338.472713) (xy 91.722956 -338.517484)
			(xy 91.722432 -338.558593) (xy 91.714846 -338.64046) (xy 91.699738 -338.721278) (xy 91.677236 -338.800357)
			(xy 91.647532 -338.877021) (xy 91.610881 -338.950618) (xy 91.567594 -339.020518) (xy 91.518041 -339.086125)
			(xy 91.462645 -339.146879) (xy 91.401879 -339.202262) (xy 91.336261 -339.251801) (xy 91.266352 -339.295073)
			(xy 91.192747 -339.331709) (xy 91.116076 -339.361396) (xy 91.036993 -339.383882) (xy 90.956172 -339.398973)
			(xy 90.874303 -339.406541) (xy 90.833194 -339.406992) (xy 90.791589 -339.406554) (xy 90.70874 -339.398816)
			(xy 90.626975 -339.383379) (xy 90.547007 -339.360379) (xy 90.469535 -339.330016) (xy 90.395235 -339.292555)
			(xy 90.359738 -339.270848) (xy 90.350631 -339.26562) (xy 90.329893 -339.262421) (xy 90.309608 -339.267785)
			(xy 90.301064 -339.273896) (xy 90.267427 -339.299833) (xy 90.196051 -339.345891) (xy 90.12061 -339.384937)
			(xy 90.041791 -339.416615) (xy 89.960312 -339.440636) (xy 89.876914 -339.456781) (xy 89.792357 -339.464905)
			(xy 89.749884 -339.465412) (xy 89.74963 -339.465412) (xy 89.708522 -339.464959) (xy 89.626657 -339.457377)
			(xy 89.545841 -339.442274) (xy 89.466762 -339.41978) (xy 89.390096 -339.390087) (xy 89.316497 -339.353447)
			(xy 89.246591 -339.310173) (xy 89.180976 -339.260635) (xy 89.120211 -339.205254) (xy 89.064815 -339.144504)
			(xy 89.015259 -339.078902) (xy 88.971967 -339.009008) (xy 88.935308 -338.935418) (xy 88.905594 -338.85876)
			(xy 88.883079 -338.779687) (xy 88.867956 -338.698875) (xy 88.860352 -338.617012) (xy 88.859868 -338.575904)
			(xy 88.860448 -338.531135) (xy 88.869454 -338.44205) (xy 88.887354 -338.354319) (xy 88.913968 -338.268827)
			(xy 88.930988 -338.227416) (xy 88.934553 -338.217825) (xy 88.934554 -338.197382) (xy 88.930988 -338.187792)
			(xy 88.913972 -338.146446) (xy 88.887363 -338.061082) (xy 88.86946 -337.973478) (xy 88.860442 -337.884519)
			(xy 88.859868 -337.839812) (xy 88.859868 -337.838796) (xy 88.860122 -337.827366) (xy 88.833644 -337.821416)
			(xy 88.781409 -337.806676) (xy 88.755728 -337.797902) (xy 88.747531 -337.795388) (xy 88.730397 -337.795388)
			(xy 88.7222 -337.797902) (xy 88.68698 -337.809838) (xy 88.614971 -337.828427) (xy 88.54165 -337.84087)
			(xy 88.467539 -337.847078) (xy 88.430354 -337.847432) (xy 88.393169 -337.84708) (xy 88.319061 -337.840854)
			(xy 88.245741 -337.828406) (xy 88.173731 -337.809827) (xy 88.138508 -337.797902) (xy 88.130311 -337.795388)
			(xy 88.113177 -337.795388) (xy 88.10498 -337.797902) (xy 88.069882 -337.809802) (xy 87.998124 -337.828349)
			(xy 87.92506 -337.840792) (xy 87.851208 -337.847041) (xy 87.81415 -337.847432) (xy 87.813134 -337.847432)
			(xy 87.771208 -337.846923) (xy 87.687734 -337.838955) (xy 87.605396 -337.823088) (xy 87.52494 -337.799467)
			(xy 87.447092 -337.768304) (xy 87.37256 -337.729883) (xy 87.302018 -337.68455) (xy 87.236104 -337.632717)
			(xy 87.175416 -337.574854) (xy 87.120503 -337.511483) (xy 87.071862 -337.443179) (xy 87.029935 -337.370561)
			(xy 86.9951 -337.294287) (xy 86.967674 -337.215046) (xy 86.947905 -337.133557) (xy 86.935971 -337.050558)
			(xy 86.931981 -336.9668) (xy 83.360149 -336.9668) (xy 83.364863 -337.017649) (xy 83.36534 -337.058762)
			(xy 83.364781 -337.103532) (xy 83.35577 -337.192617) (xy 83.337863 -337.280348) (xy 83.311243 -337.365839)
			(xy 83.29422 -337.40725) (xy 83.290679 -337.416847) (xy 83.290665 -337.437283) (xy 83.29422 -337.446874)
			(xy 83.311248 -337.488284) (xy 83.337884 -337.573771) (xy 83.355791 -337.661503) (xy 83.364787 -337.750591)
			(xy 83.36534 -337.795362) (xy 83.364781 -337.840132) (xy 83.35577 -337.929217) (xy 83.337863 -338.016948)
			(xy 83.311243 -338.102439) (xy 83.29422 -338.14385) (xy 83.290679 -338.153447) (xy 83.290665 -338.173883)
			(xy 83.29422 -338.183474) (xy 83.311248 -338.224884) (xy 83.337884 -338.310371) (xy 83.355791 -338.398103)
			(xy 83.364787 -338.487191) (xy 83.36534 -338.531962) (xy 83.364865 -338.573077) (xy 83.357281 -338.654956)
			(xy 83.342174 -338.735786) (xy 83.319674 -338.814878) (xy 83.289971 -338.891556) (xy 83.253319 -338.965166)
			(xy 83.210032 -339.03508) (xy 83.160479 -339.100701) (xy 83.105082 -339.16147) (xy 83.044313 -339.216869)
			(xy 82.978693 -339.266423) (xy 82.90878 -339.309712) (xy 82.83517 -339.346364) (xy 82.758493 -339.376068)
			(xy 82.679402 -339.398571) (xy 82.598572 -339.413679) (xy 82.516693 -339.421265) (xy 82.475578 -339.421724)
			(xy 82.433968 -339.421253) (xy 82.351111 -339.413475) (xy 82.269342 -339.397998) (xy 82.189374 -339.374957)
			(xy 82.111906 -339.344554) (xy 82.037613 -339.307053) (xy 82.002122 -339.285326) (xy 81.992978 -339.280175)
			(xy 81.972265 -339.276953) (xy 81.951992 -339.282282) (xy 81.943448 -339.288374) (xy 81.909821 -339.314367)
			(xy 81.838426 -339.360491) (xy 81.762954 -339.399592) (xy 81.684096 -339.431311) (xy 81.602571 -339.455361)
			(xy 81.519123 -339.471521) (xy 81.434513 -339.479643) (xy 81.392014 -339.480144) (xy 81.350899 -339.479688)
			(xy 81.269019 -339.472102) (xy 81.188189 -339.456993) (xy 81.109097 -339.434491) (xy 81.032419 -339.404786)
			(xy 80.95881 -339.368133) (xy 80.888896 -339.324845) (xy 80.823275 -339.27529) (xy 80.762506 -339.219892)
			(xy 80.707108 -339.159122) (xy 80.657553 -339.093501) (xy 80.614265 -339.023587) (xy 80.577612 -338.949977)
			(xy 80.547908 -338.873299) (xy 80.525406 -338.794207) (xy 80.510297 -338.713377) (xy 80.502712 -338.631497)
			(xy 80.502252 -338.590382) (xy 80.502826 -338.545613) (xy 80.511834 -338.456528) (xy 80.529735 -338.368797)
			(xy 80.556351 -338.283305) (xy 80.573372 -338.241894) (xy 80.576945 -338.232306) (xy 80.576939 -338.211861)
			(xy 80.573372 -338.20227) (xy 80.556348 -338.160927) (xy 80.529742 -338.075562) (xy 80.511841 -337.987957)
			(xy 80.502825 -337.898997) (xy 80.502252 -337.85429) (xy 80.502252 -337.853274) (xy 80.502506 -337.841844)
			(xy 80.476028 -337.835896) (xy 80.423793 -337.821155) (xy 80.398112 -337.81238) (xy 80.389915 -337.809866)
			(xy 80.372781 -337.809866) (xy 80.364584 -337.81238) (xy 80.329366 -337.824336) (xy 80.257364 -337.842992)
			(xy 80.184043 -337.855502) (xy 80.109928 -337.861777) (xy 80.072738 -337.862164) (xy 80.035549 -337.861761)
			(xy 79.961436 -337.855475) (xy 79.888116 -337.842969) (xy 79.81611 -337.824332) (xy 79.780892 -337.81238)
			(xy 79.772695 -337.809866) (xy 79.755561 -337.809866) (xy 79.747364 -337.81238) (xy 79.712148 -337.824342)
			(xy 79.640145 -337.842996) (xy 79.566824 -337.855505) (xy 79.492708 -337.861778) (xy 79.455518 -337.862164)
			(xy 79.413579 -337.861698) (xy 79.330081 -337.853726) (xy 79.247718 -337.837853) (xy 79.167237 -337.814224)
			(xy 79.089367 -337.783051) (xy 79.014813 -337.744616) (xy 78.94425 -337.69927) (xy 78.878316 -337.64742)
			(xy 78.81761 -337.589539) (xy 78.762681 -337.526148) (xy 78.714027 -337.457824) (xy 78.672087 -337.385183)
			(xy 78.637243 -337.308885) (xy 78.609809 -337.229621) (xy 78.590033 -337.148107) (xy 78.578096 -337.065083)
			(xy 78.574105 -336.9813) (xy 75.005252 -336.9813) (xy 75.00928 -337.024761) (xy 75.009756 -337.065874)
			(xy 75.009201 -337.110644) (xy 75.000188 -337.199729) (xy 74.982281 -337.28746) (xy 74.95566 -337.372951)
			(xy 74.938636 -337.414362) (xy 74.935088 -337.423957) (xy 74.935078 -337.444395) (xy 74.938636 -337.453986)
			(xy 74.955669 -337.495394) (xy 74.982303 -337.580882) (xy 75.000209 -337.668615) (xy 75.009203 -337.757703)
			(xy 75.009756 -337.802474) (xy 75.009201 -337.847244) (xy 75.000188 -337.936329) (xy 74.982281 -338.02406)
			(xy 74.95566 -338.109551) (xy 74.938636 -338.150962) (xy 74.935088 -338.160557) (xy 74.935078 -338.180995)
			(xy 74.938636 -338.190586) (xy 74.955669 -338.231994) (xy 74.982303 -338.317482) (xy 75.000209 -338.405215)
			(xy 75.009203 -338.494303) (xy 75.009756 -338.539074) (xy 75.009277 -338.580189) (xy 75.001692 -338.662067)
			(xy 74.986584 -338.742897) (xy 74.964083 -338.821988) (xy 74.93438 -338.898665) (xy 74.897729 -338.972274)
			(xy 74.854442 -339.042187) (xy 74.804888 -339.107809) (xy 74.749492 -339.168577) (xy 74.688724 -339.223976)
			(xy 74.623104 -339.27353) (xy 74.553192 -339.316819) (xy 74.479583 -339.353472) (xy 74.402907 -339.383177)
			(xy 74.323816 -339.40568) (xy 74.242987 -339.420789) (xy 74.161109 -339.428376) (xy 74.119994 -339.428836)
			(xy 74.078384 -339.428356) (xy 73.995528 -339.420579) (xy 73.913759 -339.405104) (xy 73.833791 -339.382065)
			(xy 73.756322 -339.351663) (xy 73.682029 -339.314164) (xy 73.646538 -339.292438) (xy 73.63743 -339.287211)
			(xy 73.616693 -339.284013) (xy 73.596408 -339.289376) (xy 73.587864 -339.295486) (xy 73.554233 -339.321473)
			(xy 73.482838 -339.367598) (xy 73.407368 -339.406699) (xy 73.32851 -339.438419) (xy 73.246986 -339.46247)
			(xy 73.163538 -339.47863) (xy 73.078929 -339.486754) (xy 73.03643 -339.487256) (xy 72.995315 -339.486773)
			(xy 72.913437 -339.479188) (xy 72.832607 -339.464081) (xy 72.753517 -339.44158) (xy 72.67684 -339.411877)
			(xy 72.60323 -339.375226) (xy 72.533317 -339.33194) (xy 72.467696 -339.282387) (xy 72.406927 -339.22699)
			(xy 72.351529 -339.166223) (xy 72.301974 -339.100603) (xy 72.258685 -339.030691) (xy 72.222032 -338.957082)
			(xy 72.192327 -338.880406) (xy 72.169824 -338.801316) (xy 72.154715 -338.720487) (xy 72.147128 -338.638609)
			(xy 72.146668 -338.597494) (xy 72.147245 -338.552725) (xy 72.156251 -338.46364) (xy 72.174152 -338.375909)
			(xy 72.200767 -338.290417) (xy 72.217788 -338.249006) (xy 72.221359 -338.239417) (xy 72.221356 -338.218972)
			(xy 72.217788 -338.209382) (xy 72.200768 -338.168037) (xy 72.174161 -338.082673) (xy 72.156259 -337.995068)
			(xy 72.147241 -337.906109) (xy 72.146668 -337.861402) (xy 72.146668 -337.860386) (xy 72.146922 -337.848956)
			(xy 72.120444 -337.843006) (xy 72.068209 -337.828266) (xy 72.042528 -337.819492) (xy 72.034331 -337.816978)
			(xy 72.017197 -337.816978) (xy 72.009 -337.819492) (xy 71.973781 -337.831444) (xy 71.901779 -337.850101)
			(xy 71.828459 -337.862612) (xy 71.754344 -337.868888) (xy 71.717154 -337.869276) (xy 71.679965 -337.868873)
			(xy 71.605852 -337.862587) (xy 71.532532 -337.850082) (xy 71.460526 -337.831445) (xy 71.425308 -337.819492)
			(xy 71.417111 -337.816978) (xy 71.399977 -337.816978) (xy 71.39178 -337.819492) (xy 71.356562 -337.83145)
			(xy 71.28456 -337.850105) (xy 71.211239 -337.862615) (xy 71.137124 -337.868889) (xy 71.099934 -337.869276)
			(xy 71.057995 -337.868786) (xy 70.974497 -337.860816) (xy 70.892134 -337.844945) (xy 70.811653 -337.821316)
			(xy 70.733783 -337.790144) (xy 70.659228 -337.751711) (xy 70.588664 -337.706365) (xy 70.522731 -337.654517)
			(xy 70.462025 -337.596636) (xy 70.407095 -337.533246) (xy 70.35844 -337.464922) (xy 70.3165 -337.392282)
			(xy 70.281655 -337.315985) (xy 70.254221 -337.23672) (xy 70.234446 -337.155207) (xy 70.222508 -337.072183)
			(xy 70.218517 -336.9884) (xy 2.509012 -336.9884) (xy 2.509012 -341.9277) (xy 103.538816 -341.9277)
			(xy 103.542807 -341.843921) (xy 103.554743 -341.760902) (xy 103.574517 -341.679392) (xy 103.601948 -341.600131)
			(xy 103.63679 -341.523837) (xy 103.678726 -341.4512) (xy 103.727376 -341.382878) (xy 103.7823 -341.319489)
			(xy 103.843001 -341.261608) (xy 103.908929 -341.20976) (xy 103.979486 -341.164412) (xy 104.054035 -341.125977)
			(xy 104.131899 -341.094802) (xy 104.212375 -341.071169) (xy 104.294732 -341.055293) (xy 104.378225 -341.047317)
			(xy 104.420162 -341.046816) (xy 104.457351 -341.047215) (xy 104.531464 -341.053502) (xy 104.604784 -341.066008)
			(xy 104.67679 -341.084646) (xy 104.712008 -341.0966) (xy 104.720205 -341.099114) (xy 104.737339 -341.099114)
			(xy 104.745536 -341.0966) (xy 104.780752 -341.084638) (xy 104.852755 -341.065983) (xy 104.926076 -341.053475)
			(xy 105.000192 -341.047202) (xy 105.037382 -341.046816) (xy 105.07218 -341.047578) (xy 105.081741 -341.004913)
			(xy 105.108207 -340.921573) (xy 105.125012 -340.881208) (xy 105.128629 -340.871492) (xy 105.128644 -340.850784)
			(xy 105.125012 -340.841076) (xy 105.107898 -340.799819) (xy 105.081109 -340.714608) (xy 105.063074 -340.627124)
			(xy 105.053979 -340.538265) (xy 105.053384 -340.493604) (xy 105.053384 -340.492842) (xy 105.053883 -340.450917)
			(xy 105.061853 -340.367446) (xy 105.077722 -340.285111) (xy 105.101345 -340.204657) (xy 105.132509 -340.126813)
			(xy 105.170932 -340.052283) (xy 105.216265 -339.981744) (xy 105.268098 -339.915833) (xy 105.325961 -339.855147)
			(xy 105.389331 -339.800237) (xy 105.457634 -339.751599) (xy 105.530251 -339.709674) (xy 105.606524 -339.674841)
			(xy 105.685763 -339.647416) (xy 105.767249 -339.627647) (xy 105.850246 -339.615714) (xy 105.934002 -339.611725)
			(xy 106.017758 -339.615714) (xy 106.100755 -339.627647) (xy 106.182241 -339.647416) (xy 106.26148 -339.674841)
			(xy 106.337753 -339.709674) (xy 106.41037 -339.751599) (xy 106.478673 -339.800237) (xy 106.542043 -339.855147)
			(xy 106.599906 -339.915833) (xy 106.651739 -339.981744) (xy 106.697072 -340.052283) (xy 106.735495 -340.126813)
			(xy 106.766659 -340.204657) (xy 106.790282 -340.285111) (xy 106.806151 -340.367446) (xy 106.814121 -340.450917)
			(xy 106.81462 -340.492842) (xy 106.81462 -340.493604) (xy 106.814051 -340.538267) (xy 106.804977 -340.627133)
			(xy 106.786945 -340.714621) (xy 106.760139 -340.799831) (xy 106.742992 -340.841076) (xy 106.739326 -340.850777)
			(xy 106.739342 -340.871499) (xy 106.742992 -340.881208) (xy 106.751628 -340.901528) (xy 106.756582 -340.912278)
			(xy 106.774248 -340.927996) (xy 106.797062 -340.934212) (xy 106.808778 -340.932516) (xy 106.8525 -340.924198)
			(xy 106.941059 -340.915292) (xy 106.985562 -340.914736) (xy 106.98607 -340.914736) (xy 107.027176 -340.915241)
			(xy 107.109038 -340.922823) (xy 107.189852 -340.937924) (xy 107.268928 -340.960416) (xy 107.345591 -340.990108)
			(xy 107.419189 -341.026745) (xy 107.489092 -341.070016) (xy 107.554706 -341.119551) (xy 107.61547 -341.174927)
			(xy 107.670867 -341.235674) (xy 107.720423 -341.301272) (xy 107.763716 -341.371161) (xy 107.800377 -341.444747)
			(xy 107.830093 -341.521401) (xy 107.85261 -341.60047) (xy 107.867738 -341.681278) (xy 107.875346 -341.763138)
			(xy 107.875832 -341.804244) (xy 107.875268 -341.849014) (xy 107.867795 -341.9229) (xy 351.475729 -341.9229)
			(xy 351.479719 -341.839138) (xy 351.491654 -341.756134) (xy 351.511424 -341.674641) (xy 351.538852 -341.595396)
			(xy 351.573688 -341.519117) (xy 351.615617 -341.446494) (xy 351.66426 -341.378187) (xy 351.719176 -341.314813)
			(xy 351.779867 -341.256945) (xy 351.845785 -341.205109) (xy 351.916331 -341.159774) (xy 351.990867 -341.12135)
			(xy 352.068718 -341.090185) (xy 352.149179 -341.066562) (xy 352.231522 -341.050694) (xy 352.314999 -341.042726)
			(xy 352.356928 -341.042244) (xy 352.357944 -341.042244) (xy 352.395001 -341.04264) (xy 352.46885 -341.048907)
			(xy 352.541913 -341.061352) (xy 352.613673 -341.079887) (xy 352.648774 -341.091774) (xy 352.656971 -341.094288)
			(xy 352.674105 -341.094288) (xy 352.682302 -341.091774) (xy 352.717522 -341.079841) (xy 352.789531 -341.06125)
			(xy 352.862852 -341.048806) (xy 352.936963 -341.042598) (xy 352.974148 -341.042244) (xy 352.988626 -341.042244)
			(xy 352.999994 -341.041829) (xy 353.020668 -341.032414) (xy 353.035248 -341.014994) (xy 353.038664 -341.004144)
			(xy 353.047281 -340.972176) (xy 353.068638 -340.909499) (xy 353.081336 -340.878922) (xy 353.084895 -340.86933)
			(xy 353.084899 -340.848889) (xy 353.081336 -340.839298) (xy 353.064328 -340.797915) (xy 353.037705 -340.71249)
			(xy 353.019796 -340.624824) (xy 353.010783 -340.535802) (xy 353.010216 -340.491064) (xy 353.010216 -340.49081)
			(xy 353.01072 -340.448462) (xy 353.018771 -340.364148) (xy 353.0348 -340.280982) (xy 353.058661 -340.199715)
			(xy 353.09014 -340.121085) (xy 353.128951 -340.045804) (xy 353.174741 -339.974552) (xy 353.227097 -339.907976)
			(xy 353.285545 -339.846678) (xy 353.349555 -339.791213) (xy 353.418547 -339.742084) (xy 353.491897 -339.699735)
			(xy 353.56894 -339.664551) (xy 353.648979 -339.636849) (xy 353.731288 -339.616881) (xy 353.815123 -339.604828)
			(xy 353.899724 -339.600798) (xy 353.984325 -339.604828) (xy 354.06816 -339.616881) (xy 354.150469 -339.636849)
			(xy 354.230508 -339.664551) (xy 354.307551 -339.699735) (xy 354.380901 -339.742084) (xy 354.449893 -339.791213)
			(xy 354.513903 -339.846678) (xy 354.572351 -339.907976) (xy 354.624707 -339.974552) (xy 354.670497 -340.045804)
			(xy 354.709308 -340.121085) (xy 354.740787 -340.199715) (xy 354.764648 -340.280982) (xy 354.780677 -340.364148)
			(xy 354.788728 -340.448462) (xy 354.789232 -340.49081) (xy 354.789232 -340.491064) (xy 354.788666 -340.535802)
			(xy 354.779649 -340.624824) (xy 354.761744 -340.712491) (xy 354.73513 -340.797919) (xy 354.718112 -340.839298)
			(xy 354.714539 -340.848887) (xy 354.714543 -340.869332) (xy 354.718112 -340.878922) (xy 354.735129 -340.920302)
			(xy 354.761749 -341.005728) (xy 354.779655 -341.093395) (xy 354.788666 -341.182417) (xy 354.789232 -341.227156)
			(xy 354.789232 -341.228172) (xy 354.789643 -341.238195) (xy 354.79731 -341.256718) (xy 354.811486 -341.270892)
			(xy 354.830009 -341.278557) (xy 354.840032 -341.278972) (xy 354.840286 -341.278972) (xy 354.84794 -341.278603)
			(xy 354.862532 -341.273956) (xy 354.868988 -341.269828) (xy 354.869242 -341.269828) (xy 354.906515 -341.244617)
			(xy 354.985224 -341.200991) (xy 355.067937 -341.165538) (xy 355.153807 -341.13862) (xy 355.241957 -341.120513)
			(xy 355.331485 -341.111402) (xy 355.37648 -341.110824) (xy 355.376988 -341.110824) (xy 355.418092 -341.111264)
			(xy 355.499949 -341.118848) (xy 355.580757 -341.133953) (xy 355.659827 -341.15645) (xy 355.736484 -341.186147)
			(xy 355.810073 -341.22279) (xy 355.879967 -341.266067) (xy 355.94557 -341.315609) (xy 356.006322 -341.370992)
			(xy 356.061704 -341.431745) (xy 356.111244 -341.497349) (xy 356.15452 -341.567245) (xy 356.191162 -341.640835)
			(xy 356.220857 -341.717492) (xy 356.243352 -341.796562) (xy 356.258455 -341.877371) (xy 356.266037 -341.959228)
			(xy 356.266496 -342.000332) (xy 356.266496 -342.000586) (xy 356.26594 -342.045325) (xy 356.256921 -342.134347)
			(xy 356.239013 -342.222014) (xy 356.212396 -342.307441) (xy 356.195376 -342.34882) (xy 356.191792 -342.358405)
			(xy 356.191804 -342.378853) (xy 356.195376 -342.388444) (xy 356.212409 -342.429852) (xy 356.239041 -342.515341)
			(xy 356.256946 -342.603073) (xy 356.265942 -342.692161) (xy 356.266496 -342.736932) (xy 356.265952 -342.781703)
			(xy 356.256945 -342.87079) (xy 356.239036 -342.958522) (xy 356.212407 -343.044011) (xy 356.195376 -343.08542)
			(xy 356.191792 -343.095005) (xy 356.191804 -343.115453) (xy 356.195376 -343.125044) (xy 356.212398 -343.166422)
			(xy 356.239017 -343.251848) (xy 356.256922 -343.339516) (xy 356.265931 -343.428539) (xy 356.266496 -343.473278)
			(xy 356.266496 -343.473532) (xy 356.266064 -343.514635) (xy 356.258476 -343.596491) (xy 356.243368 -343.677298)
			(xy 356.220868 -343.756366) (xy 356.191169 -343.83302) (xy 356.154525 -343.906608) (xy 356.111246 -343.9765)
			(xy 356.061704 -344.042101) (xy 356.00632 -344.102851) (xy 355.945567 -344.158232) (xy 355.879964 -344.207771)
			(xy 355.810069 -344.251046) (xy 355.73648 -344.287687) (xy 355.659824 -344.317382) (xy 355.580755 -344.339878)
			(xy 355.499948 -344.354982) (xy 355.418091 -344.362566) (xy 355.376988 -344.36304) (xy 355.376226 -344.36304)
			(xy 355.334685 -344.362565) (xy 355.251968 -344.35478) (xy 355.170337 -344.33932) (xy 355.090501 -344.316321)
			(xy 355.013156 -344.285984) (xy 354.938974 -344.248571) (xy 354.903532 -344.226896) (xy 354.894382 -344.221758)
			(xy 354.873674 -344.218535) (xy 354.853403 -344.223857) (xy 354.844858 -344.229944) (xy 354.811228 -344.255891)
			(xy 354.73985 -344.301947) (xy 354.664408 -344.340991) (xy 354.585588 -344.372667) (xy 354.504107 -344.396686)
			(xy 354.420709 -344.412831) (xy 354.336151 -344.420953) (xy 354.293678 -344.42146) (xy 354.293424 -344.42146)
			(xy 354.25232 -344.421025) (xy 354.170462 -344.413441) (xy 354.089653 -344.398337) (xy 354.010583 -344.375841)
			(xy 353.933926 -344.346144) (xy 353.860336 -344.309501) (xy 353.790441 -344.266224) (xy 353.724837 -344.216682)
			(xy 353.664085 -344.161298) (xy 353.608703 -344.100544) (xy 353.559163 -344.03494) (xy 353.515887 -343.965043)
			(xy 353.479246 -343.891453) (xy 353.449552 -343.814794) (xy 353.427057 -343.735723) (xy 353.411955 -343.654914)
			(xy 353.404374 -343.573056) (xy 353.403916 -343.531952) (xy 353.403916 -343.531698) (xy 353.4045 -343.48696)
			(xy 353.413511 -343.397939) (xy 353.431411 -343.310272) (xy 353.45802 -343.224844) (xy 353.475036 -343.183464)
			(xy 353.478628 -343.173881) (xy 353.47861 -343.153431) (xy 353.475036 -343.14384) (xy 353.457998 -343.102434)
			(xy 353.431368 -343.016945) (xy 353.413464 -342.929211) (xy 353.404469 -342.840123) (xy 353.403916 -342.795352)
			(xy 353.403916 -342.783414) (xy 353.377438 -342.777466) (xy 353.325203 -342.762725) (xy 353.299522 -342.75395)
			(xy 353.291325 -342.751436) (xy 353.274191 -342.751436) (xy 353.265994 -342.75395) (xy 353.230774 -342.765885)
			(xy 353.158765 -342.784475) (xy 353.085444 -342.796919) (xy 353.011333 -342.803127) (xy 352.974148 -342.80348)
			(xy 352.936964 -342.803098) (xy 352.862857 -342.79688) (xy 352.789537 -342.784441) (xy 352.717525 -342.76587)
			(xy 352.682302 -342.75395) (xy 352.674105 -342.751436) (xy 352.656971 -342.751436) (xy 352.648774 -342.75395)
			(xy 352.613678 -342.765853) (xy 352.541919 -342.784399) (xy 352.468854 -342.796841) (xy 352.395002 -342.80309)
			(xy 352.357944 -342.80348) (xy 352.356928 -342.80348) (xy 352.314999 -342.803074) (xy 352.231522 -342.795106)
			(xy 352.149179 -342.779238) (xy 352.068718 -342.755615) (xy 351.990867 -342.72445) (xy 351.916331 -342.686026)
			(xy 351.845785 -342.640691) (xy 351.779867 -342.588855) (xy 351.719176 -342.530987) (xy 351.66426 -342.467613)
			(xy 351.615617 -342.399306) (xy 351.573688 -342.326683) (xy 351.538852 -342.250404) (xy 351.511424 -342.171159)
			(xy 351.491654 -342.089666) (xy 351.479719 -342.006662) (xy 351.475729 -341.9229) (xy 107.867795 -341.9229)
			(xy 107.866258 -341.938099) (xy 107.848353 -342.02583) (xy 107.821735 -342.111321) (xy 107.804712 -342.152732)
			(xy 107.80112 -342.162315) (xy 107.801136 -342.182765) (xy 107.804712 -342.192356) (xy 107.821734 -342.233768)
			(xy 107.848372 -342.319255) (xy 107.86628 -342.406986) (xy 107.875278 -342.496074) (xy 107.875832 -342.540844)
			(xy 107.875405 -342.579435) (xy 107.868704 -342.656327) (xy 107.855365 -342.732349) (xy 107.835489 -342.806929)
			(xy 107.822746 -342.843358) (xy 107.81982 -342.852801) (xy 107.820595 -342.872535) (xy 107.82427 -342.881712)
			(xy 107.843314 -342.925129) (xy 107.873091 -343.015145) (xy 107.893121 -343.107819) (xy 107.903177 -343.202097)
			(xy 107.903772 -343.249504) (xy 107.903199 -343.294273) (xy 107.894192 -343.383358) (xy 107.87629 -343.471089)
			(xy 107.849674 -343.556581) (xy 107.832652 -343.597992) (xy 107.829086 -343.607582) (xy 107.829087 -343.628025)
			(xy 107.832652 -343.637616) (xy 107.849695 -343.67902) (xy 107.876327 -343.76451) (xy 107.894229 -343.852244)
			(xy 107.903221 -343.941333) (xy 107.903772 -343.986104) (xy 107.903338 -344.0272) (xy 107.895755 -344.109042)
			(xy 107.880654 -344.189835) (xy 107.858164 -344.268891) (xy 107.828477 -344.345534) (xy 107.791846 -344.419112)
			(xy 107.748583 -344.488997) (xy 107.699057 -344.554593) (xy 107.643692 -344.61534) (xy 107.582958 -344.670721)
			(xy 107.517374 -344.720262) (xy 107.447499 -344.763541) (xy 107.37393 -344.80019) (xy 107.297294 -344.829896)
			(xy 107.218244 -344.852405) (xy 107.137454 -344.867525) (xy 107.055614 -344.875128) (xy 107.014518 -344.875612)
			(xy 107.01401 -344.875612) (xy 106.971454 -344.875048) (xy 106.886731 -344.866913) (xy 106.803172 -344.850725)
			(xy 106.72154 -344.826633) (xy 106.642582 -344.794856) (xy 106.567018 -344.755685) (xy 106.49554 -344.709478)
			(xy 106.428801 -344.656658) (xy 106.36741 -344.597706) (xy 106.311928 -344.533162) (xy 106.262863 -344.463615)
			(xy 106.220663 -344.389701) (xy 106.202734 -344.351102) (xy 106.197143 -344.340314) (xy 106.178175 -344.325188)
			(xy 106.166412 -344.322146) (xy 106.123815 -344.31302) (xy 106.04054 -344.287419) (xy 105.960165 -344.253801)
			(xy 105.883461 -344.212489) (xy 105.811162 -344.163878) (xy 105.74396 -344.108434) (xy 105.682498 -344.046687)
			(xy 105.627365 -343.979229) (xy 105.579089 -343.906705) (xy 105.538133 -343.829811) (xy 105.504888 -343.749281)
			(xy 105.479672 -343.665888) (xy 105.462727 -343.58043) (xy 105.454216 -343.493725) (xy 105.453688 -343.450164)
			(xy 105.454253 -343.405394) (xy 105.463263 -343.316309) (xy 105.481167 -343.228578) (xy 105.507785 -343.143087)
			(xy 105.524808 -343.101676) (xy 105.528395 -343.092092) (xy 105.528382 -343.071643) (xy 105.524808 -343.062052)
			(xy 105.508891 -343.02338) (xy 105.483531 -342.943684) (xy 105.46577 -342.861957) (xy 105.460292 -342.820498)
			(xy 105.458558 -342.81058) (xy 105.448632 -342.793088) (xy 105.43277 -342.780723) (xy 105.423208 -342.777572)
			(xy 105.40795 -342.773353) (xy 105.377717 -342.763951) (xy 105.362756 -342.758776) (xy 105.354559 -342.756262)
			(xy 105.337425 -342.756262) (xy 105.329228 -342.758776) (xy 105.294015 -342.770747) (xy 105.222011 -342.789399)
			(xy 105.148689 -342.801905) (xy 105.074572 -342.808175) (xy 105.037382 -342.80856) (xy 105.000192 -342.808173)
			(xy 104.926079 -342.801882) (xy 104.85276 -342.789372) (xy 104.780754 -342.770731) (xy 104.745536 -342.758776)
			(xy 104.737339 -342.756262) (xy 104.720205 -342.756262) (xy 104.712008 -342.758776) (xy 104.676797 -342.770753)
			(xy 104.604792 -342.789403) (xy 104.531469 -342.801908) (xy 104.457353 -342.808176) (xy 104.420162 -342.80856)
			(xy 104.378225 -342.808083) (xy 104.294732 -342.800107) (xy 104.212375 -342.784231) (xy 104.131899 -342.760598)
			(xy 104.054035 -342.729423) (xy 103.979486 -342.690988) (xy 103.908929 -342.64564) (xy 103.843001 -342.593792)
			(xy 103.7823 -342.535911) (xy 103.727376 -342.472522) (xy 103.678726 -342.4042) (xy 103.63679 -342.331563)
			(xy 103.601948 -342.255269) (xy 103.574517 -342.176008) (xy 103.554743 -342.094498) (xy 103.542807 -342.011479)
			(xy 103.538816 -341.9277) (xy 2.509012 -341.9277) (xy 2.509012 -345.238324) (xy 88.42502 -345.238324)
			(xy 88.42502 -345.237562) (xy 88.425476 -345.196455) (xy 88.433064 -345.114592) (xy 88.448171 -345.033778)
			(xy 88.470668 -344.954703) (xy 88.500364 -344.87804) (xy 88.537005 -344.804443) (xy 88.58028 -344.73454)
			(xy 88.629818 -344.668927) (xy 88.685198 -344.608163) (xy 88.745947 -344.552768) (xy 88.811546 -344.503212)
			(xy 88.881438 -344.459919) (xy 88.955025 -344.423259) (xy 89.031681 -344.393542) (xy 89.110751 -344.371024)
			(xy 89.19156 -344.355896) (xy 89.273421 -344.348287) (xy 89.314528 -344.3478) (xy 89.358923 -344.348358)
			(xy 89.447268 -344.357247) (xy 89.534288 -344.374894) (xy 89.619117 -344.401123) (xy 89.660222 -344.417904)
			(xy 89.668919 -344.421068) (xy 89.687398 -344.421734) (xy 89.69629 -344.419174) (xy 89.742575 -344.404089)
			(xy 89.837607 -344.382956) (xy 89.934379 -344.372329) (xy 89.983056 -344.371676) (xy 90.021372 -344.372058)
			(xy 90.097725 -344.378586) (xy 90.173232 -344.391667) (xy 90.247331 -344.411203) (xy 90.283538 -344.423746)
			(xy 90.291854 -344.426332) (xy 90.309258 -344.426332) (xy 90.317574 -344.423746) (xy 90.353782 -344.41121)
			(xy 90.427885 -344.391692) (xy 90.503391 -344.378612) (xy 90.579741 -344.372068) (xy 90.618056 -344.371676)
			(xy 90.664451 -344.372276) (xy 90.756739 -344.381916) (xy 90.847523 -344.401107) (xy 90.935817 -344.429641)
			(xy 90.978482 -344.447876) (xy 90.988424 -344.451682) (xy 91.009688 -344.451682) (xy 91.01963 -344.447876)
			(xy 91.062298 -344.429645) (xy 91.150588 -344.401097) (xy 91.241371 -344.381901) (xy 91.33366 -344.372263)
			(xy 91.380056 -344.371676) (xy 91.418372 -344.372058) (xy 91.494725 -344.378586) (xy 91.570232 -344.391667)
			(xy 91.644331 -344.411203) (xy 91.680538 -344.423746) (xy 91.688854 -344.426332) (xy 91.706258 -344.426332)
			(xy 91.714574 -344.423746) (xy 91.750782 -344.41121) (xy 91.824885 -344.391692) (xy 91.900391 -344.378612)
			(xy 91.976741 -344.372068) (xy 92.015056 -344.371676) (xy 92.053372 -344.372058) (xy 92.129725 -344.378586)
			(xy 92.205232 -344.391667) (xy 92.279331 -344.411203) (xy 92.315538 -344.423746) (xy 92.323854 -344.426332)
			(xy 92.341258 -344.426332) (xy 92.349574 -344.423746) (xy 92.385691 -344.411238) (xy 92.459606 -344.391753)
			(xy 92.534918 -344.378674) (xy 92.611074 -344.372097) (xy 92.649294 -344.371676) (xy 92.650056 -344.371676)
			(xy 92.691158 -344.372194) (xy 92.773012 -344.379775) (xy 92.853817 -344.394876) (xy 92.932883 -344.417369)
			(xy 93.009537 -344.447061) (xy 93.083125 -344.4837) (xy 93.153018 -344.526972) (xy 93.21862 -344.576508)
			(xy 93.279371 -344.631887) (xy 93.334753 -344.692634) (xy 93.384294 -344.758233) (xy 93.427571 -344.828123)
			(xy 93.464215 -344.901708) (xy 93.493912 -344.97836) (xy 93.51641 -345.057425) (xy 93.531517 -345.138229)
			(xy 93.539103 -345.220082) (xy 93.539564 -345.261184) (xy 93.539564 -345.261692) (xy 93.539139 -345.302203)
			(xy 93.531771 -345.38289) (xy 93.517086 -345.462571) (xy 93.495207 -345.540583) (xy 93.466315 -345.616279)
			(xy 93.448886 -345.652852) (xy 93.444973 -345.661871) (xy 93.443532 -345.68146) (xy 93.446092 -345.690952)
			(xy 93.460285 -345.736019) (xy 93.480192 -345.828387) (xy 93.490186 -345.922345) (xy 93.490796 -345.96959)
			(xy 93.490238 -346.015229) (xy 93.480936 -346.106032) (xy 93.462388 -346.195406) (xy 93.44914 -346.239084)
			(xy 93.446696 -346.248096) (xy 93.447735 -346.266724) (xy 93.451172 -346.275406) (xy 93.469867 -346.318487)
			(xy 93.49915 -346.407722) (xy 93.518862 -346.499547) (xy 93.527728 -346.583) (xy 200.85558 -346.583)
			(xy 200.856207 -346.536598) (xy 200.865897 -346.444301) (xy 200.88515 -346.353515) (xy 200.913758 -346.26523)
			(xy 200.932034 -346.222574) (xy 200.935843 -346.212632) (xy 200.935843 -346.191368) (xy 200.932034 -346.181426)
			(xy 200.913772 -346.138765) (xy 200.885179 -346.050477) (xy 200.865922 -345.959694) (xy 200.856209 -345.867401)
			(xy 200.85558 -345.821) (xy 200.856064 -345.779859) (xy 200.863695 -345.69793) (xy 200.878855 -345.617056)
			(xy 200.901414 -345.537926) (xy 200.931179 -345.461215) (xy 200.967897 -345.38758) (xy 200.989184 -345.35237)
			(xy 200.993752 -345.344157) (xy 200.997195 -345.3257) (xy 200.993752 -345.307243) (xy 200.989184 -345.29903)
			(xy 200.967885 -345.263826) (xy 200.931155 -345.190194) (xy 200.901383 -345.113484) (xy 200.878824 -345.034352)
			(xy 200.86367 -344.953474) (xy 200.856051 -344.871542) (xy 200.85558 -344.8304) (xy 200.856207 -344.783998)
			(xy 200.865897 -344.691701) (xy 200.88515 -344.600915) (xy 200.913758 -344.51263) (xy 200.932034 -344.469974)
			(xy 200.935843 -344.460032) (xy 200.935843 -344.438768) (xy 200.932034 -344.428826) (xy 200.913772 -344.386165)
			(xy 200.885179 -344.297877) (xy 200.865922 -344.207094) (xy 200.856209 -344.114801) (xy 200.85558 -344.0684)
			(xy 200.856084 -344.026039) (xy 200.864137 -343.941702) (xy 200.880171 -343.858512) (xy 200.904039 -343.777222)
			(xy 200.935527 -343.69857) (xy 200.974349 -343.623267) (xy 201.020152 -343.551995) (xy 201.072523 -343.485399)
			(xy 201.130988 -343.424084) (xy 201.195016 -343.368603) (xy 201.264028 -343.31946) (xy 201.337398 -343.2771)
			(xy 201.414463 -343.241905) (xy 201.494525 -343.214196) (xy 201.576858 -343.194222) (xy 201.660717 -343.182165)
			(xy 201.745342 -343.178134) (xy 201.829967 -343.182165) (xy 201.913826 -343.194222) (xy 201.996159 -343.214196)
			(xy 202.076221 -343.241905) (xy 202.153286 -343.2771) (xy 202.226656 -343.31946) (xy 202.295668 -343.368603)
			(xy 202.359696 -343.424084) (xy 202.418161 -343.485399) (xy 202.470532 -343.551995) (xy 202.516335 -343.623267)
			(xy 202.555157 -343.69857) (xy 202.586645 -343.777222) (xy 202.610513 -343.858512) (xy 202.626547 -343.941702)
			(xy 202.6346 -344.026039) (xy 202.635104 -344.0684) (xy 202.634479 -344.114802) (xy 202.624789 -344.2071)
			(xy 202.605534 -344.297885) (xy 202.576926 -344.38617) (xy 202.55865 -344.428826) (xy 202.554842 -344.438768)
			(xy 202.554842 -344.460032) (xy 202.55865 -344.469974) (xy 202.576911 -344.512635) (xy 202.605505 -344.600923)
			(xy 202.624762 -344.691706) (xy 202.634475 -344.783999) (xy 202.635104 -344.8304) (xy 202.634622 -344.871541)
			(xy 202.626991 -344.95347) (xy 202.611831 -345.034344) (xy 202.589272 -345.113474) (xy 202.559506 -345.190185)
			(xy 202.522787 -345.263821) (xy 202.5015 -345.29903) (xy 202.496933 -345.307243) (xy 202.493491 -345.3257)
			(xy 202.496933 -345.344157) (xy 202.5015 -345.35237) (xy 202.522797 -345.387575) (xy 202.559528 -345.461207)
			(xy 202.5893 -345.537917) (xy 202.61186 -345.617049) (xy 202.627014 -345.697926) (xy 202.634633 -345.779858)
			(xy 202.635104 -345.821) (xy 202.634479 -345.867402) (xy 202.624789 -345.9597) (xy 202.605534 -346.050485)
			(xy 202.576926 -346.13877) (xy 202.55865 -346.181426) (xy 202.554842 -346.191368) (xy 202.554842 -346.212632)
			(xy 202.55865 -346.222574) (xy 202.576911 -346.265235) (xy 202.605505 -346.353523) (xy 202.624762 -346.444306)
			(xy 202.634475 -346.536599) (xy 202.635104 -346.583) (xy 202.6346 -346.625361) (xy 202.626547 -346.709698)
			(xy 202.610513 -346.792888) (xy 202.586645 -346.874178) (xy 202.555157 -346.95283) (xy 202.516335 -347.028133)
			(xy 202.470532 -347.099405) (xy 202.418161 -347.166001) (xy 202.359696 -347.227316) (xy 202.295668 -347.282797)
			(xy 202.226656 -347.33194) (xy 202.153286 -347.3743) (xy 202.076221 -347.409495) (xy 201.996159 -347.437204)
			(xy 201.913826 -347.457178) (xy 201.829967 -347.469235) (xy 201.745342 -347.473267) (xy 201.660717 -347.469235)
			(xy 201.576858 -347.457178) (xy 201.494525 -347.437204) (xy 201.414463 -347.409495) (xy 201.337398 -347.3743)
			(xy 201.264028 -347.33194) (xy 201.195016 -347.282797) (xy 201.130988 -347.227316) (xy 201.072523 -347.166001)
			(xy 201.020152 -347.099405) (xy 200.974349 -347.028133) (xy 200.935527 -346.95283) (xy 200.904039 -346.874178)
			(xy 200.880171 -346.792888) (xy 200.864137 -346.709698) (xy 200.856084 -346.625361) (xy 200.85558 -346.583)
			(xy 93.527728 -346.583) (xy 93.528784 -346.592938) (xy 93.529404 -346.639896) (xy 93.528944 -346.681007)
			(xy 93.521356 -346.762877) (xy 93.506246 -346.843698) (xy 93.483741 -346.92278) (xy 93.454034 -346.999447)
			(xy 93.417379 -347.073045) (xy 93.374088 -347.142947) (xy 93.324531 -347.208555) (xy 93.269131 -347.26931)
			(xy 93.20836 -347.324693) (xy 93.142737 -347.374232) (xy 93.072823 -347.417503) (xy 92.999214 -347.454137)
			(xy 92.922539 -347.483822) (xy 92.843451 -347.506304) (xy 92.762626 -347.521391) (xy 92.680753 -347.528955)
			(xy 92.639642 -347.529404) (xy 92.601326 -347.529024) (xy 92.524973 -347.522495) (xy 92.449466 -347.509414)
			(xy 92.375367 -347.489878) (xy 92.33916 -347.477334) (xy 92.330844 -347.474748) (xy 92.31344 -347.474748)
			(xy 92.305124 -347.477334) (xy 92.268906 -347.489842) (xy 92.194807 -347.509368) (xy 92.119304 -347.522455)
			(xy 92.042956 -347.529008) (xy 92.004642 -347.529404) (xy 91.961529 -347.52892) (xy 91.875703 -347.520642)
			(xy 91.791081 -347.504091) (xy 91.70846 -347.479423) (xy 91.668346 -347.463618) (xy 91.658977 -347.460281)
			(xy 91.639107 -347.460281) (xy 91.629738 -347.463618) (xy 91.589623 -347.479419) (xy 91.506999 -347.504075)
			(xy 91.422379 -347.520627) (xy 91.336554 -347.528919) (xy 91.293442 -347.529404) (xy 91.255126 -347.529024)
			(xy 91.178773 -347.522495) (xy 91.103266 -347.509414) (xy 91.029167 -347.489878) (xy 90.99296 -347.477334)
			(xy 90.984644 -347.474748) (xy 90.96724 -347.474748) (xy 90.958924 -347.477334) (xy 90.922706 -347.489842)
			(xy 90.848607 -347.509368) (xy 90.773104 -347.522455) (xy 90.696756 -347.529008) (xy 90.658442 -347.529404)
			(xy 90.620126 -347.529024) (xy 90.543773 -347.522495) (xy 90.468266 -347.509414) (xy 90.394167 -347.489878)
			(xy 90.35796 -347.477334) (xy 90.349644 -347.474748) (xy 90.33224 -347.474748) (xy 90.323924 -347.477334)
			(xy 90.287706 -347.489842) (xy 90.213607 -347.509368) (xy 90.138104 -347.522455) (xy 90.061756 -347.529008)
			(xy 90.023442 -347.529404) (xy 89.985126 -347.529024) (xy 89.908773 -347.522495) (xy 89.833266 -347.509414)
			(xy 89.759167 -347.489878) (xy 89.72296 -347.477334) (xy 89.714644 -347.474748) (xy 89.69724 -347.474748)
			(xy 89.688924 -347.477334) (xy 89.652807 -347.489842) (xy 89.578892 -347.509327) (xy 89.50358 -347.522407)
			(xy 89.427424 -347.528983) (xy 89.389204 -347.529404) (xy 89.388442 -347.529404) (xy 89.347337 -347.528847)
			(xy 89.265478 -347.521267) (xy 89.184667 -347.506168) (xy 89.105593 -347.483678) (xy 89.028932 -347.453989)
			(xy 88.955336 -347.417355) (xy 88.885433 -347.374087) (xy 88.81982 -347.324556) (xy 88.759057 -347.269183)
			(xy 88.70366 -347.20844) (xy 88.654104 -347.142846) (xy 88.61081 -347.07296) (xy 88.574148 -346.999378)
			(xy 88.54443 -346.922728) (xy 88.52191 -346.843663) (xy 88.506779 -346.762857) (xy 88.499168 -346.681001)
			(xy 88.49868 -346.639896) (xy 88.49928 -346.594251) (xy 88.508675 -346.503445) (xy 88.527305 -346.414075)
			(xy 88.54059 -346.370402) (xy 88.543039 -346.361391) (xy 88.541996 -346.342762) (xy 88.538558 -346.33408)
			(xy 88.519895 -346.290993) (xy 88.490688 -346.201748) (xy 88.471043 -346.109924) (xy 88.461176 -346.016541)
			(xy 88.46058 -345.96959) (xy 88.460997 -345.930463) (xy 88.467845 -345.852508) (xy 88.481506 -345.775455)
			(xy 88.501874 -345.699897) (xy 88.514936 -345.663012) (xy 88.517951 -345.653293) (xy 88.516917 -345.632991)
			(xy 88.512904 -345.623642) (xy 88.496039 -345.587523) (xy 88.46806 -345.512874) (xy 88.44687 -345.436021)
			(xy 88.432638 -345.357582) (xy 88.425479 -345.278184) (xy 88.42502 -345.238324) (xy 2.509012 -345.238324)
			(xy 2.509012 -348.70949) (xy 28.410141 -348.70949) (xy 28.414132 -348.625708) (xy 28.426069 -348.542686)
			(xy 28.445844 -348.461173) (xy 28.473277 -348.38191) (xy 28.508121 -348.305613) (xy 28.550059 -348.232974)
			(xy 28.598712 -348.16465) (xy 28.65364 -348.101261) (xy 28.714345 -348.043379) (xy 28.780276 -347.99153)
			(xy 28.850838 -347.946183) (xy 28.92539 -347.907749) (xy 29.003259 -347.876576) (xy 29.083738 -347.852945)
			(xy 29.166099 -347.837072) (xy 29.249596 -347.829099) (xy 29.291534 -347.828616) (xy 29.328723 -347.829023)
			(xy 29.402836 -347.835307) (xy 29.476156 -347.847812) (xy 29.548162 -347.866448) (xy 29.58338 -347.8784)
			(xy 29.591577 -347.880914) (xy 29.608711 -347.880914) (xy 29.616908 -347.8784) (xy 29.652035 -347.866473)
			(xy 29.723849 -347.847849) (xy 29.796976 -347.835339) (xy 29.870898 -347.829031) (xy 29.907992 -347.828616)
			(xy 29.909516 -347.828616) (xy 29.916374 -347.82887) (xy 29.922431 -347.792721) (xy 29.939716 -347.721486)
			(xy 29.962803 -347.651915) (xy 29.976826 -347.61805) (xy 29.980289 -347.608427) (xy 29.980173 -347.587996)
			(xy 29.976572 -347.578426) (xy 29.959544 -347.537016) (xy 29.932908 -347.451529) (xy 29.915001 -347.363797)
			(xy 29.906005 -347.274709) (xy 29.905452 -347.229938) (xy 29.905933 -347.189355) (xy 29.913331 -347.108527)
			(xy 29.928059 -347.028709) (xy 29.949995 -346.950564) (xy 29.978957 -346.874741) (xy 30.014703 -346.801871)
			(xy 30.056938 -346.732559) (xy 30.10531 -346.667382) (xy 30.159416 -346.606881) (xy 30.218807 -346.551559)
			(xy 30.28299 -346.501876) (xy 30.351431 -346.458245) (xy 30.38729 -346.439236) (xy 30.395816 -346.434265)
			(xy 30.408633 -346.419285) (xy 30.414885 -346.400588) (xy 30.414722 -346.390722) (xy 30.41396 -346.365322)
			(xy 30.414481 -346.337437) (xy 30.422793 -346.28229) (xy 30.439231 -346.228998) (xy 30.463429 -346.178752)
			(xy 30.494845 -346.132673) (xy 30.532778 -346.091791) (xy 30.57638 -346.057019) (xy 30.624678 -346.029134)
			(xy 30.676593 -346.008759) (xy 30.730964 -345.996349) (xy 30.786578 -345.992182) (xy 30.842192 -345.996349)
			(xy 30.896563 -346.008759) (xy 30.948478 -346.029134) (xy 30.996776 -346.057019) (xy 31.040378 -346.091791)
			(xy 31.078311 -346.132673) (xy 31.109727 -346.178752) (xy 31.133925 -346.228998) (xy 31.150363 -346.28229)
			(xy 31.158675 -346.337437) (xy 31.159196 -346.365322) (xy 31.158688 -346.383356) (xy 31.15866 -346.393249)
			(xy 31.165282 -346.411875) (xy 31.178455 -346.426614) (xy 31.187136 -346.431362) (xy 31.224041 -346.449965)
			(xy 31.294555 -346.49308) (xy 31.360766 -346.542551) (xy 31.4221 -346.597952) (xy 31.47803 -346.658805)
			(xy 31.528073 -346.724585) (xy 31.571797 -346.794724) (xy 31.608825 -346.868616) (xy 31.638837 -346.945626)
			(xy 31.661575 -347.025088) (xy 31.676842 -347.106317) (xy 31.684507 -347.188612) (xy 31.684976 -347.229938)
			(xy 31.684414 -347.274708) (xy 31.675404 -347.363793) (xy 31.657499 -347.451524) (xy 31.630879 -347.537015)
			(xy 31.613856 -347.578426) (xy 31.61027 -347.58801) (xy 31.610284 -347.608459) (xy 31.613856 -347.61805)
			(xy 31.630031 -347.657368) (xy 31.655701 -347.738424) (xy 31.673532 -347.821557) (xy 31.68336 -347.906011)
			(xy 31.684722 -347.948504) (xy 31.684976 -347.96222) (xy 31.6992 -347.985588) (xy 31.788862 -348.034102)
			(xy 31.796927 -348.038113) (xy 31.814734 -348.040741) (xy 31.832352 -348.037052) (xy 31.84017 -348.032578)
			(xy 31.875522 -348.010993) (xy 31.949529 -347.973778) (xy 32.026677 -347.943609) (xy 32.106297 -347.920748)
			(xy 32.187699 -347.905393) (xy 32.270176 -347.897677) (xy 32.311594 -347.897196) (xy 32.352707 -347.897719)
			(xy 32.434582 -347.905305) (xy 32.515408 -347.920413) (xy 32.594495 -347.942914) (xy 32.671169 -347.972616)
			(xy 32.744775 -348.009266) (xy 32.814686 -348.05255) (xy 32.880304 -348.102101) (xy 32.941071 -348.157495)
			(xy 32.996468 -348.218259) (xy 33.046022 -348.283875) (xy 33.089311 -348.353783) (xy 33.125965 -348.427387)
			(xy 33.155671 -348.504059) (xy 33.178176 -348.583145) (xy 33.193289 -348.66397) (xy 33.197509 -348.70949)
			(xy 36.690541 -348.70949) (xy 36.694532 -348.625708) (xy 36.706469 -348.542686) (xy 36.726244 -348.461173)
			(xy 36.753677 -348.38191) (xy 36.788521 -348.305613) (xy 36.830459 -348.232974) (xy 36.879112 -348.16465)
			(xy 36.93404 -348.101261) (xy 36.994745 -348.043379) (xy 37.060676 -347.99153) (xy 37.131238 -347.946183)
			(xy 37.20579 -347.907749) (xy 37.283659 -347.876576) (xy 37.364138 -347.852945) (xy 37.446499 -347.837072)
			(xy 37.529996 -347.829099) (xy 37.571934 -347.828616) (xy 37.609123 -347.829023) (xy 37.683236 -347.835307)
			(xy 37.756556 -347.847812) (xy 37.828562 -347.866448) (xy 37.86378 -347.8784) (xy 37.871977 -347.880914)
			(xy 37.889111 -347.880914) (xy 37.897308 -347.8784) (xy 37.93549 -347.865472) (xy 38.013674 -347.845816)
			(xy 38.093328 -347.833391) (xy 38.133528 -347.830394) (xy 38.144516 -347.829167) (xy 38.163935 -347.818636)
			(xy 38.177169 -347.800949) (xy 38.18001 -347.790262) (xy 38.189419 -347.748079) (xy 38.215379 -347.665637)
			(xy 38.231826 -347.62567) (xy 38.235335 -347.61606) (xy 38.235189 -347.595617) (xy 38.231572 -347.586046)
			(xy 38.21455 -347.544634) (xy 38.187912 -347.459147) (xy 38.170004 -347.371416) (xy 38.161006 -347.282328)
			(xy 38.160452 -347.237558) (xy 38.160956 -347.195197) (xy 38.169009 -347.11086) (xy 38.185043 -347.02767)
			(xy 38.208911 -346.94638) (xy 38.240399 -346.867728) (xy 38.279221 -346.792425) (xy 38.325024 -346.721153)
			(xy 38.377395 -346.654557) (xy 38.43586 -346.593242) (xy 38.499888 -346.537761) (xy 38.5689 -346.488618)
			(xy 38.64227 -346.446258) (xy 38.719335 -346.411063) (xy 38.799397 -346.383354) (xy 38.88173 -346.36338)
			(xy 38.965589 -346.351323) (xy 39.050214 -346.347292) (xy 39.134839 -346.351323) (xy 39.218698 -346.36338)
			(xy 39.301031 -346.383354) (xy 39.381093 -346.411063) (xy 39.458158 -346.446258) (xy 39.531528 -346.488618)
			(xy 39.60054 -346.537761) (xy 39.664568 -346.593242) (xy 39.723033 -346.654557) (xy 39.775404 -346.721153)
			(xy 39.821207 -346.792425) (xy 39.860029 -346.867728) (xy 39.891517 -346.94638) (xy 39.915385 -347.02767)
			(xy 39.931419 -347.11086) (xy 39.939472 -347.195197) (xy 39.939976 -347.237558) (xy 39.939421 -347.282328)
			(xy 39.930409 -347.371413) (xy 39.912502 -347.459144) (xy 39.88588 -347.544635) (xy 39.868856 -347.586046)
			(xy 39.865251 -347.595621) (xy 39.865104 -347.616057) (xy 39.868602 -347.62567) (xy 39.88516 -347.665899)
			(xy 39.911278 -347.748887) (xy 39.929176 -347.834027) (xy 39.938683 -347.920507) (xy 39.939722 -347.963998)
			(xy 39.939722 -347.964252) (xy 39.94031 -347.973302) (xy 39.94696 -347.990157) (xy 39.959055 -348.003648)
			(xy 39.9669 -348.008194) (xy 40.058086 -348.056454) (xy 40.086026 -348.05493) (xy 40.09771 -348.04731)
			(xy 40.134305 -348.023444) (xy 40.211348 -347.98223) (xy 40.292061 -347.948768) (xy 40.375665 -347.923381)
			(xy 40.461356 -347.906311) (xy 40.548307 -347.897725) (xy 40.591994 -347.897196) (xy 40.633107 -347.897719)
			(xy 40.714982 -347.905305) (xy 40.795808 -347.920413) (xy 40.874895 -347.942914) (xy 40.951569 -347.972616)
			(xy 41.025175 -348.009266) (xy 41.095086 -348.05255) (xy 41.160704 -348.102101) (xy 41.221471 -348.157495)
			(xy 41.276868 -348.218259) (xy 41.326422 -348.283875) (xy 41.369711 -348.353783) (xy 41.406365 -348.427387)
			(xy 41.436071 -348.504059) (xy 41.458576 -348.583145) (xy 41.473689 -348.66397) (xy 41.47791 -348.7095)
			(xy 44.996301 -348.7095) (xy 45.000292 -348.625716) (xy 45.01223 -348.54269) (xy 45.032006 -348.461175)
			(xy 45.05944 -348.381909) (xy 45.094286 -348.30561) (xy 45.136227 -348.232969) (xy 45.184883 -348.164644)
			(xy 45.239813 -348.101253) (xy 45.30052 -348.043371) (xy 45.366455 -347.991522) (xy 45.43702 -347.946175)
			(xy 45.511576 -347.907741) (xy 45.589448 -347.876568) (xy 45.66993 -347.852939) (xy 45.752294 -347.837068)
			(xy 45.835794 -347.829098) (xy 45.877734 -347.828616) (xy 45.914923 -347.829023) (xy 45.989036 -347.835307)
			(xy 46.062356 -347.847812) (xy 46.134362 -347.866448) (xy 46.16958 -347.8784) (xy 46.177777 -347.880914)
			(xy 46.194911 -347.880914) (xy 46.203108 -347.8784) (xy 46.238327 -347.866445) (xy 46.310329 -347.847789)
			(xy 46.383649 -347.835279) (xy 46.457764 -347.829003) (xy 46.494954 -347.828616) (xy 46.496732 -347.82887)
			(xy 46.506097 -347.78788) (xy 46.53154 -347.707736) (xy 46.547532 -347.66885) (xy 46.551076 -347.659253)
			(xy 46.55109 -347.638816) (xy 46.547532 -347.629226) (xy 46.530501 -347.587817) (xy 46.503866 -347.502329)
			(xy 46.485961 -347.414597) (xy 46.476965 -347.325509) (xy 46.476412 -347.280738) (xy 46.476916 -347.238377)
			(xy 46.484969 -347.15404) (xy 46.501003 -347.07085) (xy 46.524871 -346.98956) (xy 46.556359 -346.910908)
			(xy 46.595181 -346.835605) (xy 46.640984 -346.764333) (xy 46.693355 -346.697737) (xy 46.75182 -346.636422)
			(xy 46.815848 -346.580941) (xy 46.88486 -346.531798) (xy 46.95823 -346.489438) (xy 47.035295 -346.454243)
			(xy 47.115357 -346.426534) (xy 47.19769 -346.40656) (xy 47.281549 -346.394503) (xy 47.366174 -346.390472)
			(xy 47.450799 -346.394503) (xy 47.534658 -346.40656) (xy 47.616991 -346.426534) (xy 47.697053 -346.454243)
			(xy 47.774118 -346.489438) (xy 47.847488 -346.531798) (xy 47.9165 -346.580941) (xy 47.980528 -346.636422)
			(xy 48.038993 -346.697737) (xy 48.091364 -346.764333) (xy 48.137167 -346.835605) (xy 48.175989 -346.910908)
			(xy 48.207477 -346.98956) (xy 48.231345 -347.07085) (xy 48.247379 -347.15404) (xy 48.255432 -347.238377)
			(xy 48.255936 -347.280738) (xy 48.25537 -347.325508) (xy 48.24636 -347.414592) (xy 48.228456 -347.502324)
			(xy 48.201838 -347.587815) (xy 48.184816 -347.629226) (xy 48.181232 -347.638811) (xy 48.181246 -347.659259)
			(xy 48.184816 -347.66885) (xy 48.199304 -347.703977) (xy 48.222973 -347.776187) (xy 48.2404 -347.850153)
			(xy 48.251457 -347.925335) (xy 48.254158 -347.963236) (xy 48.255104 -347.972078) (xy 48.26215 -347.988388)
			(xy 48.274337 -348.001315) (xy 48.282098 -348.005654) (xy 48.37303 -348.051374) (xy 48.3997 -348.04985)
			(xy 48.41113 -348.04223) (xy 48.447343 -348.019182) (xy 48.523387 -347.979349) (xy 48.602912 -347.947022)
			(xy 48.685181 -347.922504) (xy 48.769429 -347.90602) (xy 48.854872 -347.897725) (xy 48.897794 -347.897196)
			(xy 48.938907 -347.897719) (xy 49.020782 -347.905305) (xy 49.101608 -347.920413) (xy 49.180695 -347.942914)
			(xy 49.257369 -347.972616) (xy 49.330975 -348.009266) (xy 49.400886 -348.05255) (xy 49.466504 -348.102101)
			(xy 49.527271 -348.157495) (xy 49.582668 -348.218259) (xy 49.632222 -348.283875) (xy 49.675511 -348.353783)
			(xy 49.712165 -348.427387) (xy 49.741871 -348.504059) (xy 49.764376 -348.583145) (xy 49.779489 -348.66397)
			(xy 49.78371 -348.7095) (xy 53.352901 -348.7095) (xy 53.356892 -348.625716) (xy 53.36883 -348.54269)
			(xy 53.388606 -348.461175) (xy 53.41604 -348.381909) (xy 53.450886 -348.30561) (xy 53.492827 -348.232969)
			(xy 53.541483 -348.164644) (xy 53.596413 -348.101253) (xy 53.65712 -348.043371) (xy 53.723055 -347.991522)
			(xy 53.79362 -347.946175) (xy 53.868176 -347.907741) (xy 53.946048 -347.876568) (xy 54.02653 -347.852939)
			(xy 54.108894 -347.837068) (xy 54.192394 -347.829098) (xy 54.234334 -347.828616) (xy 54.271523 -347.829023)
			(xy 54.345636 -347.835307) (xy 54.418956 -347.847812) (xy 54.490962 -347.866448) (xy 54.52618 -347.8784)
			(xy 54.534377 -347.880914) (xy 54.551511 -347.880914) (xy 54.559708 -347.8784) (xy 54.594654 -347.86653)
			(xy 54.66609 -347.847969) (xy 54.738831 -347.835458) (xy 54.812365 -347.829087) (xy 54.849268 -347.828616)
			(xy 54.85384 -347.82887) (xy 54.854348 -347.82887) (xy 54.863907 -347.782599) (xy 54.89152 -347.692237)
			(xy 54.909466 -347.64853) (xy 54.912939 -347.63891) (xy 54.912815 -347.618477) (xy 54.909212 -347.608906)
			(xy 54.892173 -347.5675) (xy 54.865541 -347.482011) (xy 54.847637 -347.394278) (xy 54.838644 -347.305189)
			(xy 54.838092 -347.260418) (xy 54.838596 -347.218057) (xy 54.846649 -347.13372) (xy 54.862683 -347.05053)
			(xy 54.886551 -346.96924) (xy 54.918039 -346.890588) (xy 54.956861 -346.815285) (xy 55.002664 -346.744013)
			(xy 55.055035 -346.677417) (xy 55.1135 -346.616102) (xy 55.177528 -346.560621) (xy 55.24654 -346.511478)
			(xy 55.31991 -346.469118) (xy 55.396975 -346.433923) (xy 55.477037 -346.406214) (xy 55.55937 -346.38624)
			(xy 55.643229 -346.374183) (xy 55.727854 -346.370152) (xy 55.812479 -346.374183) (xy 55.896338 -346.38624)
			(xy 55.978671 -346.406214) (xy 56.058733 -346.433923) (xy 56.135798 -346.469118) (xy 56.209168 -346.511478)
			(xy 56.27818 -346.560621) (xy 56.342208 -346.616102) (xy 56.400673 -346.677417) (xy 56.453044 -346.744013)
			(xy 56.498847 -346.815285) (xy 56.537669 -346.890588) (xy 56.569157 -346.96924) (xy 56.593025 -347.05053)
			(xy 56.609059 -347.13372) (xy 56.617112 -347.218057) (xy 56.617616 -347.260418) (xy 56.617044 -347.305187)
			(xy 56.608037 -347.394272) (xy 56.590134 -347.482003) (xy 56.563518 -347.567495) (xy 56.546496 -347.608906)
			(xy 56.542919 -347.618493) (xy 56.542926 -347.63894) (xy 56.546496 -347.64853) (xy 56.561684 -347.685398)
			(xy 56.586189 -347.761282) (xy 56.603812 -347.839053) (xy 56.614411 -347.918088) (xy 56.6166 -347.957902)
			(xy 56.617108 -347.971364) (xy 56.63184 -347.994224) (xy 56.734456 -348.047564) (xy 56.761634 -348.04604)
			(xy 56.773064 -348.038674) (xy 56.808981 -348.016152) (xy 56.88432 -347.977266) (xy 56.963017 -347.945725)
			(xy 57.044358 -347.921816) (xy 57.127605 -347.905754) (xy 57.212003 -347.897686) (xy 57.254394 -347.897196)
			(xy 57.295507 -347.897719) (xy 57.377382 -347.905305) (xy 57.458208 -347.920413) (xy 57.537295 -347.942914)
			(xy 57.613969 -347.972616) (xy 57.687575 -348.009266) (xy 57.757486 -348.05255) (xy 57.823104 -348.102101)
			(xy 57.883871 -348.157495) (xy 57.939268 -348.218259) (xy 57.988822 -348.283875) (xy 58.032111 -348.353783)
			(xy 58.068765 -348.427387) (xy 58.098471 -348.504059) (xy 58.120976 -348.583145) (xy 58.136089 -348.66397)
			(xy 58.14031 -348.7095) (xy 61.684101 -348.7095) (xy 61.688092 -348.625716) (xy 61.70003 -348.54269)
			(xy 61.719806 -348.461175) (xy 61.74724 -348.381909) (xy 61.782086 -348.30561) (xy 61.824027 -348.232969)
			(xy 61.872683 -348.164644) (xy 61.927613 -348.101253) (xy 61.98832 -348.043371) (xy 62.054255 -347.991522)
			(xy 62.12482 -347.946175) (xy 62.199376 -347.907741) (xy 62.277248 -347.876568) (xy 62.35773 -347.852939)
			(xy 62.440094 -347.837068) (xy 62.523594 -347.829098) (xy 62.565534 -347.828616) (xy 62.602723 -347.829023)
			(xy 62.676836 -347.835307) (xy 62.750156 -347.847812) (xy 62.822162 -347.866448) (xy 62.85738 -347.8784)
			(xy 62.865577 -347.880914) (xy 62.882711 -347.880914) (xy 62.890908 -347.8784) (xy 62.926096 -347.866455)
			(xy 62.998036 -347.847809) (xy 63.071292 -347.835299) (xy 63.145342 -347.829013) (xy 63.1825 -347.828616)
			(xy 63.183008 -347.828616) (xy 63.206122 -347.829124) (xy 63.215205 -347.793715) (xy 63.238479 -347.724411)
			(xy 63.252604 -347.690694) (xy 63.256229 -347.680981) (xy 63.25624 -347.66027) (xy 63.252604 -347.650562)
			(xy 63.235485 -347.609307) (xy 63.208697 -347.524095) (xy 63.190664 -347.436611) (xy 63.181571 -347.347751)
			(xy 63.180976 -347.30309) (xy 63.180976 -347.302328) (xy 63.181475 -347.260403) (xy 63.189445 -347.176932)
			(xy 63.205314 -347.094597) (xy 63.228937 -347.014143) (xy 63.260101 -346.936299) (xy 63.298524 -346.861769)
			(xy 63.343857 -346.79123) (xy 63.39569 -346.725319) (xy 63.453553 -346.664633) (xy 63.516923 -346.609723)
			(xy 63.585226 -346.561085) (xy 63.657843 -346.51916) (xy 63.734116 -346.484327) (xy 63.813355 -346.456902)
			(xy 63.894841 -346.437133) (xy 63.977838 -346.4252) (xy 64.061594 -346.421211) (xy 64.14535 -346.4252)
			(xy 64.228347 -346.437133) (xy 64.309833 -346.456902) (xy 64.389072 -346.484327) (xy 64.465345 -346.51916)
			(xy 64.537962 -346.561085) (xy 64.606265 -346.609723) (xy 64.669635 -346.664633) (xy 64.727498 -346.725319)
			(xy 64.779331 -346.79123) (xy 64.824664 -346.861769) (xy 64.863087 -346.936299) (xy 64.894251 -347.014143)
			(xy 64.917874 -347.094597) (xy 64.933743 -347.176932) (xy 64.941713 -347.260403) (xy 64.942212 -347.302328)
			(xy 64.942212 -347.30309) (xy 64.941639 -347.347753) (xy 64.932567 -347.436619) (xy 64.914535 -347.524107)
			(xy 64.88773 -347.609317) (xy 64.870584 -347.650562) (xy 64.866927 -347.660266) (xy 64.866937 -347.680985)
			(xy 64.870584 -347.690694) (xy 64.888862 -347.734789) (xy 64.91689 -347.826038) (xy 64.934892 -347.919782)
			(xy 64.939418 -347.9673) (xy 64.940434 -347.980508) (xy 64.955674 -348.00286) (xy 65.046352 -348.047056)
			(xy 65.054393 -348.050544) (xy 65.071798 -348.052482) (xy 65.088843 -348.048463) (xy 65.09639 -348.044008)
			(xy 65.096644 -348.043754) (xy 65.132959 -348.020439) (xy 65.209305 -347.980191) (xy 65.289189 -347.947525)
			(xy 65.371861 -347.922748) (xy 65.456544 -347.906093) (xy 65.542442 -347.897716) (xy 65.585594 -347.897196)
			(xy 65.626707 -347.897719) (xy 65.708582 -347.905305) (xy 65.789408 -347.920413) (xy 65.868495 -347.942914)
			(xy 65.945169 -347.972616) (xy 66.018775 -348.009266) (xy 66.088686 -348.05255) (xy 66.154304 -348.102101)
			(xy 66.215071 -348.157495) (xy 66.270468 -348.218259) (xy 66.320022 -348.283875) (xy 66.363311 -348.353783)
			(xy 66.399965 -348.427387) (xy 66.429671 -348.504059) (xy 66.452176 -348.583145) (xy 66.467289 -348.66397)
			(xy 66.474879 -348.745845) (xy 66.475356 -348.786958) (xy 66.474795 -348.831728) (xy 66.467942 -348.89948)
			(xy 81.294224 -348.89948) (xy 81.294687 -348.858913) (xy 81.30208 -348.778118) (xy 81.316804 -348.698332)
			(xy 81.338734 -348.620219) (xy 81.36769 -348.544429) (xy 81.385156 -348.507812) (xy 81.389058 -348.498717)
			(xy 81.390365 -348.478988) (xy 81.387696 -348.469458) (xy 81.373498 -348.424437) (xy 81.353605 -348.332151)
			(xy 81.343609 -348.238277) (xy 81.342992 -348.191074) (xy 81.343496 -348.148713) (xy 81.351549 -348.064376)
			(xy 81.367583 -347.981186) (xy 81.391451 -347.899896) (xy 81.422939 -347.821244) (xy 81.461761 -347.745941)
			(xy 81.507564 -347.674669) (xy 81.559935 -347.608073) (xy 81.6184 -347.546758) (xy 81.682428 -347.491277)
			(xy 81.75144 -347.442134) (xy 81.82481 -347.399774) (xy 81.901875 -347.364579) (xy 81.981937 -347.33687)
			(xy 82.06427 -347.316896) (xy 82.148129 -347.304839) (xy 82.232754 -347.300808) (xy 82.317379 -347.304839)
			(xy 82.401238 -347.316896) (xy 82.483571 -347.33687) (xy 82.563633 -347.364579) (xy 82.640698 -347.399774)
			(xy 82.714068 -347.442134) (xy 82.78308 -347.491277) (xy 82.847108 -347.546758) (xy 82.905573 -347.608073)
			(xy 82.957944 -347.674669) (xy 83.003747 -347.745941) (xy 83.042569 -347.821244) (xy 83.074057 -347.899896)
			(xy 83.097925 -347.981186) (xy 83.113959 -348.064376) (xy 83.122012 -348.148713) (xy 83.122516 -348.191074)
			(xy 83.12207 -348.231641) (xy 83.114672 -348.312437) (xy 83.099945 -348.392223) (xy 83.07801 -348.470336)
			(xy 83.049051 -348.546125) (xy 83.031584 -348.582742) (xy 83.027707 -348.591846) (xy 83.026383 -348.611567)
			(xy 83.029044 -348.621096) (xy 83.043232 -348.66612) (xy 83.063129 -348.758404) (xy 83.073129 -348.852278)
			(xy 83.073245 -348.861126) (xy 83.956144 -348.861126) (xy 83.956552 -348.820564) (xy 83.963891 -348.739773)
			(xy 83.978566 -348.659987) (xy 84.000454 -348.581872) (xy 84.029373 -348.506078) (xy 84.046822 -348.469458)
			(xy 84.05073 -348.460437) (xy 84.052174 -348.440849) (xy 84.049616 -348.431358) (xy 84.035467 -348.386455)
			(xy 84.015597 -348.294425) (xy 84.005567 -348.200811) (xy 84.004912 -348.153736) (xy 84.004912 -348.15272)
			(xy 84.005416 -348.110372) (xy 84.013467 -348.026058) (xy 84.029496 -347.942892) (xy 84.053357 -347.861625)
			(xy 84.084836 -347.782995) (xy 84.123647 -347.707714) (xy 84.169437 -347.636462) (xy 84.221793 -347.569886)
			(xy 84.280241 -347.508588) (xy 84.344251 -347.453123) (xy 84.413243 -347.403994) (xy 84.486593 -347.361645)
			(xy 84.563636 -347.326461) (xy 84.643675 -347.298759) (xy 84.725984 -347.278791) (xy 84.809819 -347.266738)
			(xy 84.89442 -347.262708) (xy 84.979021 -347.266738) (xy 85.062856 -347.278791) (xy 85.145165 -347.298759)
			(xy 85.225204 -347.326461) (xy 85.302247 -347.361645) (xy 85.375597 -347.403994) (xy 85.444589 -347.453123)
			(xy 85.508599 -347.508588) (xy 85.567047 -347.569886) (xy 85.619403 -347.636462) (xy 85.665193 -347.707714)
			(xy 85.704004 -347.782995) (xy 85.735483 -347.861625) (xy 85.759344 -347.942892) (xy 85.775373 -348.026058)
			(xy 85.783424 -348.110372) (xy 85.783928 -348.15272) (xy 85.783928 -348.153228) (xy 85.783471 -348.193738)
			(xy 85.77611 -348.274424) (xy 85.761432 -348.354104) (xy 85.73956 -348.432117) (xy 85.710675 -348.507814)
			(xy 85.69325 -348.544388) (xy 85.689318 -348.553401) (xy 85.687887 -348.572996) (xy 85.690456 -348.582488)
			(xy 85.70466 -348.627551) (xy 85.721282 -348.7047) (xy 275.231844 -348.7047) (xy 275.235834 -348.620942)
			(xy 275.247768 -348.537942) (xy 275.267537 -348.456452) (xy 275.294962 -348.377211) (xy 275.329796 -348.300935)
			(xy 275.371722 -348.228316) (xy 275.420361 -348.16001) (xy 275.475273 -348.096638) (xy 275.53596 -348.038772)
			(xy 275.601873 -347.986937) (xy 275.672414 -347.941602) (xy 275.746946 -347.903177) (xy 275.824792 -347.872011)
			(xy 275.905248 -347.848386) (xy 275.987586 -347.832515) (xy 276.071059 -347.824543) (xy 276.112986 -347.824044)
			(xy 276.114002 -347.824044) (xy 276.151059 -347.824452) (xy 276.224908 -347.830716) (xy 276.29797 -347.843157)
			(xy 276.36973 -347.861689) (xy 276.404832 -347.873574) (xy 276.413029 -347.876088) (xy 276.430163 -347.876088)
			(xy 276.43836 -347.873574) (xy 276.478966 -347.8599) (xy 276.562216 -347.839604) (xy 276.647042 -347.827484)
			(xy 276.68982 -347.82506) (xy 276.700434 -347.823969) (xy 276.719453 -347.814348) (xy 276.732947 -347.797851)
			(xy 276.736302 -347.787722) (xy 276.744404 -347.759433) (xy 276.763852 -347.703889) (xy 276.775164 -347.676724)
			(xy 276.778721 -347.667131) (xy 276.778725 -347.646691) (xy 276.775164 -347.6371) (xy 276.758127 -347.595694)
			(xy 276.731493 -347.510205) (xy 276.713589 -347.422472) (xy 276.704596 -347.333383) (xy 276.704044 -347.288612)
			(xy 276.704548 -347.246251) (xy 276.712601 -347.161914) (xy 276.728635 -347.078724) (xy 276.752503 -346.997434)
			(xy 276.783991 -346.918782) (xy 276.822813 -346.843479) (xy 276.868616 -346.772207) (xy 276.920987 -346.705611)
			(xy 276.979452 -346.644296) (xy 277.04348 -346.588815) (xy 277.112492 -346.539672) (xy 277.185862 -346.497312)
			(xy 277.262927 -346.462117) (xy 277.342989 -346.434408) (xy 277.425322 -346.414434) (xy 277.509181 -346.402377)
			(xy 277.593806 -346.398346) (xy 277.678431 -346.402377) (xy 277.76229 -346.414434) (xy 277.844623 -346.434408)
			(xy 277.924685 -346.462117) (xy 278.00175 -346.497312) (xy 278.07512 -346.539672) (xy 278.144132 -346.588815)
			(xy 278.20816 -346.644296) (xy 278.266625 -346.705611) (xy 278.318996 -346.772207) (xy 278.364799 -346.843479)
			(xy 278.403621 -346.918782) (xy 278.435109 -346.997434) (xy 278.458977 -347.078724) (xy 278.475011 -347.161914)
			(xy 278.483064 -347.246251) (xy 278.483568 -347.288612) (xy 278.482998 -347.333381) (xy 278.47399 -347.422466)
			(xy 278.456088 -347.510198) (xy 278.42947 -347.595689) (xy 278.412448 -347.6371) (xy 278.408812 -347.646665)
			(xy 278.408686 -347.667111) (xy 278.412194 -347.676724) (xy 278.426408 -347.711074) (xy 278.449728 -347.781668)
			(xy 278.467082 -347.85396) (xy 278.478348 -347.927447) (xy 278.481282 -347.964506) (xy 278.482267 -347.973327)
			(xy 278.489457 -347.989544) (xy 278.501708 -348.002373) (xy 278.509476 -348.00667) (xy 278.600662 -348.051628)
			(xy 278.62784 -348.049596) (xy 278.639016 -348.04223) (xy 278.675581 -348.018458) (xy 278.752524 -347.977387)
			(xy 278.833117 -347.944041) (xy 278.916586 -347.91874) (xy 279.00213 -347.901729) (xy 279.088929 -347.893169)
			(xy 279.132538 -347.892624) (xy 279.133046 -347.892624) (xy 279.174153 -347.893069) (xy 279.256016 -347.900657)
			(xy 279.336831 -347.915765) (xy 279.415907 -347.938263) (xy 279.49257 -347.96796) (xy 279.566167 -348.004602)
			(xy 279.63607 -348.047877) (xy 279.701683 -348.097416) (xy 279.762447 -348.152796) (xy 279.817842 -348.213546)
			(xy 279.867398 -348.279147) (xy 279.91069 -348.349039) (xy 279.947351 -348.422627) (xy 279.977067 -348.499283)
			(xy 279.999585 -348.578353) (xy 280.014712 -348.659164) (xy 280.018945 -348.7047) (xy 283.512244 -348.7047)
			(xy 283.516234 -348.620942) (xy 283.528168 -348.537942) (xy 283.547937 -348.456452) (xy 283.575362 -348.377211)
			(xy 283.610196 -348.300935) (xy 283.652122 -348.228316) (xy 283.700761 -348.16001) (xy 283.755673 -348.096638)
			(xy 283.81636 -348.038772) (xy 283.882273 -347.986937) (xy 283.952814 -347.941602) (xy 284.027346 -347.903177)
			(xy 284.105192 -347.872011) (xy 284.185648 -347.848386) (xy 284.267986 -347.832515) (xy 284.351459 -347.824543)
			(xy 284.393386 -347.824044) (xy 284.394402 -347.824044) (xy 284.431459 -347.824452) (xy 284.505308 -347.830716)
			(xy 284.57837 -347.843157) (xy 284.65013 -347.861689) (xy 284.685232 -347.873574) (xy 284.693429 -347.876088)
			(xy 284.710563 -347.876088) (xy 284.71876 -347.873574) (xy 284.756938 -347.860634) (xy 284.835124 -347.840982)
			(xy 284.91478 -347.828562) (xy 284.95498 -347.825568) (xy 284.965838 -347.82436) (xy 284.985096 -347.814096)
			(xy 284.99831 -347.79673) (xy 285.001208 -347.786198) (xy 285.010486 -347.747118) (xy 285.035162 -347.670674)
			(xy 285.050484 -347.633544) (xy 285.054028 -347.623948) (xy 285.05404 -347.603511) (xy 285.050484 -347.59392)
			(xy 285.033454 -347.552511) (xy 285.006819 -347.467023) (xy 284.988912 -347.379291) (xy 284.979917 -347.290203)
			(xy 284.979364 -347.245432) (xy 284.979868 -347.203071) (xy 284.987921 -347.118734) (xy 285.003955 -347.035544)
			(xy 285.027823 -346.954254) (xy 285.059311 -346.875602) (xy 285.098133 -346.800299) (xy 285.143936 -346.729027)
			(xy 285.196307 -346.662431) (xy 285.254772 -346.601116) (xy 285.3188 -346.545635) (xy 285.387812 -346.496492)
			(xy 285.461182 -346.454132) (xy 285.538247 -346.418937) (xy 285.618309 -346.391228) (xy 285.700642 -346.371254)
			(xy 285.784501 -346.359197) (xy 285.869126 -346.355166) (xy 285.953751 -346.359197) (xy 286.03761 -346.371254)
			(xy 286.119943 -346.391228) (xy 286.200005 -346.418937) (xy 286.27707 -346.454132) (xy 286.35044 -346.496492)
			(xy 286.419452 -346.545635) (xy 286.48348 -346.601116) (xy 286.541945 -346.662431) (xy 286.594316 -346.729027)
			(xy 286.640119 -346.800299) (xy 286.678941 -346.875602) (xy 286.710429 -346.954254) (xy 286.734297 -347.035544)
			(xy 286.750331 -347.118734) (xy 286.758384 -347.203071) (xy 286.758888 -347.245432) (xy 286.758323 -347.290202)
			(xy 286.749314 -347.379287) (xy 286.73141 -347.467018) (xy 286.704791 -347.552509) (xy 286.687768 -347.59392)
			(xy 286.684185 -347.603505) (xy 286.684197 -347.623953) (xy 286.687768 -347.633544) (xy 286.703871 -347.672618)
			(xy 286.72945 -347.753174) (xy 286.747275 -347.835792) (xy 286.757183 -347.919728) (xy 286.758634 -347.961966)
			(xy 286.758888 -347.975936) (xy 286.77362 -347.999558) (xy 286.86506 -348.047056) (xy 286.873276 -348.050887)
			(xy 286.891249 -348.053129) (xy 286.908879 -348.048973) (xy 286.916622 -348.044262) (xy 286.916876 -348.044008)
			(xy 286.95358 -348.019938) (xy 287.030887 -347.978361) (xy 287.111915 -347.944605) (xy 287.195876 -347.918998)
			(xy 287.281951 -347.901791) (xy 287.369303 -347.893149) (xy 287.413192 -347.892624) (xy 287.413446 -347.892624)
			(xy 287.454553 -347.893069) (xy 287.536416 -347.900657) (xy 287.617231 -347.915765) (xy 287.696307 -347.938263)
			(xy 287.77297 -347.96796) (xy 287.846567 -348.004602) (xy 287.91647 -348.047877) (xy 287.982083 -348.097416)
			(xy 288.042847 -348.152796) (xy 288.098242 -348.213546) (xy 288.147798 -348.279147) (xy 288.19109 -348.349039)
			(xy 288.227751 -348.422627) (xy 288.257467 -348.499283) (xy 288.279985 -348.578353) (xy 288.295112 -348.659164)
			(xy 288.299345 -348.7047) (xy 291.818044 -348.7047) (xy 291.822034 -348.620942) (xy 291.833968 -348.537942)
			(xy 291.853737 -348.456452) (xy 291.881162 -348.377211) (xy 291.915996 -348.300935) (xy 291.957922 -348.228316)
			(xy 292.006561 -348.16001) (xy 292.061473 -348.096638) (xy 292.12216 -348.038772) (xy 292.188073 -347.986937)
			(xy 292.258614 -347.941602) (xy 292.333146 -347.903177) (xy 292.410992 -347.872011) (xy 292.491448 -347.848386)
			(xy 292.573786 -347.832515) (xy 292.657259 -347.824543) (xy 292.699186 -347.824044) (xy 292.700202 -347.824044)
			(xy 292.737259 -347.824452) (xy 292.811108 -347.830716) (xy 292.88417 -347.843157) (xy 292.95593 -347.861689)
			(xy 292.991032 -347.873574) (xy 292.999229 -347.876088) (xy 293.016363 -347.876088) (xy 293.02456 -347.873574)
			(xy 293.057737 -347.862322) (xy 293.125493 -347.844496) (xy 293.194454 -347.832123) (xy 293.229284 -347.828362)
			(xy 293.240044 -347.82673) (xy 293.258819 -347.815766) (xy 293.271409 -347.798041) (xy 293.273988 -347.787468)
			(xy 293.28351 -347.742121) (xy 293.310744 -347.653548) (xy 293.328344 -347.610684) (xy 293.331924 -347.601098)
			(xy 293.331914 -347.580651) (xy 293.328344 -347.57106) (xy 293.311293 -347.529659) (xy 293.284663 -347.444168)
			(xy 293.266763 -347.356433) (xy 293.257774 -347.267343) (xy 293.257224 -347.222572) (xy 293.257728 -347.180211)
			(xy 293.265781 -347.095874) (xy 293.281815 -347.012684) (xy 293.305683 -346.931394) (xy 293.337171 -346.852742)
			(xy 293.375993 -346.777439) (xy 293.421796 -346.706167) (xy 293.474167 -346.639571) (xy 293.532632 -346.578256)
			(xy 293.59666 -346.522775) (xy 293.665672 -346.473632) (xy 293.739042 -346.431272) (xy 293.816107 -346.396077)
			(xy 293.896169 -346.368368) (xy 293.978502 -346.348394) (xy 294.062361 -346.336337) (xy 294.146986 -346.332306)
			(xy 294.231611 -346.336337) (xy 294.31547 -346.348394) (xy 294.397803 -346.368368) (xy 294.477865 -346.396077)
			(xy 294.55493 -346.431272) (xy 294.6283 -346.473632) (xy 294.697312 -346.522775) (xy 294.76134 -346.578256)
			(xy 294.819805 -346.639571) (xy 294.872176 -346.706167) (xy 294.917979 -346.777439) (xy 294.956801 -346.852742)
			(xy 294.988289 -346.931394) (xy 295.012157 -347.012684) (xy 295.028191 -347.095874) (xy 295.036244 -347.180211)
			(xy 295.036748 -347.222572) (xy 295.036192 -347.267342) (xy 295.027179 -347.356427) (xy 295.009272 -347.444158)
			(xy 294.982652 -347.529649) (xy 294.965628 -347.57106) (xy 294.962081 -347.580656) (xy 294.96207 -347.601093)
			(xy 294.965628 -347.610684) (xy 294.982659 -347.652092) (xy 295.009295 -347.73758) (xy 295.0272 -347.825313)
			(xy 295.036195 -347.914401) (xy 295.036748 -347.959172) (xy 295.036494 -347.977206) (xy 295.03624 -347.991684)
			(xy 295.050718 -348.016576) (xy 295.157144 -348.071948) (xy 295.185846 -348.069916) (xy 295.19753 -348.061534)
			(xy 295.230035 -348.038582) (xy 295.298406 -347.997866) (xy 295.370142 -347.963421) (xy 295.444669 -347.935524)
			(xy 295.521391 -347.914398) (xy 295.599693 -347.900211) (xy 295.67895 -347.893078) (xy 295.718738 -347.892624)
			(xy 295.719246 -347.892624) (xy 295.760353 -347.893069) (xy 295.842216 -347.900657) (xy 295.923031 -347.915765)
			(xy 296.002107 -347.938263) (xy 296.07877 -347.96796) (xy 296.152367 -348.004602) (xy 296.22227 -348.047877)
			(xy 296.287883 -348.097416) (xy 296.348647 -348.152796) (xy 296.404042 -348.213546) (xy 296.453598 -348.279147)
			(xy 296.49689 -348.349039) (xy 296.533551 -348.422627) (xy 296.563267 -348.499283) (xy 296.585785 -348.578353)
			(xy 296.600912 -348.659164) (xy 296.605145 -348.7047) (xy 300.174644 -348.7047) (xy 300.178634 -348.620942)
			(xy 300.190568 -348.537942) (xy 300.210337 -348.456452) (xy 300.237762 -348.377211) (xy 300.272596 -348.300935)
			(xy 300.314522 -348.228316) (xy 300.363161 -348.16001) (xy 300.418073 -348.096638) (xy 300.47876 -348.038772)
			(xy 300.544673 -347.986937) (xy 300.615214 -347.941602) (xy 300.689746 -347.903177) (xy 300.767592 -347.872011)
			(xy 300.848048 -347.848386) (xy 300.930386 -347.832515) (xy 301.013859 -347.824543) (xy 301.055786 -347.824044)
			(xy 301.056802 -347.824044) (xy 301.093859 -347.824452) (xy 301.167708 -347.830716) (xy 301.24077 -347.843157)
			(xy 301.31253 -347.861689) (xy 301.347632 -347.873574) (xy 301.355829 -347.876088) (xy 301.372963 -347.876088)
			(xy 301.38116 -347.873574) (xy 301.419296 -347.860641) (xy 301.497398 -347.840993) (xy 301.576968 -347.828568)
			(xy 301.617126 -347.825568) (xy 301.627844 -347.824451) (xy 301.646914 -347.814446) (xy 301.660249 -347.797535)
			(xy 301.663354 -347.787214) (xy 301.672203 -347.75314) (xy 301.694583 -347.686387) (xy 301.708058 -347.653864)
			(xy 301.711569 -347.644255) (xy 301.711421 -347.623811) (xy 301.707804 -347.61424) (xy 301.690776 -347.57283)
			(xy 301.66414 -347.487343) (xy 301.646234 -347.39961) (xy 301.637237 -347.310523) (xy 301.636684 -347.265752)
			(xy 301.637188 -347.223391) (xy 301.645241 -347.139054) (xy 301.661275 -347.055864) (xy 301.685143 -346.974574)
			(xy 301.716631 -346.895922) (xy 301.755453 -346.820619) (xy 301.801256 -346.749347) (xy 301.853627 -346.682751)
			(xy 301.912092 -346.621436) (xy 301.97612 -346.565955) (xy 302.045132 -346.516812) (xy 302.118502 -346.474452)
			(xy 302.195567 -346.439257) (xy 302.275629 -346.411548) (xy 302.357962 -346.391574) (xy 302.441821 -346.379517)
			(xy 302.526446 -346.375486) (xy 302.611071 -346.379517) (xy 302.69493 -346.391574) (xy 302.777263 -346.411548)
			(xy 302.857325 -346.439257) (xy 302.93439 -346.474452) (xy 303.00776 -346.516812) (xy 303.076772 -346.565955)
			(xy 303.1408 -346.621436) (xy 303.199265 -346.682751) (xy 303.251636 -346.749347) (xy 303.297439 -346.820619)
			(xy 303.336261 -346.895922) (xy 303.367749 -346.974574) (xy 303.391617 -347.055864) (xy 303.407651 -347.139054)
			(xy 303.415704 -347.223391) (xy 303.416208 -347.265752) (xy 303.415649 -347.310522) (xy 303.406637 -347.399607)
			(xy 303.388731 -347.487338) (xy 303.362111 -347.572829) (xy 303.345088 -347.61424) (xy 303.341549 -347.623838)
			(xy 303.341532 -347.644274) (xy 303.345088 -347.653864) (xy 303.36051 -347.691224) (xy 303.385289 -347.768163)
			(xy 303.402976 -347.847034) (xy 303.413426 -347.927187) (xy 303.415446 -347.967554) (xy 303.415954 -347.981524)
			(xy 303.430686 -348.004638) (xy 303.535334 -348.057216) (xy 303.562766 -348.055184) (xy 303.574196 -348.04731)
			(xy 303.611146 -348.022772) (xy 303.689046 -347.980345) (xy 303.770779 -347.945874) (xy 303.855535 -347.919702)
			(xy 303.942473 -347.902087) (xy 304.030732 -347.893205) (xy 304.075084 -347.892624) (xy 304.075846 -347.892624)
			(xy 304.116953 -347.893069) (xy 304.198816 -347.900657) (xy 304.279631 -347.915765) (xy 304.358707 -347.938263)
			(xy 304.43537 -347.96796) (xy 304.508967 -348.004602) (xy 304.57887 -348.047877) (xy 304.644483 -348.097416)
			(xy 304.705247 -348.152796) (xy 304.760642 -348.213546) (xy 304.810198 -348.279147) (xy 304.85349 -348.349039)
			(xy 304.890151 -348.422627) (xy 304.919867 -348.499283) (xy 304.942385 -348.578353) (xy 304.957512 -348.659164)
			(xy 304.961745 -348.7047) (xy 308.505844 -348.7047) (xy 308.509834 -348.620942) (xy 308.521768 -348.537942)
			(xy 308.541537 -348.456452) (xy 308.568962 -348.377211) (xy 308.603796 -348.300935) (xy 308.645722 -348.228316)
			(xy 308.694361 -348.16001) (xy 308.749273 -348.096638) (xy 308.80996 -348.038772) (xy 308.875873 -347.986937)
			(xy 308.946414 -347.941602) (xy 309.020946 -347.903177) (xy 309.098792 -347.872011) (xy 309.179248 -347.848386)
			(xy 309.261586 -347.832515) (xy 309.345059 -347.824543) (xy 309.386986 -347.824044) (xy 309.388002 -347.824044)
			(xy 309.425059 -347.824452) (xy 309.498908 -347.830716) (xy 309.57197 -347.843157) (xy 309.64373 -347.861689)
			(xy 309.678832 -347.873574) (xy 309.687029 -347.876088) (xy 309.704163 -347.876088) (xy 309.71236 -347.873574)
			(xy 309.752087 -347.860214) (xy 309.833476 -347.84017) (xy 309.916402 -347.827952) (xy 309.958232 -347.825314)
			(xy 309.969008 -347.824123) (xy 309.988202 -347.814097) (xy 310.001607 -347.79709) (xy 310.004714 -347.786706)
			(xy 310.013576 -347.75276) (xy 310.035956 -347.686262) (xy 310.049418 -347.653864) (xy 310.052931 -347.644255)
			(xy 310.052783 -347.623811) (xy 310.049164 -347.61424) (xy 310.03214 -347.572829) (xy 310.005503 -347.487342)
			(xy 309.987595 -347.39961) (xy 309.978598 -347.310522) (xy 309.978044 -347.265752) (xy 309.978548 -347.223391)
			(xy 309.986601 -347.139054) (xy 310.002635 -347.055864) (xy 310.026503 -346.974574) (xy 310.057991 -346.895922)
			(xy 310.096813 -346.820619) (xy 310.142616 -346.749347) (xy 310.194987 -346.682751) (xy 310.253452 -346.621436)
			(xy 310.31748 -346.565955) (xy 310.386492 -346.516812) (xy 310.459862 -346.474452) (xy 310.536927 -346.439257)
			(xy 310.616989 -346.411548) (xy 310.699322 -346.391574) (xy 310.783181 -346.379517) (xy 310.867806 -346.375486)
			(xy 310.952431 -346.379517) (xy 311.03629 -346.391574) (xy 311.118623 -346.411548) (xy 311.198685 -346.439257)
			(xy 311.27575 -346.474452) (xy 311.34912 -346.516812) (xy 311.418132 -346.565955) (xy 311.48216 -346.621436)
			(xy 311.540625 -346.682751) (xy 311.592996 -346.749347) (xy 311.638799 -346.820619) (xy 311.677621 -346.895922)
			(xy 311.709109 -346.974574) (xy 311.732977 -347.055864) (xy 311.749011 -347.139054) (xy 311.757064 -347.223391)
			(xy 311.757568 -347.265752) (xy 311.757012 -347.310522) (xy 311.748 -347.399607) (xy 311.730093 -347.487338)
			(xy 311.703472 -347.572829) (xy 311.686448 -347.61424) (xy 311.682911 -347.623839) (xy 311.682894 -347.644274)
			(xy 311.686448 -347.653864) (xy 311.701578 -347.690518) (xy 311.725997 -347.765967) (xy 311.743615 -347.843288)
			(xy 311.754293 -347.921869) (xy 311.756552 -347.961458) (xy 311.757251 -347.970429) (xy 311.764179 -347.987026)
			(xy 311.776392 -348.000229) (xy 311.784238 -348.004638) (xy 311.875678 -348.050866) (xy 311.902856 -348.049088)
			(xy 311.914286 -348.041468) (xy 311.950798 -348.017804) (xy 312.027605 -347.976914) (xy 312.10804 -347.943725)
			(xy 312.191333 -347.918554) (xy 312.276687 -347.901641) (xy 312.363285 -347.893148) (xy 312.406792 -347.892624)
			(xy 312.407046 -347.892624) (xy 312.448153 -347.893069) (xy 312.530016 -347.900657) (xy 312.610831 -347.915765)
			(xy 312.689907 -347.938263) (xy 312.76657 -347.96796) (xy 312.840167 -348.004602) (xy 312.91007 -348.047877)
			(xy 312.975683 -348.097416) (xy 313.036447 -348.152796) (xy 313.091842 -348.213546) (xy 313.141398 -348.279147)
			(xy 313.18469 -348.349039) (xy 313.221351 -348.422627) (xy 313.251067 -348.499283) (xy 313.273585 -348.578353)
			(xy 313.288712 -348.659164) (xy 313.296321 -348.741025) (xy 313.296808 -348.782132) (xy 313.296242 -348.826902)
			(xy 313.287233 -348.915987) (xy 313.269329 -349.003718) (xy 313.242711 -349.089209) (xy 313.225688 -349.13062)
			(xy 313.222104 -349.140205) (xy 313.222115 -349.160653) (xy 313.225688 -349.170244) (xy 313.242711 -349.211656)
			(xy 313.269347 -349.297143) (xy 313.287256 -349.384874) (xy 313.291976 -349.43161) (xy 326.552821 -349.43161)
			(xy 326.556826 -349.325861) (xy 326.568816 -349.220718) (xy 326.588725 -349.116783) (xy 326.616436 -349.014651)
			(xy 326.651793 -348.914907) (xy 326.694591 -348.818123) (xy 326.744587 -348.724853) (xy 326.801494 -348.635632)
			(xy 326.864985 -348.550969) (xy 326.934697 -348.471351) (xy 327.010231 -348.397233) (xy 327.091154 -348.32904)
			(xy 327.177003 -348.267162) (xy 327.267286 -348.211955) (xy 327.361485 -348.163733) (xy 327.459062 -348.122773)
			(xy 327.559457 -348.089311) (xy 327.662095 -348.063537) (xy 327.766388 -348.045599) (xy 327.871739 -348.0356)
			(xy 327.977545 -348.033597) (xy 328.083199 -348.039602) (xy 328.188096 -348.053581) (xy 328.291636 -348.075452)
			(xy 328.393225 -348.105092) (xy 328.492282 -348.14233) (xy 328.588239 -348.186952) (xy 328.680546 -348.238704)
			(xy 328.768675 -348.297289) (xy 328.852121 -348.362371) (xy 328.930405 -348.433577) (xy 329.00308 -348.5105)
			(xy 329.06973 -348.5927) (xy 329.129972 -348.679704) (xy 329.183461 -348.771015) (xy 329.229892 -348.86611)
			(xy 329.268997 -348.964444) (xy 329.300554 -349.065455) (xy 329.324381 -349.168562) (xy 329.340342 -349.273176)
			(xy 329.348346 -349.378698) (xy 329.348846 -349.43161) (xy 334.012801 -349.43161) (xy 334.016806 -349.325861)
			(xy 334.028796 -349.220718) (xy 334.048705 -349.116783) (xy 334.076416 -349.014651) (xy 334.111773 -348.914907)
			(xy 334.154571 -348.818123) (xy 334.204567 -348.724853) (xy 334.261474 -348.635632) (xy 334.324965 -348.550969)
			(xy 334.394677 -348.471351) (xy 334.470211 -348.397233) (xy 334.551134 -348.32904) (xy 334.636983 -348.267162)
			(xy 334.727266 -348.211955) (xy 334.821465 -348.163733) (xy 334.919042 -348.122773) (xy 335.019437 -348.089311)
			(xy 335.122075 -348.063537) (xy 335.226368 -348.045599) (xy 335.331719 -348.0356) (xy 335.437525 -348.033597)
			(xy 335.543179 -348.039602) (xy 335.648076 -348.053581) (xy 335.751616 -348.075452) (xy 335.853205 -348.105092)
			(xy 335.952262 -348.14233) (xy 336.048219 -348.186952) (xy 336.140526 -348.238704) (xy 336.228655 -348.297289)
			(xy 336.312101 -348.362371) (xy 336.390385 -348.433577) (xy 336.46306 -348.5105) (xy 336.52971 -348.5927)
			(xy 336.589952 -348.679704) (xy 336.643441 -348.771015) (xy 336.689872 -348.86611) (xy 336.728977 -348.964444)
			(xy 336.760534 -349.065455) (xy 336.784361 -349.168562) (xy 336.800322 -349.273176) (xy 336.808326 -349.378698)
			(xy 336.808826 -349.43161) (xy 336.808326 -349.484522) (xy 336.800322 -349.590044) (xy 336.784361 -349.694658)
			(xy 336.760534 -349.797765) (xy 336.728977 -349.898776) (xy 336.689872 -349.99711) (xy 336.643441 -350.092205)
			(xy 336.589952 -350.183516) (xy 336.52971 -350.27052) (xy 336.46306 -350.35272) (xy 336.390385 -350.429643)
			(xy 336.312101 -350.500849) (xy 336.228655 -350.565931) (xy 336.140526 -350.624516) (xy 336.048219 -350.676268)
			(xy 335.952262 -350.72089) (xy 335.853205 -350.758128) (xy 335.751616 -350.787768) (xy 335.648076 -350.809639)
			(xy 335.543179 -350.823618) (xy 335.437525 -350.829623) (xy 335.331719 -350.82762) (xy 335.226368 -350.817621)
			(xy 335.122075 -350.799683) (xy 335.019437 -350.773909) (xy 334.919042 -350.740447) (xy 334.821465 -350.699487)
			(xy 334.727266 -350.651265) (xy 334.636983 -350.596058) (xy 334.551134 -350.53418) (xy 334.470211 -350.465987)
			(xy 334.394677 -350.391869) (xy 334.324965 -350.312251) (xy 334.261474 -350.227588) (xy 334.204567 -350.138367)
			(xy 334.154571 -350.045097) (xy 334.111773 -349.948313) (xy 334.076416 -349.848569) (xy 334.048705 -349.746437)
			(xy 334.028796 -349.642502) (xy 334.016806 -349.537359) (xy 334.012801 -349.43161) (xy 329.348846 -349.43161)
			(xy 329.348346 -349.484522) (xy 329.340342 -349.590044) (xy 329.324381 -349.694658) (xy 329.300554 -349.797765)
			(xy 329.268997 -349.898776) (xy 329.229892 -349.99711) (xy 329.183461 -350.092205) (xy 329.129972 -350.183516)
			(xy 329.06973 -350.27052) (xy 329.00308 -350.35272) (xy 328.930405 -350.429643) (xy 328.852121 -350.500849)
			(xy 328.768675 -350.565931) (xy 328.680546 -350.624516) (xy 328.588239 -350.676268) (xy 328.492282 -350.72089)
			(xy 328.393225 -350.758128) (xy 328.291636 -350.787768) (xy 328.188096 -350.809639) (xy 328.083199 -350.823618)
			(xy 327.977545 -350.829623) (xy 327.871739 -350.82762) (xy 327.766388 -350.817621) (xy 327.662095 -350.799683)
			(xy 327.559457 -350.773909) (xy 327.459062 -350.740447) (xy 327.361485 -350.699487) (xy 327.267286 -350.651265)
			(xy 327.177003 -350.596058) (xy 327.091154 -350.53418) (xy 327.010231 -350.465987) (xy 326.934697 -350.391869)
			(xy 326.864985 -350.312251) (xy 326.801494 -350.227588) (xy 326.744587 -350.138367) (xy 326.694591 -350.045097)
			(xy 326.651793 -349.948313) (xy 326.616436 -349.848569) (xy 326.588725 -349.746437) (xy 326.568816 -349.642502)
			(xy 326.556826 -349.537359) (xy 326.552821 -349.43161) (xy 313.291976 -349.43161) (xy 313.296254 -349.473962)
			(xy 313.296808 -349.518732) (xy 313.296242 -349.563502) (xy 313.287233 -349.652587) (xy 313.269329 -349.740318)
			(xy 313.242711 -349.825809) (xy 313.225688 -349.86722) (xy 313.222104 -349.876805) (xy 313.222115 -349.897253)
			(xy 313.225688 -349.906844) (xy 313.242711 -349.948256) (xy 313.269347 -350.033743) (xy 313.287256 -350.121474)
			(xy 313.296254 -350.210562) (xy 313.296808 -350.255332) (xy 313.296378 -350.296443) (xy 313.288787 -350.378314)
			(xy 313.273674 -350.459136) (xy 313.251166 -350.538217) (xy 313.221457 -350.614885) (xy 313.184799 -350.688483)
			(xy 313.141506 -350.758385) (xy 313.091947 -350.823993) (xy 313.036545 -350.884747) (xy 312.975772 -350.94013)
			(xy 312.910148 -350.989668) (xy 312.840233 -351.032938) (xy 312.766623 -351.069572) (xy 312.689946 -351.099257)
			(xy 312.610857 -351.121739) (xy 312.530031 -351.136827) (xy 312.448157 -351.144391) (xy 312.407046 -351.14484)
			(xy 312.365442 -351.14437) (xy 312.282594 -351.136637) (xy 312.200829 -351.121206) (xy 312.120862 -351.098211)
			(xy 312.043389 -351.067854) (xy 311.969088 -351.0304) (xy 311.93359 -351.008696) (xy 311.924458 -351.003521)
			(xy 311.903738 -351.00031) (xy 311.883461 -351.005649) (xy 311.874916 -351.011744) (xy 311.841266 -351.037664)
			(xy 311.769892 -351.083723) (xy 311.694453 -351.12277) (xy 311.615637 -351.15445) (xy 311.53416 -351.178473)
			(xy 311.450764 -351.194623) (xy 311.366208 -351.20275) (xy 311.323736 -351.20326) (xy 311.323482 -351.20326)
			(xy 311.282375 -351.202805) (xy 311.200511 -351.195219) (xy 311.119697 -351.180113) (xy 311.04062 -351.157617)
			(xy 310.963956 -351.127921) (xy 310.890359 -351.09128) (xy 310.820455 -351.048006) (xy 310.754841 -350.998468)
			(xy 310.694077 -350.943088) (xy 310.638682 -350.882339) (xy 310.589126 -350.816738) (xy 310.545833 -350.746846)
			(xy 310.509173 -350.673258) (xy 310.479458 -350.596602) (xy 310.456941 -350.517531) (xy 310.441814 -350.43672)
			(xy 310.434206 -350.354859) (xy 310.43372 -350.313752) (xy 310.434279 -350.268982) (xy 310.44329 -350.179897)
			(xy 310.461196 -350.092166) (xy 310.487816 -350.006675) (xy 310.50484 -349.965264) (xy 310.508432 -349.955681)
			(xy 310.508415 -349.935231) (xy 310.50484 -349.92564) (xy 310.487836 -349.884289) (xy 310.461225 -349.798927)
			(xy 310.443318 -349.711324) (xy 310.434296 -349.622367) (xy 310.43372 -349.57766) (xy 310.43372 -349.576644)
			(xy 310.433974 -349.565214) (xy 310.407495 -349.559269) (xy 310.35526 -349.544526) (xy 310.32958 -349.53575)
			(xy 310.321383 -349.533236) (xy 310.304249 -349.533236) (xy 310.296052 -349.53575) (xy 310.260836 -349.547697)
			(xy 310.188826 -349.566284) (xy 310.115503 -349.578724) (xy 310.041392 -349.584928) (xy 310.004206 -349.58528)
			(xy 309.967022 -349.584911) (xy 309.892914 -349.578689) (xy 309.819594 -349.566246) (xy 309.747583 -349.547672)
			(xy 309.71236 -349.53575) (xy 309.704163 -349.533236) (xy 309.687029 -349.533236) (xy 309.678832 -349.53575)
			(xy 309.64373 -349.547637) (xy 309.571974 -349.566187) (xy 309.498911 -349.578634) (xy 309.42506 -349.584887)
			(xy 309.388002 -349.58528) (xy 309.386986 -349.58528) (xy 309.345059 -349.584857) (xy 309.261586 -349.576885)
			(xy 309.179248 -349.561014) (xy 309.098792 -349.537389) (xy 309.020946 -349.506223) (xy 308.946414 -349.467798)
			(xy 308.875873 -349.422463) (xy 308.80996 -349.370628) (xy 308.749273 -349.312762) (xy 308.694361 -349.24939)
			(xy 308.645722 -349.181084) (xy 308.603796 -349.108465) (xy 308.568962 -349.032189) (xy 308.541537 -348.952948)
			(xy 308.521768 -348.871458) (xy 308.509834 -348.788458) (xy 308.505844 -348.7047) (xy 304.961745 -348.7047)
			(xy 304.965121 -348.741025) (xy 304.965608 -348.782132) (xy 304.965042 -348.826902) (xy 304.956033 -348.915987)
			(xy 304.938129 -349.003718) (xy 304.911511 -349.089209) (xy 304.894488 -349.13062) (xy 304.890904 -349.140205)
			(xy 304.890915 -349.160653) (xy 304.894488 -349.170244) (xy 304.911511 -349.211656) (xy 304.938147 -349.297143)
			(xy 304.956056 -349.384874) (xy 304.965054 -349.473962) (xy 304.965608 -349.518732) (xy 304.965042 -349.563502)
			(xy 304.956033 -349.652587) (xy 304.938129 -349.740318) (xy 304.911511 -349.825809) (xy 304.894488 -349.86722)
			(xy 304.890904 -349.876805) (xy 304.890915 -349.897253) (xy 304.894488 -349.906844) (xy 304.911511 -349.948256)
			(xy 304.938147 -350.033743) (xy 304.956056 -350.121474) (xy 304.965054 -350.210562) (xy 304.965608 -350.255332)
			(xy 304.965178 -350.296443) (xy 304.957587 -350.378314) (xy 304.942474 -350.459136) (xy 304.919966 -350.538217)
			(xy 304.890257 -350.614885) (xy 304.853599 -350.688483) (xy 304.810306 -350.758385) (xy 304.760747 -350.823993)
			(xy 304.705345 -350.884747) (xy 304.644572 -350.94013) (xy 304.578948 -350.989668) (xy 304.509033 -351.032938)
			(xy 304.435423 -351.069572) (xy 304.358746 -351.099257) (xy 304.279657 -351.121739) (xy 304.198831 -351.136827)
			(xy 304.116957 -351.144391) (xy 304.075846 -351.14484) (xy 304.034242 -351.14437) (xy 303.951394 -351.136637)
			(xy 303.869629 -351.121206) (xy 303.789662 -351.098211) (xy 303.712189 -351.067854) (xy 303.637888 -351.0304)
			(xy 303.60239 -351.008696) (xy 303.593258 -351.003521) (xy 303.572538 -351.00031) (xy 303.552261 -351.005649)
			(xy 303.543716 -351.011744) (xy 303.510066 -351.037664) (xy 303.438692 -351.083723) (xy 303.363253 -351.12277)
			(xy 303.284437 -351.15445) (xy 303.20296 -351.178473) (xy 303.119564 -351.194623) (xy 303.035008 -351.20275)
			(xy 302.992536 -351.20326) (xy 302.992282 -351.20326) (xy 302.951175 -351.202805) (xy 302.869311 -351.195219)
			(xy 302.788497 -351.180113) (xy 302.70942 -351.157617) (xy 302.632756 -351.127921) (xy 302.559159 -351.09128)
			(xy 302.489255 -351.048006) (xy 302.423641 -350.998468) (xy 302.362877 -350.943088) (xy 302.307482 -350.882339)
			(xy 302.257926 -350.816738) (xy 302.214633 -350.746846) (xy 302.177973 -350.673258) (xy 302.148258 -350.596602)
			(xy 302.125741 -350.517531) (xy 302.110614 -350.43672) (xy 302.103006 -350.354859) (xy 302.10252 -350.313752)
			(xy 302.103079 -350.268982) (xy 302.11209 -350.179897) (xy 302.129996 -350.092166) (xy 302.156616 -350.006675)
			(xy 302.17364 -349.965264) (xy 302.177232 -349.955681) (xy 302.177215 -349.935231) (xy 302.17364 -349.92564)
			(xy 302.156636 -349.884289) (xy 302.130025 -349.798927) (xy 302.112118 -349.711324) (xy 302.103096 -349.622367)
			(xy 302.10252 -349.57766) (xy 302.10252 -349.576644) (xy 302.102774 -349.565214) (xy 302.076295 -349.559269)
			(xy 302.02406 -349.544526) (xy 301.99838 -349.53575) (xy 301.990183 -349.533236) (xy 301.973049 -349.533236)
			(xy 301.964852 -349.53575) (xy 301.929636 -349.547697) (xy 301.857626 -349.566284) (xy 301.784303 -349.578724)
			(xy 301.710192 -349.584928) (xy 301.673006 -349.58528) (xy 301.635822 -349.584911) (xy 301.561714 -349.578689)
			(xy 301.488394 -349.566246) (xy 301.416383 -349.547672) (xy 301.38116 -349.53575) (xy 301.372963 -349.533236)
			(xy 301.355829 -349.533236) (xy 301.347632 -349.53575) (xy 301.31253 -349.547637) (xy 301.240774 -349.566187)
			(xy 301.167711 -349.578634) (xy 301.09386 -349.584887) (xy 301.056802 -349.58528) (xy 301.055786 -349.58528)
			(xy 301.013859 -349.584857) (xy 300.930386 -349.576885) (xy 300.848048 -349.561014) (xy 300.767592 -349.537389)
			(xy 300.689746 -349.506223) (xy 300.615214 -349.467798) (xy 300.544673 -349.422463) (xy 300.47876 -349.370628)
			(xy 300.418073 -349.312762) (xy 300.363161 -349.24939) (xy 300.314522 -349.181084) (xy 300.272596 -349.108465)
			(xy 300.237762 -349.032189) (xy 300.210337 -348.952948) (xy 300.190568 -348.871458) (xy 300.178634 -348.788458)
			(xy 300.174644 -348.7047) (xy 296.605145 -348.7047) (xy 296.608521 -348.741025) (xy 296.609008 -348.782132)
			(xy 296.608442 -348.826902) (xy 296.599433 -348.915987) (xy 296.581529 -349.003718) (xy 296.554911 -349.089209)
			(xy 296.537888 -349.13062) (xy 296.534304 -349.140205) (xy 296.534315 -349.160653) (xy 296.537888 -349.170244)
			(xy 296.554911 -349.211656) (xy 296.581547 -349.297143) (xy 296.599456 -349.384874) (xy 296.608454 -349.473962)
			(xy 296.609008 -349.518732) (xy 296.608442 -349.563502) (xy 296.599433 -349.652587) (xy 296.581529 -349.740318)
			(xy 296.554911 -349.825809) (xy 296.537888 -349.86722) (xy 296.534304 -349.876805) (xy 296.534315 -349.897253)
			(xy 296.537888 -349.906844) (xy 296.554911 -349.948256) (xy 296.581547 -350.033743) (xy 296.599456 -350.121474)
			(xy 296.608454 -350.210562) (xy 296.609008 -350.255332) (xy 296.608578 -350.296443) (xy 296.600987 -350.378314)
			(xy 296.585874 -350.459136) (xy 296.563366 -350.538217) (xy 296.533657 -350.614885) (xy 296.496999 -350.688483)
			(xy 296.453706 -350.758385) (xy 296.404147 -350.823993) (xy 296.348745 -350.884747) (xy 296.287972 -350.94013)
			(xy 296.222348 -350.989668) (xy 296.152433 -351.032938) (xy 296.078823 -351.069572) (xy 296.002146 -351.099257)
			(xy 295.923057 -351.121739) (xy 295.842231 -351.136827) (xy 295.760357 -351.144391) (xy 295.719246 -351.14484)
			(xy 295.677642 -351.14437) (xy 295.594794 -351.136637) (xy 295.513029 -351.121206) (xy 295.433062 -351.098211)
			(xy 295.355589 -351.067854) (xy 295.281288 -351.0304) (xy 295.24579 -351.008696) (xy 295.236658 -351.003521)
			(xy 295.215938 -351.00031) (xy 295.195661 -351.005649) (xy 295.187116 -351.011744) (xy 295.153466 -351.037664)
			(xy 295.082092 -351.083723) (xy 295.006653 -351.12277) (xy 294.927837 -351.15445) (xy 294.84636 -351.178473)
			(xy 294.762964 -351.194623) (xy 294.678408 -351.20275) (xy 294.635936 -351.20326) (xy 294.635682 -351.20326)
			(xy 294.594575 -351.202805) (xy 294.512711 -351.195219) (xy 294.431897 -351.180113) (xy 294.35282 -351.157617)
			(xy 294.276156 -351.127921) (xy 294.202559 -351.09128) (xy 294.132655 -351.048006) (xy 294.067041 -350.998468)
			(xy 294.006277 -350.943088) (xy 293.950882 -350.882339) (xy 293.901326 -350.816738) (xy 293.858033 -350.746846)
			(xy 293.821373 -350.673258) (xy 293.791658 -350.596602) (xy 293.769141 -350.517531) (xy 293.754014 -350.43672)
			(xy 293.746406 -350.354859) (xy 293.74592 -350.313752) (xy 293.746479 -350.268982) (xy 293.75549 -350.179897)
			(xy 293.773396 -350.092166) (xy 293.800016 -350.006675) (xy 293.81704 -349.965264) (xy 293.820632 -349.955681)
			(xy 293.820615 -349.935231) (xy 293.81704 -349.92564) (xy 293.800036 -349.884289) (xy 293.773425 -349.798927)
			(xy 293.755518 -349.711324) (xy 293.746496 -349.622367) (xy 293.74592 -349.57766) (xy 293.74592 -349.576644)
			(xy 293.746174 -349.565214) (xy 293.719695 -349.559269) (xy 293.66746 -349.544526) (xy 293.64178 -349.53575)
			(xy 293.633583 -349.533236) (xy 293.616449 -349.533236) (xy 293.608252 -349.53575) (xy 293.573036 -349.547697)
			(xy 293.501026 -349.566284) (xy 293.427703 -349.578724) (xy 293.353592 -349.584928) (xy 293.316406 -349.58528)
			(xy 293.279222 -349.584911) (xy 293.205114 -349.578689) (xy 293.131794 -349.566246) (xy 293.059783 -349.547672)
			(xy 293.02456 -349.53575) (xy 293.016363 -349.533236) (xy 292.999229 -349.533236) (xy 292.991032 -349.53575)
			(xy 292.95593 -349.547637) (xy 292.884174 -349.566187) (xy 292.811111 -349.578634) (xy 292.73726 -349.584887)
			(xy 292.700202 -349.58528) (xy 292.699186 -349.58528) (xy 292.657259 -349.584857) (xy 292.573786 -349.576885)
			(xy 292.491448 -349.561014) (xy 292.410992 -349.537389) (xy 292.333146 -349.506223) (xy 292.258614 -349.467798)
			(xy 292.188073 -349.422463) (xy 292.12216 -349.370628) (xy 292.061473 -349.312762) (xy 292.006561 -349.24939)
			(xy 291.957922 -349.181084) (xy 291.915996 -349.108465) (xy 291.881162 -349.032189) (xy 291.853737 -348.952948)
			(xy 291.833968 -348.871458) (xy 291.822034 -348.788458) (xy 291.818044 -348.7047) (xy 288.299345 -348.7047)
			(xy 288.302721 -348.741025) (xy 288.303208 -348.782132) (xy 288.302642 -348.826902) (xy 288.293633 -348.915987)
			(xy 288.275729 -349.003718) (xy 288.249111 -349.089209) (xy 288.232088 -349.13062) (xy 288.228504 -349.140205)
			(xy 288.228515 -349.160653) (xy 288.232088 -349.170244) (xy 288.249111 -349.211656) (xy 288.275747 -349.297143)
			(xy 288.293656 -349.384874) (xy 288.302654 -349.473962) (xy 288.303208 -349.518732) (xy 288.302642 -349.563502)
			(xy 288.293633 -349.652587) (xy 288.275729 -349.740318) (xy 288.249111 -349.825809) (xy 288.232088 -349.86722)
			(xy 288.228504 -349.876805) (xy 288.228515 -349.897253) (xy 288.232088 -349.906844) (xy 288.249111 -349.948256)
			(xy 288.275747 -350.033743) (xy 288.293656 -350.121474) (xy 288.302654 -350.210562) (xy 288.303208 -350.255332)
			(xy 288.302778 -350.296443) (xy 288.295187 -350.378314) (xy 288.280074 -350.459136) (xy 288.257566 -350.538217)
			(xy 288.227857 -350.614885) (xy 288.191199 -350.688483) (xy 288.147906 -350.758385) (xy 288.098347 -350.823993)
			(xy 288.042945 -350.884747) (xy 287.982172 -350.94013) (xy 287.916548 -350.989668) (xy 287.846633 -351.032938)
			(xy 287.773023 -351.069572) (xy 287.696346 -351.099257) (xy 287.617257 -351.121739) (xy 287.536431 -351.136827)
			(xy 287.454557 -351.144391) (xy 287.413446 -351.14484) (xy 287.371842 -351.14437) (xy 287.288994 -351.136637)
			(xy 287.207229 -351.121206) (xy 287.127262 -351.098211) (xy 287.049789 -351.067854) (xy 286.975488 -351.0304)
			(xy 286.93999 -351.008696) (xy 286.930858 -351.003521) (xy 286.910138 -351.00031) (xy 286.889861 -351.005649)
			(xy 286.881316 -351.011744) (xy 286.847666 -351.037664) (xy 286.776292 -351.083723) (xy 286.700853 -351.12277)
			(xy 286.622037 -351.15445) (xy 286.54056 -351.178473) (xy 286.457164 -351.194623) (xy 286.372608 -351.20275)
			(xy 286.330136 -351.20326) (xy 286.329882 -351.20326) (xy 286.288775 -351.202805) (xy 286.206911 -351.195219)
			(xy 286.126097 -351.180113) (xy 286.04702 -351.157617) (xy 285.970356 -351.127921) (xy 285.896759 -351.09128)
			(xy 285.826855 -351.048006) (xy 285.761241 -350.998468) (xy 285.700477 -350.943088) (xy 285.645082 -350.882339)
			(xy 285.595526 -350.816738) (xy 285.552233 -350.746846) (xy 285.515573 -350.673258) (xy 285.485858 -350.596602)
			(xy 285.463341 -350.517531) (xy 285.448214 -350.43672) (xy 285.440606 -350.354859) (xy 285.44012 -350.313752)
			(xy 285.440679 -350.268982) (xy 285.44969 -350.179897) (xy 285.467596 -350.092166) (xy 285.494216 -350.006675)
			(xy 285.51124 -349.965264) (xy 285.514832 -349.955681) (xy 285.514815 -349.935231) (xy 285.51124 -349.92564)
			(xy 285.494236 -349.884289) (xy 285.467625 -349.798927) (xy 285.449718 -349.711324) (xy 285.440696 -349.622367)
			(xy 285.44012 -349.57766) (xy 285.44012 -349.576644) (xy 285.440374 -349.565214) (xy 285.413895 -349.559269)
			(xy 285.36166 -349.544526) (xy 285.33598 -349.53575) (xy 285.327783 -349.533236) (xy 285.310649 -349.533236)
			(xy 285.302452 -349.53575) (xy 285.267236 -349.547697) (xy 285.195226 -349.566284) (xy 285.121903 -349.578724)
			(xy 285.047792 -349.584928) (xy 285.010606 -349.58528) (xy 284.973422 -349.584911) (xy 284.899314 -349.578689)
			(xy 284.825994 -349.566246) (xy 284.753983 -349.547672) (xy 284.71876 -349.53575) (xy 284.710563 -349.533236)
			(xy 284.693429 -349.533236) (xy 284.685232 -349.53575) (xy 284.65013 -349.547637) (xy 284.578374 -349.566187)
			(xy 284.505311 -349.578634) (xy 284.43146 -349.584887) (xy 284.394402 -349.58528) (xy 284.393386 -349.58528)
			(xy 284.351459 -349.584857) (xy 284.267986 -349.576885) (xy 284.185648 -349.561014) (xy 284.105192 -349.537389)
			(xy 284.027346 -349.506223) (xy 283.952814 -349.467798) (xy 283.882273 -349.422463) (xy 283.81636 -349.370628)
			(xy 283.755673 -349.312762) (xy 283.700761 -349.24939) (xy 283.652122 -349.181084) (xy 283.610196 -349.108465)
			(xy 283.575362 -349.032189) (xy 283.547937 -348.952948) (xy 283.528168 -348.871458) (xy 283.516234 -348.788458)
			(xy 283.512244 -348.7047) (xy 280.018945 -348.7047) (xy 280.022321 -348.741025) (xy 280.022808 -348.782132)
			(xy 280.022242 -348.826902) (xy 280.013233 -348.915987) (xy 279.995329 -349.003718) (xy 279.968711 -349.089209)
			(xy 279.951688 -349.13062) (xy 279.948104 -349.140205) (xy 279.948115 -349.160653) (xy 279.951688 -349.170244)
			(xy 279.968711 -349.211656) (xy 279.995347 -349.297143) (xy 280.013256 -349.384874) (xy 280.022254 -349.473962)
			(xy 280.022808 -349.518732) (xy 280.022242 -349.563502) (xy 280.013233 -349.652587) (xy 279.995329 -349.740318)
			(xy 279.968711 -349.825809) (xy 279.951688 -349.86722) (xy 279.948104 -349.876805) (xy 279.948115 -349.897253)
			(xy 279.951688 -349.906844) (xy 279.968711 -349.948256) (xy 279.995347 -350.033743) (xy 280.013256 -350.121474)
			(xy 280.022254 -350.210562) (xy 280.022808 -350.255332) (xy 280.022378 -350.296443) (xy 280.014787 -350.378314)
			(xy 279.999674 -350.459136) (xy 279.977166 -350.538217) (xy 279.947457 -350.614885) (xy 279.910799 -350.688483)
			(xy 279.867506 -350.758385) (xy 279.817947 -350.823993) (xy 279.762545 -350.884747) (xy 279.701772 -350.94013)
			(xy 279.636148 -350.989668) (xy 279.566233 -351.032938) (xy 279.492623 -351.069572) (xy 279.415946 -351.099257)
			(xy 279.336857 -351.121739) (xy 279.256031 -351.136827) (xy 279.174157 -351.144391) (xy 279.133046 -351.14484)
			(xy 279.091442 -351.14437) (xy 279.008594 -351.136637) (xy 278.926829 -351.121206) (xy 278.846862 -351.098211)
			(xy 278.769389 -351.067854) (xy 278.695088 -351.0304) (xy 278.65959 -351.008696) (xy 278.650458 -351.003521)
			(xy 278.629738 -351.00031) (xy 278.609461 -351.005649) (xy 278.600916 -351.011744) (xy 278.567266 -351.037664)
			(xy 278.495892 -351.083723) (xy 278.420453 -351.12277) (xy 278.341637 -351.15445) (xy 278.26016 -351.178473)
			(xy 278.176764 -351.194623) (xy 278.092208 -351.20275) (xy 278.049736 -351.20326) (xy 278.049482 -351.20326)
			(xy 278.008375 -351.202805) (xy 277.926511 -351.195219) (xy 277.845697 -351.180113) (xy 277.76662 -351.157617)
			(xy 277.689956 -351.127921) (xy 277.616359 -351.09128) (xy 277.546455 -351.048006) (xy 277.480841 -350.998468)
			(xy 277.420077 -350.943088) (xy 277.364682 -350.882339) (xy 277.315126 -350.816738) (xy 277.271833 -350.746846)
			(xy 277.235173 -350.673258) (xy 277.205458 -350.596602) (xy 277.182941 -350.517531) (xy 277.167814 -350.43672)
			(xy 277.160206 -350.354859) (xy 277.15972 -350.313752) (xy 277.160279 -350.268982) (xy 277.16929 -350.179897)
			(xy 277.187196 -350.092166) (xy 277.213816 -350.006675) (xy 277.23084 -349.965264) (xy 277.234432 -349.955681)
			(xy 277.234415 -349.935231) (xy 277.23084 -349.92564) (xy 277.213836 -349.884289) (xy 277.187225 -349.798927)
			(xy 277.169318 -349.711324) (xy 277.160296 -349.622367) (xy 277.15972 -349.57766) (xy 277.15972 -349.576644)
			(xy 277.159974 -349.565214) (xy 277.133495 -349.559269) (xy 277.08126 -349.544526) (xy 277.05558 -349.53575)
			(xy 277.047383 -349.533236) (xy 277.030249 -349.533236) (xy 277.022052 -349.53575) (xy 276.986836 -349.547697)
			(xy 276.914826 -349.566284) (xy 276.841503 -349.578724) (xy 276.767392 -349.584928) (xy 276.730206 -349.58528)
			(xy 276.693022 -349.584911) (xy 276.618914 -349.578689) (xy 276.545594 -349.566246) (xy 276.473583 -349.547672)
			(xy 276.43836 -349.53575) (xy 276.430163 -349.533236) (xy 276.413029 -349.533236) (xy 276.404832 -349.53575)
			(xy 276.36973 -349.547637) (xy 276.297974 -349.566187) (xy 276.224911 -349.578634) (xy 276.15106 -349.584887)
			(xy 276.114002 -349.58528) (xy 276.112986 -349.58528) (xy 276.071059 -349.584857) (xy 275.987586 -349.576885)
			(xy 275.905248 -349.561014) (xy 275.824792 -349.537389) (xy 275.746946 -349.506223) (xy 275.672414 -349.467798)
			(xy 275.601873 -349.422463) (xy 275.53596 -349.370628) (xy 275.475273 -349.312762) (xy 275.420361 -349.24939)
			(xy 275.371722 -349.181084) (xy 275.329796 -349.108465) (xy 275.294962 -349.032189) (xy 275.267537 -348.952948)
			(xy 275.247768 -348.871458) (xy 275.235834 -348.788458) (xy 275.231844 -348.7047) (xy 85.721282 -348.7047)
			(xy 85.724562 -348.719921) (xy 85.734552 -348.813881) (xy 85.73516 -348.861126) (xy 85.734613 -348.906766)
			(xy 85.725307 -348.997569) (xy 85.706754 -349.086942) (xy 85.693504 -349.13062) (xy 85.691044 -349.139629)
			(xy 85.692095 -349.15826) (xy 85.695536 -349.166942) (xy 85.714247 -349.210016) (xy 85.743525 -349.299254)
			(xy 85.763232 -349.391081) (xy 85.77315 -349.484473) (xy 85.773768 -349.531432) (xy 85.77323 -349.574377)
			(xy 85.764932 -349.659867) (xy 85.748446 -349.744161) (xy 85.723925 -349.826477) (xy 85.708236 -349.866458)
			(xy 85.704966 -349.875707) (xy 85.704968 -349.895308) (xy 85.708236 -349.904558) (xy 85.723959 -349.944561)
			(xy 85.748521 -350.026936) (xy 85.765013 -350.111298) (xy 85.773281 -350.196858) (xy 85.773768 -350.239838)
			(xy 85.773264 -350.282199) (xy 85.765211 -350.366536) (xy 85.749177 -350.449726) (xy 85.725309 -350.531016)
			(xy 85.693821 -350.609668) (xy 85.654999 -350.684971) (xy 85.609196 -350.756243) (xy 85.556825 -350.822839)
			(xy 85.49836 -350.884154) (xy 85.434332 -350.939635) (xy 85.36532 -350.988778) (xy 85.29195 -351.031138)
			(xy 85.214885 -351.066333) (xy 85.134823 -351.094042) (xy 85.05249 -351.114016) (xy 84.968631 -351.126073)
			(xy 84.884006 -351.130105) (xy 84.799381 -351.126073) (xy 84.715522 -351.114016) (xy 84.633189 -351.094042)
			(xy 84.553127 -351.066333) (xy 84.476062 -351.031138) (xy 84.402692 -350.988778) (xy 84.33368 -350.939635)
			(xy 84.269652 -350.884154) (xy 84.211187 -350.822839) (xy 84.158816 -350.756243) (xy 84.113013 -350.684971)
			(xy 84.074191 -350.609668) (xy 84.042703 -350.531016) (xy 84.018835 -350.449726) (xy 84.002801 -350.366536)
			(xy 83.994748 -350.282199) (xy 83.994244 -350.239838) (xy 83.994769 -350.196861) (xy 84.003053 -350.111306)
			(xy 84.01954 -350.026947) (xy 84.044076 -349.944568) (xy 84.059776 -349.904558) (xy 84.063037 -349.895306)
			(xy 84.06304 -349.875708) (xy 84.059776 -349.866458) (xy 84.044053 -349.826489) (xy 84.019511 -349.744174)
			(xy 84.003027 -349.659876) (xy 83.994754 -349.57438) (xy 83.994244 -349.531432) (xy 83.994855 -349.485787)
			(xy 84.004246 -349.394981) (xy 84.022872 -349.305612) (xy 84.036154 -349.261938) (xy 84.038586 -349.252923)
			(xy 84.037555 -349.234298) (xy 84.034122 -349.225616) (xy 84.015469 -349.182525) (xy 83.98626 -349.093282)
			(xy 83.966612 -349.001459) (xy 83.956742 -348.908077) (xy 83.956144 -348.861126) (xy 83.073245 -348.861126)
			(xy 83.073748 -348.89948) (xy 83.073141 -348.945125) (xy 83.063748 -349.035931) (xy 83.045121 -349.1253)
			(xy 83.031838 -349.168974) (xy 83.0294 -349.177987) (xy 83.030435 -349.196614) (xy 83.03387 -349.205296)
			(xy 83.052527 -349.248385) (xy 83.081735 -349.337629) (xy 83.101382 -349.429453) (xy 83.111251 -349.522835)
			(xy 83.111848 -349.569786) (xy 83.111412 -349.610119) (xy 83.104141 -349.690457) (xy 83.08963 -349.769807)
			(xy 83.067997 -349.847519) (xy 83.039422 -349.922954) (xy 83.022186 -349.959422) (xy 83.017653 -349.970011)
			(xy 83.017661 -349.993024) (xy 83.022186 -350.003618) (xy 83.039397 -350.040069) (xy 83.067953 -350.115455)
			(xy 83.089579 -350.193114) (xy 83.104099 -350.27241) (xy 83.111393 -350.352693) (xy 83.111848 -350.393)
			(xy 83.111344 -350.435361) (xy 83.103291 -350.519698) (xy 83.087257 -350.602888) (xy 83.063389 -350.684178)
			(xy 83.031901 -350.76283) (xy 82.993079 -350.838133) (xy 82.947276 -350.909405) (xy 82.894905 -350.976001)
			(xy 82.83644 -351.037316) (xy 82.772412 -351.092797) (xy 82.7034 -351.14194) (xy 82.63003 -351.1843)
			(xy 82.552965 -351.219495) (xy 82.472903 -351.247204) (xy 82.39057 -351.267178) (xy 82.306711 -351.279235)
			(xy 82.222086 -351.283267) (xy 82.137461 -351.279235) (xy 82.053602 -351.267178) (xy 81.971269 -351.247204)
			(xy 81.891207 -351.219495) (xy 81.814142 -351.1843) (xy 81.740772 -351.14194) (xy 81.67176 -351.092797)
			(xy 81.607732 -351.037316) (xy 81.549267 -350.976001) (xy 81.496896 -350.909405) (xy 81.451093 -350.838133)
			(xy 81.412271 -350.76283) (xy 81.380783 -350.684178) (xy 81.356915 -350.602888) (xy 81.340881 -350.519698)
			(xy 81.332828 -350.435361) (xy 81.332324 -350.393) (xy 81.332778 -350.35266) (xy 81.340081 -350.272312)
			(xy 81.354637 -350.192956) (xy 81.376326 -350.115246) (xy 81.404968 -350.039822) (xy 81.42224 -350.003364)
			(xy 81.426812 -349.992711) (xy 81.426828 -349.969558) (xy 81.42224 -349.958914) (xy 81.405059 -349.922483)
			(xy 81.376548 -349.847143) (xy 81.35497 -349.769534) (xy 81.340501 -349.69029) (xy 81.33326 -349.610063)
			(xy 81.332832 -349.569786) (xy 81.333382 -349.524146) (xy 81.342687 -349.433343) (xy 81.361239 -349.34397)
			(xy 81.374488 -349.300292) (xy 81.376942 -349.291282) (xy 81.375896 -349.272652) (xy 81.372456 -349.26397)
			(xy 81.353748 -349.220894) (xy 81.32447 -349.131657) (xy 81.304762 -349.039831) (xy 81.294843 -348.946439)
			(xy 81.294224 -348.89948) (xy 66.467942 -348.89948) (xy 66.465784 -348.920813) (xy 66.447878 -349.008544)
			(xy 66.421259 -349.094035) (xy 66.404236 -349.135446) (xy 66.400697 -349.145044) (xy 66.400681 -349.16548)
			(xy 66.404236 -349.17507) (xy 66.421263 -349.21648) (xy 66.4479 -349.301967) (xy 66.465806 -349.3897)
			(xy 66.474803 -349.478787) (xy 66.475356 -349.523558) (xy 66.474795 -349.568328) (xy 66.465784 -349.657413)
			(xy 66.447878 -349.745144) (xy 66.421259 -349.830635) (xy 66.404236 -349.872046) (xy 66.400697 -349.881644)
			(xy 66.400681 -349.90208) (xy 66.404236 -349.91167) (xy 66.421263 -349.95308) (xy 66.4479 -350.038567)
			(xy 66.465806 -350.1263) (xy 66.474803 -350.215387) (xy 66.475356 -350.260158) (xy 66.474861 -350.301272)
			(xy 66.467278 -350.383151) (xy 66.452172 -350.46398) (xy 66.429672 -350.54307) (xy 66.39997 -350.619748)
			(xy 66.36332 -350.693357) (xy 66.320034 -350.76327) (xy 66.270482 -350.828891) (xy 66.215086 -350.88966)
			(xy 66.154319 -350.945059) (xy 66.0887 -350.994614) (xy 66.018788 -351.037902) (xy 65.94518 -351.074555)
			(xy 65.868505 -351.10426) (xy 65.789415 -351.126764) (xy 65.708586 -351.141873) (xy 65.626708 -351.14946)
			(xy 65.585594 -351.14992) (xy 65.543984 -351.149442) (xy 65.461127 -351.141665) (xy 65.379358 -351.12619)
			(xy 65.299391 -351.10315) (xy 65.221922 -351.072748) (xy 65.147629 -351.035248) (xy 65.112138 -351.013522)
			(xy 65.10303 -351.008297) (xy 65.082293 -351.005101) (xy 65.062008 -351.010462) (xy 65.053464 -351.01657)
			(xy 65.019831 -351.042555) (xy 64.948437 -351.08868) (xy 64.872967 -351.127782) (xy 64.79411 -351.159503)
			(xy 64.712585 -351.183553) (xy 64.629138 -351.199714) (xy 64.544529 -351.207838) (xy 64.50203 -351.20834)
			(xy 64.460915 -351.207873) (xy 64.379035 -351.200288) (xy 64.298205 -351.185181) (xy 64.219114 -351.162679)
			(xy 64.142436 -351.132976) (xy 64.068826 -351.096324) (xy 63.998912 -351.053036) (xy 63.93329 -351.003482)
			(xy 63.872521 -350.948084) (xy 63.817123 -350.887316) (xy 63.767568 -350.821695) (xy 63.72428 -350.751781)
			(xy 63.687628 -350.678172) (xy 63.657923 -350.601494) (xy 63.635421 -350.522403) (xy 63.620313 -350.441573)
			(xy 63.612727 -350.359693) (xy 63.612268 -350.318578) (xy 63.61284 -350.273809) (xy 63.621847 -350.184724)
			(xy 63.63975 -350.096993) (xy 63.666366 -350.011501) (xy 63.683388 -349.97009) (xy 63.686968 -349.960503)
			(xy 63.68696 -349.940056) (xy 63.683388 -349.930466) (xy 63.666363 -349.889123) (xy 63.639757 -349.803758)
			(xy 63.621856 -349.716153) (xy 63.612841 -349.627193) (xy 63.612268 -349.582486) (xy 63.612268 -349.58147)
			(xy 63.612522 -349.57004) (xy 63.586044 -349.564091) (xy 63.533809 -349.54935) (xy 63.508128 -349.540576)
			(xy 63.499931 -349.538062) (xy 63.482797 -349.538062) (xy 63.4746 -349.540576) (xy 63.43938 -349.552528)
			(xy 63.367379 -349.571185) (xy 63.294059 -349.583696) (xy 63.219944 -349.589972) (xy 63.182754 -349.59036)
			(xy 63.145565 -349.589952) (xy 63.071452 -349.583667) (xy 62.998133 -349.571163) (xy 62.926126 -349.552528)
			(xy 62.890908 -349.540576) (xy 62.882711 -349.538062) (xy 62.865577 -349.538062) (xy 62.85738 -349.540576)
			(xy 62.822162 -349.552533) (xy 62.75016 -349.571189) (xy 62.676839 -349.583699) (xy 62.602724 -349.589973)
			(xy 62.565534 -349.59036) (xy 62.523594 -349.589902) (xy 62.440094 -349.581932) (xy 62.35773 -349.566061)
			(xy 62.277248 -349.542432) (xy 62.199376 -349.511259) (xy 62.12482 -349.472825) (xy 62.054255 -349.427478)
			(xy 61.98832 -349.375629) (xy 61.927613 -349.317747) (xy 61.872683 -349.254356) (xy 61.824027 -349.186031)
			(xy 61.782086 -349.11339) (xy 61.74724 -349.037091) (xy 61.719806 -348.957825) (xy 61.70003 -348.87631)
			(xy 61.688092 -348.793284) (xy 61.684101 -348.7095) (xy 58.14031 -348.7095) (xy 58.143679 -348.745845)
			(xy 58.144156 -348.786958) (xy 58.143595 -348.831728) (xy 58.134584 -348.920813) (xy 58.116678 -349.008544)
			(xy 58.090059 -349.094035) (xy 58.073036 -349.135446) (xy 58.069497 -349.145044) (xy 58.069481 -349.16548)
			(xy 58.073036 -349.17507) (xy 58.090063 -349.21648) (xy 58.1167 -349.301967) (xy 58.134606 -349.3897)
			(xy 58.143603 -349.478787) (xy 58.144156 -349.523558) (xy 58.143595 -349.568328) (xy 58.134584 -349.657413)
			(xy 58.116678 -349.745144) (xy 58.090059 -349.830635) (xy 58.073036 -349.872046) (xy 58.069497 -349.881644)
			(xy 58.069481 -349.90208) (xy 58.073036 -349.91167) (xy 58.090063 -349.95308) (xy 58.1167 -350.038567)
			(xy 58.134606 -350.1263) (xy 58.143603 -350.215387) (xy 58.144156 -350.260158) (xy 58.143661 -350.301272)
			(xy 58.136078 -350.383151) (xy 58.120972 -350.46398) (xy 58.098472 -350.54307) (xy 58.06877 -350.619748)
			(xy 58.03212 -350.693357) (xy 57.988834 -350.76327) (xy 57.939282 -350.828891) (xy 57.883886 -350.88966)
			(xy 57.823119 -350.945059) (xy 57.7575 -350.994614) (xy 57.687588 -351.037902) (xy 57.61398 -351.074555)
			(xy 57.537305 -351.10426) (xy 57.458215 -351.126764) (xy 57.377386 -351.141873) (xy 57.295508 -351.14946)
			(xy 57.254394 -351.14992) (xy 57.212784 -351.149442) (xy 57.129927 -351.141665) (xy 57.048158 -351.12619)
			(xy 56.968191 -351.10315) (xy 56.890722 -351.072748) (xy 56.816429 -351.035248) (xy 56.780938 -351.013522)
			(xy 56.77183 -351.008297) (xy 56.751093 -351.005101) (xy 56.730808 -351.010462) (xy 56.722264 -351.01657)
			(xy 56.688631 -351.042555) (xy 56.617237 -351.08868) (xy 56.541767 -351.127782) (xy 56.46291 -351.159503)
			(xy 56.381385 -351.183553) (xy 56.297938 -351.199714) (xy 56.213329 -351.207838) (xy 56.17083 -351.20834)
			(xy 56.129715 -351.207873) (xy 56.047835 -351.200288) (xy 55.967005 -351.185181) (xy 55.887914 -351.162679)
			(xy 55.811236 -351.132976) (xy 55.737626 -351.096324) (xy 55.667712 -351.053036) (xy 55.60209 -351.003482)
			(xy 55.541321 -350.948084) (xy 55.485923 -350.887316) (xy 55.436368 -350.821695) (xy 55.39308 -350.751781)
			(xy 55.356428 -350.678172) (xy 55.326723 -350.601494) (xy 55.304221 -350.522403) (xy 55.289113 -350.441573)
			(xy 55.281527 -350.359693) (xy 55.281068 -350.318578) (xy 55.28164 -350.273809) (xy 55.290647 -350.184724)
			(xy 55.30855 -350.096993) (xy 55.335166 -350.011501) (xy 55.352188 -349.97009) (xy 55.355768 -349.960503)
			(xy 55.35576 -349.940056) (xy 55.352188 -349.930466) (xy 55.335163 -349.889123) (xy 55.308557 -349.803758)
			(xy 55.290656 -349.716153) (xy 55.281641 -349.627193) (xy 55.281068 -349.582486) (xy 55.281068 -349.58147)
			(xy 55.281322 -349.57004) (xy 55.254844 -349.564091) (xy 55.202609 -349.54935) (xy 55.176928 -349.540576)
			(xy 55.168731 -349.538062) (xy 55.151597 -349.538062) (xy 55.1434 -349.540576) (xy 55.10818 -349.552528)
			(xy 55.036179 -349.571185) (xy 54.962859 -349.583696) (xy 54.888744 -349.589972) (xy 54.851554 -349.59036)
			(xy 54.814365 -349.589952) (xy 54.740252 -349.583667) (xy 54.666933 -349.571163) (xy 54.594926 -349.552528)
			(xy 54.559708 -349.540576) (xy 54.551511 -349.538062) (xy 54.534377 -349.538062) (xy 54.52618 -349.540576)
			(xy 54.490962 -349.552533) (xy 54.41896 -349.571189) (xy 54.345639 -349.583699) (xy 54.271524 -349.589973)
			(xy 54.234334 -349.59036) (xy 54.192394 -349.589902) (xy 54.108894 -349.581932) (xy 54.02653 -349.566061)
			(xy 53.946048 -349.542432) (xy 53.868176 -349.511259) (xy 53.79362 -349.472825) (xy 53.723055 -349.427478)
			(xy 53.65712 -349.375629) (xy 53.596413 -349.317747) (xy 53.541483 -349.254356) (xy 53.492827 -349.186031)
			(xy 53.450886 -349.11339) (xy 53.41604 -349.037091) (xy 53.388606 -348.957825) (xy 53.36883 -348.87631)
			(xy 53.356892 -348.793284) (xy 53.352901 -348.7095) (xy 49.78371 -348.7095) (xy 49.787079 -348.745845)
			(xy 49.787556 -348.786958) (xy 49.786995 -348.831728) (xy 49.777984 -348.920813) (xy 49.760078 -349.008544)
			(xy 49.733459 -349.094035) (xy 49.716436 -349.135446) (xy 49.712897 -349.145044) (xy 49.712881 -349.16548)
			(xy 49.716436 -349.17507) (xy 49.733463 -349.21648) (xy 49.7601 -349.301967) (xy 49.778006 -349.3897)
			(xy 49.787003 -349.478787) (xy 49.787556 -349.523558) (xy 49.786995 -349.568328) (xy 49.777984 -349.657413)
			(xy 49.760078 -349.745144) (xy 49.733459 -349.830635) (xy 49.716436 -349.872046) (xy 49.712897 -349.881644)
			(xy 49.712881 -349.90208) (xy 49.716436 -349.91167) (xy 49.733463 -349.95308) (xy 49.7601 -350.038567)
			(xy 49.778006 -350.1263) (xy 49.787003 -350.215387) (xy 49.787556 -350.260158) (xy 49.787061 -350.301272)
			(xy 49.779478 -350.383151) (xy 49.764372 -350.46398) (xy 49.741872 -350.54307) (xy 49.71217 -350.619748)
			(xy 49.67552 -350.693357) (xy 49.632234 -350.76327) (xy 49.582682 -350.828891) (xy 49.527286 -350.88966)
			(xy 49.466519 -350.945059) (xy 49.4009 -350.994614) (xy 49.330988 -351.037902) (xy 49.25738 -351.074555)
			(xy 49.180705 -351.10426) (xy 49.101615 -351.126764) (xy 49.020786 -351.141873) (xy 48.938908 -351.14946)
			(xy 48.897794 -351.14992) (xy 48.856184 -351.149442) (xy 48.773327 -351.141665) (xy 48.691558 -351.12619)
			(xy 48.611591 -351.10315) (xy 48.534122 -351.072748) (xy 48.459829 -351.035248) (xy 48.424338 -351.013522)
			(xy 48.41523 -351.008297) (xy 48.394493 -351.005101) (xy 48.374208 -351.010462) (xy 48.365664 -351.01657)
			(xy 48.332031 -351.042555) (xy 48.260637 -351.08868) (xy 48.185167 -351.127782) (xy 48.10631 -351.159503)
			(xy 48.024785 -351.183553) (xy 47.941338 -351.199714) (xy 47.856729 -351.207838) (xy 47.81423 -351.20834)
			(xy 47.773115 -351.207873) (xy 47.691235 -351.200288) (xy 47.610405 -351.185181) (xy 47.531314 -351.162679)
			(xy 47.454636 -351.132976) (xy 47.381026 -351.096324) (xy 47.311112 -351.053036) (xy 47.24549 -351.003482)
			(xy 47.184721 -350.948084) (xy 47.129323 -350.887316) (xy 47.079768 -350.821695) (xy 47.03648 -350.751781)
			(xy 46.999828 -350.678172) (xy 46.970123 -350.601494) (xy 46.947621 -350.522403) (xy 46.932513 -350.441573)
			(xy 46.924927 -350.359693) (xy 46.924468 -350.318578) (xy 46.92504 -350.273809) (xy 46.934047 -350.184724)
			(xy 46.95195 -350.096993) (xy 46.978566 -350.011501) (xy 46.995588 -349.97009) (xy 46.999168 -349.960503)
			(xy 46.99916 -349.940056) (xy 46.995588 -349.930466) (xy 46.978563 -349.889123) (xy 46.951957 -349.803758)
			(xy 46.934056 -349.716153) (xy 46.925041 -349.627193) (xy 46.924468 -349.582486) (xy 46.924468 -349.58147)
			(xy 46.924722 -349.57004) (xy 46.898244 -349.564091) (xy 46.846009 -349.54935) (xy 46.820328 -349.540576)
			(xy 46.812131 -349.538062) (xy 46.794997 -349.538062) (xy 46.7868 -349.540576) (xy 46.75158 -349.552528)
			(xy 46.679579 -349.571185) (xy 46.606259 -349.583696) (xy 46.532144 -349.589972) (xy 46.494954 -349.59036)
			(xy 46.457765 -349.589952) (xy 46.383652 -349.583667) (xy 46.310333 -349.571163) (xy 46.238326 -349.552528)
			(xy 46.203108 -349.540576) (xy 46.194911 -349.538062) (xy 46.177777 -349.538062) (xy 46.16958 -349.540576)
			(xy 46.134362 -349.552533) (xy 46.06236 -349.571189) (xy 45.989039 -349.583699) (xy 45.914924 -349.589973)
			(xy 45.877734 -349.59036) (xy 45.835794 -349.589902) (xy 45.752294 -349.581932) (xy 45.66993 -349.566061)
			(xy 45.589448 -349.542432) (xy 45.511576 -349.511259) (xy 45.43702 -349.472825) (xy 45.366455 -349.427478)
			(xy 45.30052 -349.375629) (xy 45.239813 -349.317747) (xy 45.184883 -349.254356) (xy 45.136227 -349.186031)
			(xy 45.094286 -349.11339) (xy 45.05944 -349.037091) (xy 45.032006 -348.957825) (xy 45.01223 -348.87631)
			(xy 45.000292 -348.793284) (xy 44.996301 -348.7095) (xy 41.47791 -348.7095) (xy 41.481279 -348.745845)
			(xy 41.481756 -348.786958) (xy 41.481195 -348.831728) (xy 41.472184 -348.920813) (xy 41.454278 -349.008544)
			(xy 41.427659 -349.094035) (xy 41.410636 -349.135446) (xy 41.407097 -349.145044) (xy 41.407081 -349.16548)
			(xy 41.410636 -349.17507) (xy 41.427663 -349.21648) (xy 41.4543 -349.301967) (xy 41.472206 -349.3897)
			(xy 41.481203 -349.478787) (xy 41.481756 -349.523558) (xy 41.481195 -349.568328) (xy 41.472184 -349.657413)
			(xy 41.454278 -349.745144) (xy 41.427659 -349.830635) (xy 41.410636 -349.872046) (xy 41.407097 -349.881644)
			(xy 41.407081 -349.90208) (xy 41.410636 -349.91167) (xy 41.427663 -349.95308) (xy 41.4543 -350.038567)
			(xy 41.472206 -350.1263) (xy 41.481203 -350.215387) (xy 41.481756 -350.260158) (xy 41.481261 -350.301272)
			(xy 41.473678 -350.383151) (xy 41.458572 -350.46398) (xy 41.436072 -350.54307) (xy 41.40637 -350.619748)
			(xy 41.36972 -350.693357) (xy 41.326434 -350.76327) (xy 41.276882 -350.828891) (xy 41.221486 -350.88966)
			(xy 41.160719 -350.945059) (xy 41.0951 -350.994614) (xy 41.025188 -351.037902) (xy 40.95158 -351.074555)
			(xy 40.874905 -351.10426) (xy 40.795815 -351.126764) (xy 40.714986 -351.141873) (xy 40.633108 -351.14946)
			(xy 40.591994 -351.14992) (xy 40.550384 -351.149442) (xy 40.467527 -351.141665) (xy 40.385758 -351.12619)
			(xy 40.305791 -351.10315) (xy 40.228322 -351.072748) (xy 40.154029 -351.035248) (xy 40.118538 -351.013522)
			(xy 40.10943 -351.008297) (xy 40.088693 -351.005101) (xy 40.068408 -351.010462) (xy 40.059864 -351.01657)
			(xy 40.026231 -351.042555) (xy 39.954837 -351.08868) (xy 39.879367 -351.127782) (xy 39.80051 -351.159503)
			(xy 39.718985 -351.183553) (xy 39.635538 -351.199714) (xy 39.550929 -351.207838) (xy 39.50843 -351.20834)
			(xy 39.467315 -351.207873) (xy 39.385435 -351.200288) (xy 39.304605 -351.185181) (xy 39.225514 -351.162679)
			(xy 39.148836 -351.132976) (xy 39.075226 -351.096324) (xy 39.005312 -351.053036) (xy 38.93969 -351.003482)
			(xy 38.878921 -350.948084) (xy 38.823523 -350.887316) (xy 38.773968 -350.821695) (xy 38.73068 -350.751781)
			(xy 38.694028 -350.678172) (xy 38.664323 -350.601494) (xy 38.641821 -350.522403) (xy 38.626713 -350.441573)
			(xy 38.619127 -350.359693) (xy 38.618668 -350.318578) (xy 38.61924 -350.273809) (xy 38.628247 -350.184724)
			(xy 38.64615 -350.096993) (xy 38.672766 -350.011501) (xy 38.689788 -349.97009) (xy 38.693368 -349.960503)
			(xy 38.69336 -349.940056) (xy 38.689788 -349.930466) (xy 38.672763 -349.889123) (xy 38.646157 -349.803758)
			(xy 38.628256 -349.716153) (xy 38.619241 -349.627193) (xy 38.618668 -349.582486) (xy 38.618668 -349.58147)
			(xy 38.618922 -349.57004) (xy 38.592444 -349.564091) (xy 38.540209 -349.54935) (xy 38.514528 -349.540576)
			(xy 38.506331 -349.538062) (xy 38.489197 -349.538062) (xy 38.481 -349.540576) (xy 38.44578 -349.552528)
			(xy 38.373779 -349.571185) (xy 38.300459 -349.583696) (xy 38.226344 -349.589972) (xy 38.189154 -349.59036)
			(xy 38.151965 -349.589952) (xy 38.077852 -349.583667) (xy 38.004533 -349.571163) (xy 37.932526 -349.552528)
			(xy 37.897308 -349.540576) (xy 37.889111 -349.538062) (xy 37.871977 -349.538062) (xy 37.86378 -349.540576)
			(xy 37.828562 -349.552533) (xy 37.75656 -349.571189) (xy 37.683239 -349.583699) (xy 37.609124 -349.589973)
			(xy 37.571934 -349.59036) (xy 37.529996 -349.589881) (xy 37.446499 -349.581908) (xy 37.364138 -349.566035)
			(xy 37.283659 -349.542404) (xy 37.20579 -349.511231) (xy 37.131238 -349.472797) (xy 37.060676 -349.42745)
			(xy 36.994745 -349.375601) (xy 36.93404 -349.317719) (xy 36.879112 -349.25433) (xy 36.830459 -349.186006)
			(xy 36.788521 -349.113367) (xy 36.753677 -349.03707) (xy 36.726244 -348.957807) (xy 36.706469 -348.876294)
			(xy 36.694532 -348.793272) (xy 36.690541 -348.70949) (xy 33.197509 -348.70949) (xy 33.200879 -348.745845)
			(xy 33.201356 -348.786958) (xy 33.200795 -348.831728) (xy 33.191784 -348.920813) (xy 33.173878 -349.008544)
			(xy 33.147259 -349.094035) (xy 33.130236 -349.135446) (xy 33.126697 -349.145044) (xy 33.126681 -349.16548)
			(xy 33.130236 -349.17507) (xy 33.147263 -349.21648) (xy 33.1739 -349.301967) (xy 33.191806 -349.3897)
			(xy 33.200803 -349.478787) (xy 33.201356 -349.523558) (xy 33.200795 -349.568328) (xy 33.191784 -349.657413)
			(xy 33.173878 -349.745144) (xy 33.147259 -349.830635) (xy 33.130236 -349.872046) (xy 33.126697 -349.881644)
			(xy 33.126681 -349.90208) (xy 33.130236 -349.91167) (xy 33.147263 -349.95308) (xy 33.1739 -350.038567)
			(xy 33.191806 -350.1263) (xy 33.200803 -350.215387) (xy 33.201356 -350.260158) (xy 33.200861 -350.301272)
			(xy 33.193278 -350.383151) (xy 33.178172 -350.46398) (xy 33.155672 -350.54307) (xy 33.12597 -350.619748)
			(xy 33.08932 -350.693357) (xy 33.046034 -350.76327) (xy 32.996482 -350.828891) (xy 32.941086 -350.88966)
			(xy 32.880319 -350.945059) (xy 32.8147 -350.994614) (xy 32.744788 -351.037902) (xy 32.67118 -351.074555)
			(xy 32.594505 -351.10426) (xy 32.515415 -351.126764) (xy 32.434586 -351.141873) (xy 32.352708 -351.14946)
			(xy 32.311594 -351.14992) (xy 32.269984 -351.149442) (xy 32.187127 -351.141665) (xy 32.105358 -351.12619)
			(xy 32.025391 -351.10315) (xy 31.947922 -351.072748) (xy 31.873629 -351.035248) (xy 31.838138 -351.013522)
			(xy 31.82903 -351.008297) (xy 31.808293 -351.005101) (xy 31.788008 -351.010462) (xy 31.779464 -351.01657)
			(xy 31.745831 -351.042555) (xy 31.674437 -351.08868) (xy 31.598967 -351.127782) (xy 31.52011 -351.159503)
			(xy 31.438585 -351.183553) (xy 31.355138 -351.199714) (xy 31.270529 -351.207838) (xy 31.22803 -351.20834)
			(xy 31.186915 -351.207873) (xy 31.105035 -351.200288) (xy 31.024205 -351.185181) (xy 30.945114 -351.162679)
			(xy 30.868436 -351.132976) (xy 30.794826 -351.096324) (xy 30.724912 -351.053036) (xy 30.65929 -351.003482)
			(xy 30.598521 -350.948084) (xy 30.543123 -350.887316) (xy 30.493568 -350.821695) (xy 30.45028 -350.751781)
			(xy 30.413628 -350.678172) (xy 30.383923 -350.601494) (xy 30.361421 -350.522403) (xy 30.346313 -350.441573)
			(xy 30.338727 -350.359693) (xy 30.338268 -350.318578) (xy 30.33884 -350.273809) (xy 30.347847 -350.184724)
			(xy 30.36575 -350.096993) (xy 30.392366 -350.011501) (xy 30.409388 -349.97009) (xy 30.412968 -349.960503)
			(xy 30.41296 -349.940056) (xy 30.409388 -349.930466) (xy 30.392363 -349.889123) (xy 30.365757 -349.803758)
			(xy 30.347856 -349.716153) (xy 30.338841 -349.627193) (xy 30.338268 -349.582486) (xy 30.338268 -349.58147)
			(xy 30.338522 -349.57004) (xy 30.312044 -349.564091) (xy 30.259809 -349.54935) (xy 30.234128 -349.540576)
			(xy 30.225931 -349.538062) (xy 30.208797 -349.538062) (xy 30.2006 -349.540576) (xy 30.16538 -349.552528)
			(xy 30.093379 -349.571185) (xy 30.020059 -349.583696) (xy 29.945944 -349.589972) (xy 29.908754 -349.59036)
			(xy 29.871565 -349.589952) (xy 29.797452 -349.583667) (xy 29.724133 -349.571163) (xy 29.652126 -349.552528)
			(xy 29.616908 -349.540576) (xy 29.608711 -349.538062) (xy 29.591577 -349.538062) (xy 29.58338 -349.540576)
			(xy 29.548162 -349.552533) (xy 29.47616 -349.571189) (xy 29.402839 -349.583699) (xy 29.328724 -349.589973)
			(xy 29.291534 -349.59036) (xy 29.249596 -349.589881) (xy 29.166099 -349.581908) (xy 29.083738 -349.566035)
			(xy 29.003259 -349.542404) (xy 28.92539 -349.511231) (xy 28.850838 -349.472797) (xy 28.780276 -349.42745)
			(xy 28.714345 -349.375601) (xy 28.65364 -349.317719) (xy 28.598712 -349.25433) (xy 28.550059 -349.186006)
			(xy 28.508121 -349.113367) (xy 28.473277 -349.03707) (xy 28.445844 -348.957807) (xy 28.426069 -348.876294)
			(xy 28.414132 -348.793272) (xy 28.410141 -348.70949) (xy 2.509012 -348.70949) (xy 2.509012 -351.637854)
			(xy 73.92162 -351.637854) (xy 73.922073 -351.597287) (xy 73.929469 -351.516491) (xy 73.944194 -351.436705)
			(xy 73.966127 -351.358593) (xy 73.995085 -351.282803) (xy 74.012552 -351.246186) (xy 74.016468 -351.237096)
			(xy 74.017766 -351.217362) (xy 74.015092 -351.207832) (xy 74.000912 -351.162806) (xy 73.981012 -351.070523)
			(xy 73.971009 -350.97665) (xy 73.970388 -350.929448) (xy 73.970892 -350.887087) (xy 73.978945 -350.80275)
			(xy 73.994979 -350.71956) (xy 74.018847 -350.63827) (xy 74.050335 -350.559618) (xy 74.089157 -350.484315)
			(xy 74.13496 -350.413043) (xy 74.187331 -350.346447) (xy 74.245796 -350.285132) (xy 74.309824 -350.229651)
			(xy 74.378836 -350.180508) (xy 74.452206 -350.138148) (xy 74.529271 -350.102953) (xy 74.609333 -350.075244)
			(xy 74.691666 -350.05527) (xy 74.775525 -350.043213) (xy 74.86015 -350.039182) (xy 74.944775 -350.043213)
			(xy 75.028634 -350.05527) (xy 75.110967 -350.075244) (xy 75.191029 -350.102953) (xy 75.268094 -350.138148)
			(xy 75.341464 -350.180508) (xy 75.410476 -350.229651) (xy 75.474504 -350.285132) (xy 75.532969 -350.346447)
			(xy 75.58534 -350.413043) (xy 75.631143 -350.484315) (xy 75.669965 -350.559618) (xy 75.701453 -350.63827)
			(xy 75.725321 -350.71956) (xy 75.741355 -350.80275) (xy 75.749408 -350.887087) (xy 75.749912 -350.929448)
			(xy 75.749456 -350.970015) (xy 75.742061 -351.05081) (xy 75.727336 -351.130596) (xy 75.705403 -351.208709)
			(xy 75.676446 -351.284499) (xy 75.65898 -351.321116) (xy 75.655063 -351.330206) (xy 75.653765 -351.34994)
			(xy 75.65644 -351.35947) (xy 75.670621 -351.404496) (xy 75.69052 -351.496779) (xy 75.700524 -351.590652)
			(xy 75.70064 -351.5995) (xy 76.58354 -351.5995) (xy 76.583977 -351.558938) (xy 76.59131 -351.478148)
			(xy 76.605978 -351.398363) (xy 76.62786 -351.320247) (xy 76.656772 -351.244452) (xy 76.674218 -351.207832)
			(xy 76.67814 -351.198816) (xy 76.679575 -351.179224) (xy 76.677012 -351.169732) (xy 76.662856 -351.124831)
			(xy 76.642989 -351.0328) (xy 76.632962 -350.939185) (xy 76.632308 -350.89211) (xy 76.632308 -350.891094)
			(xy 76.632812 -350.848746) (xy 76.640863 -350.764432) (xy 76.656892 -350.681266) (xy 76.680753 -350.599999)
			(xy 76.712232 -350.521369) (xy 76.751043 -350.446088) (xy 76.796833 -350.374836) (xy 76.849189 -350.30826)
			(xy 76.907637 -350.246962) (xy 76.971647 -350.191497) (xy 77.040639 -350.142368) (xy 77.113989 -350.100019)
			(xy 77.191032 -350.064835) (xy 77.271071 -350.037133) (xy 77.35338 -350.017165) (xy 77.437215 -350.005112)
			(xy 77.521816 -350.001082) (xy 77.606417 -350.005112) (xy 77.690252 -350.017165) (xy 77.772561 -350.037133)
			(xy 77.8526 -350.064835) (xy 77.929643 -350.100019) (xy 78.002993 -350.142368) (xy 78.071985 -350.191497)
			(xy 78.135995 -350.246962) (xy 78.194443 -350.30826) (xy 78.246799 -350.374836) (xy 78.292589 -350.446088)
			(xy 78.3314 -350.521369) (xy 78.362879 -350.599999) (xy 78.38674 -350.681266) (xy 78.402769 -350.764432)
			(xy 78.41082 -350.848746) (xy 78.411324 -350.891094) (xy 78.411324 -350.891602) (xy 78.410897 -350.932113)
			(xy 78.403528 -351.0128) (xy 78.388844 -351.09248) (xy 78.366965 -351.170492) (xy 78.338074 -351.246189)
			(xy 78.320646 -351.282762) (xy 78.316728 -351.291779) (xy 78.315288 -351.31137) (xy 78.317852 -351.320862)
			(xy 78.33205 -351.365927) (xy 78.351954 -351.458296) (xy 78.361947 -351.552255) (xy 78.362556 -351.5995)
			(xy 78.362003 -351.645139) (xy 78.352699 -351.735943) (xy 78.334149 -351.825316) (xy 78.3209 -351.868994)
			(xy 78.318454 -351.878006) (xy 78.319496 -351.896634) (xy 78.322932 -351.905316) (xy 78.341634 -351.948394)
			(xy 78.370914 -352.03763) (xy 78.390624 -352.129456) (xy 78.400545 -352.222848) (xy 78.401164 -352.269806)
			(xy 78.400653 -352.312784) (xy 78.392364 -352.398339) (xy 78.375873 -352.482698) (xy 78.351334 -352.565076)
			(xy 78.335632 -352.605086) (xy 78.332346 -352.614331) (xy 78.332359 -352.633935) (xy 78.335632 -352.643186)
			(xy 78.351338 -352.683162) (xy 78.375884 -352.765474) (xy 78.392373 -352.84977) (xy 78.400651 -352.935265)
			(xy 78.401164 -352.978212) (xy 78.40066 -353.020573) (xy 78.392607 -353.10491) (xy 78.376573 -353.1881)
			(xy 78.352705 -353.26939) (xy 78.346936 -353.2838) (xy 182.729656 -353.2838) (xy 182.733646 -353.200045)
			(xy 182.745579 -353.117047) (xy 182.765347 -353.035561) (xy 182.792771 -352.956321) (xy 182.827603 -352.880048)
			(xy 182.869527 -352.807431) (xy 182.918163 -352.739127) (xy 182.973072 -352.675756) (xy 183.033756 -352.617891)
			(xy 183.099666 -352.566056) (xy 183.170204 -352.520721) (xy 183.244732 -352.482296) (xy 183.322575 -352.451129)
			(xy 183.403028 -352.427503) (xy 183.485362 -352.411631) (xy 183.568833 -352.403656) (xy 183.610758 -352.403156)
			(xy 183.611774 -352.403156) (xy 183.648831 -352.403571) (xy 183.72268 -352.409833) (xy 183.795742 -352.422272)
			(xy 183.867502 -352.440802) (xy 183.902604 -352.452686) (xy 183.910801 -352.4552) (xy 183.927935 -352.4552)
			(xy 183.936132 -352.452686) (xy 183.964337 -352.443048) (xy 184.021791 -352.42716) (xy 184.05094 -352.420936)
			(xy 184.060579 -352.41851) (xy 184.077071 -352.407448) (xy 184.088123 -352.390948) (xy 184.090564 -352.381312)
			(xy 184.100088 -352.337416) (xy 184.126813 -352.251655) (xy 184.143904 -352.210116) (xy 184.147468 -352.200525)
			(xy 184.147469 -352.180082) (xy 184.143904 -352.170492) (xy 184.126892 -352.12911) (xy 184.100271 -352.043685)
			(xy 184.082363 -351.956018) (xy 184.073351 -351.866996) (xy 184.072784 -351.822258) (xy 184.072784 -351.822004)
			(xy 184.073288 -351.779656) (xy 184.081339 -351.695342) (xy 184.097368 -351.612176) (xy 184.121229 -351.530909)
			(xy 184.152708 -351.452279) (xy 184.191519 -351.376998) (xy 184.237309 -351.305746) (xy 184.289665 -351.23917)
			(xy 184.348113 -351.177872) (xy 184.412123 -351.122407) (xy 184.481115 -351.073278) (xy 184.554465 -351.030929)
			(xy 184.631508 -350.995745) (xy 184.711547 -350.968043) (xy 184.793856 -350.948075) (xy 184.877691 -350.936022)
			(xy 184.962292 -350.931992) (xy 185.046893 -350.936022) (xy 185.130728 -350.948075) (xy 185.213037 -350.968043)
			(xy 185.293076 -350.995745) (xy 185.370119 -351.030929) (xy 185.443469 -351.073278) (xy 185.512461 -351.122407)
			(xy 185.576471 -351.177872) (xy 185.634919 -351.23917) (xy 185.687275 -351.305746) (xy 185.733065 -351.376998)
			(xy 185.771876 -351.452279) (xy 185.803355 -351.530909) (xy 185.827216 -351.612176) (xy 185.843245 -351.695342)
			(xy 185.851296 -351.779656) (xy 185.8518 -351.822004) (xy 185.8518 -351.822258) (xy 185.851234 -351.866996)
			(xy 185.842218 -351.956018) (xy 185.824312 -352.043685) (xy 185.797698 -352.129113) (xy 185.78068 -352.170492)
			(xy 185.777112 -352.180082) (xy 185.777113 -352.200525) (xy 185.78068 -352.210116) (xy 185.797704 -352.251527)
			(xy 185.824339 -352.337015) (xy 185.842246 -352.424746) (xy 185.851245 -352.513834) (xy 185.8518 -352.558604)
			(xy 185.85116 -352.609084) (xy 185.839825 -352.709404) (xy 185.829194 -352.758756) (xy 185.826997 -352.771225)
			(xy 185.833664 -352.795617) (xy 185.841894 -352.805238) (xy 185.882534 -352.847656) (xy 185.889646 -352.846132)
			(xy 185.898412 -352.843862) (xy 185.913646 -352.834103) (xy 185.919364 -352.827082) (xy 185.944527 -352.794419)
			(xy 185.999939 -352.733355) (xy 186.060764 -352.67768) (xy 186.126478 -352.627872) (xy 186.196519 -352.584357)
			(xy 186.270286 -352.547509) (xy 186.347146 -352.517645) (xy 186.426439 -352.49502) (xy 186.507485 -352.479828)
			(xy 186.589589 -352.472201) (xy 186.630818 -352.471736) (xy 186.671925 -352.472195) (xy 186.753788 -352.479781)
			(xy 186.834603 -352.494887) (xy 186.913679 -352.517383) (xy 186.990343 -352.547078) (xy 187.06394 -352.583719)
			(xy 187.133844 -352.626993) (xy 187.199457 -352.676531) (xy 187.260221 -352.73191) (xy 187.315617 -352.792659)
			(xy 187.365173 -352.85826) (xy 187.408465 -352.928152) (xy 187.445126 -353.001739) (xy 187.474841 -353.078395)
			(xy 187.497359 -353.157466) (xy 187.512486 -353.238276) (xy 187.519078 -353.3092) (xy 191.056256 -353.3092)
			(xy 191.060246 -353.225443) (xy 191.07218 -353.142444) (xy 191.091948 -353.060956) (xy 191.119373 -352.981715)
			(xy 191.154206 -352.90544) (xy 191.196132 -352.832822) (xy 191.244771 -352.764518) (xy 191.299682 -352.701146)
			(xy 191.360368 -352.643281) (xy 191.42628 -352.591447) (xy 191.49682 -352.546112) (xy 191.57135 -352.507688)
			(xy 191.649196 -352.476522) (xy 191.729651 -352.452897) (xy 191.811988 -352.437027) (xy 191.89546 -352.429055)
			(xy 191.937386 -352.428556) (xy 191.938402 -352.428556) (xy 191.975459 -352.428963) (xy 192.049308 -352.435227)
			(xy 192.12237 -352.447669) (xy 192.194131 -352.466201) (xy 192.229232 -352.478086) (xy 192.237429 -352.4806)
			(xy 192.254563 -352.4806) (xy 192.26276 -352.478086) (xy 192.290041 -352.468747) (xy 192.345585 -352.453243)
			(xy 192.373758 -352.447098) (xy 192.383527 -352.444576) (xy 192.400163 -352.433196) (xy 192.411142 -352.416293)
			(xy 192.413382 -352.406458) (xy 192.422838 -352.357349) (xy 192.451357 -352.261489) (xy 192.470278 -352.215196)
			(xy 192.473919 -352.205632) (xy 192.474045 -352.185185) (xy 192.470532 -352.175572) (xy 192.453515 -352.134192)
			(xy 192.426895 -352.048766) (xy 192.408989 -351.961099) (xy 192.399978 -351.872077) (xy 192.399412 -351.827338)
			(xy 192.399412 -351.827084) (xy 192.399916 -351.784736) (xy 192.407967 -351.700422) (xy 192.423996 -351.617256)
			(xy 192.447857 -351.535989) (xy 192.479336 -351.457359) (xy 192.518147 -351.382078) (xy 192.563937 -351.310826)
			(xy 192.616293 -351.24425) (xy 192.674741 -351.182952) (xy 192.738751 -351.127487) (xy 192.807743 -351.078358)
			(xy 192.881093 -351.036009) (xy 192.958136 -351.000825) (xy 193.038175 -350.973123) (xy 193.120484 -350.953155)
			(xy 193.204319 -350.941102) (xy 193.28892 -350.937072) (xy 193.373521 -350.941102) (xy 193.457356 -350.953155)
			(xy 193.539665 -350.973123) (xy 193.619704 -351.000825) (xy 193.696747 -351.036009) (xy 193.770097 -351.078358)
			(xy 193.839089 -351.127487) (xy 193.903099 -351.182952) (xy 193.961547 -351.24425) (xy 194.013903 -351.310826)
			(xy 194.059693 -351.382078) (xy 194.098504 -351.457359) (xy 194.129983 -351.535989) (xy 194.153844 -351.617256)
			(xy 194.169873 -351.700422) (xy 194.177924 -351.784736) (xy 194.178428 -351.827084) (xy 194.178428 -351.827338)
			(xy 194.177853 -351.872076) (xy 194.168839 -351.961098) (xy 194.150936 -352.048765) (xy 194.124325 -352.134193)
			(xy 194.107308 -352.175572) (xy 194.10375 -352.185165) (xy 194.103744 -352.205606) (xy 194.107308 -352.215196)
			(xy 194.12436 -352.256596) (xy 194.150986 -352.342088) (xy 194.165052 -352.41103) (xy 206.449676 -352.41103)
			(xy 206.449676 -351.54743) (xy 206.450162 -351.520179) (xy 206.457918 -351.466231) (xy 206.473273 -351.413936)
			(xy 206.495915 -351.364359) (xy 206.525381 -351.318509) (xy 206.561072 -351.277318) (xy 206.602263 -351.241627)
			(xy 206.648113 -351.212161) (xy 206.69769 -351.189519) (xy 206.749985 -351.174164) (xy 206.803933 -351.166408)
			(xy 206.858435 -351.166408) (xy 206.912383 -351.174164) (xy 206.964678 -351.189519) (xy 207.014255 -351.212161)
			(xy 207.060105 -351.241627) (xy 207.101296 -351.277318) (xy 207.136987 -351.318509) (xy 207.166453 -351.364359)
			(xy 207.189095 -351.413936) (xy 207.20445 -351.466231) (xy 207.212206 -351.520179) (xy 207.212692 -351.54743)
			(xy 207.212692 -352.41103) (xy 207.212206 -352.438281) (xy 207.20445 -352.492229) (xy 207.189095 -352.544524)
			(xy 207.166453 -352.594101) (xy 207.136987 -352.639951) (xy 207.101296 -352.681142) (xy 207.060105 -352.716833)
			(xy 207.014255 -352.746299) (xy 206.964678 -352.768941) (xy 206.912383 -352.784296) (xy 206.858435 -352.792052)
			(xy 206.803933 -352.792052) (xy 206.749985 -352.784296) (xy 206.69769 -352.768941) (xy 206.648113 -352.746299)
			(xy 206.602263 -352.716833) (xy 206.561072 -352.681142) (xy 206.525381 -352.639951) (xy 206.495915 -352.594101)
			(xy 206.473273 -352.544524) (xy 206.457918 -352.492229) (xy 206.450162 -352.438281) (xy 206.449676 -352.41103)
			(xy 194.165052 -352.41103) (xy 194.168886 -352.429823) (xy 194.177877 -352.518913) (xy 194.178428 -352.563684)
			(xy 194.178055 -352.600778) (xy 194.171875 -352.674709) (xy 194.159556 -352.747868) (xy 194.150742 -352.783902)
			(xy 194.149 -352.792252) (xy 194.15051 -352.809229) (xy 194.157543 -352.824754) (xy 194.163188 -352.831146)
			(xy 194.203574 -352.874326) (xy 194.216274 -352.871532) (xy 194.225043 -352.869274) (xy 194.240276 -352.859506)
			(xy 194.245992 -352.852482) (xy 194.271138 -352.819805) (xy 194.326552 -352.758742) (xy 194.387379 -352.703068)
			(xy 194.453095 -352.65326) (xy 194.523138 -352.609746) (xy 194.596907 -352.5729) (xy 194.673768 -352.543037)
			(xy 194.753063 -352.520414) (xy 194.834111 -352.505225) (xy 194.916217 -352.4976) (xy 194.957446 -352.497136)
			(xy 194.998553 -352.497569) (xy 195.080417 -352.505157) (xy 195.161232 -352.520265) (xy 195.240309 -352.542764)
			(xy 195.316973 -352.572461) (xy 195.390571 -352.609104) (xy 195.460474 -352.652379) (xy 195.526087 -352.701919)
			(xy 195.586851 -352.757301) (xy 195.642247 -352.818051) (xy 195.691802 -352.883653) (xy 195.735094 -352.953546)
			(xy 195.744851 -352.973132) (xy 338.849208 -352.973132) (xy 338.849825 -352.926972) (xy 338.859426 -352.835153)
			(xy 338.878488 -352.744823) (xy 338.906804 -352.656953) (xy 338.9249 -352.614484) (xy 338.928699 -352.60454)
			(xy 338.928703 -352.583278) (xy 338.9249 -352.573336) (xy 338.90688 -352.530918) (xy 338.878719 -352.443158)
			(xy 338.859786 -352.352956) (xy 338.850284 -352.26128) (xy 338.849716 -352.215196) (xy 338.850295 -352.1688)
			(xy 338.859941 -352.076512) (xy 338.879138 -351.985728) (xy 338.907678 -351.897435) (xy 338.925916 -351.85477)
			(xy 338.929722 -351.844828) (xy 338.929721 -351.823565) (xy 338.925916 -351.813622) (xy 338.907694 -351.771019)
			(xy 338.879176 -351.682852) (xy 338.859983 -351.592196) (xy 338.850324 -351.500036) (xy 338.849716 -351.453704)
			(xy 338.849716 -351.453196) (xy 338.850148 -351.412092) (xy 338.857734 -351.330235) (xy 338.87284 -351.249427)
			(xy 338.895338 -351.170357) (xy 338.925036 -351.093701) (xy 338.96168 -351.020112) (xy 339.004958 -350.950218)
			(xy 339.0545 -350.884616) (xy 339.109884 -350.823864) (xy 339.170637 -350.768482) (xy 339.236241 -350.718942)
			(xy 339.306137 -350.675666) (xy 339.379727 -350.639025) (xy 339.456384 -350.609329) (xy 339.535454 -350.586834)
			(xy 339.616263 -350.57173) (xy 339.69812 -350.564147) (xy 339.739224 -350.563688) (xy 339.739732 -350.563688)
			(xy 339.786063 -350.564321) (xy 339.87822 -350.573985) (xy 339.968874 -350.593172) (xy 340.057044 -350.621677)
			(xy 340.09965 -350.639888) (xy 340.109592 -350.643694) (xy 340.130856 -350.643694) (xy 340.140798 -350.639888)
			(xy 340.183457 -350.621635) (xy 340.27175 -350.593093) (xy 340.362537 -350.573902) (xy 340.454828 -350.564272)
			(xy 340.501224 -350.563688) (xy 340.547619 -350.564298) (xy 340.639906 -350.573935) (xy 340.73069 -350.593123)
			(xy 340.818984 -350.621654) (xy 340.86165 -350.639888) (xy 340.871592 -350.643694) (xy 340.892856 -350.643694)
			(xy 340.902798 -350.639888) (xy 340.945457 -350.621635) (xy 341.03375 -350.593093) (xy 341.124537 -350.573902)
			(xy 341.216828 -350.564272) (xy 341.263224 -350.563688) (xy 341.309619 -350.564298) (xy 341.401906 -350.573935)
			(xy 341.49269 -350.593123) (xy 341.580984 -350.621654) (xy 341.62365 -350.639888) (xy 341.633592 -350.643694)
			(xy 341.654856 -350.643694) (xy 341.664798 -350.639888) (xy 341.707457 -350.621635) (xy 341.79575 -350.593093)
			(xy 341.886537 -350.573902) (xy 341.978828 -350.564272) (xy 342.025224 -350.563688) (xy 342.071619 -350.564298)
			(xy 342.163906 -350.573935) (xy 342.25469 -350.593123) (xy 342.342984 -350.621654) (xy 342.38565 -350.639888)
			(xy 342.395592 -350.643694) (xy 342.416856 -350.643694) (xy 342.426798 -350.639888) (xy 342.469457 -350.621635)
			(xy 342.55775 -350.593093) (xy 342.648537 -350.573902) (xy 342.740828 -350.564272) (xy 342.787224 -350.563688)
			(xy 342.833689 -350.564308) (xy 342.926112 -350.573988) (xy 343.017025 -350.593241) (xy 343.105438 -350.621857)
			(xy 343.148158 -350.640142) (xy 343.156911 -350.643584) (xy 343.175683 -350.644482) (xy 343.184734 -350.64192)
			(xy 343.230109 -350.62753) (xy 343.323147 -350.607378) (xy 343.417806 -350.597287) (xy 343.465404 -350.596708)
			(xy 343.506508 -350.597148) (xy 343.588364 -350.604734) (xy 343.669172 -350.61984) (xy 343.748241 -350.642338)
			(xy 343.824897 -350.672035) (xy 343.898486 -350.708679) (xy 343.968379 -350.751956) (xy 344.033982 -350.801498)
			(xy 344.094733 -350.856881) (xy 344.150115 -350.917634) (xy 344.199655 -350.983237) (xy 344.242931 -351.053132)
			(xy 344.279573 -351.126721) (xy 344.309269 -351.203378) (xy 344.331765 -351.282448) (xy 344.346869 -351.363255)
			(xy 344.354453 -351.445112) (xy 344.354912 -351.486216) (xy 344.354912 -351.486724) (xy 344.354311 -351.533056)
			(xy 344.344638 -351.625214) (xy 344.325441 -351.715868) (xy 344.296928 -351.804037) (xy 344.278712 -351.846642)
			(xy 344.274897 -351.856581) (xy 344.274903 -351.877848) (xy 344.278712 -351.88779) (xy 344.296962 -351.93045)
			(xy 344.325505 -352.018743) (xy 344.344696 -352.109529) (xy 344.354328 -352.20182) (xy 344.354912 -352.248216)
			(xy 344.354328 -352.294369) (xy 344.344776 -352.386179) (xy 344.325776 -352.476508) (xy 344.297531 -352.564386)
			(xy 344.279474 -352.606864) (xy 344.275648 -352.6168) (xy 344.275662 -352.638069) (xy 344.279474 -352.648012)
			(xy 344.29749 -352.690438) (xy 344.325707 -352.77819) (xy 344.344711 -352.868387) (xy 344.354297 -352.960064)
			(xy 344.354912 -353.006152) (xy 344.354402 -353.047262) (xy 344.34922 -353.1032) (xy 423.453493 -353.1032)
			(xy 423.457484 -353.019415) (xy 423.469422 -352.936388) (xy 423.489198 -352.854872) (xy 423.516634 -352.775605)
			(xy 423.55148 -352.699305) (xy 423.593421 -352.626663) (xy 423.642078 -352.558337) (xy 423.697009 -352.494945)
			(xy 423.757718 -352.437063) (xy 423.823654 -352.385213) (xy 423.89422 -352.339866) (xy 423.968777 -352.301432)
			(xy 424.04665 -352.270259) (xy 424.127133 -352.24663) (xy 424.209499 -352.230759) (xy 424.293 -352.222789)
			(xy 424.33494 -352.222308) (xy 424.372129 -352.222714) (xy 424.446242 -352.228999) (xy 424.519562 -352.241503)
			(xy 424.591568 -352.260139) (xy 424.626786 -352.272092) (xy 424.634983 -352.274606) (xy 424.652117 -352.274606)
			(xy 424.660314 -352.272092) (xy 424.687596 -352.262757) (xy 424.74314 -352.24725) (xy 424.771312 -352.241104)
			(xy 424.781089 -352.238609) (xy 424.797722 -352.227214) (xy 424.808697 -352.210302) (xy 424.810936 -352.200464)
			(xy 424.820391 -352.151355) (xy 424.84891 -352.055495) (xy 424.867832 -352.009202) (xy 424.871403 -351.999613)
			(xy 424.871399 -351.979169) (xy 424.867832 -351.969578) (xy 424.850786 -351.928175) (xy 424.824155 -351.842685)
			(xy 424.806254 -351.754951) (xy 424.797263 -351.665861) (xy 424.796712 -351.62109) (xy 424.797216 -351.578729)
			(xy 424.805269 -351.494392) (xy 424.821303 -351.411202) (xy 424.845171 -351.329912) (xy 424.876659 -351.25126)
			(xy 424.915481 -351.175957) (xy 424.961284 -351.104685) (xy 425.013655 -351.038089) (xy 425.07212 -350.976774)
			(xy 425.136148 -350.921293) (xy 425.20516 -350.87215) (xy 425.27853 -350.82979) (xy 425.355595 -350.794595)
			(xy 425.435657 -350.766886) (xy 425.51799 -350.746912) (xy 425.601849 -350.734855) (xy 425.686474 -350.730824)
			(xy 425.771099 -350.734855) (xy 425.854958 -350.746912) (xy 425.937291 -350.766886) (xy 426.017353 -350.794595)
			(xy 426.094418 -350.82979) (xy 426.167788 -350.87215) (xy 426.2368 -350.921293) (xy 426.300828 -350.976774)
			(xy 426.359293 -351.038089) (xy 426.411664 -351.104685) (xy 426.457467 -351.175957) (xy 426.496289 -351.25126)
			(xy 426.527777 -351.329912) (xy 426.551645 -351.411202) (xy 426.567679 -351.494392) (xy 426.575732 -351.578729)
			(xy 426.576236 -351.62109) (xy 426.575653 -351.665859) (xy 426.566649 -351.754944) (xy 426.548749 -351.842675)
			(xy 426.522136 -351.928167) (xy 426.505116 -351.969578) (xy 426.501559 -351.979171) (xy 426.501555 -351.999611)
			(xy 426.505116 -352.009202) (xy 426.522153 -352.050608) (xy 426.548787 -352.136097) (xy 426.566691 -352.22383)
			(xy 426.575684 -352.312919) (xy 426.576236 -352.35769) (xy 426.575843 -352.394784) (xy 426.569667 -352.468714)
			(xy 426.557358 -352.541873) (xy 426.54855 -352.577908) (xy 426.5467 -352.586267) (xy 426.54815 -352.603318)
			(xy 426.55512 -352.618947) (xy 426.560742 -352.625406) (xy 426.601128 -352.668332) (xy 426.613574 -352.665538)
			(xy 426.622391 -352.663274) (xy 426.637739 -352.653501) (xy 426.643546 -352.646488) (xy 426.66867 -352.613784)
			(xy 426.724067 -352.552685) (xy 426.784882 -352.496976) (xy 426.850593 -352.447136) (xy 426.920635 -352.403592)
			(xy 426.994408 -352.366719) (xy 427.071277 -352.336834) (xy 427.150582 -352.314192) (xy 427.231643 -352.298989)
			(xy 427.313763 -352.291354) (xy 427.355 -352.290888) (xy 427.396111 -352.291352) (xy 427.477981 -352.29894)
			(xy 427.558801 -352.314051) (xy 427.637882 -352.336556) (xy 427.714549 -352.366262) (xy 427.788147 -352.402918)
			(xy 427.858049 -352.446208) (xy 427.923657 -352.495765) (xy 427.984412 -352.551165) (xy 428.039795 -352.611935)
			(xy 428.089333 -352.677557) (xy 428.132604 -352.747471) (xy 428.169239 -352.82108) (xy 428.198924 -352.897755)
			(xy 428.221406 -352.976842) (xy 428.236494 -353.057667) (xy 428.243048 -353.1286) (xy 431.780208 -353.1286)
			(xy 431.784199 -353.04482) (xy 431.796136 -352.961799) (xy 431.815909 -352.880289) (xy 431.843342 -352.801027)
			(xy 431.878184 -352.724732) (xy 431.92012 -352.652094) (xy 431.968771 -352.583771) (xy 432.023696 -352.520381)
			(xy 432.084398 -352.4625) (xy 432.150327 -352.410651) (xy 432.220886 -352.365303) (xy 432.295436 -352.326868)
			(xy 432.373301 -352.295693) (xy 432.453778 -352.27206) (xy 432.536136 -352.256184) (xy 432.619631 -352.248208)
			(xy 432.661568 -352.247708) (xy 432.698757 -352.248106) (xy 432.77287 -352.254393) (xy 432.84619 -352.2669)
			(xy 432.918196 -352.285538) (xy 432.953414 -352.297492) (xy 432.961611 -352.300006) (xy 432.978745 -352.300006)
			(xy 432.986942 -352.297492) (xy 433.014223 -352.288155) (xy 433.069768 -352.27265) (xy 433.09794 -352.266504)
			(xy 433.107722 -352.264025) (xy 433.124353 -352.252622) (xy 433.135327 -352.235704) (xy 433.137564 -352.225864)
			(xy 433.147017 -352.176755) (xy 433.175537 -352.080895) (xy 433.19446 -352.034602) (xy 433.19803 -352.025013)
			(xy 433.198026 -352.004569) (xy 433.19446 -351.994978) (xy 433.177416 -351.953575) (xy 433.150784 -351.868085)
			(xy 433.132882 -351.780351) (xy 433.123891 -351.691261) (xy 433.12334 -351.64649) (xy 433.123844 -351.604129)
			(xy 433.131897 -351.519792) (xy 433.147931 -351.436602) (xy 433.171799 -351.355312) (xy 433.203287 -351.27666)
			(xy 433.242109 -351.201357) (xy 433.287912 -351.130085) (xy 433.340283 -351.063489) (xy 433.398748 -351.002174)
			(xy 433.462776 -350.946693) (xy 433.531788 -350.89755) (xy 433.605158 -350.85519) (xy 433.682223 -350.819995)
			(xy 433.762285 -350.792286) (xy 433.844618 -350.772312) (xy 433.928477 -350.760255) (xy 434.013102 -350.756224)
			(xy 434.097727 -350.760255) (xy 434.181586 -350.772312) (xy 434.263919 -350.792286) (xy 434.343981 -350.819995)
			(xy 434.421046 -350.85519) (xy 434.494416 -350.89755) (xy 434.563428 -350.946693) (xy 434.627456 -351.002174)
			(xy 434.685921 -351.063489) (xy 434.738292 -351.130085) (xy 434.784095 -351.201357) (xy 434.822917 -351.27666)
			(xy 434.854405 -351.355312) (xy 434.878273 -351.436602) (xy 434.894307 -351.519792) (xy 434.90236 -351.604129)
			(xy 434.902864 -351.64649) (xy 434.902279 -351.691259) (xy 434.893275 -351.780343) (xy 434.875376 -351.868074)
			(xy 434.848764 -351.953566) (xy 434.831744 -351.994978) (xy 434.828186 -352.00457) (xy 434.828182 -352.025011)
			(xy 434.831744 -352.034602) (xy 434.848782 -352.076008) (xy 434.875415 -352.161497) (xy 434.893319 -352.24923)
			(xy 434.902312 -352.338319) (xy 434.902864 -352.38309) (xy 434.90247 -352.420184) (xy 434.896295 -352.494114)
			(xy 434.883986 -352.567273) (xy 434.875178 -352.603308) (xy 434.873347 -352.611669) (xy 434.874795 -352.628716)
			(xy 434.881755 -352.644345) (xy 434.88737 -352.650806) (xy 434.927756 -352.693732) (xy 434.940202 -352.690938)
			(xy 434.94901 -352.688645) (xy 434.964363 -352.678893) (xy 434.970174 -352.671888) (xy 434.995281 -352.639171)
			(xy 435.05068 -352.578072) (xy 435.111497 -352.522364) (xy 435.17721 -352.472524) (xy 435.247255 -352.428982)
			(xy 435.321029 -352.39211) (xy 435.3979 -352.362226) (xy 435.477207 -352.339586) (xy 435.558269 -352.324385)
			(xy 435.64039 -352.316753) (xy 435.681628 -352.316288) (xy 435.722739 -352.316726) (xy 435.80461 -352.324316)
			(xy 435.885431 -352.339429) (xy 435.964512 -352.361936) (xy 436.041179 -352.391645) (xy 436.114778 -352.428302)
			(xy 436.184679 -352.471595) (xy 436.250287 -352.521154) (xy 436.311041 -352.576555) (xy 436.366424 -352.637327)
			(xy 436.415962 -352.70295) (xy 436.459233 -352.772865) (xy 436.495867 -352.846475) (xy 436.525552 -352.923151)
			(xy 436.548034 -353.00224) (xy 436.563122 -353.083066) (xy 436.570687 -353.164939) (xy 436.571136 -353.20605)
			(xy 436.570568 -353.25082) (xy 436.561569 -353.339906) (xy 436.543667 -353.427639) (xy 436.517044 -353.513129)
			(xy 436.500016 -353.554538) (xy 436.496425 -353.564121) (xy 436.496444 -353.58457) (xy 436.500016 -353.594162)
			(xy 436.517052 -353.635569) (xy 436.543684 -353.721058) (xy 436.561588 -353.808791) (xy 436.570583 -353.897879)
			(xy 436.571136 -353.94265) (xy 436.570568 -353.98742) (xy 436.561569 -354.076506) (xy 436.543667 -354.164239)
			(xy 436.517044 -354.249729) (xy 436.500016 -354.291138) (xy 436.496425 -354.300721) (xy 436.496444 -354.32117)
			(xy 436.500016 -354.330762) (xy 436.517046 -354.372136) (xy 436.543663 -354.457564) (xy 436.561565 -354.545233)
			(xy 436.570572 -354.634257) (xy 436.571136 -354.678996) (xy 436.571136 -354.67925) (xy 436.57064 -354.720357)
			(xy 436.56306 -354.80222) (xy 436.547959 -354.883035) (xy 436.525468 -354.962112) (xy 436.495777 -355.038776)
			(xy 436.45914 -355.112375) (xy 436.415869 -355.18228) (xy 436.366333 -355.247894) (xy 436.310956 -355.308659)
			(xy 436.250208 -355.364056) (xy 436.184609 -355.413612) (xy 436.114718 -355.456904) (xy 436.041131 -355.493565)
			(xy 435.964475 -355.523279) (xy 435.885405 -355.545796) (xy 435.804595 -355.560921) (xy 435.722735 -355.568527)
			(xy 435.681628 -355.569012) (xy 435.640018 -355.568519) (xy 435.557162 -355.560745) (xy 435.475393 -355.545272)
			(xy 435.395426 -355.522236) (xy 435.317957 -355.491836) (xy 435.243663 -355.454339) (xy 435.208172 -355.432614)
			(xy 435.199049 -355.42742) (xy 435.178322 -355.424214) (xy 435.158043 -355.429561) (xy 435.149498 -355.435662)
			(xy 435.115852 -355.46163) (xy 435.044461 -355.507757) (xy 434.968993 -355.546861) (xy 434.890138 -355.578584)
			(xy 434.808616 -355.602638) (xy 434.72517 -355.618802) (xy 434.640562 -355.626929) (xy 434.598064 -355.627432)
			(xy 434.556953 -355.626982) (xy 434.475084 -355.619391) (xy 434.394263 -355.604278) (xy 434.315183 -355.581771)
			(xy 434.238517 -355.552062) (xy 434.164919 -355.515405) (xy 434.095019 -355.472113) (xy 434.029411 -355.422555)
			(xy 433.968657 -355.367155) (xy 433.913275 -355.306384) (xy 433.863736 -355.240762) (xy 433.820465 -355.170848)
			(xy 433.783831 -355.09724) (xy 433.754145 -355.020565) (xy 433.731661 -354.941477) (xy 433.716572 -354.860653)
			(xy 433.709006 -354.778781) (xy 433.708556 -354.73767) (xy 433.709098 -354.692899) (xy 433.718104 -354.603812)
			(xy 433.736014 -354.51608) (xy 433.762645 -354.430591) (xy 433.779676 -354.389182) (xy 433.783256 -354.379596)
			(xy 433.783245 -354.359149) (xy 433.779676 -354.349558) (xy 433.762646 -354.308149) (xy 433.736013 -354.222661)
			(xy 433.718107 -354.134928) (xy 433.70911 -354.045841) (xy 433.708556 -354.00107) (xy 433.708556 -353.989132)
			(xy 433.682076 -353.983189) (xy 433.629842 -353.968444) (xy 433.604162 -353.959668) (xy 433.595965 -353.957154)
			(xy 433.578831 -353.957154) (xy 433.570634 -353.959668) (xy 433.535422 -353.971642) (xy 433.463417 -353.990292)
			(xy 433.390095 -354.002797) (xy 433.315979 -354.009067) (xy 433.278788 -354.009452) (xy 433.241598 -354.009064)
			(xy 433.167486 -354.002773) (xy 433.094166 -353.990263) (xy 433.02216 -353.971623) (xy 432.986942 -353.959668)
			(xy 432.978745 -353.957154) (xy 432.961611 -353.957154) (xy 432.953414 -353.959668) (xy 432.918203 -353.971647)
			(xy 432.846198 -353.990296) (xy 432.772875 -354.0028) (xy 432.698759 -354.009068) (xy 432.661568 -354.009452)
			(xy 432.619631 -354.008992) (xy 432.536136 -354.001016) (xy 432.453778 -353.98514) (xy 432.373301 -353.961507)
			(xy 432.295436 -353.930332) (xy 432.220886 -353.891897) (xy 432.150327 -353.846549) (xy 432.084398 -353.7947)
			(xy 432.023696 -353.736819) (xy 431.968771 -353.673429) (xy 431.92012 -353.605106) (xy 431.878184 -353.532468)
			(xy 431.843342 -353.456173) (xy 431.815909 -353.376911) (xy 431.796136 -353.295401) (xy 431.784199 -353.21238)
			(xy 431.780208 -353.1286) (xy 428.243048 -353.1286) (xy 428.244059 -353.139539) (xy 428.244508 -353.18065)
			(xy 428.243935 -353.22542) (xy 428.234936 -353.314506) (xy 428.217036 -353.402238) (xy 428.190415 -353.487729)
			(xy 428.173388 -353.529138) (xy 428.169793 -353.53872) (xy 428.169812 -353.559171) (xy 428.173388 -353.568762)
			(xy 428.190428 -353.610167) (xy 428.217058 -353.695657) (xy 428.23496 -353.783391) (xy 428.243955 -353.872479)
			(xy 428.244508 -353.91725) (xy 428.243935 -353.96202) (xy 428.234936 -354.051106) (xy 428.217036 -354.138838)
			(xy 428.190415 -354.224329) (xy 428.173388 -354.265738) (xy 428.169793 -354.27532) (xy 428.169812 -354.295771)
			(xy 428.173388 -354.305362) (xy 428.190417 -354.346737) (xy 428.217034 -354.432165) (xy 428.234937 -354.519833)
			(xy 428.243944 -354.608857) (xy 428.244508 -354.653596) (xy 428.244508 -354.65385) (xy 428.24394 -354.694955)
			(xy 428.23636 -354.776814) (xy 428.221262 -354.857624) (xy 428.198773 -354.936698) (xy 428.169085 -355.013359)
			(xy 428.132451 -355.086955) (xy 428.089184 -355.156857) (xy 428.039654 -355.22247) (xy 427.984281 -355.283233)
			(xy 427.923539 -355.33863) (xy 427.857946 -355.388186) (xy 427.788061 -355.431481) (xy 427.714479 -355.468143)
			(xy 427.63783 -355.497861) (xy 427.558765 -355.520382) (xy 427.47796 -355.535512) (xy 427.396104 -355.543124)
			(xy 427.355 -355.543612) (xy 427.31339 -355.543132) (xy 427.230533 -355.535356) (xy 427.148764 -355.519881)
			(xy 427.068797 -355.496842) (xy 426.991328 -355.46644) (xy 426.917035 -355.42894) (xy 426.881544 -355.407214)
			(xy 426.872433 -355.401996) (xy 426.851698 -355.398798) (xy 426.831415 -355.404156) (xy 426.82287 -355.410262)
			(xy 426.789234 -355.436243) (xy 426.717841 -355.482369) (xy 426.642371 -355.521471) (xy 426.563514 -355.553192)
			(xy 426.481991 -355.577244) (xy 426.398543 -355.593405) (xy 426.313935 -355.60153) (xy 426.271436 -355.602032)
			(xy 426.230327 -355.601513) (xy 426.148459 -355.593929) (xy 426.06764 -355.578822) (xy 425.98856 -355.556321)
			(xy 425.911894 -355.526617) (xy 425.838297 -355.489966) (xy 425.768396 -355.446679) (xy 425.702788 -355.397126)
			(xy 425.642034 -355.341729) (xy 425.58665 -355.280962) (xy 425.537111 -355.215344) (xy 425.49384 -355.145433)
			(xy 425.457204 -355.071828) (xy 425.427518 -354.995156) (xy 425.405034 -354.916071) (xy 425.389944 -354.835249)
			(xy 425.382378 -354.753379) (xy 425.381928 -354.71227) (xy 425.382471 -354.667499) (xy 425.391478 -354.578412)
			(xy 425.409387 -354.49068) (xy 425.436017 -354.40519) (xy 425.453048 -354.363782) (xy 425.45663 -354.354196)
			(xy 425.456619 -354.333749) (xy 425.453048 -354.324158) (xy 425.436017 -354.28275) (xy 425.409384 -354.197261)
			(xy 425.391479 -354.109528) (xy 425.382482 -354.020441) (xy 425.381928 -353.97567) (xy 425.381928 -353.963732)
			(xy 425.35545 -353.957782) (xy 425.303215 -353.943042) (xy 425.277534 -353.934268) (xy 425.269337 -353.931754)
			(xy 425.252203 -353.931754) (xy 425.244006 -353.934268) (xy 425.208787 -353.946222) (xy 425.136785 -353.964878)
			(xy 425.063465 -353.977388) (xy 424.98935 -353.983664) (xy 424.95216 -353.984052) (xy 424.914971 -353.983643)
			(xy 424.840858 -353.977359) (xy 424.767539 -353.964855) (xy 424.695532 -353.94622) (xy 424.660314 -353.934268)
			(xy 424.652117 -353.931754) (xy 424.634983 -353.931754) (xy 424.626786 -353.934268) (xy 424.591569 -353.946227)
			(xy 424.519566 -353.964882) (xy 424.446245 -353.977391) (xy 424.37213 -353.983665) (xy 424.33494 -353.984052)
			(xy 424.293 -353.983611) (xy 424.209499 -353.975641) (xy 424.127133 -353.95977) (xy 424.04665 -353.936141)
			(xy 423.968777 -353.904968) (xy 423.89422 -353.866534) (xy 423.823654 -353.821187) (xy 423.757718 -353.769337)
			(xy 423.697009 -353.711455) (xy 423.642078 -353.648063) (xy 423.593421 -353.579737) (xy 423.55148 -353.507095)
			(xy 423.516634 -353.430795) (xy 423.489198 -353.351528) (xy 423.469422 -353.270012) (xy 423.457484 -353.186985)
			(xy 423.453493 -353.1032) (xy 344.34922 -353.1032) (xy 344.346818 -353.129131) (xy 344.331712 -353.20995)
			(xy 344.309211 -353.289031) (xy 344.279508 -353.365698) (xy 344.242856 -353.439296) (xy 344.199569 -353.509197)
			(xy 344.150015 -353.574806) (xy 344.094618 -353.635561) (xy 344.03385 -353.690944) (xy 343.968231 -353.740483)
			(xy 343.898319 -353.783755) (xy 343.824713 -353.82039) (xy 343.748039 -353.850075) (xy 343.668954 -353.872558)
			(xy 343.58813 -353.887646) (xy 343.50626 -353.895211) (xy 343.46515 -353.89566) (xy 343.421566 -353.895134)
			(xy 343.334811 -353.886653) (xy 343.249302 -353.869729) (xy 343.165858 -353.844524) (xy 343.085279 -353.81128)
			(xy 343.046558 -353.791266) (xy 343.035092 -353.785848) (xy 343.009764 -353.785848) (xy 342.998298 -353.791266)
			(xy 342.959077 -353.812027) (xy 342.877306 -353.846516) (xy 342.792508 -353.872694) (xy 342.705525 -353.890299)
			(xy 342.617221 -353.899159) (xy 342.572848 -353.899724) (xy 342.534532 -353.899341) (xy 342.458179 -353.892813)
			(xy 342.382672 -353.879733) (xy 342.308573 -353.860197) (xy 342.272366 -353.847654) (xy 342.26405 -353.845068)
			(xy 342.246646 -353.845068) (xy 342.23833 -353.847654) (xy 342.202121 -353.860189) (xy 342.128019 -353.879707)
			(xy 342.052513 -353.892787) (xy 341.976163 -353.899332) (xy 341.937848 -353.899724) (xy 341.899532 -353.899341)
			(xy 341.823179 -353.892813) (xy 341.747672 -353.879733) (xy 341.673573 -353.860197) (xy 341.637366 -353.847654)
			(xy 341.62905 -353.845068) (xy 341.611646 -353.845068) (xy 341.60333 -353.847654) (xy 341.567121 -353.860189)
			(xy 341.493019 -353.879707) (xy 341.417513 -353.892787) (xy 341.341163 -353.899332) (xy 341.302848 -353.899724)
			(xy 341.264532 -353.899341) (xy 341.188179 -353.892813) (xy 341.112672 -353.879733) (xy 341.038573 -353.860197)
			(xy 341.002366 -353.847654) (xy 340.99405 -353.845068) (xy 340.976646 -353.845068) (xy 340.96833 -353.847654)
			(xy 340.932121 -353.860189) (xy 340.858019 -353.879707) (xy 340.782513 -353.892787) (xy 340.706163 -353.899332)
			(xy 340.667848 -353.899724) (xy 340.626539 -353.899263) (xy 340.544274 -353.89164) (xy 340.463071 -353.876418)
			(xy 340.38363 -353.853729) (xy 340.306637 -353.823768) (xy 340.232755 -353.786793) (xy 340.19744 -353.765358)
			(xy 340.189803 -353.761082) (xy 340.172701 -353.75742) (xy 340.155358 -353.759679) (xy 340.147402 -353.763326)
			(xy 340.109501 -353.782381) (xy 340.030769 -353.813979) (xy 339.949386 -353.837938) (xy 339.866091 -353.85404)
			(xy 339.781642 -353.862138) (xy 339.739224 -353.86264) (xy 339.73897 -353.86264) (xy 339.697862 -353.862216)
			(xy 339.615997 -353.854629) (xy 339.535181 -353.839522) (xy 339.456103 -353.817024) (xy 339.379438 -353.787327)
			(xy 339.30584 -353.750684) (xy 339.235936 -353.707408) (xy 339.170322 -353.657867) (xy 339.109558 -353.602485)
			(xy 339.054162 -353.541734) (xy 339.004606 -353.476131) (xy 338.961314 -353.406237) (xy 338.924655 -353.332646)
			(xy 338.89494 -353.255988) (xy 338.872425 -353.176916) (xy 338.857299 -353.096103) (xy 338.849693 -353.01424)
			(xy 338.849208 -352.973132) (xy 195.744851 -352.973132) (xy 195.771754 -353.027135) (xy 195.80147 -353.103792)
			(xy 195.823987 -353.182863) (xy 195.839114 -353.263674) (xy 195.846722 -353.345537) (xy 195.847208 -353.386644)
			(xy 195.846646 -353.431414) (xy 195.837635 -353.520499) (xy 195.81973 -353.60823) (xy 195.793111 -353.693721)
			(xy 195.776088 -353.735132) (xy 195.772497 -353.744715) (xy 195.772513 -353.765165) (xy 195.776088 -353.774756)
			(xy 195.793114 -353.816166) (xy 195.81975 -353.901654) (xy 195.837657 -353.989386) (xy 195.846654 -354.078474)
			(xy 195.847208 -354.123244) (xy 195.846646 -354.168014) (xy 195.837635 -354.257099) (xy 195.81973 -354.34483)
			(xy 195.793111 -354.430321) (xy 195.776088 -354.471732) (xy 195.772497 -354.481315) (xy 195.772513 -354.501765)
			(xy 195.776088 -354.511356) (xy 195.793114 -354.552766) (xy 195.81975 -354.638254) (xy 195.837657 -354.725986)
			(xy 195.846654 -354.815074) (xy 195.847208 -354.859844) (xy 195.84679 -354.900955) (xy 195.839198 -354.982827)
			(xy 195.824083 -355.063648) (xy 195.801575 -355.14273) (xy 195.771864 -355.219398) (xy 195.742079 -355.279198)
			(xy 285.476188 -355.279198) (xy 285.476597 -355.238082) (xy 285.484185 -355.1562) (xy 285.499295 -355.075367)
			(xy 285.5218 -354.996274) (xy 285.551507 -354.919594) (xy 285.588163 -354.845983) (xy 285.631455 -354.776069)
			(xy 285.681013 -354.710447) (xy 285.736414 -354.649677) (xy 285.797187 -354.594279) (xy 285.862811 -354.544725)
			(xy 285.932729 -354.501438) (xy 286.006342 -354.464786) (xy 286.083023 -354.435084) (xy 286.162118 -354.412584)
			(xy 286.242951 -354.397477) (xy 286.324834 -354.389894) (xy 286.36595 -354.389436) (xy 286.404239 -354.389856)
			(xy 286.480533 -354.39646) (xy 286.555976 -354.409605) (xy 286.630007 -354.429194) (xy 286.666178 -354.44176)
			(xy 286.674615 -354.444411) (xy 286.692285 -354.444411) (xy 286.700722 -354.44176) (xy 286.736903 -354.429226)
			(xy 286.810935 -354.409651) (xy 286.886373 -354.396501) (xy 286.962662 -354.389874) (xy 287.00095 -354.389436)
			(xy 287.039239 -354.389856) (xy 287.115533 -354.39646) (xy 287.190976 -354.409605) (xy 287.265007 -354.429194)
			(xy 287.301178 -354.44176) (xy 287.309615 -354.444411) (xy 287.327285 -354.444411) (xy 287.335722 -354.44176)
			(xy 287.371903 -354.429226) (xy 287.445935 -354.409651) (xy 287.521373 -354.396501) (xy 287.597662 -354.389874)
			(xy 287.63595 -354.389436) (xy 287.674239 -354.389856) (xy 287.750533 -354.39646) (xy 287.825976 -354.409605)
			(xy 287.900007 -354.429194) (xy 287.936178 -354.44176) (xy 287.944615 -354.444411) (xy 287.962285 -354.444411)
			(xy 287.970722 -354.44176) (xy 288.006903 -354.429226) (xy 288.080935 -354.409651) (xy 288.156373 -354.396501)
			(xy 288.232662 -354.389874) (xy 288.27095 -354.389436) (xy 288.309239 -354.389856) (xy 288.385533 -354.39646)
			(xy 288.460976 -354.409605) (xy 288.535007 -354.429194) (xy 288.571178 -354.44176) (xy 288.579615 -354.444411)
			(xy 288.597285 -354.444411) (xy 288.605722 -354.44176) (xy 288.641903 -354.429226) (xy 288.715935 -354.409651)
			(xy 288.791373 -354.396501) (xy 288.867662 -354.389874) (xy 288.90595 -354.389436) (xy 288.947064 -354.389946)
			(xy 289.028942 -354.397529) (xy 289.10977 -354.412634) (xy 289.18886 -354.435133) (xy 289.265537 -354.464834)
			(xy 289.339146 -354.501483) (xy 289.409059 -354.544768) (xy 289.47468 -354.594319) (xy 289.535449 -354.649714)
			(xy 289.590847 -354.71048) (xy 289.640402 -354.776098) (xy 289.683691 -354.846009) (xy 289.720345 -354.919615)
			(xy 289.75005 -354.99629) (xy 289.772554 -355.075379) (xy 289.787664 -355.156207) (xy 289.795251 -355.238084)
			(xy 289.795712 -355.279198) (xy 289.795298 -355.318061) (xy 289.788487 -355.395488) (xy 289.77495 -355.472025)
			(xy 289.75479 -355.547092) (xy 289.741864 -355.583744) (xy 289.739034 -355.592628) (xy 289.739308 -355.611259)
			(xy 289.742372 -355.620066) (xy 289.757559 -355.659473) (xy 289.781314 -355.740522) (xy 289.797291 -355.823456)
			(xy 289.805346 -355.907529) (xy 289.805872 -355.949758) (xy 289.805454 -355.988048) (xy 289.79885 -356.064341)
			(xy 289.785704 -356.139784) (xy 289.766114 -356.213815) (xy 289.753548 -356.249986) (xy 289.750918 -356.258428)
			(xy 289.750905 -356.276094) (xy 289.753548 -356.28453) (xy 289.766084 -356.32071) (xy 289.785659 -356.394742)
			(xy 289.798808 -356.470181) (xy 289.805435 -356.54647) (xy 289.805872 -356.584758) (xy 289.805362 -356.625872)
			(xy 289.797778 -356.707749) (xy 289.782672 -356.788578) (xy 289.760173 -356.867667) (xy 289.730472 -356.944344)
			(xy 289.693822 -357.017952) (xy 289.650537 -357.087865) (xy 289.600986 -357.153486) (xy 289.545592 -357.214255)
			(xy 289.484826 -357.269653) (xy 289.419208 -357.319208) (xy 289.349298 -357.362497) (xy 289.275691 -357.399151)
			(xy 289.199017 -357.428856) (xy 289.119928 -357.45136) (xy 289.039101 -357.466471) (xy 288.957224 -357.474059)
			(xy 288.91611 -357.47452) (xy 288.87782 -357.474114) (xy 288.801526 -357.467506) (xy 288.726084 -357.454357)
			(xy 288.652053 -357.434764) (xy 288.615882 -357.422196) (xy 288.607445 -357.419545) (xy 288.589775 -357.419545)
			(xy 288.581338 -357.422196) (xy 288.54516 -357.434739) (xy 288.471127 -357.454312) (xy 288.395688 -357.46746)
			(xy 288.319398 -357.474084) (xy 288.28111 -357.47452) (xy 288.24282 -357.474114) (xy 288.166526 -357.467506)
			(xy 288.091084 -357.454357) (xy 288.017053 -357.434764) (xy 287.980882 -357.422196) (xy 287.972445 -357.419545)
			(xy 287.954775 -357.419545) (xy 287.946338 -357.422196) (xy 287.91016 -357.434739) (xy 287.836127 -357.454312)
			(xy 287.760688 -357.46746) (xy 287.684398 -357.474084) (xy 287.64611 -357.47452) (xy 287.60782 -357.474114)
			(xy 287.531526 -357.467506) (xy 287.456084 -357.454357) (xy 287.382053 -357.434764) (xy 287.345882 -357.422196)
			(xy 287.337445 -357.419545) (xy 287.319775 -357.419545) (xy 287.311338 -357.422196) (xy 287.27516 -357.434739)
			(xy 287.201127 -357.454312) (xy 287.125688 -357.46746) (xy 287.049398 -357.474084) (xy 287.01111 -357.47452)
			(xy 286.97282 -357.474114) (xy 286.896526 -357.467506) (xy 286.821084 -357.454357) (xy 286.747053 -357.434764)
			(xy 286.710882 -357.422196) (xy 286.702445 -357.419545) (xy 286.684775 -357.419545) (xy 286.676338 -357.422196)
			(xy 286.64016 -357.434739) (xy 286.566127 -357.454312) (xy 286.490688 -357.46746) (xy 286.414398 -357.474084)
			(xy 286.37611 -357.47452) (xy 286.334994 -357.474092) (xy 286.253113 -357.466505) (xy 286.172281 -357.451395)
			(xy 286.093188 -357.428892) (xy 286.016509 -357.399186) (xy 285.942899 -357.362532) (xy 285.872984 -357.319241)
			(xy 285.807362 -357.269685) (xy 285.746593 -357.214284) (xy 285.691195 -357.153513) (xy 285.641641 -357.08789)
			(xy 285.598353 -357.017973) (xy 285.561701 -356.944361) (xy 285.531998 -356.867681) (xy 285.509497 -356.788588)
			(xy 285.49439 -356.707755) (xy 285.486807 -356.625874) (xy 285.486348 -356.584758) (xy 285.48677 -356.546469)
			(xy 285.493373 -356.470175) (xy 285.506518 -356.394732) (xy 285.526107 -356.320701) (xy 285.538672 -356.28453)
			(xy 285.541343 -356.276098) (xy 285.541329 -356.258423) (xy 285.538672 -356.249986) (xy 285.526141 -356.213804)
			(xy 285.506565 -356.139773) (xy 285.493414 -356.064334) (xy 285.486786 -355.988046) (xy 285.486348 -355.949758)
			(xy 285.486781 -355.910896) (xy 285.493587 -355.833469) (xy 285.507119 -355.756932) (xy 285.527272 -355.681865)
			(xy 285.540196 -355.645212) (xy 285.542998 -355.636321) (xy 285.542744 -355.617697) (xy 285.539688 -355.60889)
			(xy 285.524486 -355.569489) (xy 285.500735 -355.488437) (xy 285.484763 -355.405502) (xy 285.476712 -355.321427)
			(xy 285.476188 -355.279198) (xy 195.742079 -355.279198) (xy 195.735206 -355.292996) (xy 195.691912 -355.362897)
			(xy 195.642352 -355.428505) (xy 195.586949 -355.48926) (xy 195.526176 -355.544642) (xy 195.460551 -355.59418)
			(xy 195.390636 -355.637451) (xy 195.317025 -355.674085) (xy 195.240348 -355.703769) (xy 195.161258 -355.726251)
			(xy 195.080432 -355.741339) (xy 194.998557 -355.748903) (xy 194.957446 -355.749352) (xy 194.915842 -355.74888)
			(xy 194.832994 -355.741147) (xy 194.75123 -355.725716) (xy 194.671262 -355.702722) (xy 194.593789 -355.672366)
			(xy 194.519488 -355.634911) (xy 194.48399 -355.613208) (xy 194.474858 -355.608031) (xy 194.454138 -355.60482)
			(xy 194.433861 -355.61016) (xy 194.425316 -355.616256) (xy 194.391667 -355.642178) (xy 194.320293 -355.688236)
			(xy 194.244854 -355.727283) (xy 194.166037 -355.758962) (xy 194.08456 -355.782986) (xy 194.001164 -355.799135)
			(xy 193.916608 -355.807262) (xy 193.874136 -355.807772) (xy 193.873882 -355.807772) (xy 193.832775 -355.807305)
			(xy 193.750912 -355.799719) (xy 193.670098 -355.784614) (xy 193.591023 -355.762118) (xy 193.514359 -355.732423)
			(xy 193.440762 -355.695782) (xy 193.370859 -355.652509) (xy 193.305245 -355.602971) (xy 193.244482 -355.547592)
			(xy 193.189086 -355.486844) (xy 193.13953 -355.421244) (xy 193.096237 -355.351353) (xy 193.059577 -355.277766)
			(xy 193.029861 -355.201111) (xy 193.007343 -355.122041) (xy 192.992215 -355.041231) (xy 192.984607 -354.959371)
			(xy 192.98412 -354.918264) (xy 192.984683 -354.873494) (xy 192.993693 -354.784409) (xy 193.011598 -354.696678)
			(xy 193.038217 -354.611187) (xy 193.05524 -354.569776) (xy 193.058825 -354.560191) (xy 193.058812 -354.539743)
			(xy 193.05524 -354.530152) (xy 193.03824 -354.4888) (xy 193.011628 -354.403438) (xy 192.99372 -354.315836)
			(xy 192.984697 -354.226879) (xy 192.98412 -354.182172) (xy 192.98412 -354.181156) (xy 192.984374 -354.169726)
			(xy 192.957895 -354.163781) (xy 192.90566 -354.149038) (xy 192.87998 -354.140262) (xy 192.871783 -354.137748)
			(xy 192.854649 -354.137748) (xy 192.846452 -354.140262) (xy 192.811236 -354.152209) (xy 192.739226 -354.170796)
			(xy 192.665903 -354.183236) (xy 192.591792 -354.18944) (xy 192.554606 -354.189792) (xy 192.517422 -354.189422)
			(xy 192.443314 -354.1832) (xy 192.369994 -354.170758) (xy 192.297983 -354.152184) (xy 192.26276 -354.140262)
			(xy 192.254563 -354.137748) (xy 192.237429 -354.137748) (xy 192.229232 -354.140262) (xy 192.19413 -354.15215)
			(xy 192.122374 -354.1707) (xy 192.049311 -354.183146) (xy 191.97546 -354.189399) (xy 191.938402 -354.189792)
			(xy 191.937386 -354.189792) (xy 191.89546 -354.189345) (xy 191.811988 -354.181373) (xy 191.729651 -354.165503)
			(xy 191.649196 -354.141878) (xy 191.57135 -354.110712) (xy 191.49682 -354.072288) (xy 191.42628 -354.026953)
			(xy 191.360368 -353.975119) (xy 191.299682 -353.917254) (xy 191.244771 -353.853882) (xy 191.196132 -353.785578)
			(xy 191.154206 -353.71296) (xy 191.119373 -353.636685) (xy 191.091948 -353.557444) (xy 191.07218 -353.475956)
			(xy 191.060246 -353.392957) (xy 191.056256 -353.3092) (xy 187.519078 -353.3092) (xy 187.520094 -353.320137)
			(xy 187.52058 -353.361244) (xy 187.52002 -353.406014) (xy 187.511009 -353.495099) (xy 187.493104 -353.58283)
			(xy 187.466484 -353.668321) (xy 187.44946 -353.709732) (xy 187.44587 -353.719315) (xy 187.445886 -353.739765)
			(xy 187.44946 -353.749356) (xy 187.466484 -353.790767) (xy 187.493121 -353.876254) (xy 187.511029 -353.963986)
			(xy 187.520026 -354.053074) (xy 187.52058 -354.097844) (xy 187.52002 -354.142614) (xy 187.511009 -354.231699)
			(xy 187.493104 -354.31943) (xy 187.466484 -354.404921) (xy 187.44946 -354.446332) (xy 187.44587 -354.455915)
			(xy 187.445886 -354.476365) (xy 187.44946 -354.485956) (xy 187.466484 -354.527367) (xy 187.493121 -354.612854)
			(xy 187.511029 -354.700586) (xy 187.520026 -354.789674) (xy 187.52058 -354.834444) (xy 187.520189 -354.875556)
			(xy 187.512597 -354.957429) (xy 187.497482 -355.038252) (xy 187.474973 -355.117336) (xy 187.445261 -355.194004)
			(xy 187.408601 -355.267604) (xy 187.365306 -355.337506) (xy 187.315744 -355.403115) (xy 187.260339 -355.46387)
			(xy 187.199564 -355.519252) (xy 187.133937 -355.56879) (xy 187.064019 -355.61206) (xy 186.990406 -355.648693)
			(xy 186.913727 -355.678376) (xy 186.834635 -355.700857) (xy 186.753806 -355.715942) (xy 186.67193 -355.723505)
			(xy 186.630818 -355.723952) (xy 186.589214 -355.723494) (xy 186.506365 -355.715758) (xy 186.424601 -355.700325)
			(xy 186.344633 -355.677328) (xy 186.267161 -355.646969) (xy 186.192859 -355.609513) (xy 186.157362 -355.587808)
			(xy 186.148243 -355.582606) (xy 186.127514 -355.579404) (xy 186.107233 -355.584754) (xy 186.098688 -355.590856)
			(xy 186.065049 -355.616791) (xy 185.993673 -355.662848) (xy 185.918232 -355.701893) (xy 185.839413 -355.73357)
			(xy 185.757935 -355.757592) (xy 185.674537 -355.773739) (xy 185.589981 -355.781864) (xy 185.547508 -355.782372)
			(xy 185.547254 -355.782372) (xy 185.506147 -355.781931) (xy 185.424283 -355.774343) (xy 185.343469 -355.759235)
			(xy 185.264393 -355.736737) (xy 185.187729 -355.70704) (xy 185.114132 -355.670398) (xy 185.044229 -355.627122)
			(xy 184.978615 -355.577583) (xy 184.917852 -355.522202) (xy 184.862456 -355.461452) (xy 184.812901 -355.395851)
			(xy 184.769609 -355.325959) (xy 184.732948 -355.252371) (xy 184.703232 -355.175714) (xy 184.680715 -355.096644)
			(xy 184.665587 -355.015833) (xy 184.657979 -354.933971) (xy 184.657492 -354.892864) (xy 184.658057 -354.848094)
			(xy 184.667066 -354.759009) (xy 184.684971 -354.671278) (xy 184.711589 -354.585787) (xy 184.728612 -354.544376)
			(xy 184.732199 -354.534792) (xy 184.732185 -354.514343) (xy 184.728612 -354.504752) (xy 184.711616 -354.463398)
			(xy 184.685002 -354.378037) (xy 184.667093 -354.290435) (xy 184.658069 -354.201478) (xy 184.657492 -354.156772)
			(xy 184.657492 -354.155756) (xy 184.657746 -354.144326) (xy 184.631266 -354.138384) (xy 184.579032 -354.123639)
			(xy 184.553352 -354.114862) (xy 184.545155 -354.112348) (xy 184.528021 -354.112348) (xy 184.519824 -354.114862)
			(xy 184.484602 -354.126789) (xy 184.412594 -354.145381) (xy 184.339273 -354.157827) (xy 184.265163 -354.164037)
			(xy 184.227978 -354.164392) (xy 184.190794 -354.16403) (xy 184.116686 -354.157806) (xy 184.043366 -354.145361)
			(xy 183.971355 -354.126785) (xy 183.936132 -354.114862) (xy 183.927935 -354.112348) (xy 183.910801 -354.112348)
			(xy 183.902604 -354.114862) (xy 183.867505 -354.126757) (xy 183.795747 -354.145305) (xy 183.722684 -354.157749)
			(xy 183.648832 -354.164001) (xy 183.611774 -354.164392) (xy 183.610758 -354.164392) (xy 183.568833 -354.163944)
			(xy 183.485362 -354.155969) (xy 183.403028 -354.140097) (xy 183.322575 -354.11647) (xy 183.244732 -354.085304)
			(xy 183.170204 -354.046879) (xy 183.099666 -354.001544) (xy 183.033756 -353.949709) (xy 182.973072 -353.891844)
			(xy 182.918163 -353.828473) (xy 182.869527 -353.760169) (xy 182.827603 -353.687552) (xy 182.792771 -353.611278)
			(xy 182.765347 -353.532039) (xy 182.745579 -353.450553) (xy 182.733646 -353.367555) (xy 182.729656 -353.2838)
			(xy 78.346936 -353.2838) (xy 78.321217 -353.348042) (xy 78.282395 -353.423345) (xy 78.236592 -353.494617)
			(xy 78.184221 -353.561213) (xy 78.125756 -353.622528) (xy 78.061728 -353.678009) (xy 77.992716 -353.727152)
			(xy 77.919346 -353.769512) (xy 77.842281 -353.804707) (xy 77.762219 -353.832416) (xy 77.679886 -353.85239)
			(xy 77.596027 -353.864447) (xy 77.511402 -353.868479) (xy 77.426777 -353.864447) (xy 77.342918 -353.85239)
			(xy 77.260585 -353.832416) (xy 77.180523 -353.804707) (xy 77.103458 -353.769512) (xy 77.030088 -353.727152)
			(xy 76.961076 -353.678009) (xy 76.897048 -353.622528) (xy 76.838583 -353.561213) (xy 76.786212 -353.494617)
			(xy 76.740409 -353.423345) (xy 76.701587 -353.348042) (xy 76.670099 -353.26939) (xy 76.646231 -353.1881)
			(xy 76.630197 -353.10491) (xy 76.622144 -353.020573) (xy 76.62164 -352.978212) (xy 76.622159 -352.935266)
			(xy 76.630462 -352.849776) (xy 76.646954 -352.765482) (xy 76.671481 -352.683166) (xy 76.687172 -352.643186)
			(xy 76.690418 -352.63393) (xy 76.690431 -352.614336) (xy 76.687172 -352.605086) (xy 76.671432 -352.565089)
			(xy 76.646875 -352.482712) (xy 76.630388 -352.398348) (xy 76.622124 -352.312786) (xy 76.62164 -352.269806)
			(xy 76.622244 -352.224161) (xy 76.631638 -352.133355) (xy 76.650266 -352.043985) (xy 76.66355 -352.000312)
			(xy 76.665996 -351.9913) (xy 76.664956 -351.972672) (xy 76.661518 -351.96399) (xy 76.642856 -351.920903)
			(xy 76.61365 -351.831658) (xy 76.594004 -351.739834) (xy 76.584137 -351.646451) (xy 76.58354 -351.5995)
			(xy 75.70064 -351.5995) (xy 75.701144 -351.637854) (xy 75.70053 -351.683499) (xy 75.691141 -351.774304)
			(xy 75.672516 -351.863674) (xy 75.659234 -351.907348) (xy 75.65681 -351.916364) (xy 75.657836 -351.934988)
			(xy 75.661266 -351.94367) (xy 75.679947 -351.986749) (xy 75.709149 -352.075997) (xy 75.728789 -352.167824)
			(xy 75.738651 -352.261208) (xy 75.739244 -352.30816) (xy 75.738798 -352.348493) (xy 75.731529 -352.428831)
			(xy 75.71702 -352.508181) (xy 75.69539 -352.585893) (xy 75.666817 -352.661328) (xy 75.649582 -352.697796)
			(xy 75.645066 -352.708391) (xy 75.645063 -352.731399) (xy 75.649582 -352.741992) (xy 75.666819 -352.778431)
			(xy 75.69537 -352.853821) (xy 75.716991 -352.931483) (xy 75.731505 -353.010781) (xy 75.738793 -353.091066)
			(xy 75.739244 -353.131374) (xy 75.73874 -353.173735) (xy 75.730687 -353.258072) (xy 75.714653 -353.341262)
			(xy 75.690785 -353.422552) (xy 75.659297 -353.501204) (xy 75.620475 -353.576507) (xy 75.574672 -353.647779)
			(xy 75.522301 -353.714375) (xy 75.463836 -353.77569) (xy 75.399808 -353.831171) (xy 75.330796 -353.880314)
			(xy 75.257426 -353.922674) (xy 75.180361 -353.957869) (xy 75.100299 -353.985578) (xy 75.017966 -354.005552)
			(xy 74.934107 -354.017609) (xy 74.849482 -354.021641) (xy 74.764857 -354.017609) (xy 74.680998 -354.005552)
			(xy 74.598665 -353.985578) (xy 74.518603 -353.957869) (xy 74.441538 -353.922674) (xy 74.368168 -353.880314)
			(xy 74.299156 -353.831171) (xy 74.235128 -353.77569) (xy 74.176663 -353.714375) (xy 74.124292 -353.647779)
			(xy 74.078489 -353.576507) (xy 74.039667 -353.501204) (xy 74.008179 -353.422552) (xy 73.984311 -353.341262)
			(xy 73.968277 -353.258072) (xy 73.960224 -353.173735) (xy 73.95972 -353.131374) (xy 73.960164 -353.091034)
			(xy 73.96747 -353.010685) (xy 73.982028 -352.931329) (xy 74.003719 -352.85362) (xy 74.032363 -352.778196)
			(xy 74.049636 -352.741738) (xy 74.054225 -352.731091) (xy 74.054231 -352.707932) (xy 74.049636 -352.697288)
			(xy 74.032445 -352.660861) (xy 74.003936 -352.58552) (xy 73.98236 -352.50791) (xy 73.967893 -352.428665)
			(xy 73.960655 -352.348437) (xy 73.960228 -352.30816) (xy 73.960797 -352.262521) (xy 73.970094 -352.171718)
			(xy 73.988639 -352.082344) (xy 74.001884 -352.038666) (xy 74.004352 -352.029659) (xy 74.003297 -352.011026)
			(xy 73.999852 -352.002344) (xy 73.981136 -351.959272) (xy 73.95186 -351.870033) (xy 73.932154 -351.778206)
			(xy 73.922237 -351.684813) (xy 73.92162 -351.637854) (xy 2.509012 -351.637854) (xy 2.509012 -358.071674)
			(xy 14.438884 -358.071674) (xy 14.438884 -357.208074) (xy 14.43937 -357.180805) (xy 14.447132 -357.126821)
			(xy 14.462497 -357.074491) (xy 14.485154 -357.024881) (xy 14.51464 -356.979) (xy 14.550355 -356.937783)
			(xy 14.591572 -356.902068) (xy 14.637453 -356.872582) (xy 14.687063 -356.849925) (xy 14.739393 -356.83456)
			(xy 14.793377 -356.826798) (xy 14.847915 -356.826798) (xy 14.901899 -356.83456) (xy 14.954229 -356.849925)
			(xy 15.003839 -356.872582) (xy 15.04972 -356.902068) (xy 15.090937 -356.937783) (xy 15.126652 -356.979)
			(xy 15.156138 -357.024881) (xy 15.178795 -357.074491) (xy 15.19416 -357.126821) (xy 15.201922 -357.180805)
			(xy 15.202408 -357.208074) (xy 15.202408 -358.071674) (xy 15.201922 -358.098943) (xy 15.19416 -358.152927)
			(xy 15.178795 -358.205257) (xy 15.156138 -358.254867) (xy 15.126652 -358.300748) (xy 15.090937 -358.341965)
			(xy 15.04972 -358.37768) (xy 15.003839 -358.407166) (xy 14.954229 -358.429823) (xy 14.901899 -358.445188)
			(xy 14.847915 -358.45295) (xy 14.793377 -358.45295) (xy 14.739393 -358.445188) (xy 14.687063 -358.429823)
			(xy 14.637453 -358.407166) (xy 14.591572 -358.37768) (xy 14.550355 -358.341965) (xy 14.51464 -358.300748)
			(xy 14.485154 -358.254867) (xy 14.462497 -358.205257) (xy 14.447132 -358.152927) (xy 14.43937 -358.098943)
			(xy 14.438884 -358.071674) (xy 2.509012 -358.071674) (xy 2.509012 -358.549194) (xy 40.47998 -358.549194)
			(xy 40.480352 -358.511134) (xy 40.486825 -358.435291) (xy 40.499758 -358.360279) (xy 40.519056 -358.286646)
			(xy 40.544577 -358.214933) (xy 40.55999 -358.180132) (xy 40.563435 -358.171803) (xy 40.56487 -358.153848)
			(xy 40.562784 -358.14508) (xy 40.551663 -358.104882) (xy 40.536092 -358.022938) (xy 40.528245 -357.939897)
			(xy 40.527732 -357.898192) (xy 40.528135 -357.859902) (xy 40.534744 -357.783608) (xy 40.547894 -357.708165)
			(xy 40.567488 -357.634135) (xy 40.580056 -357.597964) (xy 40.58271 -357.589528) (xy 40.582708 -357.571857)
			(xy 40.580056 -357.56342) (xy 40.567506 -357.527245) (xy 40.547935 -357.453211) (xy 40.53479 -357.37777)
			(xy 40.528167 -357.30148) (xy 40.527732 -357.263192) (xy 40.528236 -357.220831) (xy 40.536289 -357.136494)
			(xy 40.552323 -357.053304) (xy 40.576191 -356.972014) (xy 40.607679 -356.893362) (xy 40.646501 -356.818059)
			(xy 40.692304 -356.746787) (xy 40.744675 -356.680191) (xy 40.80314 -356.618876) (xy 40.867168 -356.563395)
			(xy 40.93618 -356.514252) (xy 41.00955 -356.471892) (xy 41.086615 -356.436697) (xy 41.166677 -356.408988)
			(xy 41.24901 -356.389014) (xy 41.332869 -356.376957) (xy 41.417494 -356.372926) (xy 41.502119 -356.376957)
			(xy 41.585978 -356.389014) (xy 41.668311 -356.408988) (xy 41.748373 -356.436697) (xy 41.825438 -356.471892)
			(xy 41.898808 -356.514252) (xy 41.96782 -356.563395) (xy 42.031848 -356.618876) (xy 42.090313 -356.680191)
			(xy 42.142684 -356.746787) (xy 42.188487 -356.818059) (xy 42.227309 -356.893362) (xy 42.258797 -356.972014)
			(xy 42.282665 -357.053304) (xy 42.298699 -357.136494) (xy 42.306752 -357.220831) (xy 42.307256 -357.263192)
			(xy 42.306849 -357.301482) (xy 42.300241 -357.377776) (xy 42.287093 -357.453218) (xy 42.2675 -357.527249)
			(xy 42.254932 -357.56342) (xy 42.252286 -357.571858) (xy 42.252283 -357.589527) (xy 42.254932 -357.597964)
			(xy 42.267477 -357.634141) (xy 42.28705 -357.708174) (xy 42.300196 -357.783614) (xy 42.30682 -357.859904)
			(xy 42.307256 -357.898192) (xy 42.306876 -357.936251) (xy 42.300404 -358.012094) (xy 42.287473 -358.087107)
			(xy 42.268177 -358.160739) (xy 42.242658 -358.232452) (xy 42.227246 -358.267254) (xy 42.223809 -358.275586)
			(xy 42.222368 -358.293538) (xy 42.224452 -358.302306) (xy 42.23557 -358.342505) (xy 42.251142 -358.424449)
			(xy 42.258991 -358.507489) (xy 42.259032 -358.51084) (xy 43.046396 -358.51084) (xy 43.046759 -358.47278)
			(xy 43.053225 -358.396935) (xy 43.066156 -358.321921) (xy 43.085458 -358.248289) (xy 43.110988 -358.176577)
			(xy 43.126406 -358.141778) (xy 43.129746 -358.133421) (xy 43.131033 -358.115482) (xy 43.128946 -358.106726)
			(xy 43.117873 -358.066521) (xy 43.102375 -357.984574) (xy 43.094614 -357.901538) (xy 43.094148 -357.859838)
			(xy 43.094524 -357.821522) (xy 43.101053 -357.745169) (xy 43.114136 -357.669662) (xy 43.133673 -357.595562)
			(xy 43.146218 -357.559356) (xy 43.148787 -357.551035) (xy 43.148799 -357.533636) (xy 43.146218 -357.52532)
			(xy 43.13374 -357.489193) (xy 43.114246 -357.415282) (xy 43.101158 -357.339973) (xy 43.094573 -357.263819)
			(xy 43.094148 -357.2256) (xy 43.094148 -357.224838) (xy 43.094652 -357.18249) (xy 43.102703 -357.098176)
			(xy 43.118732 -357.01501) (xy 43.142593 -356.933743) (xy 43.174072 -356.855113) (xy 43.212883 -356.779832)
			(xy 43.258673 -356.70858) (xy 43.311029 -356.642004) (xy 43.369477 -356.580706) (xy 43.433487 -356.525241)
			(xy 43.502479 -356.476112) (xy 43.575829 -356.433763) (xy 43.652872 -356.398579) (xy 43.732911 -356.370877)
			(xy 43.81522 -356.350909) (xy 43.899055 -356.338856) (xy 43.983656 -356.334826) (xy 44.068257 -356.338856)
			(xy 44.152092 -356.350909) (xy 44.234401 -356.370877) (xy 44.31444 -356.398579) (xy 44.391483 -356.433763)
			(xy 44.464833 -356.476112) (xy 44.533825 -356.525241) (xy 44.597835 -356.580706) (xy 44.656283 -356.642004)
			(xy 44.708639 -356.70858) (xy 44.754429 -356.779832) (xy 44.79324 -356.855113) (xy 44.824719 -356.933743)
			(xy 44.84858 -357.01501) (xy 44.864609 -357.098176) (xy 44.87266 -357.18249) (xy 44.873164 -357.224838)
			(xy 44.873164 -357.2256) (xy 44.87277 -357.263821) (xy 44.866201 -357.339979) (xy 44.853113 -357.415292)
			(xy 44.833602 -357.489202) (xy 44.821094 -357.52532) (xy 44.818487 -357.533631) (xy 44.818499 -357.55104)
			(xy 44.821094 -357.559356) (xy 44.833623 -357.595567) (xy 44.853143 -357.669669) (xy 44.866225 -357.745173)
			(xy 44.872771 -357.821523) (xy 44.873164 -357.859838) (xy 44.872788 -357.897898) (xy 44.866324 -357.973742)
			(xy 44.853395 -358.048756) (xy 44.837736 -358.108504) (xy 46.991016 -358.108504) (xy 46.991397 -358.070445)
			(xy 46.997869 -357.994602) (xy 47.0108 -357.919589) (xy 47.030096 -357.845957) (xy 47.055615 -357.774244)
			(xy 47.071026 -357.739442) (xy 47.074466 -357.731111) (xy 47.075906 -357.713158) (xy 47.07382 -357.70439)
			(xy 47.0627 -357.664192) (xy 47.047129 -357.582247) (xy 47.039281 -357.499207) (xy 47.038768 -357.457502)
			(xy 47.039173 -357.419212) (xy 47.045781 -357.342918) (xy 47.05893 -357.267476) (xy 47.078524 -357.193445)
			(xy 47.091092 -357.157274) (xy 47.09374 -357.148837) (xy 47.093741 -357.131167) (xy 47.091092 -357.12273)
			(xy 47.078546 -357.086553) (xy 47.058974 -357.01252) (xy 47.045827 -356.93708) (xy 47.039204 -356.86079)
			(xy 47.038768 -356.822502) (xy 47.0392 -356.781386) (xy 47.046788 -356.699506) (xy 47.061898 -356.618674)
			(xy 47.084402 -356.539582) (xy 47.114108 -356.462904) (xy 47.150762 -356.389293) (xy 47.194052 -356.319379)
			(xy 47.243609 -356.253758) (xy 47.299008 -356.192989) (xy 47.359779 -356.137591) (xy 47.425402 -356.088036)
			(xy 47.495318 -356.044749) (xy 47.568929 -356.008097) (xy 47.645609 -355.978393) (xy 47.724702 -355.955891)
			(xy 47.805533 -355.940784) (xy 47.887414 -355.933199) (xy 47.92853 -355.93274) (xy 47.969637 -355.933252)
			(xy 48.051499 -355.940877) (xy 48.132307 -355.956023) (xy 48.211373 -355.97856) (xy 48.288023 -356.008296)
			(xy 48.325024 -356.026212) (xy 48.335846 -356.030917) (xy 48.359414 -356.030917) (xy 48.370236 -356.026212)
			(xy 48.407247 -356.008316) (xy 48.483894 -355.978575) (xy 48.562957 -355.956031) (xy 48.643763 -355.940876)
			(xy 48.725623 -355.93324) (xy 48.76673 -355.93274) (xy 48.80502 -355.933136) (xy 48.881314 -355.939747)
			(xy 48.956757 -355.952899) (xy 49.030787 -355.972495) (xy 49.066958 -355.985064) (xy 49.075395 -355.987715)
			(xy 49.093065 -355.987715) (xy 49.101502 -355.985064) (xy 49.137675 -355.972508) (xy 49.21171 -355.952938)
			(xy 49.287151 -355.939795) (xy 49.363442 -355.933174) (xy 49.40173 -355.93274) (xy 49.44002 -355.933136)
			(xy 49.516314 -355.939747) (xy 49.591757 -355.952899) (xy 49.665787 -355.972495) (xy 49.701958 -355.985064)
			(xy 49.710395 -355.987715) (xy 49.728065 -355.987715) (xy 49.736502 -355.985064) (xy 49.772675 -355.972508)
			(xy 49.84671 -355.952938) (xy 49.922151 -355.939795) (xy 49.998442 -355.933174) (xy 50.03673 -355.93274)
			(xy 50.07502 -355.933136) (xy 50.151314 -355.939747) (xy 50.226757 -355.952899) (xy 50.300787 -355.972495)
			(xy 50.336958 -355.985064) (xy 50.345395 -355.987715) (xy 50.363065 -355.987715) (xy 50.371502 -355.985064)
			(xy 50.407675 -355.972508) (xy 50.48171 -355.952938) (xy 50.557151 -355.939795) (xy 50.633442 -355.933174)
			(xy 50.67173 -355.93274) (xy 50.712845 -355.933184) (xy 50.794723 -355.940774) (xy 50.875552 -355.955886)
			(xy 50.954642 -355.978392) (xy 51.031318 -356.008098) (xy 51.104926 -356.044753) (xy 51.174838 -356.088043)
			(xy 51.240458 -356.137599) (xy 51.301225 -356.192997) (xy 51.356622 -356.253767) (xy 51.406175 -356.319388)
			(xy 51.449463 -356.389302) (xy 51.486115 -356.462911) (xy 51.515819 -356.539588) (xy 51.538321 -356.618679)
			(xy 51.55343 -356.699508) (xy 51.561017 -356.781387) (xy 51.561492 -356.822502) (xy 51.561091 -356.860792)
			(xy 51.554482 -356.937086) (xy 51.541332 -357.012529) (xy 51.521737 -357.086559) (xy 51.509168 -357.12273)
			(xy 51.506515 -357.131166) (xy 51.506516 -357.148837) (xy 51.509168 -357.157274) (xy 51.521713 -357.193451)
			(xy 51.541286 -357.267484) (xy 51.554433 -357.342924) (xy 51.561057 -357.419214) (xy 51.561492 -357.457502)
			(xy 51.561112 -357.495561) (xy 51.55464 -357.571404) (xy 51.541708 -357.646417) (xy 51.522413 -357.720049)
			(xy 51.496894 -357.791762) (xy 51.481482 -357.826564) (xy 51.478039 -357.834894) (xy 51.476603 -357.852848)
			(xy 51.478688 -357.861616) (xy 51.48981 -357.901814) (xy 51.50538 -357.983758) (xy 51.513227 -358.066799)
			(xy 51.51374 -358.108504) (xy 51.513251 -358.149614) (xy 51.505664 -358.231482) (xy 51.490553 -358.312301)
			(xy 51.468049 -358.391381) (xy 51.438343 -358.468047) (xy 51.401689 -358.541644) (xy 51.3584 -358.611544)
			(xy 51.308844 -358.677152) (xy 51.253446 -358.737906) (xy 51.192678 -358.793289) (xy 51.127058 -358.842827)
			(xy 51.057146 -358.886099) (xy 50.98354 -358.922734) (xy 50.906867 -358.952421) (xy 50.827781 -358.974905)
			(xy 50.746958 -358.989995) (xy 50.665088 -358.997562) (xy 50.623978 -358.998012) (xy 50.585661 -358.99765)
			(xy 50.509308 -358.991116) (xy 50.433801 -358.97803) (xy 50.359702 -358.958488) (xy 50.323496 -358.945942)
			(xy 50.31518 -358.943356) (xy 50.297776 -358.943356) (xy 50.28946 -358.945942) (xy 50.253248 -358.958468)
			(xy 50.179147 -358.977989) (xy 50.103642 -358.991071) (xy 50.027293 -358.997619) (xy 49.988978 -358.998012)
			(xy 49.950661 -358.99765) (xy 49.874308 -358.991116) (xy 49.798801 -358.97803) (xy 49.724702 -358.958488)
			(xy 49.688496 -358.945942) (xy 49.68018 -358.943356) (xy 49.662776 -358.943356) (xy 49.65446 -358.945942)
			(xy 49.618248 -358.958468) (xy 49.544147 -358.977989) (xy 49.468642 -358.991071) (xy 49.392293 -358.997619)
			(xy 49.353978 -358.998012) (xy 49.315661 -358.99765) (xy 49.239308 -358.991116) (xy 49.163801 -358.97803)
			(xy 49.089702 -358.958488) (xy 49.053496 -358.945942) (xy 49.04518 -358.943356) (xy 49.027776 -358.943356)
			(xy 49.01946 -358.945942) (xy 48.983339 -358.95844) (xy 48.909426 -358.977928) (xy 48.834115 -358.99101)
			(xy 48.757959 -358.99759) (xy 48.71974 -358.998012) (xy 48.718978 -358.998012) (xy 48.677876 -358.99753)
			(xy 48.596022 -358.989953) (xy 48.515216 -358.974857) (xy 48.436148 -358.95237) (xy 48.359491 -358.922685)
			(xy 48.322484 -358.904794) (xy 48.311662 -358.900089) (xy 48.288094 -358.900089) (xy 48.277272 -358.904794)
			(xy 48.240271 -358.922698) (xy 48.163612 -358.952379) (xy 48.084542 -358.974864) (xy 48.003735 -358.98996)
			(xy 47.92188 -358.997539) (xy 47.880778 -358.998012) (xy 47.839669 -358.997608) (xy 47.757803 -358.990022)
			(xy 47.676986 -358.974915) (xy 47.597907 -358.952416) (xy 47.52124 -358.922719) (xy 47.447641 -358.886075)
			(xy 47.377735 -358.842798) (xy 47.312121 -358.793256) (xy 47.251356 -358.737873) (xy 47.19596 -358.677119)
			(xy 47.146405 -358.611515) (xy 47.103114 -358.541618) (xy 47.066455 -358.468026) (xy 47.036742 -358.391366)
			(xy 47.014227 -358.312292) (xy 46.999104 -358.231477) (xy 46.9915 -358.149612) (xy 46.991016 -358.108504)
			(xy 44.837736 -358.108504) (xy 44.834097 -358.122388) (xy 44.808571 -358.1941) (xy 44.793154 -358.2289)
			(xy 44.789778 -358.237249) (xy 44.788481 -358.255202) (xy 44.790614 -358.263952) (xy 44.801704 -358.304153)
			(xy 44.817195 -358.386101) (xy 44.82495 -358.46914) (xy 44.825412 -358.51084) (xy 44.824852 -358.556303)
			(xy 44.815599 -358.646758) (xy 44.797171 -358.735798) (xy 44.78401 -358.779318) (xy 44.78146 -358.788893)
			(xy 44.783017 -358.808626) (xy 44.787058 -358.817672) (xy 44.805431 -358.855048) (xy 44.835897 -358.932566)
			(xy 44.858991 -359.012591) (xy 44.87451 -359.094423) (xy 44.882318 -359.177347) (xy 44.882816 -359.218992)
			(xy 44.882816 -359.219246) (xy 44.882312 -359.261594) (xy 44.874261 -359.345908) (xy 44.858232 -359.429074)
			(xy 44.834371 -359.510341) (xy 44.802892 -359.588971) (xy 44.764081 -359.664252) (xy 44.718291 -359.735504)
			(xy 44.665935 -359.80208) (xy 44.607487 -359.863378) (xy 44.543477 -359.918843) (xy 44.474485 -359.967972)
			(xy 44.401135 -360.010321) (xy 44.324092 -360.045505) (xy 44.244053 -360.073207) (xy 44.161744 -360.093175)
			(xy 44.077909 -360.105228) (xy 43.993308 -360.109259) (xy 43.908707 -360.105228) (xy 43.824872 -360.093175)
			(xy 43.742563 -360.073207) (xy 43.662524 -360.045505) (xy 43.585481 -360.010321) (xy 43.512131 -359.967972)
			(xy 43.443139 -359.918843) (xy 43.379129 -359.863378) (xy 43.320681 -359.80208) (xy 43.268325 -359.735504)
			(xy 43.222535 -359.664252) (xy 43.183724 -359.588971) (xy 43.152245 -359.510341) (xy 43.128384 -359.429074)
			(xy 43.112355 -359.345908) (xy 43.104304 -359.261594) (xy 43.1038 -359.219246) (xy 43.104356 -359.173782)
			(xy 43.113611 -359.083328) (xy 43.13204 -358.994288) (xy 43.145202 -358.950768) (xy 43.147759 -358.941194)
			(xy 43.146197 -358.921461) (xy 43.142154 -358.912414) (xy 43.123767 -358.875016) (xy 43.093286 -358.797449)
			(xy 43.070189 -358.717372) (xy 43.054676 -358.635487) (xy 43.046883 -358.552511) (xy 43.046396 -358.51084)
			(xy 42.259032 -358.51084) (xy 42.259504 -358.549194) (xy 42.258889 -358.594663) (xy 42.249552 -358.685121)
			(xy 42.231047 -358.774157) (xy 42.217848 -358.817672) (xy 42.215273 -358.827242) (xy 42.216849 -358.846979)
			(xy 42.220896 -358.856026) (xy 42.239309 -358.893418) (xy 42.269845 -358.970977) (xy 42.292996 -359.051051)
			(xy 42.308559 -359.132939) (xy 42.316398 -359.215923) (xy 42.316908 -359.2576) (xy 42.316404 -359.299961)
			(xy 42.308351 -359.384298) (xy 42.292317 -359.467488) (xy 42.268449 -359.548778) (xy 42.236961 -359.62743)
			(xy 42.198139 -359.702733) (xy 42.152336 -359.774005) (xy 42.099965 -359.840601) (xy 42.0415 -359.901916)
			(xy 41.977472 -359.957397) (xy 41.90846 -360.00654) (xy 41.83509 -360.0489) (xy 41.758025 -360.084095)
			(xy 41.677963 -360.111804) (xy 41.59563 -360.131778) (xy 41.511771 -360.143835) (xy 41.427146 -360.147867)
			(xy 41.342521 -360.143835) (xy 41.258662 -360.131778) (xy 41.176329 -360.111804) (xy 41.096267 -360.084095)
			(xy 41.019202 -360.0489) (xy 40.945832 -360.00654) (xy 40.87682 -359.957397) (xy 40.812792 -359.901916)
			(xy 40.754327 -359.840601) (xy 40.701956 -359.774005) (xy 40.656153 -359.702733) (xy 40.617331 -359.62743)
			(xy 40.585843 -359.548778) (xy 40.561975 -359.467488) (xy 40.545941 -359.384298) (xy 40.537888 -359.299961)
			(xy 40.537384 -359.2576) (xy 40.537998 -359.212131) (xy 40.547335 -359.121673) (xy 40.565841 -359.032637)
			(xy 40.57904 -358.989122) (xy 40.581619 -358.979553) (xy 40.580041 -358.959815) (xy 40.575992 -358.950768)
			(xy 40.557613 -358.91336) (xy 40.527071 -358.835806) (xy 40.503913 -358.755736) (xy 40.488342 -358.673851)
			(xy 40.480494 -358.59087) (xy 40.47998 -358.549194) (xy 2.509012 -358.549194) (xy 2.509012 -361.825848)
			(xy 5.986007 -361.825848) (xy 5.986007 -361.696708) (xy 5.993957 -361.567813) (xy 6.009827 -361.439653)
			(xy 6.033556 -361.312712) (xy 6.065055 -361.187473) (xy 6.104204 -361.06441) (xy 6.150855 -360.943991)
			(xy 6.20483 -360.826672) (xy 6.265925 -360.712898) (xy 6.333908 -360.603101) (xy 6.408522 -360.497698)
			(xy 6.489483 -360.397088) (xy 6.576483 -360.301653) (xy 6.669194 -360.211754) (xy 6.767264 -360.127733)
			(xy 6.870319 -360.049909) (xy 6.97797 -359.978577) (xy 7.089809 -359.914007) (xy 7.20541 -359.856445)
			(xy 7.324335 -359.806108) (xy 7.446134 -359.763188) (xy 7.570344 -359.727847) (xy 7.696493 -359.70022)
			(xy 7.824105 -359.680411) (xy 7.952694 -359.668495) (xy 8.081772 -359.664519) (xy 8.21085 -359.668495)
			(xy 8.339439 -359.680411) (xy 8.467051 -359.70022) (xy 8.5932 -359.727847) (xy 8.71741 -359.763188)
			(xy 8.839209 -359.806108) (xy 8.958134 -359.856445) (xy 9.073735 -359.914007) (xy 9.185574 -359.978577)
			(xy 9.293225 -360.049909) (xy 9.39628 -360.127733) (xy 9.49435 -360.211754) (xy 9.587061 -360.301653)
			(xy 9.674061 -360.397088) (xy 9.689764 -360.416602) (xy 12.542012 -360.416602) (xy 12.542012 -359.553002)
			(xy 12.542498 -359.525751) (xy 12.550254 -359.471803) (xy 12.565609 -359.419508) (xy 12.588251 -359.369931)
			(xy 12.617717 -359.324081) (xy 12.653408 -359.28289) (xy 12.694599 -359.247199) (xy 12.740449 -359.217733)
			(xy 12.790026 -359.195091) (xy 12.842321 -359.179736) (xy 12.896269 -359.17198) (xy 12.950771 -359.17198)
			(xy 13.004719 -359.179736) (xy 13.057014 -359.195091) (xy 13.106591 -359.217733) (xy 13.152441 -359.247199)
			(xy 13.193632 -359.28289) (xy 13.229323 -359.324081) (xy 13.258789 -359.369931) (xy 13.281431 -359.419508)
			(xy 13.296786 -359.471803) (xy 13.304542 -359.525751) (xy 13.305028 -359.553002) (xy 13.305028 -360.416602)
			(xy 13.304542 -360.443853) (xy 13.296786 -360.497801) (xy 13.281431 -360.550096) (xy 13.258789 -360.599673)
			(xy 13.229323 -360.645523) (xy 13.193632 -360.686714) (xy 13.152441 -360.722405) (xy 13.106591 -360.751871)
			(xy 13.057014 -360.774513) (xy 13.004719 -360.789868) (xy 12.950771 -360.797624) (xy 12.896269 -360.797624)
			(xy 12.842321 -360.789868) (xy 12.790026 -360.774513) (xy 12.740449 -360.751871) (xy 12.694599 -360.722405)
			(xy 12.653408 -360.686714) (xy 12.617717 -360.645523) (xy 12.588251 -360.599673) (xy 12.565609 -360.550096)
			(xy 12.550254 -360.497801) (xy 12.542498 -360.443853) (xy 12.542012 -360.416602) (xy 9.689764 -360.416602)
			(xy 9.755022 -360.497698) (xy 9.829636 -360.603101) (xy 9.897619 -360.712898) (xy 9.958714 -360.826672)
			(xy 10.012689 -360.943991) (xy 10.05934 -361.06441) (xy 10.098489 -361.187473) (xy 10.129988 -361.312712)
			(xy 10.153717 -361.439653) (xy 10.169587 -361.567813) (xy 10.177537 -361.696708) (xy 10.178034 -361.761278)
			(xy 10.177537 -361.825848) (xy 10.169587 -361.954743) (xy 10.153717 -362.082903) (xy 10.129988 -362.209844)
			(xy 10.098489 -362.335083) (xy 10.079022 -362.396278) (xy 165.733984 -362.396278) (xy 165.733984 -361.532678)
			(xy 165.73447 -361.505409) (xy 165.742232 -361.451425) (xy 165.757597 -361.399095) (xy 165.780254 -361.349485)
			(xy 165.80974 -361.303604) (xy 165.845455 -361.262387) (xy 165.886672 -361.226672) (xy 165.932553 -361.197186)
			(xy 165.982163 -361.174529) (xy 166.034493 -361.159164) (xy 166.088477 -361.151402) (xy 166.143015 -361.151402)
			(xy 166.196999 -361.159164) (xy 166.249329 -361.174529) (xy 166.298939 -361.197186) (xy 166.34482 -361.226672)
			(xy 166.386037 -361.262387) (xy 166.421752 -361.303604) (xy 166.451238 -361.349485) (xy 166.473895 -361.399095)
			(xy 166.48926 -361.451425) (xy 166.497022 -361.505409) (xy 166.497508 -361.532678) (xy 166.497508 -362.234988)
			(xy 185.144664 -362.234988) (xy 185.144664 -362.23448) (xy 185.145268 -362.188148) (xy 185.154941 -362.09599)
			(xy 185.174137 -362.005336) (xy 185.202649 -361.917167) (xy 185.220864 -361.874562) (xy 185.224678 -361.864622)
			(xy 185.224673 -361.843356) (xy 185.220864 -361.833414) (xy 185.202614 -361.790754) (xy 185.174071 -361.702461)
			(xy 185.15488 -361.611675) (xy 185.145248 -361.519384) (xy 185.144664 -361.472988) (xy 185.145245 -361.426592)
			(xy 185.154891 -361.334304) (xy 185.174088 -361.24352) (xy 185.202626 -361.155227) (xy 185.220864 -361.112562)
			(xy 185.224678 -361.102622) (xy 185.224673 -361.081356) (xy 185.220864 -361.071414) (xy 185.202636 -361.028813)
			(xy 185.17412 -360.940645) (xy 185.154929 -360.849989) (xy 185.145271 -360.757828) (xy 185.144664 -360.711496)
			(xy 185.144664 -360.710988) (xy 185.145155 -360.669886) (xy 185.152741 -360.588033) (xy 185.167846 -360.507229)
			(xy 185.190343 -360.428164) (xy 185.220039 -360.351511) (xy 185.25668 -360.277925) (xy 185.299955 -360.208034)
			(xy 185.349493 -360.142434) (xy 185.404873 -360.081684) (xy 185.465622 -360.026303) (xy 185.531221 -359.976764)
			(xy 185.601111 -359.933488) (xy 185.674696 -359.896845) (xy 185.751348 -359.867148) (xy 185.830414 -359.84465)
			(xy 185.911217 -359.829543) (xy 185.99307 -359.821956) (xy 186.034172 -359.82148) (xy 186.03468 -359.82148)
			(xy 186.081011 -359.822097) (xy 186.173169 -359.831765) (xy 186.263823 -359.850958) (xy 186.351992 -359.879466)
			(xy 186.394598 -359.89768) (xy 186.40454 -359.901486) (xy 186.425804 -359.901486) (xy 186.435746 -359.89768)
			(xy 186.478352 -359.879466) (xy 186.566519 -359.850947) (xy 186.657173 -359.831752) (xy 186.749332 -359.822089)
			(xy 186.795664 -359.82148) (xy 186.796172 -359.82148) (xy 186.837274 -359.821979) (xy 186.919129 -359.829561)
			(xy 186.999934 -359.844664) (xy 187.079001 -359.867158) (xy 187.155656 -359.896852) (xy 187.229243 -359.933492)
			(xy 187.299136 -359.976765) (xy 187.364738 -360.026303) (xy 187.425489 -360.081682) (xy 187.480872 -360.142431)
			(xy 187.530412 -360.208031) (xy 187.573689 -360.277922) (xy 187.610332 -360.351508) (xy 187.640029 -360.428161)
			(xy 187.662527 -360.507227) (xy 187.677633 -360.588032) (xy 187.685219 -360.669886) (xy 187.68568 -360.710988)
			(xy 187.68568 -360.711496) (xy 187.685072 -360.757828) (xy 187.684417 -360.764074) (xy 211.161635 -360.764074)
			(xy 211.16566 -360.621882) (xy 211.177723 -360.480146) (xy 211.197786 -360.33932) (xy 211.225784 -360.199854)
			(xy 211.261628 -360.062195) (xy 211.305202 -359.926785) (xy 211.356367 -359.794057) (xy 211.41496 -359.664436)
			(xy 211.480791 -359.538338) (xy 211.553652 -359.416166) (xy 211.633307 -359.298312) (xy 211.719503 -359.185153)
			(xy 211.811962 -359.077051) (xy 211.91039 -358.974354) (xy 212.014469 -358.87739) (xy 212.123868 -358.78647)
			(xy 212.238236 -358.701884) (xy 212.357205 -358.623904) (xy 212.480396 -358.55278) (xy 212.607413 -358.488739)
			(xy 212.73785 -358.431987) (xy 212.871289 -358.382705) (xy 213.007302 -358.341051) (xy 213.145454 -358.307159)
			(xy 213.285303 -358.281138) (xy 213.426399 -358.26307) (xy 213.568291 -358.253013) (xy 213.710526 -358.251)
			(xy 213.852646 -358.257037) (xy 213.994197 -358.271105) (xy 214.134726 -358.293159) (xy 214.273781 -358.323128)
			(xy 214.410919 -358.360916) (xy 214.545699 -358.406402) (xy 214.67769 -358.45944) (xy 214.806469 -358.519861)
			(xy 214.931623 -358.58747) (xy 215.052751 -358.662052) (xy 215.169467 -358.743368) (xy 215.281395 -358.831156)
			(xy 215.388177 -358.925136) (xy 215.489471 -359.025006) (xy 215.584952 -359.130448) (xy 215.674316 -359.241122)
			(xy 215.757274 -359.356675) (xy 215.833563 -359.476736) (xy 215.902937 -359.600921) (xy 215.965174 -359.728832)
			(xy 216.020075 -359.860059) (xy 216.067463 -359.994182) (xy 216.107188 -360.130771) (xy 216.139121 -360.269389)
			(xy 216.163162 -360.409591) (xy 216.179231 -360.550929) (xy 216.187279 -360.69295) (xy 216.187782 -360.764074)
			(xy 255.611635 -360.764074) (xy 255.61566 -360.621882) (xy 255.627723 -360.480146) (xy 255.647786 -360.33932)
			(xy 255.675784 -360.199854) (xy 255.711628 -360.062195) (xy 255.755202 -359.926785) (xy 255.806367 -359.794057)
			(xy 255.86496 -359.664436) (xy 255.930791 -359.538338) (xy 256.003652 -359.416166) (xy 256.083307 -359.298312)
			(xy 256.169503 -359.185153) (xy 256.261962 -359.077051) (xy 256.36039 -358.974354) (xy 256.464469 -358.87739)
			(xy 256.573868 -358.78647) (xy 256.688236 -358.701884) (xy 256.807205 -358.623904) (xy 256.930396 -358.55278)
			(xy 257.057413 -358.488739) (xy 257.18785 -358.431987) (xy 257.321289 -358.382705) (xy 257.457302 -358.341051)
			(xy 257.595454 -358.307159) (xy 257.735303 -358.281138) (xy 257.876399 -358.26307) (xy 258.018291 -358.253013)
			(xy 258.160526 -358.251) (xy 258.302646 -358.257037) (xy 258.444197 -358.271105) (xy 258.584726 -358.293159)
			(xy 258.723781 -358.323128) (xy 258.860919 -358.360916) (xy 258.995699 -358.406402) (xy 259.12769 -358.45944)
			(xy 259.256469 -358.519861) (xy 259.381623 -358.58747) (xy 259.502751 -358.662052) (xy 259.619467 -358.743368)
			(xy 259.652996 -358.769666) (xy 294.901627 -358.769666) (xy 294.905632 -358.663917) (xy 294.917622 -358.558774)
			(xy 294.937531 -358.454839) (xy 294.965242 -358.352707) (xy 295.000599 -358.252963) (xy 295.043397 -358.156179)
			(xy 295.093393 -358.062909) (xy 295.1503 -357.973688) (xy 295.213791 -357.889025) (xy 295.283503 -357.809407)
			(xy 295.359037 -357.735289) (xy 295.43996 -357.667096) (xy 295.525809 -357.605218) (xy 295.616092 -357.550011)
			(xy 295.710291 -357.501789) (xy 295.807868 -357.460829) (xy 295.908263 -357.427367) (xy 296.010901 -357.401593)
			(xy 296.115194 -357.383655) (xy 296.220545 -357.373656) (xy 296.326351 -357.371653) (xy 296.432005 -357.377658)
			(xy 296.536902 -357.391637) (xy 296.640442 -357.413508) (xy 296.742031 -357.443148) (xy 296.841088 -357.480386)
			(xy 296.937045 -357.525008) (xy 297.029352 -357.57676) (xy 297.117481 -357.635345) (xy 297.200927 -357.700427)
			(xy 297.279211 -357.771633) (xy 297.351886 -357.848556) (xy 297.418536 -357.930756) (xy 297.478778 -358.01776)
			(xy 297.532267 -358.109071) (xy 297.578698 -358.204166) (xy 297.617803 -358.3025) (xy 297.64936 -358.403511)
			(xy 297.673187 -358.506618) (xy 297.689148 -358.611232) (xy 297.697152 -358.716754) (xy 297.697652 -358.769666)
			(xy 297.697152 -358.822578) (xy 297.689148 -358.9281) (xy 297.673187 -359.032714) (xy 297.64936 -359.135821)
			(xy 297.617803 -359.236832) (xy 297.578698 -359.335166) (xy 297.532267 -359.430261) (xy 297.478778 -359.521572)
			(xy 297.418536 -359.608576) (xy 297.351886 -359.690776) (xy 297.279211 -359.767699) (xy 297.200927 -359.838905)
			(xy 297.117481 -359.903987) (xy 297.029352 -359.962572) (xy 296.937045 -360.014324) (xy 296.841088 -360.058946)
			(xy 296.742031 -360.096184) (xy 296.640442 -360.125824) (xy 296.536902 -360.147695) (xy 296.432005 -360.161674)
			(xy 296.326351 -360.167679) (xy 296.220545 -360.165676) (xy 296.115194 -360.155677) (xy 296.010901 -360.137739)
			(xy 295.908263 -360.111965) (xy 295.807868 -360.078503) (xy 295.710291 -360.037543) (xy 295.616092 -359.989321)
			(xy 295.525809 -359.934114) (xy 295.43996 -359.872236) (xy 295.359037 -359.804043) (xy 295.283503 -359.729925)
			(xy 295.213791 -359.650307) (xy 295.1503 -359.565644) (xy 295.093393 -359.476423) (xy 295.043397 -359.383153)
			(xy 295.000599 -359.286369) (xy 294.965242 -359.186625) (xy 294.937531 -359.084493) (xy 294.917622 -358.980558)
			(xy 294.905632 -358.875415) (xy 294.901627 -358.769666) (xy 259.652996 -358.769666) (xy 259.731395 -358.831156)
			(xy 259.838177 -358.925136) (xy 259.939471 -359.025006) (xy 260.034952 -359.130448) (xy 260.124316 -359.241122)
			(xy 260.207274 -359.356675) (xy 260.283563 -359.476736) (xy 260.352937 -359.600921) (xy 260.415174 -359.728832)
			(xy 260.470075 -359.860059) (xy 260.517463 -359.994182) (xy 260.557188 -360.130771) (xy 260.589121 -360.269389)
			(xy 260.613162 -360.409591) (xy 260.629231 -360.550929) (xy 260.637279 -360.69295) (xy 260.637782 -360.764074)
			(xy 260.637279 -360.835198) (xy 260.629231 -360.977219) (xy 260.613162 -361.118557) (xy 260.589121 -361.258759)
			(xy 260.557188 -361.397377) (xy 260.517463 -361.533966) (xy 260.470075 -361.668089) (xy 260.415174 -361.799316)
			(xy 260.401302 -361.827826) (xy 430.615097 -361.827826) (xy 430.619102 -361.722077) (xy 430.631092 -361.616934)
			(xy 430.651001 -361.512999) (xy 430.678712 -361.410867) (xy 430.714069 -361.311123) (xy 430.756867 -361.214339)
			(xy 430.806863 -361.121069) (xy 430.86377 -361.031848) (xy 430.927261 -360.947185) (xy 430.996973 -360.867567)
			(xy 431.072507 -360.793449) (xy 431.15343 -360.725256) (xy 431.239279 -360.663378) (xy 431.329562 -360.608171)
			(xy 431.423761 -360.559949) (xy 431.521338 -360.518989) (xy 431.621733 -360.485527) (xy 431.724371 -360.459753)
			(xy 431.828664 -360.441815) (xy 431.934015 -360.431816) (xy 432.039821 -360.429813) (xy 432.145475 -360.435818)
			(xy 432.250372 -360.449797) (xy 432.353912 -360.471668) (xy 432.455501 -360.501308) (xy 432.554558 -360.538546)
			(xy 432.650515 -360.583168) (xy 432.742822 -360.63492) (xy 432.830951 -360.693505) (xy 432.914397 -360.758587)
			(xy 432.992681 -360.829793) (xy 433.065356 -360.906716) (xy 433.132006 -360.988916) (xy 433.192248 -361.07592)
			(xy 433.245737 -361.167231) (xy 433.292168 -361.262326) (xy 433.331273 -361.36066) (xy 433.36283 -361.461671)
			(xy 433.370787 -361.496102) (xy 434.579776 -361.496102) (xy 434.580404 -361.4497) (xy 434.590093 -361.357403)
			(xy 434.609347 -361.266617) (xy 434.637954 -361.178332) (xy 434.65623 -361.135676) (xy 434.660038 -361.125734)
			(xy 434.660039 -361.10447) (xy 434.65623 -361.094528) (xy 434.637968 -361.051867) (xy 434.609375 -360.963579)
			(xy 434.590118 -360.872796) (xy 434.580405 -360.780503) (xy 434.579776 -360.734102) (xy 434.580404 -360.6877)
			(xy 434.590093 -360.595403) (xy 434.609347 -360.504617) (xy 434.637954 -360.416332) (xy 434.65623 -360.373676)
			(xy 434.660038 -360.363734) (xy 434.660039 -360.34247) (xy 434.65623 -360.332528) (xy 434.637968 -360.289867)
			(xy 434.609375 -360.201579) (xy 434.590118 -360.110796) (xy 434.580405 -360.018503) (xy 434.579776 -359.972102)
			(xy 434.5802 -359.930986) (xy 434.587788 -359.849105) (xy 434.602898 -359.768273) (xy 434.625402 -359.68918)
			(xy 434.655109 -359.612502) (xy 434.691763 -359.538891) (xy 434.735054 -359.468977) (xy 434.784611 -359.403355)
			(xy 434.840011 -359.342586) (xy 434.900783 -359.287188) (xy 434.966406 -359.237634) (xy 435.036323 -359.194346)
			(xy 435.109935 -359.157694) (xy 435.186615 -359.127991) (xy 435.265708 -359.10549) (xy 435.346541 -359.090383)
			(xy 435.428422 -359.082799) (xy 435.469538 -359.08234) (xy 435.51594 -359.082957) (xy 435.608238 -359.09265)
			(xy 435.699023 -359.111907) (xy 435.787308 -359.140517) (xy 435.829964 -359.158794) (xy 435.839906 -359.1626)
			(xy 435.86117 -359.1626) (xy 435.871112 -359.158794) (xy 435.913767 -359.140517) (xy 436.002057 -359.111928)
			(xy 436.092842 -359.092675) (xy 436.185137 -359.082967) (xy 436.231538 -359.08234) (xy 436.272653 -359.082777)
			(xy 436.354532 -359.090367) (xy 436.435361 -359.10548) (xy 436.514451 -359.127986) (xy 436.591127 -359.157693)
			(xy 436.664735 -359.194349) (xy 436.734647 -359.237639) (xy 436.800266 -359.287195) (xy 436.861034 -359.342595)
			(xy 436.91643 -359.403364) (xy 436.965984 -359.468986) (xy 437.009271 -359.5389) (xy 437.045923 -359.61251)
			(xy 437.075627 -359.689187) (xy 437.098129 -359.768278) (xy 437.113238 -359.849108) (xy 437.120825 -359.930987)
			(xy 437.1213 -359.972102) (xy 437.120676 -360.018504) (xy 437.110985 -360.110802) (xy 437.091731 -360.201587)
			(xy 437.063122 -360.289872) (xy 437.044846 -360.332528) (xy 437.041037 -360.34247) (xy 437.041038 -360.363734)
			(xy 437.044846 -360.373676) (xy 437.063108 -360.416337) (xy 437.091701 -360.504625) (xy 437.110959 -360.595408)
			(xy 437.120671 -360.687701) (xy 437.1213 -360.734102) (xy 437.120676 -360.780504) (xy 437.110985 -360.872802)
			(xy 437.091731 -360.963587) (xy 437.063122 -361.051872) (xy 437.044846 -361.094528) (xy 437.041037 -361.10447)
			(xy 437.041038 -361.125734) (xy 437.044846 -361.135676) (xy 437.063108 -361.178337) (xy 437.091701 -361.266625)
			(xy 437.110959 -361.357408) (xy 437.120671 -361.449701) (xy 437.1213 -361.496102) (xy 437.120789 -361.537215)
			(xy 437.113202 -361.619091) (xy 437.098093 -361.699917) (xy 437.075592 -361.779004) (xy 437.045889 -361.855678)
			(xy 437.009238 -361.929285) (xy 436.965952 -361.999196) (xy 436.916401 -362.064814) (xy 436.861007 -362.125581)
			(xy 436.800242 -362.180978) (xy 436.734625 -362.230532) (xy 436.664716 -362.273821) (xy 436.591111 -362.310474)
			(xy 436.514439 -362.34018) (xy 436.435352 -362.362685) (xy 436.354526 -362.377797) (xy 436.272651 -362.385387)
			(xy 436.231538 -362.385864) (xy 436.185135 -362.385256) (xy 436.092838 -362.37556) (xy 436.002052 -362.356301)
			(xy 435.913768 -362.327688) (xy 435.871112 -362.30941) (xy 435.86117 -362.305604) (xy 435.839906 -362.305604)
			(xy 435.829964 -362.30941) (xy 435.787299 -362.327662) (xy 435.699012 -362.356257) (xy 435.608231 -362.375517)
			(xy 435.515939 -362.385233) (xy 435.469538 -362.385864) (xy 435.428424 -362.385365) (xy 435.346546 -362.377782)
			(xy 435.265717 -362.362675) (xy 435.186627 -362.340175) (xy 435.10995 -362.310473) (xy 435.036341 -362.273823)
			(xy 434.966428 -362.230538) (xy 434.900807 -362.180986) (xy 434.840038 -362.12559) (xy 434.78464 -362.064824)
			(xy 434.735085 -361.999205) (xy 434.691796 -361.929294) (xy 434.655143 -361.855686) (xy 434.625438 -361.779011)
			(xy 434.602934 -361.699922) (xy 434.587824 -361.619094) (xy 434.580237 -361.537216) (xy 434.579776 -361.496102)
			(xy 433.370787 -361.496102) (xy 433.386657 -361.564778) (xy 433.402618 -361.669392) (xy 433.410622 -361.774914)
			(xy 433.411122 -361.827826) (xy 433.410622 -361.880738) (xy 433.402618 -361.98626) (xy 433.386657 -362.090874)
			(xy 433.36283 -362.193981) (xy 433.331273 -362.294992) (xy 433.292168 -362.393326) (xy 433.245737 -362.488421)
			(xy 433.192248 -362.579732) (xy 433.132006 -362.666736) (xy 433.065356 -362.748936) (xy 432.992681 -362.825859)
			(xy 432.914397 -362.897065) (xy 432.830951 -362.962147) (xy 432.742822 -363.020732) (xy 432.650515 -363.072484)
			(xy 432.554558 -363.117106) (xy 432.455501 -363.154344) (xy 432.353912 -363.183984) (xy 432.250372 -363.205855)
			(xy 432.145475 -363.219834) (xy 432.039821 -363.225839) (xy 431.934015 -363.223836) (xy 431.828664 -363.213837)
			(xy 431.724371 -363.195899) (xy 431.621733 -363.170125) (xy 431.521338 -363.136663) (xy 431.423761 -363.095703)
			(xy 431.329562 -363.047481) (xy 431.239279 -362.992274) (xy 431.15343 -362.930396) (xy 431.072507 -362.862203)
			(xy 430.996973 -362.788085) (xy 430.927261 -362.708467) (xy 430.86377 -362.623804) (xy 430.806863 -362.534583)
			(xy 430.756867 -362.441313) (xy 430.714069 -362.344529) (xy 430.678712 -362.244785) (xy 430.651001 -362.142653)
			(xy 430.631092 -362.038718) (xy 430.619102 -361.933575) (xy 430.615097 -361.827826) (xy 260.401302 -361.827826)
			(xy 260.352937 -361.927227) (xy 260.283563 -362.051412) (xy 260.207274 -362.171473) (xy 260.124316 -362.287026)
			(xy 260.034952 -362.3977) (xy 259.939471 -362.503142) (xy 259.838177 -362.603012) (xy 259.731395 -362.696992)
			(xy 259.619467 -362.78478) (xy 259.502751 -362.866096) (xy 259.381623 -362.940678) (xy 259.256469 -363.008287)
			(xy 259.12769 -363.068708) (xy 258.995699 -363.121746) (xy 258.860919 -363.167232) (xy 258.723781 -363.20502)
			(xy 258.584726 -363.234989) (xy 258.444197 -363.257043) (xy 258.302646 -363.271111) (xy 258.160526 -363.277148)
			(xy 258.018291 -363.275135) (xy 257.876399 -363.265078) (xy 257.735303 -363.24701) (xy 257.595454 -363.220989)
			(xy 257.457302 -363.187097) (xy 257.321289 -363.145443) (xy 257.18785 -363.096161) (xy 257.057413 -363.039409)
			(xy 256.930396 -362.975368) (xy 256.807205 -362.904244) (xy 256.688236 -362.826264) (xy 256.573868 -362.741678)
			(xy 256.464469 -362.650758) (xy 256.36039 -362.553794) (xy 256.261962 -362.451097) (xy 256.169503 -362.342995)
			(xy 256.083307 -362.229836) (xy 256.003652 -362.111982) (xy 255.930791 -361.98981) (xy 255.86496 -361.863712)
			(xy 255.806367 -361.734091) (xy 255.755202 -361.601363) (xy 255.711628 -361.465953) (xy 255.675784 -361.328294)
			(xy 255.647786 -361.188828) (xy 255.627723 -361.048002) (xy 255.61566 -360.906266) (xy 255.611635 -360.764074)
			(xy 216.187782 -360.764074) (xy 216.187279 -360.835198) (xy 216.179231 -360.977219) (xy 216.163162 -361.118557)
			(xy 216.139121 -361.258759) (xy 216.107188 -361.397377) (xy 216.067463 -361.533966) (xy 216.020075 -361.668089)
			(xy 215.965174 -361.799316) (xy 215.902937 -361.927227) (xy 215.833563 -362.051412) (xy 215.757274 -362.171473)
			(xy 215.674316 -362.287026) (xy 215.584952 -362.3977) (xy 215.489471 -362.503142) (xy 215.388177 -362.603012)
			(xy 215.281395 -362.696992) (xy 215.169467 -362.78478) (xy 215.052751 -362.866096) (xy 214.931623 -362.940678)
			(xy 214.806469 -363.008287) (xy 214.67769 -363.068708) (xy 214.545699 -363.121746) (xy 214.410919 -363.167232)
			(xy 214.273781 -363.20502) (xy 214.134726 -363.234989) (xy 213.994197 -363.257043) (xy 213.852646 -363.271111)
			(xy 213.710526 -363.277148) (xy 213.568291 -363.275135) (xy 213.426399 -363.265078) (xy 213.285303 -363.24701)
			(xy 213.145454 -363.220989) (xy 213.007302 -363.187097) (xy 212.871289 -363.145443) (xy 212.73785 -363.096161)
			(xy 212.607413 -363.039409) (xy 212.480396 -362.975368) (xy 212.357205 -362.904244) (xy 212.238236 -362.826264)
			(xy 212.123868 -362.741678) (xy 212.014469 -362.650758) (xy 211.91039 -362.553794) (xy 211.811962 -362.451097)
			(xy 211.719503 -362.342995) (xy 211.633307 -362.229836) (xy 211.553652 -362.111982) (xy 211.480791 -361.98981)
			(xy 211.41496 -361.863712) (xy 211.356367 -361.734091) (xy 211.305202 -361.601363) (xy 211.261628 -361.465953)
			(xy 211.225784 -361.328294) (xy 211.197786 -361.188828) (xy 211.177723 -361.048002) (xy 211.16566 -360.906266)
			(xy 211.161635 -360.764074) (xy 187.684417 -360.764074) (xy 187.675402 -360.849986) (xy 187.656207 -360.94064)
			(xy 187.627695 -361.028809) (xy 187.60948 -361.071414) (xy 187.605683 -361.081359) (xy 187.605679 -361.10262)
			(xy 187.60948 -361.112562) (xy 187.627719 -361.155227) (xy 187.656265 -361.243518) (xy 187.67546 -361.334302)
			(xy 187.685094 -361.426592) (xy 187.68568 -361.472988) (xy 187.685095 -361.519384) (xy 187.675451 -361.611672)
			(xy 187.656256 -361.702456) (xy 187.627718 -361.790749) (xy 187.60948 -361.833414) (xy 187.605683 -361.843359)
			(xy 187.605679 -361.86462) (xy 187.60948 -361.874562) (xy 187.627696 -361.917167) (xy 187.656216 -362.005334)
			(xy 187.67541 -362.095988) (xy 187.685071 -362.188148) (xy 187.68568 -362.23448) (xy 187.68568 -362.234988)
			(xy 187.685236 -362.276092) (xy 187.677652 -362.357949) (xy 187.664078 -362.430568) (xy 190.281567 -362.430568)
			(xy 190.285572 -362.324819) (xy 190.297562 -362.219676) (xy 190.317471 -362.115741) (xy 190.345182 -362.013609)
			(xy 190.380539 -361.913865) (xy 190.423337 -361.817081) (xy 190.473333 -361.723811) (xy 190.53024 -361.63459)
			(xy 190.593731 -361.549927) (xy 190.663443 -361.470309) (xy 190.738977 -361.396191) (xy 190.8199 -361.327998)
			(xy 190.905749 -361.26612) (xy 190.996032 -361.210913) (xy 191.090231 -361.162691) (xy 191.187808 -361.121731)
			(xy 191.288203 -361.088269) (xy 191.390841 -361.062495) (xy 191.495134 -361.044557) (xy 191.600485 -361.034558)
			(xy 191.706291 -361.032555) (xy 191.811945 -361.03856) (xy 191.916842 -361.052539) (xy 192.020382 -361.07441)
			(xy 192.121971 -361.10405) (xy 192.221028 -361.141288) (xy 192.316985 -361.18591) (xy 192.409292 -361.237662)
			(xy 192.497421 -361.296247) (xy 192.580867 -361.361329) (xy 192.659151 -361.432535) (xy 192.731826 -361.509458)
			(xy 192.798476 -361.591658) (xy 192.858718 -361.678662) (xy 192.912207 -361.769973) (xy 192.958638 -361.865068)
			(xy 192.997743 -361.963402) (xy 193.0293 -362.064413) (xy 193.053127 -362.16752) (xy 193.069088 -362.272134)
			(xy 193.077092 -362.377656) (xy 193.077592 -362.430568) (xy 193.077092 -362.48348) (xy 193.069088 -362.589002)
			(xy 193.053127 -362.693616) (xy 193.0293 -362.796723) (xy 192.997743 -362.897734) (xy 192.958638 -362.996068)
			(xy 192.912207 -363.091163) (xy 192.858718 -363.182474) (xy 192.798476 -363.269478) (xy 192.731826 -363.351678)
			(xy 192.659151 -363.428601) (xy 192.580867 -363.499807) (xy 192.497421 -363.564889) (xy 192.409292 -363.623474)
			(xy 192.316985 -363.675226) (xy 192.221028 -363.719848) (xy 192.121971 -363.757086) (xy 192.020382 -363.786726)
			(xy 191.916842 -363.808597) (xy 191.811945 -363.822576) (xy 191.706291 -363.828581) (xy 191.600485 -363.826578)
			(xy 191.495134 -363.816579) (xy 191.390841 -363.798641) (xy 191.288203 -363.772867) (xy 191.187808 -363.739405)
			(xy 191.090231 -363.698445) (xy 190.996032 -363.650223) (xy 190.905749 -363.595016) (xy 190.8199 -363.533138)
			(xy 190.738977 -363.464945) (xy 190.663443 -363.390827) (xy 190.593731 -363.311209) (xy 190.53024 -363.226546)
			(xy 190.473333 -363.137325) (xy 190.423337 -363.044055) (xy 190.380539 -362.947271) (xy 190.345182 -362.847527)
			(xy 190.317471 -362.745395) (xy 190.297562 -362.64146) (xy 190.285572 -362.536317) (xy 190.281567 -362.430568)
			(xy 187.664078 -362.430568) (xy 187.662547 -362.438757) (xy 187.64005 -362.517826) (xy 187.610354 -362.594483)
			(xy 187.573711 -362.668072) (xy 187.530434 -362.737966) (xy 187.480892 -362.803569) (xy 187.425509 -362.86432)
			(xy 187.364756 -362.919703) (xy 187.299153 -362.969243) (xy 187.229258 -363.012519) (xy 187.155668 -363.04916)
			(xy 187.079011 -363.078856) (xy 186.999941 -363.101351) (xy 186.919133 -363.116454) (xy 186.837276 -363.124037)
			(xy 186.796172 -363.124496) (xy 186.795664 -363.124496) (xy 186.749333 -363.123866) (xy 186.657176 -363.114202)
			(xy 186.566521 -363.095013) (xy 186.478352 -363.066508) (xy 186.435746 -363.048296) (xy 186.425804 -363.04449)
			(xy 186.40454 -363.04449) (xy 186.394598 -363.048296) (xy 186.351999 -363.066527) (xy 186.26383 -363.095042)
			(xy 186.173173 -363.114232) (xy 186.081013 -363.123889) (xy 186.03468 -363.124496) (xy 186.034172 -363.124496)
			(xy 185.993069 -363.12406) (xy 185.911213 -363.116473) (xy 185.830407 -363.101365) (xy 185.751339 -363.078866)
			(xy 185.674684 -363.049167) (xy 185.601097 -363.012522) (xy 185.531204 -362.969244) (xy 185.465603 -362.919702)
			(xy 185.404853 -362.864319) (xy 185.349472 -362.803566) (xy 185.299933 -362.737963) (xy 185.256658 -362.668068)
			(xy 185.220017 -362.594479) (xy 185.190322 -362.517823) (xy 185.167826 -362.438755) (xy 185.152722 -362.357947)
			(xy 185.145138 -362.276091) (xy 185.144664 -362.234988) (xy 166.497508 -362.234988) (xy 166.497508 -362.396278)
			(xy 166.497022 -362.423547) (xy 166.48926 -362.477531) (xy 166.473895 -362.529861) (xy 166.451238 -362.579471)
			(xy 166.421752 -362.625352) (xy 166.386037 -362.666569) (xy 166.34482 -362.702284) (xy 166.298939 -362.73177)
			(xy 166.249329 -362.754427) (xy 166.196999 -362.769792) (xy 166.143015 -362.777554) (xy 166.088477 -362.777554)
			(xy 166.034493 -362.769792) (xy 165.982163 -362.754427) (xy 165.932553 -362.73177) (xy 165.886672 -362.702284)
			(xy 165.845455 -362.666569) (xy 165.80974 -362.625352) (xy 165.780254 -362.579471) (xy 165.757597 -362.529861)
			(xy 165.742232 -362.477531) (xy 165.73447 -362.423547) (xy 165.733984 -362.396278) (xy 10.079022 -362.396278)
			(xy 10.05934 -362.458146) (xy 10.012689 -362.578565) (xy 9.958714 -362.695884) (xy 9.897619 -362.809658)
			(xy 9.829636 -362.919455) (xy 9.755022 -363.024858) (xy 9.674061 -363.125468) (xy 9.587061 -363.220903)
			(xy 9.49435 -363.310802) (xy 9.39628 -363.394823) (xy 9.293225 -363.472647) (xy 9.185574 -363.543979)
			(xy 9.073735 -363.608549) (xy 8.958134 -363.666111) (xy 8.839209 -363.716448) (xy 8.71741 -363.759368)
			(xy 8.5932 -363.794709) (xy 8.467051 -363.822336) (xy 8.339439 -363.842145) (xy 8.21085 -363.854061)
			(xy 8.081772 -363.858038) (xy 7.952694 -363.854061) (xy 7.824105 -363.842145) (xy 7.696493 -363.822336)
			(xy 7.570344 -363.794709) (xy 7.446134 -363.759368) (xy 7.324335 -363.716448) (xy 7.20541 -363.666111)
			(xy 7.089809 -363.608549) (xy 6.97797 -363.543979) (xy 6.870319 -363.472647) (xy 6.767264 -363.394823)
			(xy 6.669194 -363.310802) (xy 6.576483 -363.220903) (xy 6.489483 -363.125468) (xy 6.408522 -363.024858)
			(xy 6.333908 -362.919455) (xy 6.265925 -362.809658) (xy 6.20483 -362.695884) (xy 6.150855 -362.578565)
			(xy 6.104204 -362.458146) (xy 6.065055 -362.335083) (xy 6.033556 -362.209844) (xy 6.009827 -362.082903)
			(xy 5.993957 -361.954743) (xy 5.986007 -361.825848) (xy 2.509012 -361.825848) (xy 2.509012 -369.062565)
			(xy 44.335754 -369.062565) (xy 44.335754 -369.008035) (xy 44.343514 -368.95406) (xy 44.358876 -368.901738)
			(xy 44.381527 -368.852135) (xy 44.411006 -368.806259) (xy 44.446714 -368.765046) (xy 44.487923 -368.729334)
			(xy 44.533794 -368.699849) (xy 44.583395 -368.677192) (xy 44.635715 -368.661824) (xy 44.689689 -368.654057)
			(xy 44.716954 -368.653568) (xy 45.580554 -368.653568) (xy 45.607829 -368.653968) (xy 45.661825 -368.661726)
			(xy 45.714168 -368.677089) (xy 45.763791 -368.699746) (xy 45.809684 -368.729235) (xy 45.850912 -368.764955)
			(xy 45.886638 -368.80618) (xy 45.916132 -368.852069) (xy 45.938795 -368.901689) (xy 45.954164 -368.95403)
			(xy 45.961928 -369.008025) (xy 45.961928 -369.062565) (xy 51.142954 -369.062565) (xy 51.142954 -369.008035)
			(xy 51.150714 -368.95406) (xy 51.166076 -368.901738) (xy 51.188727 -368.852135) (xy 51.218206 -368.806259)
			(xy 51.253914 -368.765046) (xy 51.295123 -368.729334) (xy 51.340994 -368.699849) (xy 51.390595 -368.677192)
			(xy 51.442915 -368.661824) (xy 51.496889 -368.654057) (xy 51.524154 -368.653568) (xy 52.387754 -368.653568)
			(xy 52.415029 -368.653968) (xy 52.469025 -368.661726) (xy 52.521368 -368.677089) (xy 52.570991 -368.699746)
			(xy 52.616884 -368.729235) (xy 52.658112 -368.764955) (xy 52.693838 -368.80618) (xy 52.723332 -368.852069)
			(xy 52.745995 -368.901689) (xy 52.761364 -368.95403) (xy 52.769128 -369.008025) (xy 52.769128 -369.062565)
			(xy 57.950154 -369.062565) (xy 57.950154 -369.008035) (xy 57.957914 -368.95406) (xy 57.973276 -368.901738)
			(xy 57.995927 -368.852135) (xy 58.025406 -368.806259) (xy 58.061114 -368.765046) (xy 58.102323 -368.729334)
			(xy 58.148194 -368.699849) (xy 58.197795 -368.677192) (xy 58.250115 -368.661824) (xy 58.304089 -368.654057)
			(xy 58.331354 -368.653568) (xy 59.194954 -368.653568) (xy 59.222229 -368.653968) (xy 59.276225 -368.661726)
			(xy 59.328568 -368.677089) (xy 59.378191 -368.699746) (xy 59.424084 -368.729235) (xy 59.465312 -368.764955)
			(xy 59.501038 -368.80618) (xy 59.530532 -368.852069) (xy 59.553195 -368.901689) (xy 59.568564 -368.95403)
			(xy 59.576328 -369.008025) (xy 59.576328 -369.062565) (xy 64.757354 -369.062565) (xy 64.757354 -369.008035)
			(xy 64.765114 -368.95406) (xy 64.780476 -368.901738) (xy 64.803127 -368.852135) (xy 64.832606 -368.806259)
			(xy 64.868314 -368.765046) (xy 64.909523 -368.729334) (xy 64.955394 -368.699849) (xy 65.004995 -368.677192)
			(xy 65.057315 -368.661824) (xy 65.111289 -368.654057) (xy 65.138554 -368.653568) (xy 66.002154 -368.653568)
			(xy 66.029429 -368.653968) (xy 66.083425 -368.661726) (xy 66.135768 -368.677089) (xy 66.185391 -368.699746)
			(xy 66.231284 -368.729235) (xy 66.272512 -368.764955) (xy 66.308238 -368.80618) (xy 66.337732 -368.852069)
			(xy 66.360395 -368.901689) (xy 66.375764 -368.95403) (xy 66.383528 -369.008025) (xy 66.383528 -369.062565)
			(xy 68.160954 -369.062565) (xy 68.160954 -369.008035) (xy 68.168714 -368.95406) (xy 68.184076 -368.901738)
			(xy 68.206727 -368.852135) (xy 68.236206 -368.806259) (xy 68.271914 -368.765046) (xy 68.313123 -368.729334)
			(xy 68.358994 -368.699849) (xy 68.408595 -368.677192) (xy 68.460915 -368.661824) (xy 68.514889 -368.654057)
			(xy 68.542154 -368.653568) (xy 69.405754 -368.653568) (xy 69.433029 -368.653968) (xy 69.487025 -368.661726)
			(xy 69.539368 -368.677089) (xy 69.588991 -368.699746) (xy 69.634884 -368.729235) (xy 69.676112 -368.764955)
			(xy 69.711838 -368.80618) (xy 69.741332 -368.852069) (xy 69.763995 -368.901689) (xy 69.779364 -368.95403)
			(xy 69.787128 -369.008025) (xy 69.787128 -369.062569) (xy 76.863431 -369.062569) (xy 76.863431 -369.008031)
			(xy 76.871193 -368.954048) (xy 76.886558 -368.90172) (xy 76.909214 -368.85211) (xy 76.9387 -368.80623)
			(xy 76.974414 -368.765013) (xy 77.015632 -368.729298) (xy 77.061512 -368.699813) (xy 77.111121 -368.677157)
			(xy 77.16345 -368.661793) (xy 77.217433 -368.654031) (xy 77.244702 -368.653568) (xy 78.108302 -368.653568)
			(xy 78.135573 -368.653995) (xy 78.189561 -368.661757) (xy 78.241894 -368.677124) (xy 78.291508 -368.699782)
			(xy 78.337393 -368.72927) (xy 78.378613 -368.764988) (xy 78.414331 -368.806209) (xy 78.443819 -368.852093)
			(xy 78.466477 -368.901707) (xy 78.481843 -368.954041) (xy 78.489606 -369.008029) (xy 78.489606 -369.062569)
			(xy 83.670631 -369.062569) (xy 83.670631 -369.008031) (xy 83.678393 -368.954048) (xy 83.693758 -368.90172)
			(xy 83.716414 -368.85211) (xy 83.7459 -368.80623) (xy 83.781614 -368.765013) (xy 83.822832 -368.729298)
			(xy 83.868712 -368.699813) (xy 83.918321 -368.677157) (xy 83.97065 -368.661793) (xy 84.024633 -368.654031)
			(xy 84.051902 -368.653568) (xy 84.915502 -368.653568) (xy 84.942773 -368.653995) (xy 84.996761 -368.661757)
			(xy 85.049094 -368.677124) (xy 85.098708 -368.699782) (xy 85.144593 -368.72927) (xy 85.185813 -368.764988)
			(xy 85.221531 -368.806209) (xy 85.251019 -368.852093) (xy 85.273677 -368.901707) (xy 85.289043 -368.954041)
			(xy 85.296806 -369.008029) (xy 85.296806 -369.062569) (xy 90.477831 -369.062569) (xy 90.477831 -369.008031)
			(xy 90.485593 -368.954048) (xy 90.500958 -368.90172) (xy 90.523614 -368.85211) (xy 90.5531 -368.80623)
			(xy 90.588814 -368.765013) (xy 90.630032 -368.729298) (xy 90.675912 -368.699813) (xy 90.725521 -368.677157)
			(xy 90.77785 -368.661793) (xy 90.831833 -368.654031) (xy 90.859102 -368.653568) (xy 91.722702 -368.653568)
			(xy 91.749973 -368.653995) (xy 91.803961 -368.661757) (xy 91.856294 -368.677124) (xy 91.905908 -368.699782)
			(xy 91.951793 -368.72927) (xy 91.993013 -368.764988) (xy 92.028731 -368.806209) (xy 92.058219 -368.852093)
			(xy 92.080877 -368.901707) (xy 92.096243 -368.954041) (xy 92.104006 -369.008029) (xy 92.104006 -369.062569)
			(xy 97.285031 -369.062569) (xy 97.285031 -369.008031) (xy 97.292793 -368.954048) (xy 97.308158 -368.90172)
			(xy 97.330814 -368.85211) (xy 97.3603 -368.80623) (xy 97.396014 -368.765013) (xy 97.437232 -368.729298)
			(xy 97.483112 -368.699813) (xy 97.532721 -368.677157) (xy 97.58505 -368.661793) (xy 97.639033 -368.654031)
			(xy 97.666302 -368.653568) (xy 98.529902 -368.653568) (xy 98.557173 -368.653995) (xy 98.611161 -368.661757)
			(xy 98.663494 -368.677124) (xy 98.713108 -368.699782) (xy 98.758993 -368.72927) (xy 98.800213 -368.764988)
			(xy 98.835931 -368.806209) (xy 98.865419 -368.852093) (xy 98.888077 -368.901707) (xy 98.903443 -368.954041)
			(xy 98.911206 -369.008029) (xy 98.911206 -369.062569) (xy 100.688631 -369.062569) (xy 100.688631 -369.008031)
			(xy 100.696393 -368.954048) (xy 100.711758 -368.90172) (xy 100.734414 -368.85211) (xy 100.7639 -368.80623)
			(xy 100.799614 -368.765013) (xy 100.840832 -368.729298) (xy 100.886712 -368.699813) (xy 100.936321 -368.677157)
			(xy 100.98865 -368.661793) (xy 101.042633 -368.654031) (xy 101.069902 -368.653568) (xy 101.933502 -368.653568)
			(xy 101.960773 -368.653995) (xy 102.014761 -368.661757) (xy 102.067094 -368.677124) (xy 102.116708 -368.699782)
			(xy 102.162593 -368.72927) (xy 102.203813 -368.764988) (xy 102.239531 -368.806209) (xy 102.269019 -368.852093)
			(xy 102.291677 -368.901707) (xy 102.307043 -368.954041) (xy 102.314806 -369.008029) (xy 102.314806 -369.062567)
			(xy 111.435654 -369.062567) (xy 111.435654 -369.008033) (xy 111.443415 -368.954054) (xy 111.458779 -368.901729)
			(xy 111.481433 -368.852123) (xy 111.510917 -368.806246) (xy 111.546629 -368.765031) (xy 111.587842 -368.729319)
			(xy 111.633719 -368.699835) (xy 111.683325 -368.677181) (xy 111.73565 -368.661816) (xy 111.789629 -368.654055)
			(xy 111.816896 -368.653568) (xy 112.680496 -368.653568) (xy 112.707769 -368.653971) (xy 112.761761 -368.661734)
			(xy 112.814098 -368.677101) (xy 112.863716 -368.69976) (xy 112.909603 -368.72925) (xy 112.950827 -368.76497)
			(xy 112.986548 -368.806193) (xy 113.016038 -368.852081) (xy 113.038698 -368.901698) (xy 113.054066 -368.954035)
			(xy 113.061828 -369.008027) (xy 113.061828 -369.062567) (xy 118.242854 -369.062567) (xy 118.242854 -369.008033)
			(xy 118.250615 -368.954054) (xy 118.265979 -368.901729) (xy 118.288633 -368.852123) (xy 118.318117 -368.806246)
			(xy 118.353829 -368.765031) (xy 118.395042 -368.729319) (xy 118.440919 -368.699835) (xy 118.490525 -368.677181)
			(xy 118.54285 -368.661816) (xy 118.596829 -368.654055) (xy 118.624096 -368.653568) (xy 119.487696 -368.653568)
			(xy 119.514969 -368.653971) (xy 119.568961 -368.661734) (xy 119.621298 -368.677101) (xy 119.670916 -368.69976)
			(xy 119.716803 -368.72925) (xy 119.758027 -368.76497) (xy 119.793748 -368.806193) (xy 119.823238 -368.852081)
			(xy 119.845898 -368.901698) (xy 119.861266 -368.954035) (xy 119.869028 -369.008027) (xy 119.869028 -369.062567)
			(xy 125.050054 -369.062567) (xy 125.050054 -369.008033) (xy 125.057815 -368.954054) (xy 125.073179 -368.901729)
			(xy 125.095833 -368.852123) (xy 125.125317 -368.806246) (xy 125.161029 -368.765031) (xy 125.202242 -368.729319)
			(xy 125.248119 -368.699835) (xy 125.297725 -368.677181) (xy 125.35005 -368.661816) (xy 125.404029 -368.654055)
			(xy 125.431296 -368.653568) (xy 126.294896 -368.653568) (xy 126.322169 -368.653971) (xy 126.376161 -368.661734)
			(xy 126.428498 -368.677101) (xy 126.478116 -368.69976) (xy 126.524003 -368.72925) (xy 126.565227 -368.76497)
			(xy 126.600948 -368.806193) (xy 126.630438 -368.852081) (xy 126.653098 -368.901698) (xy 126.668466 -368.954035)
			(xy 126.676228 -369.008027) (xy 126.676228 -369.062567) (xy 131.857254 -369.062567) (xy 131.857254 -369.008033)
			(xy 131.865015 -368.954054) (xy 131.880379 -368.901729) (xy 131.903033 -368.852123) (xy 131.932517 -368.806246)
			(xy 131.968229 -368.765031) (xy 132.009442 -368.729319) (xy 132.055319 -368.699835) (xy 132.104925 -368.677181)
			(xy 132.15725 -368.661816) (xy 132.211229 -368.654055) (xy 132.238496 -368.653568) (xy 133.102096 -368.653568)
			(xy 133.129369 -368.653971) (xy 133.183361 -368.661734) (xy 133.235698 -368.677101) (xy 133.285316 -368.69976)
			(xy 133.331203 -368.72925) (xy 133.372427 -368.76497) (xy 133.408148 -368.806193) (xy 133.437638 -368.852081)
			(xy 133.460298 -368.901698) (xy 133.475666 -368.954035) (xy 133.483428 -369.008027) (xy 133.483428 -369.062567)
			(xy 135.260854 -369.062567) (xy 135.260854 -369.008033) (xy 135.268615 -368.954054) (xy 135.283979 -368.901729)
			(xy 135.306633 -368.852123) (xy 135.336117 -368.806246) (xy 135.371829 -368.765031) (xy 135.413042 -368.729319)
			(xy 135.458919 -368.699835) (xy 135.508525 -368.677181) (xy 135.56085 -368.661816) (xy 135.614829 -368.654055)
			(xy 135.642096 -368.653568) (xy 136.505696 -368.653568) (xy 136.532969 -368.653971) (xy 136.586961 -368.661734)
			(xy 136.639298 -368.677101) (xy 136.688916 -368.69976) (xy 136.734803 -368.72925) (xy 136.776027 -368.76497)
			(xy 136.811748 -368.806193) (xy 136.841238 -368.852081) (xy 136.863898 -368.901698) (xy 136.879266 -368.954035)
			(xy 136.887028 -369.008027) (xy 136.887028 -369.062573) (xy 136.879266 -369.116565) (xy 136.863898 -369.168902)
			(xy 136.841238 -369.218519) (xy 136.811748 -369.264407) (xy 136.776027 -369.30563) (xy 136.734803 -369.34135)
			(xy 136.688916 -369.37084) (xy 136.639298 -369.393499) (xy 136.586961 -369.408866) (xy 136.532969 -369.416629)
			(xy 136.505696 -369.417092) (xy 135.642096 -369.417092) (xy 135.614829 -369.416545) (xy 135.56085 -369.408784)
			(xy 135.508525 -369.393419) (xy 135.458919 -369.370765) (xy 135.413042 -369.341281) (xy 135.371829 -369.305569)
			(xy 135.336117 -369.264354) (xy 135.306633 -369.218477) (xy 135.283979 -369.168871) (xy 135.268615 -369.116546)
			(xy 135.260854 -369.062567) (xy 133.483428 -369.062567) (xy 133.483428 -369.062573) (xy 133.475666 -369.116565)
			(xy 133.460298 -369.168902) (xy 133.437638 -369.218519) (xy 133.408148 -369.264407) (xy 133.372427 -369.30563)
			(xy 133.331203 -369.34135) (xy 133.285316 -369.37084) (xy 133.235698 -369.393499) (xy 133.183361 -369.408866)
			(xy 133.129369 -369.416629) (xy 133.102096 -369.417092) (xy 132.238496 -369.417092) (xy 132.211229 -369.416545)
			(xy 132.15725 -369.408784) (xy 132.104925 -369.393419) (xy 132.055319 -369.370765) (xy 132.009442 -369.341281)
			(xy 131.968229 -369.305569) (xy 131.932517 -369.264354) (xy 131.903033 -369.218477) (xy 131.880379 -369.168871)
			(xy 131.865015 -369.116546) (xy 131.857254 -369.062567) (xy 126.676228 -369.062567) (xy 126.676228 -369.062573)
			(xy 126.668466 -369.116565) (xy 126.653098 -369.168902) (xy 126.630438 -369.218519) (xy 126.600948 -369.264407)
			(xy 126.565227 -369.30563) (xy 126.524003 -369.34135) (xy 126.478116 -369.37084) (xy 126.428498 -369.393499)
			(xy 126.376161 -369.408866) (xy 126.322169 -369.416629) (xy 126.294896 -369.417092) (xy 125.431296 -369.417092)
			(xy 125.404029 -369.416545) (xy 125.35005 -369.408784) (xy 125.297725 -369.393419) (xy 125.248119 -369.370765)
			(xy 125.202242 -369.341281) (xy 125.161029 -369.305569) (xy 125.125317 -369.264354) (xy 125.095833 -369.218477)
			(xy 125.073179 -369.168871) (xy 125.057815 -369.116546) (xy 125.050054 -369.062567) (xy 119.869028 -369.062567)
			(xy 119.869028 -369.062573) (xy 119.861266 -369.116565) (xy 119.845898 -369.168902) (xy 119.823238 -369.218519)
			(xy 119.793748 -369.264407) (xy 119.758027 -369.30563) (xy 119.716803 -369.34135) (xy 119.670916 -369.37084)
			(xy 119.621298 -369.393499) (xy 119.568961 -369.408866) (xy 119.514969 -369.416629) (xy 119.487696 -369.417092)
			(xy 118.624096 -369.417092) (xy 118.596829 -369.416545) (xy 118.54285 -369.408784) (xy 118.490525 -369.393419)
			(xy 118.440919 -369.370765) (xy 118.395042 -369.341281) (xy 118.353829 -369.305569) (xy 118.318117 -369.264354)
			(xy 118.288633 -369.218477) (xy 118.265979 -369.168871) (xy 118.250615 -369.116546) (xy 118.242854 -369.062567)
			(xy 113.061828 -369.062567) (xy 113.061828 -369.062573) (xy 113.054066 -369.116565) (xy 113.038698 -369.168902)
			(xy 113.016038 -369.218519) (xy 112.986548 -369.264407) (xy 112.950827 -369.30563) (xy 112.909603 -369.34135)
			(xy 112.863716 -369.37084) (xy 112.814098 -369.393499) (xy 112.761761 -369.408866) (xy 112.707769 -369.416629)
			(xy 112.680496 -369.417092) (xy 111.816896 -369.417092) (xy 111.789629 -369.416545) (xy 111.73565 -369.408784)
			(xy 111.683325 -369.393419) (xy 111.633719 -369.370765) (xy 111.587842 -369.341281) (xy 111.546629 -369.305569)
			(xy 111.510917 -369.264354) (xy 111.481433 -369.218477) (xy 111.458779 -369.168871) (xy 111.443415 -369.116546)
			(xy 111.435654 -369.062567) (xy 102.314806 -369.062567) (xy 102.314806 -369.062571) (xy 102.307043 -369.116559)
			(xy 102.291677 -369.168893) (xy 102.269019 -369.218507) (xy 102.239531 -369.264391) (xy 102.203813 -369.305612)
			(xy 102.162593 -369.34133) (xy 102.116708 -369.370818) (xy 102.067094 -369.393476) (xy 102.014761 -369.408843)
			(xy 101.960773 -369.416605) (xy 101.933502 -369.417092) (xy 101.069902 -369.417092) (xy 101.042633 -369.416569)
			(xy 100.98865 -369.408807) (xy 100.936321 -369.393443) (xy 100.886712 -369.370787) (xy 100.840832 -369.341302)
			(xy 100.799614 -369.305587) (xy 100.7639 -369.26437) (xy 100.734414 -369.21849) (xy 100.711758 -369.16888)
			(xy 100.696393 -369.116552) (xy 100.688631 -369.062569) (xy 98.911206 -369.062569) (xy 98.911206 -369.062571)
			(xy 98.903443 -369.116559) (xy 98.888077 -369.168893) (xy 98.865419 -369.218507) (xy 98.835931 -369.264391)
			(xy 98.800213 -369.305612) (xy 98.758993 -369.34133) (xy 98.713108 -369.370818) (xy 98.663494 -369.393476)
			(xy 98.611161 -369.408843) (xy 98.557173 -369.416605) (xy 98.529902 -369.417092) (xy 97.666302 -369.417092)
			(xy 97.639033 -369.416569) (xy 97.58505 -369.408807) (xy 97.532721 -369.393443) (xy 97.483112 -369.370787)
			(xy 97.437232 -369.341302) (xy 97.396014 -369.305587) (xy 97.3603 -369.26437) (xy 97.330814 -369.21849)
			(xy 97.308158 -369.16888) (xy 97.292793 -369.116552) (xy 97.285031 -369.062569) (xy 92.104006 -369.062569)
			(xy 92.104006 -369.062571) (xy 92.096243 -369.116559) (xy 92.080877 -369.168893) (xy 92.058219 -369.218507)
			(xy 92.028731 -369.264391) (xy 91.993013 -369.305612) (xy 91.951793 -369.34133) (xy 91.905908 -369.370818)
			(xy 91.856294 -369.393476) (xy 91.803961 -369.408843) (xy 91.749973 -369.416605) (xy 91.722702 -369.417092)
			(xy 90.859102 -369.417092) (xy 90.831833 -369.416569) (xy 90.77785 -369.408807) (xy 90.725521 -369.393443)
			(xy 90.675912 -369.370787) (xy 90.630032 -369.341302) (xy 90.588814 -369.305587) (xy 90.5531 -369.26437)
			(xy 90.523614 -369.21849) (xy 90.500958 -369.16888) (xy 90.485593 -369.116552) (xy 90.477831 -369.062569)
			(xy 85.296806 -369.062569) (xy 85.296806 -369.062571) (xy 85.289043 -369.116559) (xy 85.273677 -369.168893)
			(xy 85.251019 -369.218507) (xy 85.221531 -369.264391) (xy 85.185813 -369.305612) (xy 85.144593 -369.34133)
			(xy 85.098708 -369.370818) (xy 85.049094 -369.393476) (xy 84.996761 -369.408843) (xy 84.942773 -369.416605)
			(xy 84.915502 -369.417092) (xy 84.051902 -369.417092) (xy 84.024633 -369.416569) (xy 83.97065 -369.408807)
			(xy 83.918321 -369.393443) (xy 83.868712 -369.370787) (xy 83.822832 -369.341302) (xy 83.781614 -369.305587)
			(xy 83.7459 -369.26437) (xy 83.716414 -369.21849) (xy 83.693758 -369.16888) (xy 83.678393 -369.116552)
			(xy 83.670631 -369.062569) (xy 78.489606 -369.062569) (xy 78.489606 -369.062571) (xy 78.481843 -369.116559)
			(xy 78.466477 -369.168893) (xy 78.443819 -369.218507) (xy 78.414331 -369.264391) (xy 78.378613 -369.305612)
			(xy 78.337393 -369.34133) (xy 78.291508 -369.370818) (xy 78.241894 -369.393476) (xy 78.189561 -369.408843)
			(xy 78.135573 -369.416605) (xy 78.108302 -369.417092) (xy 77.244702 -369.417092) (xy 77.217433 -369.416569)
			(xy 77.16345 -369.408807) (xy 77.111121 -369.393443) (xy 77.061512 -369.370787) (xy 77.015632 -369.341302)
			(xy 76.974414 -369.305587) (xy 76.9387 -369.26437) (xy 76.909214 -369.21849) (xy 76.886558 -369.16888)
			(xy 76.871193 -369.116552) (xy 76.863431 -369.062569) (xy 69.787128 -369.062569) (xy 69.787128 -369.062575)
			(xy 69.779364 -369.11657) (xy 69.763995 -369.168911) (xy 69.741332 -369.218531) (xy 69.711838 -369.26442)
			(xy 69.676112 -369.305645) (xy 69.634884 -369.341365) (xy 69.588991 -369.370854) (xy 69.539368 -369.393511)
			(xy 69.487025 -369.408874) (xy 69.433029 -369.416632) (xy 69.405754 -369.417092) (xy 68.542154 -369.417092)
			(xy 68.514889 -369.416543) (xy 68.460915 -369.408776) (xy 68.408595 -369.393408) (xy 68.358994 -369.370751)
			(xy 68.313123 -369.341266) (xy 68.271914 -369.305554) (xy 68.236206 -369.264341) (xy 68.206727 -369.218465)
			(xy 68.184076 -369.168862) (xy 68.168714 -369.11654) (xy 68.160954 -369.062565) (xy 66.383528 -369.062565)
			(xy 66.383528 -369.062575) (xy 66.375764 -369.11657) (xy 66.360395 -369.168911) (xy 66.337732 -369.218531)
			(xy 66.308238 -369.26442) (xy 66.272512 -369.305645) (xy 66.231284 -369.341365) (xy 66.185391 -369.370854)
			(xy 66.135768 -369.393511) (xy 66.083425 -369.408874) (xy 66.029429 -369.416632) (xy 66.002154 -369.417092)
			(xy 65.138554 -369.417092) (xy 65.111289 -369.416543) (xy 65.057315 -369.408776) (xy 65.004995 -369.393408)
			(xy 64.955394 -369.370751) (xy 64.909523 -369.341266) (xy 64.868314 -369.305554) (xy 64.832606 -369.264341)
			(xy 64.803127 -369.218465) (xy 64.780476 -369.168862) (xy 64.765114 -369.11654) (xy 64.757354 -369.062565)
			(xy 59.576328 -369.062565) (xy 59.576328 -369.062575) (xy 59.568564 -369.11657) (xy 59.553195 -369.168911)
			(xy 59.530532 -369.218531) (xy 59.501038 -369.26442) (xy 59.465312 -369.305645) (xy 59.424084 -369.341365)
			(xy 59.378191 -369.370854) (xy 59.328568 -369.393511) (xy 59.276225 -369.408874) (xy 59.222229 -369.416632)
			(xy 59.194954 -369.417092) (xy 58.331354 -369.417092) (xy 58.304089 -369.416543) (xy 58.250115 -369.408776)
			(xy 58.197795 -369.393408) (xy 58.148194 -369.370751) (xy 58.102323 -369.341266) (xy 58.061114 -369.305554)
			(xy 58.025406 -369.264341) (xy 57.995927 -369.218465) (xy 57.973276 -369.168862) (xy 57.957914 -369.11654)
			(xy 57.950154 -369.062565) (xy 52.769128 -369.062565) (xy 52.769128 -369.062575) (xy 52.761364 -369.11657)
			(xy 52.745995 -369.168911) (xy 52.723332 -369.218531) (xy 52.693838 -369.26442) (xy 52.658112 -369.305645)
			(xy 52.616884 -369.341365) (xy 52.570991 -369.370854) (xy 52.521368 -369.393511) (xy 52.469025 -369.408874)
			(xy 52.415029 -369.416632) (xy 52.387754 -369.417092) (xy 51.524154 -369.417092) (xy 51.496889 -369.416543)
			(xy 51.442915 -369.408776) (xy 51.390595 -369.393408) (xy 51.340994 -369.370751) (xy 51.295123 -369.341266)
			(xy 51.253914 -369.305554) (xy 51.218206 -369.264341) (xy 51.188727 -369.218465) (xy 51.166076 -369.168862)
			(xy 51.150714 -369.11654) (xy 51.142954 -369.062565) (xy 45.961928 -369.062565) (xy 45.961928 -369.062575)
			(xy 45.954164 -369.11657) (xy 45.938795 -369.168911) (xy 45.916132 -369.218531) (xy 45.886638 -369.26442)
			(xy 45.850912 -369.305645) (xy 45.809684 -369.341365) (xy 45.763791 -369.370854) (xy 45.714168 -369.393511)
			(xy 45.661825 -369.408874) (xy 45.607829 -369.416632) (xy 45.580554 -369.417092) (xy 44.716954 -369.417092)
			(xy 44.689689 -369.416543) (xy 44.635715 -369.408776) (xy 44.583395 -369.393408) (xy 44.533794 -369.370751)
			(xy 44.487923 -369.341266) (xy 44.446714 -369.305554) (xy 44.411006 -369.264341) (xy 44.381527 -369.218465)
			(xy 44.358876 -369.168862) (xy 44.343514 -369.11654) (xy 44.335754 -369.062565) (xy 2.509012 -369.062565)
			(xy 2.509012 -370.206778) (xy 138.3665 -370.206778) (xy 138.3665 -369.343178) (xy 138.366986 -369.315909)
			(xy 138.374748 -369.261925) (xy 138.390113 -369.209595) (xy 138.41277 -369.159985) (xy 138.442256 -369.114104)
			(xy 138.477971 -369.072887) (xy 138.519188 -369.037172) (xy 138.565069 -369.007686) (xy 138.614679 -368.985029)
			(xy 138.667009 -368.969664) (xy 138.720993 -368.961902) (xy 138.775531 -368.961902) (xy 138.829515 -368.969664)
			(xy 138.881845 -368.985029) (xy 138.931455 -369.007686) (xy 138.977336 -369.037172) (xy 139.006648 -369.062571)
			(xy 143.963332 -369.062571) (xy 143.963332 -369.008029) (xy 143.971094 -368.954043) (xy 143.986461 -368.901711)
			(xy 144.009121 -368.852098) (xy 144.03861 -368.806216) (xy 144.074329 -368.764998) (xy 144.115551 -368.729284)
			(xy 144.161437 -368.699799) (xy 144.211052 -368.677146) (xy 144.263386 -368.661785) (xy 144.317373 -368.654028)
			(xy 144.344644 -368.653568) (xy 145.208244 -368.653568) (xy 145.235513 -368.653998) (xy 145.289497 -368.661765)
			(xy 145.341825 -368.677135) (xy 145.391433 -368.699796) (xy 145.437312 -368.729285) (xy 145.478528 -368.765003)
			(xy 145.514241 -368.806223) (xy 145.543725 -368.852105) (xy 145.56638 -368.901716) (xy 145.581744 -368.954047)
			(xy 145.589506 -369.00803) (xy 145.589506 -369.06257) (xy 145.589506 -369.062571) (xy 150.770532 -369.062571)
			(xy 150.770532 -369.008029) (xy 150.778294 -368.954043) (xy 150.793661 -368.901711) (xy 150.816321 -368.852098)
			(xy 150.84581 -368.806216) (xy 150.881529 -368.764998) (xy 150.922751 -368.729284) (xy 150.968637 -368.699799)
			(xy 151.018252 -368.677146) (xy 151.070586 -368.661785) (xy 151.124573 -368.654028) (xy 151.151844 -368.653568)
			(xy 152.015444 -368.653568) (xy 152.042713 -368.653998) (xy 152.096697 -368.661765) (xy 152.149025 -368.677135)
			(xy 152.198633 -368.699796) (xy 152.244512 -368.729285) (xy 152.285728 -368.765003) (xy 152.321441 -368.806223)
			(xy 152.350925 -368.852105) (xy 152.37358 -368.901716) (xy 152.388944 -368.954047) (xy 152.396706 -369.00803)
			(xy 152.396706 -369.06257) (xy 152.396706 -369.062571) (xy 157.577732 -369.062571) (xy 157.577732 -369.008029)
			(xy 157.585494 -368.954043) (xy 157.600861 -368.901711) (xy 157.623521 -368.852098) (xy 157.65301 -368.806216)
			(xy 157.688729 -368.764998) (xy 157.729951 -368.729284) (xy 157.775837 -368.699799) (xy 157.825452 -368.677146)
			(xy 157.877786 -368.661785) (xy 157.931773 -368.654028) (xy 157.959044 -368.653568) (xy 158.822644 -368.653568)
			(xy 158.849913 -368.653998) (xy 158.903897 -368.661765) (xy 158.956225 -368.677135) (xy 159.005833 -368.699796)
			(xy 159.051712 -368.729285) (xy 159.092928 -368.765003) (xy 159.128641 -368.806223) (xy 159.158125 -368.852105)
			(xy 159.18078 -368.901716) (xy 159.196144 -368.954047) (xy 159.203906 -369.00803) (xy 159.203906 -369.06257)
			(xy 159.203906 -369.062571) (xy 164.384932 -369.062571) (xy 164.384932 -369.008029) (xy 164.392694 -368.954043)
			(xy 164.408061 -368.901711) (xy 164.430721 -368.852098) (xy 164.46021 -368.806216) (xy 164.495929 -368.764998)
			(xy 164.537151 -368.729284) (xy 164.583037 -368.699799) (xy 164.632652 -368.677146) (xy 164.684986 -368.661785)
			(xy 164.738973 -368.654028) (xy 164.766244 -368.653568) (xy 165.629844 -368.653568) (xy 165.657113 -368.653998)
			(xy 165.711097 -368.661765) (xy 165.763425 -368.677135) (xy 165.813033 -368.699796) (xy 165.858912 -368.729285)
			(xy 165.900128 -368.765003) (xy 165.935841 -368.806223) (xy 165.965325 -368.852105) (xy 165.98798 -368.901716)
			(xy 166.003344 -368.954047) (xy 166.011106 -369.00803) (xy 166.011106 -369.06257) (xy 166.011106 -369.062571)
			(xy 167.788532 -369.062571) (xy 167.788532 -369.008029) (xy 167.796294 -368.954043) (xy 167.811661 -368.901711)
			(xy 167.834321 -368.852098) (xy 167.86381 -368.806216) (xy 167.899529 -368.764998) (xy 167.940751 -368.729284)
			(xy 167.986637 -368.699799) (xy 168.036252 -368.677146) (xy 168.088586 -368.661785) (xy 168.142573 -368.654028)
			(xy 168.169844 -368.653568) (xy 169.033444 -368.653568) (xy 169.060713 -368.653998) (xy 169.114697 -368.661765)
			(xy 169.167025 -368.677135) (xy 169.216633 -368.699796) (xy 169.262512 -368.729285) (xy 169.303728 -368.765003)
			(xy 169.339441 -368.806223) (xy 169.368925 -368.852105) (xy 169.39158 -368.901716) (xy 169.406944 -368.954047)
			(xy 169.414706 -369.00803) (xy 169.414706 -369.06257) (xy 169.406944 -369.116553) (xy 169.39158 -369.168884)
			(xy 169.368925 -369.218495) (xy 169.339441 -369.264377) (xy 169.303728 -369.305597) (xy 169.262512 -369.341315)
			(xy 169.216633 -369.370804) (xy 169.167025 -369.393465) (xy 169.114697 -369.408835) (xy 169.060713 -369.416602)
			(xy 169.033444 -369.417092) (xy 168.169844 -369.417092) (xy 168.142573 -369.416572) (xy 168.088586 -369.408815)
			(xy 168.036252 -369.393454) (xy 167.986637 -369.370801) (xy 167.940751 -369.341316) (xy 167.899529 -369.305602)
			(xy 167.86381 -369.264384) (xy 167.834321 -369.218502) (xy 167.811661 -369.168889) (xy 167.796294 -369.116557)
			(xy 167.788532 -369.062571) (xy 166.011106 -369.062571) (xy 166.003344 -369.116553) (xy 165.98798 -369.168884)
			(xy 165.965325 -369.218495) (xy 165.935841 -369.264377) (xy 165.900128 -369.305597) (xy 165.858912 -369.341315)
			(xy 165.813033 -369.370804) (xy 165.763425 -369.393465) (xy 165.711097 -369.408835) (xy 165.657113 -369.416602)
			(xy 165.629844 -369.417092) (xy 164.766244 -369.417092) (xy 164.738973 -369.416572) (xy 164.684986 -369.408815)
			(xy 164.632652 -369.393454) (xy 164.583037 -369.370801) (xy 164.537151 -369.341316) (xy 164.495929 -369.305602)
			(xy 164.46021 -369.264384) (xy 164.430721 -369.218502) (xy 164.408061 -369.168889) (xy 164.392694 -369.116557)
			(xy 164.384932 -369.062571) (xy 159.203906 -369.062571) (xy 159.196144 -369.116553) (xy 159.18078 -369.168884)
			(xy 159.158125 -369.218495) (xy 159.128641 -369.264377) (xy 159.092928 -369.305597) (xy 159.051712 -369.341315)
			(xy 159.005833 -369.370804) (xy 158.956225 -369.393465) (xy 158.903897 -369.408835) (xy 158.849913 -369.416602)
			(xy 158.822644 -369.417092) (xy 157.959044 -369.417092) (xy 157.931773 -369.416572) (xy 157.877786 -369.408815)
			(xy 157.825452 -369.393454) (xy 157.775837 -369.370801) (xy 157.729951 -369.341316) (xy 157.688729 -369.305602)
			(xy 157.65301 -369.264384) (xy 157.623521 -369.218502) (xy 157.600861 -369.168889) (xy 157.585494 -369.116557)
			(xy 157.577732 -369.062571) (xy 152.396706 -369.062571) (xy 152.388944 -369.116553) (xy 152.37358 -369.168884)
			(xy 152.350925 -369.218495) (xy 152.321441 -369.264377) (xy 152.285728 -369.305597) (xy 152.244512 -369.341315)
			(xy 152.198633 -369.370804) (xy 152.149025 -369.393465) (xy 152.096697 -369.408835) (xy 152.042713 -369.416602)
			(xy 152.015444 -369.417092) (xy 151.151844 -369.417092) (xy 151.124573 -369.416572) (xy 151.070586 -369.408815)
			(xy 151.018252 -369.393454) (xy 150.968637 -369.370801) (xy 150.922751 -369.341316) (xy 150.881529 -369.305602)
			(xy 150.84581 -369.264384) (xy 150.816321 -369.218502) (xy 150.793661 -369.168889) (xy 150.778294 -369.116557)
			(xy 150.770532 -369.062571) (xy 145.589506 -369.062571) (xy 145.581744 -369.116553) (xy 145.56638 -369.168884)
			(xy 145.543725 -369.218495) (xy 145.514241 -369.264377) (xy 145.478528 -369.305597) (xy 145.437312 -369.341315)
			(xy 145.391433 -369.370804) (xy 145.341825 -369.393465) (xy 145.289497 -369.408835) (xy 145.235513 -369.416602)
			(xy 145.208244 -369.417092) (xy 144.344644 -369.417092) (xy 144.317373 -369.416572) (xy 144.263386 -369.408815)
			(xy 144.211052 -369.393454) (xy 144.161437 -369.370801) (xy 144.115551 -369.341316) (xy 144.074329 -369.305602)
			(xy 144.03861 -369.264384) (xy 144.009121 -369.218502) (xy 143.986461 -369.168889) (xy 143.971094 -369.116557)
			(xy 143.963332 -369.062571) (xy 139.006648 -369.062571) (xy 139.018553 -369.072887) (xy 139.054268 -369.114104)
			(xy 139.083754 -369.159985) (xy 139.106411 -369.209595) (xy 139.121776 -369.261925) (xy 139.129538 -369.315909)
			(xy 139.130024 -369.343178) (xy 139.130024 -370.206778) (xy 139.129538 -370.234047) (xy 139.121776 -370.288031)
			(xy 139.106411 -370.340361) (xy 139.083754 -370.389971) (xy 139.071223 -370.40947) (xy 141.572996 -370.40947)
			(xy 141.572996 -369.54587) (xy 141.573482 -369.518619) (xy 141.581238 -369.464671) (xy 141.596593 -369.412376)
			(xy 141.619235 -369.362799) (xy 141.648701 -369.316949) (xy 141.684392 -369.275758) (xy 141.725583 -369.240067)
			(xy 141.771433 -369.210601) (xy 141.82101 -369.187959) (xy 141.873305 -369.172604) (xy 141.927253 -369.164848)
			(xy 141.981755 -369.164848) (xy 142.035703 -369.172604) (xy 142.087998 -369.187959) (xy 142.137575 -369.210601)
			(xy 142.183425 -369.240067) (xy 142.224616 -369.275758) (xy 142.260307 -369.316949) (xy 142.289773 -369.362799)
			(xy 142.312415 -369.412376) (xy 142.32777 -369.464671) (xy 142.335526 -369.518619) (xy 142.336012 -369.54587)
			(xy 142.336012 -369.62565) (xy 175.203103 -369.62565) (xy 175.203103 -369.57115) (xy 175.210859 -369.517206)
			(xy 175.226214 -369.464914) (xy 175.248854 -369.41534) (xy 175.278318 -369.369493) (xy 175.314008 -369.328305)
			(xy 175.355196 -369.292616) (xy 175.401044 -369.263152) (xy 175.450618 -369.240512) (xy 175.50291 -369.225158)
			(xy 175.556854 -369.217403) (xy 175.584104 -369.21694) (xy 176.447704 -369.21694) (xy 176.474958 -369.21733)
			(xy 176.528913 -369.225088) (xy 176.581213 -369.240446) (xy 176.630796 -369.26309) (xy 176.676652 -369.29256)
			(xy 176.717847 -369.328256) (xy 176.753543 -369.369451) (xy 176.783012 -369.415307) (xy 176.805656 -369.46489)
			(xy 176.821013 -369.517191) (xy 176.82877 -369.571146) (xy 176.82877 -369.625654) (xy 176.821013 -369.679609)
			(xy 176.805656 -369.73191) (xy 176.783012 -369.781493) (xy 176.753543 -369.827349) (xy 176.717847 -369.868544)
			(xy 176.676652 -369.90424) (xy 176.630796 -369.93371) (xy 176.581213 -369.956354) (xy 176.528913 -369.971712)
			(xy 176.474958 -369.97947) (xy 176.447704 -369.979956) (xy 175.584104 -369.979956) (xy 175.556854 -369.979397)
			(xy 175.50291 -369.971642) (xy 175.450618 -369.956288) (xy 175.401044 -369.933648) (xy 175.355196 -369.904184)
			(xy 175.314008 -369.868495) (xy 175.278318 -369.827307) (xy 175.248854 -369.78146) (xy 175.226214 -369.731886)
			(xy 175.210859 -369.679594) (xy 175.203103 -369.62565) (xy 142.336012 -369.62565) (xy 142.336012 -370.40947)
			(xy 142.335526 -370.436721) (xy 142.32777 -370.490669) (xy 142.312415 -370.542964) (xy 142.289773 -370.592541)
			(xy 142.260307 -370.638391) (xy 142.224616 -370.679582) (xy 142.183425 -370.715273) (xy 142.137575 -370.744739)
			(xy 142.087998 -370.767381) (xy 142.035703 -370.782736) (xy 141.981755 -370.790492) (xy 141.927253 -370.790492)
			(xy 141.873305 -370.782736) (xy 141.82101 -370.767381) (xy 141.771433 -370.744739) (xy 141.725583 -370.715273)
			(xy 141.684392 -370.679582) (xy 141.648701 -370.638391) (xy 141.619235 -370.592541) (xy 141.596593 -370.542964)
			(xy 141.581238 -370.490669) (xy 141.573482 -370.436721) (xy 141.572996 -370.40947) (xy 139.071223 -370.40947)
			(xy 139.054268 -370.435852) (xy 139.018553 -370.477069) (xy 138.977336 -370.512784) (xy 138.931455 -370.54227)
			(xy 138.881845 -370.564927) (xy 138.829515 -370.580292) (xy 138.775531 -370.588054) (xy 138.720993 -370.588054)
			(xy 138.667009 -370.580292) (xy 138.614679 -370.564927) (xy 138.565069 -370.54227) (xy 138.519188 -370.512784)
			(xy 138.477971 -370.477069) (xy 138.442256 -370.435852) (xy 138.41277 -370.389971) (xy 138.390113 -370.340361)
			(xy 138.374748 -370.288031) (xy 138.366986 -370.234047) (xy 138.3665 -370.206778) (xy 2.509012 -370.206778)
			(xy 2.509012 -371.526365) (xy 42.633954 -371.526365) (xy 42.633954 -371.471835) (xy 42.641714 -371.41786)
			(xy 42.657076 -371.365538) (xy 42.679727 -371.315935) (xy 42.709206 -371.270059) (xy 42.744914 -371.228846)
			(xy 42.786123 -371.193134) (xy 42.831994 -371.163649) (xy 42.881595 -371.140992) (xy 42.933915 -371.125624)
			(xy 42.987889 -371.117857) (xy 43.015154 -371.117368) (xy 43.878754 -371.117368) (xy 43.906029 -371.117768)
			(xy 43.960025 -371.125526) (xy 44.012368 -371.140889) (xy 44.061991 -371.163546) (xy 44.107884 -371.193035)
			(xy 44.149112 -371.228755) (xy 44.184838 -371.26998) (xy 44.214332 -371.315869) (xy 44.236995 -371.365489)
			(xy 44.252364 -371.41783) (xy 44.260128 -371.471825) (xy 44.260128 -371.526365) (xy 49.441154 -371.526365)
			(xy 49.441154 -371.471835) (xy 49.448914 -371.41786) (xy 49.464276 -371.365538) (xy 49.486927 -371.315935)
			(xy 49.516406 -371.270059) (xy 49.552114 -371.228846) (xy 49.593323 -371.193134) (xy 49.639194 -371.163649)
			(xy 49.688795 -371.140992) (xy 49.741115 -371.125624) (xy 49.795089 -371.117857) (xy 49.822354 -371.117368)
			(xy 50.685954 -371.117368) (xy 50.713229 -371.117768) (xy 50.767225 -371.125526) (xy 50.819568 -371.140889)
			(xy 50.869191 -371.163546) (xy 50.915084 -371.193035) (xy 50.956312 -371.228755) (xy 50.992038 -371.26998)
			(xy 51.021532 -371.315869) (xy 51.044195 -371.365489) (xy 51.059564 -371.41783) (xy 51.067328 -371.471825)
			(xy 51.067328 -371.526365) (xy 56.248354 -371.526365) (xy 56.248354 -371.471835) (xy 56.256114 -371.41786)
			(xy 56.271476 -371.365538) (xy 56.294127 -371.315935) (xy 56.323606 -371.270059) (xy 56.359314 -371.228846)
			(xy 56.400523 -371.193134) (xy 56.446394 -371.163649) (xy 56.495995 -371.140992) (xy 56.548315 -371.125624)
			(xy 56.602289 -371.117857) (xy 56.629554 -371.117368) (xy 57.493154 -371.117368) (xy 57.520429 -371.117768)
			(xy 57.574425 -371.125526) (xy 57.626768 -371.140889) (xy 57.676391 -371.163546) (xy 57.722284 -371.193035)
			(xy 57.763512 -371.228755) (xy 57.799238 -371.26998) (xy 57.828732 -371.315869) (xy 57.851395 -371.365489)
			(xy 57.866764 -371.41783) (xy 57.874528 -371.471825) (xy 57.874528 -371.526365) (xy 63.055554 -371.526365)
			(xy 63.055554 -371.471835) (xy 63.063314 -371.41786) (xy 63.078676 -371.365538) (xy 63.101327 -371.315935)
			(xy 63.130806 -371.270059) (xy 63.166514 -371.228846) (xy 63.207723 -371.193134) (xy 63.253594 -371.163649)
			(xy 63.303195 -371.140992) (xy 63.355515 -371.125624) (xy 63.409489 -371.117857) (xy 63.436754 -371.117368)
			(xy 64.300354 -371.117368) (xy 64.327629 -371.117768) (xy 64.381625 -371.125526) (xy 64.433968 -371.140889)
			(xy 64.483591 -371.163546) (xy 64.529484 -371.193035) (xy 64.570712 -371.228755) (xy 64.606438 -371.26998)
			(xy 64.635932 -371.315869) (xy 64.658595 -371.365489) (xy 64.673964 -371.41783) (xy 64.681728 -371.471825)
			(xy 64.681728 -371.526369) (xy 75.161631 -371.526369) (xy 75.161631 -371.471831) (xy 75.169393 -371.417848)
			(xy 75.184758 -371.36552) (xy 75.207414 -371.31591) (xy 75.2369 -371.27003) (xy 75.272614 -371.228813)
			(xy 75.313832 -371.193098) (xy 75.359712 -371.163613) (xy 75.409321 -371.140957) (xy 75.46165 -371.125593)
			(xy 75.515633 -371.117831) (xy 75.542902 -371.117368) (xy 76.406502 -371.117368) (xy 76.433773 -371.117795)
			(xy 76.487761 -371.125557) (xy 76.540094 -371.140924) (xy 76.589708 -371.163582) (xy 76.635593 -371.19307)
			(xy 76.676813 -371.228788) (xy 76.712531 -371.270009) (xy 76.742019 -371.315893) (xy 76.764677 -371.365507)
			(xy 76.780043 -371.417841) (xy 76.787806 -371.471829) (xy 76.787806 -371.526369) (xy 81.968831 -371.526369)
			(xy 81.968831 -371.471831) (xy 81.976593 -371.417848) (xy 81.991958 -371.36552) (xy 82.014614 -371.31591)
			(xy 82.0441 -371.27003) (xy 82.079814 -371.228813) (xy 82.121032 -371.193098) (xy 82.166912 -371.163613)
			(xy 82.216521 -371.140957) (xy 82.26885 -371.125593) (xy 82.322833 -371.117831) (xy 82.350102 -371.117368)
			(xy 83.213702 -371.117368) (xy 83.240973 -371.117795) (xy 83.294961 -371.125557) (xy 83.347294 -371.140924)
			(xy 83.396908 -371.163582) (xy 83.442793 -371.19307) (xy 83.484013 -371.228788) (xy 83.519731 -371.270009)
			(xy 83.549219 -371.315893) (xy 83.571877 -371.365507) (xy 83.587243 -371.417841) (xy 83.595006 -371.471829)
			(xy 83.595006 -371.526369) (xy 88.776031 -371.526369) (xy 88.776031 -371.471831) (xy 88.783793 -371.417848)
			(xy 88.799158 -371.36552) (xy 88.821814 -371.31591) (xy 88.8513 -371.27003) (xy 88.887014 -371.228813)
			(xy 88.928232 -371.193098) (xy 88.974112 -371.163613) (xy 89.023721 -371.140957) (xy 89.07605 -371.125593)
			(xy 89.130033 -371.117831) (xy 89.157302 -371.117368) (xy 90.020902 -371.117368) (xy 90.048173 -371.117795)
			(xy 90.102161 -371.125557) (xy 90.154494 -371.140924) (xy 90.204108 -371.163582) (xy 90.249993 -371.19307)
			(xy 90.291213 -371.228788) (xy 90.326931 -371.270009) (xy 90.356419 -371.315893) (xy 90.379077 -371.365507)
			(xy 90.394443 -371.417841) (xy 90.402206 -371.471829) (xy 90.402206 -371.526369) (xy 95.583231 -371.526369)
			(xy 95.583231 -371.471831) (xy 95.590993 -371.417848) (xy 95.606358 -371.36552) (xy 95.629014 -371.31591)
			(xy 95.6585 -371.27003) (xy 95.694214 -371.228813) (xy 95.735432 -371.193098) (xy 95.781312 -371.163613)
			(xy 95.830921 -371.140957) (xy 95.88325 -371.125593) (xy 95.937233 -371.117831) (xy 95.964502 -371.117368)
			(xy 96.828102 -371.117368) (xy 96.855373 -371.117795) (xy 96.909361 -371.125557) (xy 96.961694 -371.140924)
			(xy 97.011308 -371.163582) (xy 97.057193 -371.19307) (xy 97.098413 -371.228788) (xy 97.134131 -371.270009)
			(xy 97.163619 -371.315893) (xy 97.186277 -371.365507) (xy 97.201643 -371.417841) (xy 97.209406 -371.471829)
			(xy 97.209406 -371.526367) (xy 109.733854 -371.526367) (xy 109.733854 -371.471833) (xy 109.741615 -371.417854)
			(xy 109.756979 -371.365529) (xy 109.779633 -371.315923) (xy 109.809117 -371.270046) (xy 109.844829 -371.228831)
			(xy 109.886042 -371.193119) (xy 109.931919 -371.163635) (xy 109.981525 -371.140981) (xy 110.03385 -371.125616)
			(xy 110.087829 -371.117855) (xy 110.115096 -371.117368) (xy 110.978696 -371.117368) (xy 111.005969 -371.117771)
			(xy 111.059961 -371.125534) (xy 111.112298 -371.140901) (xy 111.161916 -371.16356) (xy 111.207803 -371.19305)
			(xy 111.249027 -371.22877) (xy 111.284748 -371.269993) (xy 111.314238 -371.315881) (xy 111.336898 -371.365498)
			(xy 111.352266 -371.417835) (xy 111.360028 -371.471827) (xy 111.360028 -371.526367) (xy 116.541054 -371.526367)
			(xy 116.541054 -371.471833) (xy 116.548815 -371.417854) (xy 116.564179 -371.365529) (xy 116.586833 -371.315923)
			(xy 116.616317 -371.270046) (xy 116.652029 -371.228831) (xy 116.693242 -371.193119) (xy 116.739119 -371.163635)
			(xy 116.788725 -371.140981) (xy 116.84105 -371.125616) (xy 116.895029 -371.117855) (xy 116.922296 -371.117368)
			(xy 117.785896 -371.117368) (xy 117.813169 -371.117771) (xy 117.867161 -371.125534) (xy 117.919498 -371.140901)
			(xy 117.969116 -371.16356) (xy 118.015003 -371.19305) (xy 118.056227 -371.22877) (xy 118.091948 -371.269993)
			(xy 118.121438 -371.315881) (xy 118.144098 -371.365498) (xy 118.159466 -371.417835) (xy 118.167228 -371.471827)
			(xy 118.167228 -371.526367) (xy 123.348254 -371.526367) (xy 123.348254 -371.471833) (xy 123.356015 -371.417854)
			(xy 123.371379 -371.365529) (xy 123.394033 -371.315923) (xy 123.423517 -371.270046) (xy 123.459229 -371.228831)
			(xy 123.500442 -371.193119) (xy 123.546319 -371.163635) (xy 123.595925 -371.140981) (xy 123.64825 -371.125616)
			(xy 123.702229 -371.117855) (xy 123.729496 -371.117368) (xy 124.593096 -371.117368) (xy 124.620369 -371.117771)
			(xy 124.674361 -371.125534) (xy 124.726698 -371.140901) (xy 124.776316 -371.16356) (xy 124.822203 -371.19305)
			(xy 124.863427 -371.22877) (xy 124.899148 -371.269993) (xy 124.928638 -371.315881) (xy 124.951298 -371.365498)
			(xy 124.966666 -371.417835) (xy 124.974428 -371.471827) (xy 124.974428 -371.526367) (xy 130.155454 -371.526367)
			(xy 130.155454 -371.471833) (xy 130.163215 -371.417854) (xy 130.178579 -371.365529) (xy 130.201233 -371.315923)
			(xy 130.230717 -371.270046) (xy 130.266429 -371.228831) (xy 130.307642 -371.193119) (xy 130.353519 -371.163635)
			(xy 130.403125 -371.140981) (xy 130.45545 -371.125616) (xy 130.509429 -371.117855) (xy 130.536696 -371.117368)
			(xy 131.400296 -371.117368) (xy 131.427569 -371.117771) (xy 131.481561 -371.125534) (xy 131.533898 -371.140901)
			(xy 131.583516 -371.16356) (xy 131.629403 -371.19305) (xy 131.670627 -371.22877) (xy 131.706348 -371.269993)
			(xy 131.735838 -371.315881) (xy 131.758498 -371.365498) (xy 131.773866 -371.417835) (xy 131.781628 -371.471827)
			(xy 131.781628 -371.526371) (xy 142.261532 -371.526371) (xy 142.261532 -371.471829) (xy 142.269294 -371.417843)
			(xy 142.284661 -371.365511) (xy 142.307321 -371.315898) (xy 142.33681 -371.270016) (xy 142.372529 -371.228798)
			(xy 142.413751 -371.193084) (xy 142.459637 -371.163599) (xy 142.509252 -371.140946) (xy 142.561586 -371.125585)
			(xy 142.615573 -371.117828) (xy 142.642844 -371.117368) (xy 143.506444 -371.117368) (xy 143.533713 -371.117798)
			(xy 143.587697 -371.125565) (xy 143.640025 -371.140935) (xy 143.689633 -371.163596) (xy 143.735512 -371.193085)
			(xy 143.776728 -371.228803) (xy 143.812441 -371.270023) (xy 143.841925 -371.315905) (xy 143.86458 -371.365516)
			(xy 143.879944 -371.417847) (xy 143.887706 -371.47183) (xy 143.887706 -371.52637) (xy 143.887706 -371.526371)
			(xy 149.068732 -371.526371) (xy 149.068732 -371.471829) (xy 149.076494 -371.417843) (xy 149.091861 -371.365511)
			(xy 149.114521 -371.315898) (xy 149.14401 -371.270016) (xy 149.179729 -371.228798) (xy 149.220951 -371.193084)
			(xy 149.266837 -371.163599) (xy 149.316452 -371.140946) (xy 149.368786 -371.125585) (xy 149.422773 -371.117828)
			(xy 149.450044 -371.117368) (xy 150.313644 -371.117368) (xy 150.340913 -371.117798) (xy 150.394897 -371.125565)
			(xy 150.447225 -371.140935) (xy 150.496833 -371.163596) (xy 150.542712 -371.193085) (xy 150.583928 -371.228803)
			(xy 150.619641 -371.270023) (xy 150.649125 -371.315905) (xy 150.67178 -371.365516) (xy 150.687144 -371.417847)
			(xy 150.694906 -371.47183) (xy 150.694906 -371.52637) (xy 150.694906 -371.526371) (xy 155.875932 -371.526371)
			(xy 155.875932 -371.471829) (xy 155.883694 -371.417843) (xy 155.899061 -371.365511) (xy 155.921721 -371.315898)
			(xy 155.95121 -371.270016) (xy 155.986929 -371.228798) (xy 156.028151 -371.193084) (xy 156.074037 -371.163599)
			(xy 156.123652 -371.140946) (xy 156.175986 -371.125585) (xy 156.229973 -371.117828) (xy 156.257244 -371.117368)
			(xy 157.120844 -371.117368) (xy 157.148113 -371.117798) (xy 157.202097 -371.125565) (xy 157.254425 -371.140935)
			(xy 157.304033 -371.163596) (xy 157.349912 -371.193085) (xy 157.391128 -371.228803) (xy 157.426841 -371.270023)
			(xy 157.456325 -371.315905) (xy 157.47898 -371.365516) (xy 157.494344 -371.417847) (xy 157.502106 -371.47183)
			(xy 157.502106 -371.52637) (xy 157.502106 -371.526371) (xy 162.683132 -371.526371) (xy 162.683132 -371.471829)
			(xy 162.690894 -371.417843) (xy 162.706261 -371.365511) (xy 162.728921 -371.315898) (xy 162.75841 -371.270016)
			(xy 162.794129 -371.228798) (xy 162.835351 -371.193084) (xy 162.881237 -371.163599) (xy 162.930852 -371.140946)
			(xy 162.983186 -371.125585) (xy 163.037173 -371.117828) (xy 163.064444 -371.117368) (xy 163.928044 -371.117368)
			(xy 163.955313 -371.117798) (xy 164.009297 -371.125565) (xy 164.061625 -371.140935) (xy 164.111233 -371.163596)
			(xy 164.157112 -371.193085) (xy 164.198328 -371.228803) (xy 164.234041 -371.270023) (xy 164.263525 -371.315905)
			(xy 164.28618 -371.365516) (xy 164.301544 -371.417847) (xy 164.309306 -371.47183) (xy 164.309306 -371.52637)
			(xy 164.301544 -371.580353) (xy 164.28618 -371.632684) (xy 164.263525 -371.682295) (xy 164.234041 -371.728177)
			(xy 164.198328 -371.769397) (xy 164.157112 -371.805115) (xy 164.111233 -371.834604) (xy 164.061625 -371.857265)
			(xy 164.009297 -371.872635) (xy 163.955313 -371.880402) (xy 163.928044 -371.880892) (xy 163.064444 -371.880892)
			(xy 163.037173 -371.880372) (xy 162.983186 -371.872615) (xy 162.930852 -371.857254) (xy 162.881237 -371.834601)
			(xy 162.835351 -371.805116) (xy 162.794129 -371.769402) (xy 162.75841 -371.728184) (xy 162.728921 -371.682302)
			(xy 162.706261 -371.632689) (xy 162.690894 -371.580357) (xy 162.683132 -371.526371) (xy 157.502106 -371.526371)
			(xy 157.494344 -371.580353) (xy 157.47898 -371.632684) (xy 157.456325 -371.682295) (xy 157.426841 -371.728177)
			(xy 157.391128 -371.769397) (xy 157.349912 -371.805115) (xy 157.304033 -371.834604) (xy 157.254425 -371.857265)
			(xy 157.202097 -371.872635) (xy 157.148113 -371.880402) (xy 157.120844 -371.880892) (xy 156.257244 -371.880892)
			(xy 156.229973 -371.880372) (xy 156.175986 -371.872615) (xy 156.123652 -371.857254) (xy 156.074037 -371.834601)
			(xy 156.028151 -371.805116) (xy 155.986929 -371.769402) (xy 155.95121 -371.728184) (xy 155.921721 -371.682302)
			(xy 155.899061 -371.632689) (xy 155.883694 -371.580357) (xy 155.875932 -371.526371) (xy 150.694906 -371.526371)
			(xy 150.687144 -371.580353) (xy 150.67178 -371.632684) (xy 150.649125 -371.682295) (xy 150.619641 -371.728177)
			(xy 150.583928 -371.769397) (xy 150.542712 -371.805115) (xy 150.496833 -371.834604) (xy 150.447225 -371.857265)
			(xy 150.394897 -371.872635) (xy 150.340913 -371.880402) (xy 150.313644 -371.880892) (xy 149.450044 -371.880892)
			(xy 149.422773 -371.880372) (xy 149.368786 -371.872615) (xy 149.316452 -371.857254) (xy 149.266837 -371.834601)
			(xy 149.220951 -371.805116) (xy 149.179729 -371.769402) (xy 149.14401 -371.728184) (xy 149.114521 -371.682302)
			(xy 149.091861 -371.632689) (xy 149.076494 -371.580357) (xy 149.068732 -371.526371) (xy 143.887706 -371.526371)
			(xy 143.879944 -371.580353) (xy 143.86458 -371.632684) (xy 143.841925 -371.682295) (xy 143.812441 -371.728177)
			(xy 143.776728 -371.769397) (xy 143.735512 -371.805115) (xy 143.689633 -371.834604) (xy 143.640025 -371.857265)
			(xy 143.587697 -371.872635) (xy 143.533713 -371.880402) (xy 143.506444 -371.880892) (xy 142.642844 -371.880892)
			(xy 142.615573 -371.880372) (xy 142.561586 -371.872615) (xy 142.509252 -371.857254) (xy 142.459637 -371.834601)
			(xy 142.413751 -371.805116) (xy 142.372529 -371.769402) (xy 142.33681 -371.728184) (xy 142.307321 -371.682302)
			(xy 142.284661 -371.632689) (xy 142.269294 -371.580357) (xy 142.261532 -371.526371) (xy 131.781628 -371.526371)
			(xy 131.781628 -371.526373) (xy 131.773866 -371.580365) (xy 131.758498 -371.632702) (xy 131.735838 -371.682319)
			(xy 131.706348 -371.728207) (xy 131.670627 -371.76943) (xy 131.629403 -371.80515) (xy 131.583516 -371.83464)
			(xy 131.533898 -371.857299) (xy 131.481561 -371.872666) (xy 131.427569 -371.880429) (xy 131.400296 -371.880892)
			(xy 130.536696 -371.880892) (xy 130.509429 -371.880345) (xy 130.45545 -371.872584) (xy 130.403125 -371.857219)
			(xy 130.353519 -371.834565) (xy 130.307642 -371.805081) (xy 130.266429 -371.769369) (xy 130.230717 -371.728154)
			(xy 130.201233 -371.682277) (xy 130.178579 -371.632671) (xy 130.163215 -371.580346) (xy 130.155454 -371.526367)
			(xy 124.974428 -371.526367) (xy 124.974428 -371.526373) (xy 124.966666 -371.580365) (xy 124.951298 -371.632702)
			(xy 124.928638 -371.682319) (xy 124.899148 -371.728207) (xy 124.863427 -371.76943) (xy 124.822203 -371.80515)
			(xy 124.776316 -371.83464) (xy 124.726698 -371.857299) (xy 124.674361 -371.872666) (xy 124.620369 -371.880429)
			(xy 124.593096 -371.880892) (xy 123.729496 -371.880892) (xy 123.702229 -371.880345) (xy 123.64825 -371.872584)
			(xy 123.595925 -371.857219) (xy 123.546319 -371.834565) (xy 123.500442 -371.805081) (xy 123.459229 -371.769369)
			(xy 123.423517 -371.728154) (xy 123.394033 -371.682277) (xy 123.371379 -371.632671) (xy 123.356015 -371.580346)
			(xy 123.348254 -371.526367) (xy 118.167228 -371.526367) (xy 118.167228 -371.526373) (xy 118.159466 -371.580365)
			(xy 118.144098 -371.632702) (xy 118.121438 -371.682319) (xy 118.091948 -371.728207) (xy 118.056227 -371.76943)
			(xy 118.015003 -371.80515) (xy 117.969116 -371.83464) (xy 117.919498 -371.857299) (xy 117.867161 -371.872666)
			(xy 117.813169 -371.880429) (xy 117.785896 -371.880892) (xy 116.922296 -371.880892) (xy 116.895029 -371.880345)
			(xy 116.84105 -371.872584) (xy 116.788725 -371.857219) (xy 116.739119 -371.834565) (xy 116.693242 -371.805081)
			(xy 116.652029 -371.769369) (xy 116.616317 -371.728154) (xy 116.586833 -371.682277) (xy 116.564179 -371.632671)
			(xy 116.548815 -371.580346) (xy 116.541054 -371.526367) (xy 111.360028 -371.526367) (xy 111.360028 -371.526373)
			(xy 111.352266 -371.580365) (xy 111.336898 -371.632702) (xy 111.314238 -371.682319) (xy 111.284748 -371.728207)
			(xy 111.249027 -371.76943) (xy 111.207803 -371.80515) (xy 111.161916 -371.83464) (xy 111.112298 -371.857299)
			(xy 111.059961 -371.872666) (xy 111.005969 -371.880429) (xy 110.978696 -371.880892) (xy 110.115096 -371.880892)
			(xy 110.087829 -371.880345) (xy 110.03385 -371.872584) (xy 109.981525 -371.857219) (xy 109.931919 -371.834565)
			(xy 109.886042 -371.805081) (xy 109.844829 -371.769369) (xy 109.809117 -371.728154) (xy 109.779633 -371.682277)
			(xy 109.756979 -371.632671) (xy 109.741615 -371.580346) (xy 109.733854 -371.526367) (xy 97.209406 -371.526367)
			(xy 97.209406 -371.526371) (xy 97.201643 -371.580359) (xy 97.186277 -371.632693) (xy 97.163619 -371.682307)
			(xy 97.134131 -371.728191) (xy 97.098413 -371.769412) (xy 97.057193 -371.80513) (xy 97.011308 -371.834618)
			(xy 96.961694 -371.857276) (xy 96.909361 -371.872643) (xy 96.855373 -371.880405) (xy 96.828102 -371.880892)
			(xy 95.964502 -371.880892) (xy 95.937233 -371.880369) (xy 95.88325 -371.872607) (xy 95.830921 -371.857243)
			(xy 95.781312 -371.834587) (xy 95.735432 -371.805102) (xy 95.694214 -371.769387) (xy 95.6585 -371.72817)
			(xy 95.629014 -371.68229) (xy 95.606358 -371.63268) (xy 95.590993 -371.580352) (xy 95.583231 -371.526369)
			(xy 90.402206 -371.526369) (xy 90.402206 -371.526371) (xy 90.394443 -371.580359) (xy 90.379077 -371.632693)
			(xy 90.356419 -371.682307) (xy 90.326931 -371.728191) (xy 90.291213 -371.769412) (xy 90.249993 -371.80513)
			(xy 90.204108 -371.834618) (xy 90.154494 -371.857276) (xy 90.102161 -371.872643) (xy 90.048173 -371.880405)
			(xy 90.020902 -371.880892) (xy 89.157302 -371.880892) (xy 89.130033 -371.880369) (xy 89.07605 -371.872607)
			(xy 89.023721 -371.857243) (xy 88.974112 -371.834587) (xy 88.928232 -371.805102) (xy 88.887014 -371.769387)
			(xy 88.8513 -371.72817) (xy 88.821814 -371.68229) (xy 88.799158 -371.63268) (xy 88.783793 -371.580352)
			(xy 88.776031 -371.526369) (xy 83.595006 -371.526369) (xy 83.595006 -371.526371) (xy 83.587243 -371.580359)
			(xy 83.571877 -371.632693) (xy 83.549219 -371.682307) (xy 83.519731 -371.728191) (xy 83.484013 -371.769412)
			(xy 83.442793 -371.80513) (xy 83.396908 -371.834618) (xy 83.347294 -371.857276) (xy 83.294961 -371.872643)
			(xy 83.240973 -371.880405) (xy 83.213702 -371.880892) (xy 82.350102 -371.880892) (xy 82.322833 -371.880369)
			(xy 82.26885 -371.872607) (xy 82.216521 -371.857243) (xy 82.166912 -371.834587) (xy 82.121032 -371.805102)
			(xy 82.079814 -371.769387) (xy 82.0441 -371.72817) (xy 82.014614 -371.68229) (xy 81.991958 -371.63268)
			(xy 81.976593 -371.580352) (xy 81.968831 -371.526369) (xy 76.787806 -371.526369) (xy 76.787806 -371.526371)
			(xy 76.780043 -371.580359) (xy 76.764677 -371.632693) (xy 76.742019 -371.682307) (xy 76.712531 -371.728191)
			(xy 76.676813 -371.769412) (xy 76.635593 -371.80513) (xy 76.589708 -371.834618) (xy 76.540094 -371.857276)
			(xy 76.487761 -371.872643) (xy 76.433773 -371.880405) (xy 76.406502 -371.880892) (xy 75.542902 -371.880892)
			(xy 75.515633 -371.880369) (xy 75.46165 -371.872607) (xy 75.409321 -371.857243) (xy 75.359712 -371.834587)
			(xy 75.313832 -371.805102) (xy 75.272614 -371.769387) (xy 75.2369 -371.72817) (xy 75.207414 -371.68229)
			(xy 75.184758 -371.63268) (xy 75.169393 -371.580352) (xy 75.161631 -371.526369) (xy 64.681728 -371.526369)
			(xy 64.681728 -371.526375) (xy 64.673964 -371.58037) (xy 64.658595 -371.632711) (xy 64.635932 -371.682331)
			(xy 64.606438 -371.72822) (xy 64.570712 -371.769445) (xy 64.529484 -371.805165) (xy 64.483591 -371.834654)
			(xy 64.433968 -371.857311) (xy 64.381625 -371.872674) (xy 64.327629 -371.880432) (xy 64.300354 -371.880892)
			(xy 63.436754 -371.880892) (xy 63.409489 -371.880343) (xy 63.355515 -371.872576) (xy 63.303195 -371.857208)
			(xy 63.253594 -371.834551) (xy 63.207723 -371.805066) (xy 63.166514 -371.769354) (xy 63.130806 -371.728141)
			(xy 63.101327 -371.682265) (xy 63.078676 -371.632662) (xy 63.063314 -371.58034) (xy 63.055554 -371.526365)
			(xy 57.874528 -371.526365) (xy 57.874528 -371.526375) (xy 57.866764 -371.58037) (xy 57.851395 -371.632711)
			(xy 57.828732 -371.682331) (xy 57.799238 -371.72822) (xy 57.763512 -371.769445) (xy 57.722284 -371.805165)
			(xy 57.676391 -371.834654) (xy 57.626768 -371.857311) (xy 57.574425 -371.872674) (xy 57.520429 -371.880432)
			(xy 57.493154 -371.880892) (xy 56.629554 -371.880892) (xy 56.602289 -371.880343) (xy 56.548315 -371.872576)
			(xy 56.495995 -371.857208) (xy 56.446394 -371.834551) (xy 56.400523 -371.805066) (xy 56.359314 -371.769354)
			(xy 56.323606 -371.728141) (xy 56.294127 -371.682265) (xy 56.271476 -371.632662) (xy 56.256114 -371.58034)
			(xy 56.248354 -371.526365) (xy 51.067328 -371.526365) (xy 51.067328 -371.526375) (xy 51.059564 -371.58037)
			(xy 51.044195 -371.632711) (xy 51.021532 -371.682331) (xy 50.992038 -371.72822) (xy 50.956312 -371.769445)
			(xy 50.915084 -371.805165) (xy 50.869191 -371.834654) (xy 50.819568 -371.857311) (xy 50.767225 -371.872674)
			(xy 50.713229 -371.880432) (xy 50.685954 -371.880892) (xy 49.822354 -371.880892) (xy 49.795089 -371.880343)
			(xy 49.741115 -371.872576) (xy 49.688795 -371.857208) (xy 49.639194 -371.834551) (xy 49.593323 -371.805066)
			(xy 49.552114 -371.769354) (xy 49.516406 -371.728141) (xy 49.486927 -371.682265) (xy 49.464276 -371.632662)
			(xy 49.448914 -371.58034) (xy 49.441154 -371.526365) (xy 44.260128 -371.526365) (xy 44.260128 -371.526375)
			(xy 44.252364 -371.58037) (xy 44.236995 -371.632711) (xy 44.214332 -371.682331) (xy 44.184838 -371.72822)
			(xy 44.149112 -371.769445) (xy 44.107884 -371.805165) (xy 44.061991 -371.834654) (xy 44.012368 -371.857311)
			(xy 43.960025 -371.872674) (xy 43.906029 -371.880432) (xy 43.878754 -371.880892) (xy 43.015154 -371.880892)
			(xy 42.987889 -371.880343) (xy 42.933915 -371.872576) (xy 42.881595 -371.857208) (xy 42.831994 -371.834551)
			(xy 42.786123 -371.805066) (xy 42.744914 -371.769354) (xy 42.709206 -371.728141) (xy 42.679727 -371.682265)
			(xy 42.657076 -371.632662) (xy 42.641714 -371.58034) (xy 42.633954 -371.526365) (xy 2.509012 -371.526365)
			(xy 2.509012 -376.489976) (xy 31.068784 -376.489976) (xy 31.072756 -376.311733) (xy 31.084664 -376.133844)
			(xy 31.104485 -375.956662) (xy 31.132179 -375.780538) (xy 31.167691 -375.605823) (xy 31.210951 -375.432864)
			(xy 31.261873 -375.262003) (xy 31.320356 -375.093581) (xy 31.386283 -374.927931) (xy 31.459524 -374.765382)
			(xy 31.539934 -374.606257) (xy 31.627352 -374.450872) (xy 31.721605 -374.299536) (xy 31.822506 -374.152548)
			(xy 31.929855 -374.010201) (xy 32.043438 -373.872778) (xy 32.163031 -373.740551) (xy 32.288395 -373.613782)
			(xy 32.419282 -373.492724) (xy 32.555431 -373.377617) (xy 32.696573 -373.268689) (xy 32.842428 -373.166157)
			(xy 32.992705 -373.070223) (xy 33.147106 -372.98108) (xy 33.305325 -372.898903) (xy 33.467048 -372.823855)
			(xy 33.631953 -372.756087) (xy 33.799714 -372.695731) (xy 33.969997 -372.642909) (xy 34.142464 -372.597725)
			(xy 34.316772 -372.560268) (xy 34.492576 -372.530614) (xy 34.669526 -372.508821) (xy 34.847272 -372.494931)
			(xy 35.025459 -372.488974) (xy 35.203736 -372.49096) (xy 35.381747 -372.500886) (xy 35.559139 -372.518732)
			(xy 35.735559 -372.544462) (xy 35.910659 -372.578026) (xy 36.08409 -372.619356) (xy 36.255507 -372.668372)
			(xy 36.42457 -372.724974) (xy 36.590945 -372.789052) (xy 36.754299 -372.860478) (xy 36.91431 -372.93911)
			(xy 37.070659 -373.024791) (xy 37.223036 -373.117353) (xy 37.371139 -373.21661) (xy 37.514673 -373.322367)
			(xy 37.653353 -373.434412) (xy 37.786904 -373.552524) (xy 37.915061 -373.676468) (xy 38.03757 -373.805998)
			(xy 38.154187 -373.940857) (xy 38.193125 -373.990165) (xy 47.739354 -373.990165) (xy 47.739354 -373.935635)
			(xy 47.747114 -373.88166) (xy 47.762476 -373.829338) (xy 47.785127 -373.779735) (xy 47.814606 -373.733859)
			(xy 47.850314 -373.692646) (xy 47.891523 -373.656934) (xy 47.937394 -373.627449) (xy 47.986995 -373.604792)
			(xy 48.039315 -373.589424) (xy 48.093289 -373.581657) (xy 48.120554 -373.581168) (xy 48.984154 -373.581168)
			(xy 49.011429 -373.581568) (xy 49.065425 -373.589326) (xy 49.117768 -373.604689) (xy 49.167391 -373.627346)
			(xy 49.213284 -373.656835) (xy 49.254512 -373.692555) (xy 49.290238 -373.73378) (xy 49.319732 -373.779669)
			(xy 49.342395 -373.829289) (xy 49.357764 -373.88163) (xy 49.365528 -373.935625) (xy 49.365528 -373.990165)
			(xy 54.546554 -373.990165) (xy 54.546554 -373.935635) (xy 54.554314 -373.88166) (xy 54.569676 -373.829338)
			(xy 54.592327 -373.779735) (xy 54.621806 -373.733859) (xy 54.657514 -373.692646) (xy 54.698723 -373.656934)
			(xy 54.744594 -373.627449) (xy 54.794195 -373.604792) (xy 54.846515 -373.589424) (xy 54.900489 -373.581657)
			(xy 54.927754 -373.581168) (xy 55.791354 -373.581168) (xy 55.818629 -373.581568) (xy 55.872625 -373.589326)
			(xy 55.924968 -373.604689) (xy 55.974591 -373.627346) (xy 56.020484 -373.656835) (xy 56.061712 -373.692555)
			(xy 56.097438 -373.73378) (xy 56.126932 -373.779669) (xy 56.149595 -373.829289) (xy 56.164964 -373.88163)
			(xy 56.172728 -373.935625) (xy 56.172728 -373.990165) (xy 61.353754 -373.990165) (xy 61.353754 -373.935635)
			(xy 61.361514 -373.88166) (xy 61.376876 -373.829338) (xy 61.399527 -373.779735) (xy 61.429006 -373.733859)
			(xy 61.464714 -373.692646) (xy 61.505923 -373.656934) (xy 61.551794 -373.627449) (xy 61.601395 -373.604792)
			(xy 61.653715 -373.589424) (xy 61.707689 -373.581657) (xy 61.734954 -373.581168) (xy 62.598554 -373.581168)
			(xy 62.625829 -373.581568) (xy 62.679825 -373.589326) (xy 62.732168 -373.604689) (xy 62.781791 -373.627346)
			(xy 62.827684 -373.656835) (xy 62.868912 -373.692555) (xy 62.904638 -373.73378) (xy 62.934132 -373.779669)
			(xy 62.956795 -373.829289) (xy 62.972164 -373.88163) (xy 62.979928 -373.935625) (xy 62.979928 -373.990169)
			(xy 80.267031 -373.990169) (xy 80.267031 -373.935631) (xy 80.274793 -373.881648) (xy 80.290158 -373.82932)
			(xy 80.312814 -373.77971) (xy 80.3423 -373.73383) (xy 80.378014 -373.692613) (xy 80.419232 -373.656898)
			(xy 80.465112 -373.627413) (xy 80.514721 -373.604757) (xy 80.56705 -373.589393) (xy 80.621033 -373.581631)
			(xy 80.648302 -373.581168) (xy 81.511902 -373.581168) (xy 81.539173 -373.581595) (xy 81.593161 -373.589357)
			(xy 81.645494 -373.604724) (xy 81.695108 -373.627382) (xy 81.740993 -373.65687) (xy 81.782213 -373.692588)
			(xy 81.817931 -373.733809) (xy 81.847419 -373.779693) (xy 81.870077 -373.829307) (xy 81.885443 -373.881641)
			(xy 81.893206 -373.935629) (xy 81.893206 -373.990169) (xy 87.074231 -373.990169) (xy 87.074231 -373.935631)
			(xy 87.081993 -373.881648) (xy 87.097358 -373.82932) (xy 87.120014 -373.77971) (xy 87.1495 -373.73383)
			(xy 87.185214 -373.692613) (xy 87.226432 -373.656898) (xy 87.272312 -373.627413) (xy 87.321921 -373.604757)
			(xy 87.37425 -373.589393) (xy 87.428233 -373.581631) (xy 87.455502 -373.581168) (xy 88.319102 -373.581168)
			(xy 88.346373 -373.581595) (xy 88.400361 -373.589357) (xy 88.452694 -373.604724) (xy 88.502308 -373.627382)
			(xy 88.548193 -373.65687) (xy 88.589413 -373.692588) (xy 88.625131 -373.733809) (xy 88.654619 -373.779693)
			(xy 88.677277 -373.829307) (xy 88.692643 -373.881641) (xy 88.700406 -373.935629) (xy 88.700406 -373.990169)
			(xy 93.881431 -373.990169) (xy 93.881431 -373.935631) (xy 93.889193 -373.881648) (xy 93.904558 -373.82932)
			(xy 93.927214 -373.77971) (xy 93.9567 -373.73383) (xy 93.992414 -373.692613) (xy 94.033632 -373.656898)
			(xy 94.079512 -373.627413) (xy 94.129121 -373.604757) (xy 94.18145 -373.589393) (xy 94.235433 -373.581631)
			(xy 94.262702 -373.581168) (xy 95.126302 -373.581168) (xy 95.153573 -373.581595) (xy 95.207561 -373.589357)
			(xy 95.259894 -373.604724) (xy 95.309508 -373.627382) (xy 95.355393 -373.65687) (xy 95.396613 -373.692588)
			(xy 95.432331 -373.733809) (xy 95.461819 -373.779693) (xy 95.484477 -373.829307) (xy 95.499843 -373.881641)
			(xy 95.507606 -373.935629) (xy 95.507606 -373.990167) (xy 114.839254 -373.990167) (xy 114.839254 -373.935633)
			(xy 114.847015 -373.881654) (xy 114.862379 -373.829329) (xy 114.885033 -373.779723) (xy 114.914517 -373.733846)
			(xy 114.950229 -373.692631) (xy 114.991442 -373.656919) (xy 115.037319 -373.627435) (xy 115.086925 -373.604781)
			(xy 115.13925 -373.589416) (xy 115.193229 -373.581655) (xy 115.220496 -373.581168) (xy 116.084096 -373.581168)
			(xy 116.111369 -373.581571) (xy 116.165361 -373.589334) (xy 116.217698 -373.604701) (xy 116.267316 -373.62736)
			(xy 116.313203 -373.65685) (xy 116.354427 -373.69257) (xy 116.390148 -373.733793) (xy 116.419638 -373.779681)
			(xy 116.442298 -373.829298) (xy 116.457666 -373.881635) (xy 116.465428 -373.935627) (xy 116.465428 -373.990167)
			(xy 121.646454 -373.990167) (xy 121.646454 -373.935633) (xy 121.654215 -373.881654) (xy 121.669579 -373.829329)
			(xy 121.692233 -373.779723) (xy 121.721717 -373.733846) (xy 121.757429 -373.692631) (xy 121.798642 -373.656919)
			(xy 121.844519 -373.627435) (xy 121.894125 -373.604781) (xy 121.94645 -373.589416) (xy 122.000429 -373.581655)
			(xy 122.027696 -373.581168) (xy 122.891296 -373.581168) (xy 122.918569 -373.581571) (xy 122.972561 -373.589334)
			(xy 123.024898 -373.604701) (xy 123.074516 -373.62736) (xy 123.120403 -373.65685) (xy 123.161627 -373.69257)
			(xy 123.197348 -373.733793) (xy 123.226838 -373.779681) (xy 123.249498 -373.829298) (xy 123.264866 -373.881635)
			(xy 123.272628 -373.935627) (xy 123.272628 -373.990167) (xy 128.453654 -373.990167) (xy 128.453654 -373.935633)
			(xy 128.461415 -373.881654) (xy 128.476779 -373.829329) (xy 128.499433 -373.779723) (xy 128.528917 -373.733846)
			(xy 128.564629 -373.692631) (xy 128.605842 -373.656919) (xy 128.651719 -373.627435) (xy 128.701325 -373.604781)
			(xy 128.75365 -373.589416) (xy 128.807629 -373.581655) (xy 128.834896 -373.581168) (xy 129.698496 -373.581168)
			(xy 129.725769 -373.581571) (xy 129.779761 -373.589334) (xy 129.832098 -373.604701) (xy 129.881716 -373.62736)
			(xy 129.927603 -373.65685) (xy 129.968827 -373.69257) (xy 130.004548 -373.733793) (xy 130.034038 -373.779681)
			(xy 130.056698 -373.829298) (xy 130.072066 -373.881635) (xy 130.079828 -373.935627) (xy 130.079828 -373.990171)
			(xy 147.366932 -373.990171) (xy 147.366932 -373.935629) (xy 147.374694 -373.881643) (xy 147.390061 -373.829311)
			(xy 147.412721 -373.779698) (xy 147.44221 -373.733816) (xy 147.477929 -373.692598) (xy 147.519151 -373.656884)
			(xy 147.565037 -373.627399) (xy 147.614652 -373.604746) (xy 147.666986 -373.589385) (xy 147.720973 -373.581628)
			(xy 147.748244 -373.581168) (xy 148.611844 -373.581168) (xy 148.639113 -373.581598) (xy 148.693097 -373.589365)
			(xy 148.745425 -373.604735) (xy 148.795033 -373.627396) (xy 148.840912 -373.656885) (xy 148.882128 -373.692603)
			(xy 148.917841 -373.733823) (xy 148.947325 -373.779705) (xy 148.96998 -373.829316) (xy 148.985344 -373.881647)
			(xy 148.993106 -373.93563) (xy 148.993106 -373.99017) (xy 148.993106 -373.990171) (xy 154.174132 -373.990171)
			(xy 154.174132 -373.935629) (xy 154.181894 -373.881643) (xy 154.197261 -373.829311) (xy 154.219921 -373.779698)
			(xy 154.24941 -373.733816) (xy 154.285129 -373.692598) (xy 154.326351 -373.656884) (xy 154.372237 -373.627399)
			(xy 154.421852 -373.604746) (xy 154.474186 -373.589385) (xy 154.528173 -373.581628) (xy 154.555444 -373.581168)
			(xy 155.419044 -373.581168) (xy 155.446313 -373.581598) (xy 155.500297 -373.589365) (xy 155.552625 -373.604735)
			(xy 155.602233 -373.627396) (xy 155.648112 -373.656885) (xy 155.689328 -373.692603) (xy 155.725041 -373.733823)
			(xy 155.754525 -373.779705) (xy 155.77718 -373.829316) (xy 155.792544 -373.881647) (xy 155.800306 -373.93563)
			(xy 155.800306 -373.99017) (xy 155.800306 -373.990171) (xy 160.981332 -373.990171) (xy 160.981332 -373.935629)
			(xy 160.989094 -373.881643) (xy 161.004461 -373.829311) (xy 161.027121 -373.779698) (xy 161.05661 -373.733816)
			(xy 161.092329 -373.692598) (xy 161.133551 -373.656884) (xy 161.179437 -373.627399) (xy 161.229052 -373.604746)
			(xy 161.281386 -373.589385) (xy 161.335373 -373.581628) (xy 161.362644 -373.581168) (xy 162.226244 -373.581168)
			(xy 162.253513 -373.581598) (xy 162.307497 -373.589365) (xy 162.359825 -373.604735) (xy 162.409433 -373.627396)
			(xy 162.455312 -373.656885) (xy 162.496528 -373.692603) (xy 162.532241 -373.733823) (xy 162.561725 -373.779705)
			(xy 162.58438 -373.829316) (xy 162.599744 -373.881647) (xy 162.607506 -373.93563) (xy 162.607506 -373.99017)
			(xy 162.599744 -374.044153) (xy 162.58438 -374.096484) (xy 162.561725 -374.146095) (xy 162.532241 -374.191977)
			(xy 162.496528 -374.233197) (xy 162.455312 -374.268915) (xy 162.409433 -374.298404) (xy 162.359825 -374.321065)
			(xy 162.307497 -374.336435) (xy 162.253513 -374.344202) (xy 162.226244 -374.344692) (xy 161.362644 -374.344692)
			(xy 161.335373 -374.344172) (xy 161.281386 -374.336415) (xy 161.229052 -374.321054) (xy 161.179437 -374.298401)
			(xy 161.133551 -374.268916) (xy 161.092329 -374.233202) (xy 161.05661 -374.191984) (xy 161.027121 -374.146102)
			(xy 161.004461 -374.096489) (xy 160.989094 -374.044157) (xy 160.981332 -373.990171) (xy 155.800306 -373.990171)
			(xy 155.792544 -374.044153) (xy 155.77718 -374.096484) (xy 155.754525 -374.146095) (xy 155.725041 -374.191977)
			(xy 155.689328 -374.233197) (xy 155.648112 -374.268915) (xy 155.602233 -374.298404) (xy 155.552625 -374.321065)
			(xy 155.500297 -374.336435) (xy 155.446313 -374.344202) (xy 155.419044 -374.344692) (xy 154.555444 -374.344692)
			(xy 154.528173 -374.344172) (xy 154.474186 -374.336415) (xy 154.421852 -374.321054) (xy 154.372237 -374.298401)
			(xy 154.326351 -374.268916) (xy 154.285129 -374.233202) (xy 154.24941 -374.191984) (xy 154.219921 -374.146102)
			(xy 154.197261 -374.096489) (xy 154.181894 -374.044157) (xy 154.174132 -373.990171) (xy 148.993106 -373.990171)
			(xy 148.985344 -374.044153) (xy 148.96998 -374.096484) (xy 148.947325 -374.146095) (xy 148.917841 -374.191977)
			(xy 148.882128 -374.233197) (xy 148.840912 -374.268915) (xy 148.795033 -374.298404) (xy 148.745425 -374.321065)
			(xy 148.693097 -374.336435) (xy 148.639113 -374.344202) (xy 148.611844 -374.344692) (xy 147.748244 -374.344692)
			(xy 147.720973 -374.344172) (xy 147.666986 -374.336415) (xy 147.614652 -374.321054) (xy 147.565037 -374.298401)
			(xy 147.519151 -374.268916) (xy 147.477929 -374.233202) (xy 147.44221 -374.191984) (xy 147.412721 -374.146102)
			(xy 147.390061 -374.096489) (xy 147.374694 -374.044157) (xy 147.366932 -373.990171) (xy 130.079828 -373.990171)
			(xy 130.079828 -373.990173) (xy 130.072066 -374.044165) (xy 130.056698 -374.096502) (xy 130.034038 -374.146119)
			(xy 130.004548 -374.192007) (xy 129.968827 -374.23323) (xy 129.927603 -374.26895) (xy 129.881716 -374.29844)
			(xy 129.832098 -374.321099) (xy 129.779761 -374.336466) (xy 129.725769 -374.344229) (xy 129.698496 -374.344692)
			(xy 128.834896 -374.344692) (xy 128.807629 -374.344145) (xy 128.75365 -374.336384) (xy 128.701325 -374.321019)
			(xy 128.651719 -374.298365) (xy 128.605842 -374.268881) (xy 128.564629 -374.233169) (xy 128.528917 -374.191954)
			(xy 128.499433 -374.146077) (xy 128.476779 -374.096471) (xy 128.461415 -374.044146) (xy 128.453654 -373.990167)
			(xy 123.272628 -373.990167) (xy 123.272628 -373.990173) (xy 123.264866 -374.044165) (xy 123.249498 -374.096502)
			(xy 123.226838 -374.146119) (xy 123.197348 -374.192007) (xy 123.161627 -374.23323) (xy 123.120403 -374.26895)
			(xy 123.074516 -374.29844) (xy 123.024898 -374.321099) (xy 122.972561 -374.336466) (xy 122.918569 -374.344229)
			(xy 122.891296 -374.344692) (xy 122.027696 -374.344692) (xy 122.000429 -374.344145) (xy 121.94645 -374.336384)
			(xy 121.894125 -374.321019) (xy 121.844519 -374.298365) (xy 121.798642 -374.268881) (xy 121.757429 -374.233169)
			(xy 121.721717 -374.191954) (xy 121.692233 -374.146077) (xy 121.669579 -374.096471) (xy 121.654215 -374.044146)
			(xy 121.646454 -373.990167) (xy 116.465428 -373.990167) (xy 116.465428 -373.990173) (xy 116.457666 -374.044165)
			(xy 116.442298 -374.096502) (xy 116.419638 -374.146119) (xy 116.390148 -374.192007) (xy 116.354427 -374.23323)
			(xy 116.313203 -374.26895) (xy 116.267316 -374.29844) (xy 116.217698 -374.321099) (xy 116.165361 -374.336466)
			(xy 116.111369 -374.344229) (xy 116.084096 -374.344692) (xy 115.220496 -374.344692) (xy 115.193229 -374.344145)
			(xy 115.13925 -374.336384) (xy 115.086925 -374.321019) (xy 115.037319 -374.298365) (xy 114.991442 -374.268881)
			(xy 114.950229 -374.233169) (xy 114.914517 -374.191954) (xy 114.885033 -374.146077) (xy 114.862379 -374.096471)
			(xy 114.847015 -374.044146) (xy 114.839254 -373.990167) (xy 95.507606 -373.990167) (xy 95.507606 -373.990171)
			(xy 95.499843 -374.044159) (xy 95.484477 -374.096493) (xy 95.461819 -374.146107) (xy 95.432331 -374.191991)
			(xy 95.396613 -374.233212) (xy 95.355393 -374.26893) (xy 95.309508 -374.298418) (xy 95.259894 -374.321076)
			(xy 95.207561 -374.336443) (xy 95.153573 -374.344205) (xy 95.126302 -374.344692) (xy 94.262702 -374.344692)
			(xy 94.235433 -374.344169) (xy 94.18145 -374.336407) (xy 94.129121 -374.321043) (xy 94.079512 -374.298387)
			(xy 94.033632 -374.268902) (xy 93.992414 -374.233187) (xy 93.9567 -374.19197) (xy 93.927214 -374.14609)
			(xy 93.904558 -374.09648) (xy 93.889193 -374.044152) (xy 93.881431 -373.990169) (xy 88.700406 -373.990169)
			(xy 88.700406 -373.990171) (xy 88.692643 -374.044159) (xy 88.677277 -374.096493) (xy 88.654619 -374.146107)
			(xy 88.625131 -374.191991) (xy 88.589413 -374.233212) (xy 88.548193 -374.26893) (xy 88.502308 -374.298418)
			(xy 88.452694 -374.321076) (xy 88.400361 -374.336443) (xy 88.346373 -374.344205) (xy 88.319102 -374.344692)
			(xy 87.455502 -374.344692) (xy 87.428233 -374.344169) (xy 87.37425 -374.336407) (xy 87.321921 -374.321043)
			(xy 87.272312 -374.298387) (xy 87.226432 -374.268902) (xy 87.185214 -374.233187) (xy 87.1495 -374.19197)
			(xy 87.120014 -374.14609) (xy 87.097358 -374.09648) (xy 87.081993 -374.044152) (xy 87.074231 -373.990169)
			(xy 81.893206 -373.990169) (xy 81.893206 -373.990171) (xy 81.885443 -374.044159) (xy 81.870077 -374.096493)
			(xy 81.847419 -374.146107) (xy 81.817931 -374.191991) (xy 81.782213 -374.233212) (xy 81.740993 -374.26893)
			(xy 81.695108 -374.298418) (xy 81.645494 -374.321076) (xy 81.593161 -374.336443) (xy 81.539173 -374.344205)
			(xy 81.511902 -374.344692) (xy 80.648302 -374.344692) (xy 80.621033 -374.344169) (xy 80.56705 -374.336407)
			(xy 80.514721 -374.321043) (xy 80.465112 -374.298387) (xy 80.419232 -374.268902) (xy 80.378014 -374.233187)
			(xy 80.3423 -374.19197) (xy 80.312814 -374.14609) (xy 80.290158 -374.09648) (xy 80.274793 -374.044152)
			(xy 80.267031 -373.990169) (xy 62.979928 -373.990169) (xy 62.979928 -373.990175) (xy 62.972164 -374.04417)
			(xy 62.956795 -374.096511) (xy 62.934132 -374.146131) (xy 62.904638 -374.19202) (xy 62.868912 -374.233245)
			(xy 62.827684 -374.268965) (xy 62.781791 -374.298454) (xy 62.732168 -374.321111) (xy 62.679825 -374.336474)
			(xy 62.625829 -374.344232) (xy 62.598554 -374.344692) (xy 61.734954 -374.344692) (xy 61.707689 -374.344143)
			(xy 61.653715 -374.336376) (xy 61.601395 -374.321008) (xy 61.551794 -374.298351) (xy 61.505923 -374.268866)
			(xy 61.464714 -374.233154) (xy 61.429006 -374.191941) (xy 61.399527 -374.146065) (xy 61.376876 -374.096462)
			(xy 61.361514 -374.04414) (xy 61.353754 -373.990165) (xy 56.172728 -373.990165) (xy 56.172728 -373.990175)
			(xy 56.164964 -374.04417) (xy 56.149595 -374.096511) (xy 56.126932 -374.146131) (xy 56.097438 -374.19202)
			(xy 56.061712 -374.233245) (xy 56.020484 -374.268965) (xy 55.974591 -374.298454) (xy 55.924968 -374.321111)
			(xy 55.872625 -374.336474) (xy 55.818629 -374.344232) (xy 55.791354 -374.344692) (xy 54.927754 -374.344692)
			(xy 54.900489 -374.344143) (xy 54.846515 -374.336376) (xy 54.794195 -374.321008) (xy 54.744594 -374.298351)
			(xy 54.698723 -374.268866) (xy 54.657514 -374.233154) (xy 54.621806 -374.191941) (xy 54.592327 -374.146065)
			(xy 54.569676 -374.096462) (xy 54.554314 -374.04414) (xy 54.546554 -373.990165) (xy 49.365528 -373.990165)
			(xy 49.365528 -373.990175) (xy 49.357764 -374.04417) (xy 49.342395 -374.096511) (xy 49.319732 -374.146131)
			(xy 49.290238 -374.19202) (xy 49.254512 -374.233245) (xy 49.213284 -374.268965) (xy 49.167391 -374.298454)
			(xy 49.117768 -374.321111) (xy 49.065425 -374.336474) (xy 49.011429 -374.344232) (xy 48.984154 -374.344692)
			(xy 48.120554 -374.344692) (xy 48.093289 -374.344143) (xy 48.039315 -374.336376) (xy 47.986995 -374.321008)
			(xy 47.937394 -374.298351) (xy 47.891523 -374.268866) (xy 47.850314 -374.233154) (xy 47.814606 -374.191941)
			(xy 47.785127 -374.146065) (xy 47.762476 -374.096462) (xy 47.747114 -374.04414) (xy 47.739354 -373.990165)
			(xy 38.193125 -373.990165) (xy 38.26468 -374.080777) (xy 38.368831 -374.22548) (xy 38.466433 -374.374679)
			(xy 38.557291 -374.528078) (xy 38.641225 -374.685372) (xy 38.71807 -374.846248) (xy 38.787671 -375.010389)
			(xy 38.849892 -375.177466) (xy 38.904608 -375.34715) (xy 38.95171 -375.519103) (xy 38.991106 -375.692983)
			(xy 39.022717 -375.868446) (xy 39.046481 -376.045142) (xy 39.062349 -376.222722) (xy 39.070291 -376.400832)
			(xy 39.070788 -376.489976) (xy 39.070291 -376.57912) (xy 39.062349 -376.75723) (xy 39.05568 -376.83186)
			(xy 41.04894 -376.83186) (xy 41.04894 -375.96826) (xy 41.049426 -375.940991) (xy 41.057188 -375.887007)
			(xy 41.072553 -375.834677) (xy 41.09521 -375.785067) (xy 41.124696 -375.739186) (xy 41.160411 -375.697969)
			(xy 41.201628 -375.662254) (xy 41.247509 -375.632768) (xy 41.297119 -375.610111) (xy 41.349449 -375.594746)
			(xy 41.403433 -375.586984) (xy 41.457971 -375.586984) (xy 41.511955 -375.594746) (xy 41.564285 -375.610111)
			(xy 41.613895 -375.632768) (xy 41.659776 -375.662254) (xy 41.700993 -375.697969) (xy 41.736708 -375.739186)
			(xy 41.766194 -375.785067) (xy 41.788851 -375.834677) (xy 41.804216 -375.887007) (xy 41.811978 -375.940991)
			(xy 41.812464 -375.96826) (xy 41.812464 -376.83186) (xy 41.811978 -376.859129) (xy 41.804216 -376.913113)
			(xy 41.791381 -376.956828) (xy 70.895972 -376.956828) (xy 70.895972 -376.093228) (xy 70.896458 -376.065959)
			(xy 70.90422 -376.011975) (xy 70.919585 -375.959645) (xy 70.942242 -375.910035) (xy 70.971728 -375.864154)
			(xy 71.007443 -375.822937) (xy 71.04866 -375.787222) (xy 71.094541 -375.757736) (xy 71.144151 -375.735079)
			(xy 71.196481 -375.719714) (xy 71.250465 -375.711952) (xy 71.305003 -375.711952) (xy 71.358987 -375.719714)
			(xy 71.411317 -375.735079) (xy 71.460927 -375.757736) (xy 71.506808 -375.787222) (xy 71.548025 -375.822937)
			(xy 71.58374 -375.864154) (xy 71.613226 -375.910035) (xy 71.635883 -375.959645) (xy 71.651248 -376.011975)
			(xy 71.65901 -376.065959) (xy 71.659496 -376.093228) (xy 71.659496 -376.83186) (xy 73.576688 -376.83186)
			(xy 73.576688 -375.96826) (xy 73.577174 -375.940991) (xy 73.584936 -375.887007) (xy 73.600301 -375.834677)
			(xy 73.622958 -375.785067) (xy 73.652444 -375.739186) (xy 73.688159 -375.697969) (xy 73.729376 -375.662254)
			(xy 73.775257 -375.632768) (xy 73.824867 -375.610111) (xy 73.877197 -375.594746) (xy 73.931181 -375.586984)
			(xy 73.985719 -375.586984) (xy 74.039703 -375.594746) (xy 74.092033 -375.610111) (xy 74.141643 -375.632768)
			(xy 74.187524 -375.662254) (xy 74.228741 -375.697969) (xy 74.264456 -375.739186) (xy 74.293942 -375.785067)
			(xy 74.316599 -375.834677) (xy 74.331964 -375.887007) (xy 74.339726 -375.940991) (xy 74.340212 -375.96826)
			(xy 74.340212 -376.83186) (xy 74.339726 -376.859129) (xy 74.331964 -376.913113) (xy 74.319129 -376.956828)
			(xy 103.42372 -376.956828) (xy 103.42372 -376.093228) (xy 103.424206 -376.065959) (xy 103.431968 -376.011975)
			(xy 103.447333 -375.959645) (xy 103.46999 -375.910035) (xy 103.499476 -375.864154) (xy 103.535191 -375.822937)
			(xy 103.576408 -375.787222) (xy 103.622289 -375.757736) (xy 103.671899 -375.735079) (xy 103.724229 -375.719714)
			(xy 103.778213 -375.711952) (xy 103.832751 -375.711952) (xy 103.886735 -375.719714) (xy 103.939065 -375.735079)
			(xy 103.988675 -375.757736) (xy 104.034556 -375.787222) (xy 104.075773 -375.822937) (xy 104.111488 -375.864154)
			(xy 104.140974 -375.910035) (xy 104.163631 -375.959645) (xy 104.178996 -376.011975) (xy 104.186758 -376.065959)
			(xy 104.187244 -376.093228) (xy 104.187244 -376.83186) (xy 108.149136 -376.83186) (xy 108.149136 -375.96826)
			(xy 108.149622 -375.941009) (xy 108.157378 -375.887061) (xy 108.172733 -375.834766) (xy 108.195375 -375.785189)
			(xy 108.224841 -375.739339) (xy 108.260532 -375.698148) (xy 108.301723 -375.662457) (xy 108.347573 -375.632991)
			(xy 108.39715 -375.610349) (xy 108.449445 -375.594994) (xy 108.503393 -375.587238) (xy 108.557895 -375.587238)
			(xy 108.611843 -375.594994) (xy 108.664138 -375.610349) (xy 108.713715 -375.632991) (xy 108.759565 -375.662457)
			(xy 108.800756 -375.698148) (xy 108.836447 -375.739339) (xy 108.865913 -375.785189) (xy 108.888555 -375.834766)
			(xy 108.90391 -375.887061) (xy 108.911666 -375.941009) (xy 108.912152 -375.96826) (xy 108.912152 -376.83186)
			(xy 108.911666 -376.859111) (xy 108.90391 -376.913059) (xy 108.891058 -376.956828) (xy 137.996168 -376.956828)
			(xy 137.996168 -376.093228) (xy 137.996654 -376.065977) (xy 138.00441 -376.012029) (xy 138.019765 -375.959734)
			(xy 138.042407 -375.910157) (xy 138.071873 -375.864307) (xy 138.107564 -375.823116) (xy 138.148755 -375.787425)
			(xy 138.194605 -375.757959) (xy 138.244182 -375.735317) (xy 138.296477 -375.719962) (xy 138.350425 -375.712206)
			(xy 138.404927 -375.712206) (xy 138.458875 -375.719962) (xy 138.51117 -375.735317) (xy 138.560747 -375.757959)
			(xy 138.606597 -375.787425) (xy 138.647788 -375.823116) (xy 138.683479 -375.864307) (xy 138.712945 -375.910157)
			(xy 138.735587 -375.959734) (xy 138.750942 -376.012029) (xy 138.758698 -376.065977) (xy 138.759184 -376.093228)
			(xy 138.759184 -376.83186) (xy 140.676884 -376.83186) (xy 140.676884 -375.96826) (xy 140.67737 -375.941009)
			(xy 140.685126 -375.887061) (xy 140.700481 -375.834766) (xy 140.723123 -375.785189) (xy 140.752589 -375.739339)
			(xy 140.78828 -375.698148) (xy 140.829471 -375.662457) (xy 140.875321 -375.632991) (xy 140.924898 -375.610349)
			(xy 140.977193 -375.594994) (xy 141.031141 -375.587238) (xy 141.085643 -375.587238) (xy 141.139591 -375.594994)
			(xy 141.191886 -375.610349) (xy 141.241463 -375.632991) (xy 141.287313 -375.662457) (xy 141.328504 -375.698148)
			(xy 141.364195 -375.739339) (xy 141.393661 -375.785189) (xy 141.416303 -375.834766) (xy 141.431658 -375.887061)
			(xy 141.439414 -375.941009) (xy 141.4399 -375.96826) (xy 141.4399 -376.83186) (xy 141.439414 -376.859111)
			(xy 141.431658 -376.913059) (xy 141.418806 -376.956828) (xy 170.523916 -376.956828) (xy 170.523916 -376.093228)
			(xy 170.524402 -376.065977) (xy 170.532158 -376.012029) (xy 170.547513 -375.959734) (xy 170.570155 -375.910157)
			(xy 170.599621 -375.864307) (xy 170.635312 -375.823116) (xy 170.676503 -375.787425) (xy 170.722353 -375.757959)
			(xy 170.77193 -375.735317) (xy 170.824225 -375.719962) (xy 170.878173 -375.712206) (xy 170.932675 -375.712206)
			(xy 170.986623 -375.719962) (xy 171.038918 -375.735317) (xy 171.088495 -375.757959) (xy 171.134345 -375.787425)
			(xy 171.175536 -375.823116) (xy 171.211227 -375.864307) (xy 171.240693 -375.910157) (xy 171.263335 -375.959734)
			(xy 171.27869 -376.012029) (xy 171.286446 -376.065977) (xy 171.286932 -376.093228) (xy 171.286932 -376.489976)
			(xy 173.498776 -376.489976) (xy 173.502748 -376.311733) (xy 173.514656 -376.133844) (xy 173.534477 -375.956662)
			(xy 173.562171 -375.780538) (xy 173.597683 -375.605823) (xy 173.640943 -375.432864) (xy 173.691865 -375.262003)
			(xy 173.750348 -375.093581) (xy 173.816275 -374.927931) (xy 173.889516 -374.765382) (xy 173.969926 -374.606257)
			(xy 174.057344 -374.450872) (xy 174.151597 -374.299536) (xy 174.252498 -374.152548) (xy 174.359847 -374.010201)
			(xy 174.47343 -373.872778) (xy 174.593023 -373.740551) (xy 174.718387 -373.613782) (xy 174.849274 -373.492724)
			(xy 174.985423 -373.377617) (xy 175.126565 -373.268689) (xy 175.27242 -373.166157) (xy 175.422697 -373.070223)
			(xy 175.577098 -372.98108) (xy 175.735317 -372.898903) (xy 175.89704 -372.823855) (xy 176.061945 -372.756087)
			(xy 176.229706 -372.695731) (xy 176.399989 -372.642909) (xy 176.572456 -372.597725) (xy 176.746764 -372.560268)
			(xy 176.922568 -372.530614) (xy 177.099518 -372.508821) (xy 177.277264 -372.494931) (xy 177.455451 -372.488974)
			(xy 177.633728 -372.49096) (xy 177.811739 -372.500886) (xy 177.989131 -372.518732) (xy 178.165551 -372.544462)
			(xy 178.340651 -372.578026) (xy 178.514082 -372.619356) (xy 178.685499 -372.668372) (xy 178.854562 -372.724974)
			(xy 179.020937 -372.789052) (xy 179.184291 -372.860478) (xy 179.344302 -372.93911) (xy 179.500651 -373.024791)
			(xy 179.653028 -373.117353) (xy 179.801131 -373.21661) (xy 179.944665 -373.322367) (xy 180.083345 -373.434412)
			(xy 180.216896 -373.552524) (xy 180.345053 -373.676468) (xy 180.467562 -373.805998) (xy 180.584179 -373.940857)
			(xy 180.596796 -373.956834) (xy 282.853384 -373.956834) (xy 282.853384 -373.093234) (xy 282.85387 -373.065983)
			(xy 282.861626 -373.012035) (xy 282.876981 -372.95974) (xy 282.899623 -372.910163) (xy 282.929089 -372.864313)
			(xy 282.96478 -372.823122) (xy 283.005971 -372.787431) (xy 283.051821 -372.757965) (xy 283.101398 -372.735323)
			(xy 283.153693 -372.719968) (xy 283.207641 -372.712212) (xy 283.262143 -372.712212) (xy 283.316091 -372.719968)
			(xy 283.368386 -372.735323) (xy 283.417963 -372.757965) (xy 283.463813 -372.787431) (xy 283.505004 -372.823122)
			(xy 283.540695 -372.864313) (xy 283.570161 -372.910163) (xy 283.592803 -372.95974) (xy 283.608158 -373.012035)
			(xy 283.615914 -373.065983) (xy 283.6164 -373.093234) (xy 283.6164 -373.956834) (xy 283.615914 -373.984085)
			(xy 283.608158 -374.038033) (xy 283.592803 -374.090328) (xy 283.570161 -374.139905) (xy 283.540695 -374.185755)
			(xy 283.505004 -374.226946) (xy 283.463813 -374.262637) (xy 283.417963 -374.292103) (xy 283.368386 -374.314745)
			(xy 283.316091 -374.3301) (xy 283.262143 -374.337856) (xy 283.207641 -374.337856) (xy 283.153693 -374.3301)
			(xy 283.101398 -374.314745) (xy 283.051821 -374.292103) (xy 283.005971 -374.262637) (xy 282.96478 -374.226946)
			(xy 282.929089 -374.185755) (xy 282.899623 -374.139905) (xy 282.876981 -374.090328) (xy 282.861626 -374.038033)
			(xy 282.85387 -373.984085) (xy 282.853384 -373.956834) (xy 180.596796 -373.956834) (xy 180.694672 -374.080777)
			(xy 180.798823 -374.22548) (xy 180.896425 -374.374679) (xy 180.987283 -374.528078) (xy 181.071217 -374.685372)
			(xy 181.148062 -374.846248) (xy 181.217663 -375.010389) (xy 181.279884 -375.177466) (xy 181.3346 -375.34715)
			(xy 181.381702 -375.519103) (xy 181.421098 -375.692983) (xy 181.452709 -375.868446) (xy 181.476473 -376.045142)
			(xy 181.492341 -376.222722) (xy 181.500283 -376.400832) (xy 181.50078 -376.489976) (xy 181.500283 -376.57912)
			(xy 181.492341 -376.75723) (xy 181.476473 -376.93481) (xy 181.452709 -377.111506) (xy 181.421098 -377.286969)
			(xy 181.381702 -377.460849) (xy 181.3346 -377.632802) (xy 181.319901 -377.678385) (xy 193.900548 -377.678385)
			(xy 193.900548 -377.593663) (xy 193.908601 -377.509326) (xy 193.924635 -377.426136) (xy 193.948503 -377.344846)
			(xy 193.979991 -377.266194) (xy 194.018813 -377.190891) (xy 194.064616 -377.119619) (xy 194.116987 -377.053023)
			(xy 194.175452 -376.991708) (xy 194.23948 -376.936227) (xy 194.308492 -376.887084) (xy 194.381862 -376.844724)
			(xy 194.458927 -376.809529) (xy 194.538989 -376.78182) (xy 194.621322 -376.761846) (xy 194.705181 -376.749789)
			(xy 194.789806 -376.745758) (xy 194.874431 -376.749789) (xy 194.95829 -376.761846) (xy 195.040623 -376.78182)
			(xy 195.120685 -376.809529) (xy 195.19775 -376.844724) (xy 195.27112 -376.887084) (xy 195.340132 -376.936227)
			(xy 195.40416 -376.991708) (xy 195.462625 -377.053023) (xy 195.514996 -377.119619) (xy 195.560799 -377.190891)
			(xy 195.599621 -377.266194) (xy 195.631109 -377.344846) (xy 195.654977 -377.426136) (xy 195.671011 -377.509326)
			(xy 195.679064 -377.593663) (xy 195.679568 -377.636024) (xy 195.679064 -377.678385) (xy 195.671011 -377.762722)
			(xy 195.654977 -377.845912) (xy 195.631109 -377.927202) (xy 195.599621 -378.005854) (xy 195.560799 -378.081157)
			(xy 195.514996 -378.152429) (xy 195.47531 -378.202895) (xy 199.443082 -378.202895) (xy 199.443082 -378.118173)
			(xy 199.451135 -378.033836) (xy 199.467169 -377.950646) (xy 199.491037 -377.869356) (xy 199.522525 -377.790704)
			(xy 199.561347 -377.715401) (xy 199.60715 -377.644129) (xy 199.659521 -377.577533) (xy 199.717986 -377.516218)
			(xy 199.782014 -377.460737) (xy 199.851026 -377.411594) (xy 199.924396 -377.369234) (xy 200.001461 -377.334039)
			(xy 200.081523 -377.30633) (xy 200.163856 -377.286356) (xy 200.247715 -377.274299) (xy 200.33234 -377.270268)
			(xy 200.416965 -377.274299) (xy 200.500824 -377.286356) (xy 200.583157 -377.30633) (xy 200.663219 -377.334039)
			(xy 200.740284 -377.369234) (xy 200.813654 -377.411594) (xy 200.859958 -377.444567) (xy 300.335454 -377.444567)
			(xy 300.335454 -377.390033) (xy 300.343215 -377.336054) (xy 300.358579 -377.283729) (xy 300.381233 -377.234123)
			(xy 300.410717 -377.188246) (xy 300.446429 -377.147031) (xy 300.487642 -377.111319) (xy 300.533519 -377.081835)
			(xy 300.583125 -377.059181) (xy 300.63545 -377.043816) (xy 300.689429 -377.036055) (xy 300.716696 -377.035568)
			(xy 301.580296 -377.035568) (xy 301.607569 -377.035971) (xy 301.661561 -377.043734) (xy 301.713898 -377.059101)
			(xy 301.763516 -377.08176) (xy 301.809403 -377.11125) (xy 301.850627 -377.14697) (xy 301.886348 -377.188193)
			(xy 301.915838 -377.234081) (xy 301.938498 -377.283698) (xy 301.953866 -377.336035) (xy 301.961628 -377.390027)
			(xy 301.961628 -377.444567) (xy 307.142654 -377.444567) (xy 307.142654 -377.390033) (xy 307.150415 -377.336054)
			(xy 307.165779 -377.283729) (xy 307.188433 -377.234123) (xy 307.217917 -377.188246) (xy 307.253629 -377.147031)
			(xy 307.294842 -377.111319) (xy 307.340719 -377.081835) (xy 307.390325 -377.059181) (xy 307.44265 -377.043816)
			(xy 307.496629 -377.036055) (xy 307.523896 -377.035568) (xy 308.387496 -377.035568) (xy 308.414769 -377.035971)
			(xy 308.468761 -377.043734) (xy 308.521098 -377.059101) (xy 308.570716 -377.08176) (xy 308.616603 -377.11125)
			(xy 308.657827 -377.14697) (xy 308.693548 -377.188193) (xy 308.723038 -377.234081) (xy 308.745698 -377.283698)
			(xy 308.761066 -377.336035) (xy 308.768828 -377.390027) (xy 308.768828 -377.444567) (xy 313.949854 -377.444567)
			(xy 313.949854 -377.390033) (xy 313.957615 -377.336054) (xy 313.972979 -377.283729) (xy 313.995633 -377.234123)
			(xy 314.025117 -377.188246) (xy 314.060829 -377.147031) (xy 314.102042 -377.111319) (xy 314.147919 -377.081835)
			(xy 314.197525 -377.059181) (xy 314.24985 -377.043816) (xy 314.303829 -377.036055) (xy 314.331096 -377.035568)
			(xy 315.194696 -377.035568) (xy 315.221969 -377.035971) (xy 315.275961 -377.043734) (xy 315.328298 -377.059101)
			(xy 315.377916 -377.08176) (xy 315.423803 -377.11125) (xy 315.465027 -377.14697) (xy 315.500748 -377.188193)
			(xy 315.530238 -377.234081) (xy 315.552898 -377.283698) (xy 315.568266 -377.336035) (xy 315.576028 -377.390027)
			(xy 315.576028 -377.444567) (xy 320.757054 -377.444567) (xy 320.757054 -377.390033) (xy 320.764815 -377.336054)
			(xy 320.780179 -377.283729) (xy 320.802833 -377.234123) (xy 320.832317 -377.188246) (xy 320.868029 -377.147031)
			(xy 320.909242 -377.111319) (xy 320.955119 -377.081835) (xy 321.004725 -377.059181) (xy 321.05705 -377.043816)
			(xy 321.111029 -377.036055) (xy 321.138296 -377.035568) (xy 322.001896 -377.035568) (xy 322.029169 -377.035971)
			(xy 322.083161 -377.043734) (xy 322.135498 -377.059101) (xy 322.185116 -377.08176) (xy 322.231003 -377.11125)
			(xy 322.272227 -377.14697) (xy 322.307948 -377.188193) (xy 322.337438 -377.234081) (xy 322.360098 -377.283698)
			(xy 322.375466 -377.336035) (xy 322.383228 -377.390027) (xy 322.383228 -377.444567) (xy 324.160654 -377.444567)
			(xy 324.160654 -377.390033) (xy 324.168415 -377.336054) (xy 324.183779 -377.283729) (xy 324.206433 -377.234123)
			(xy 324.235917 -377.188246) (xy 324.271629 -377.147031) (xy 324.312842 -377.111319) (xy 324.358719 -377.081835)
			(xy 324.408325 -377.059181) (xy 324.46065 -377.043816) (xy 324.514629 -377.036055) (xy 324.541896 -377.035568)
			(xy 325.405496 -377.035568) (xy 325.432769 -377.035971) (xy 325.486761 -377.043734) (xy 325.539098 -377.059101)
			(xy 325.588716 -377.08176) (xy 325.634603 -377.11125) (xy 325.675827 -377.14697) (xy 325.711548 -377.188193)
			(xy 325.741038 -377.234081) (xy 325.763698 -377.283698) (xy 325.779066 -377.336035) (xy 325.786828 -377.390027)
			(xy 325.786828 -377.444571) (xy 332.863132 -377.444571) (xy 332.863132 -377.390029) (xy 332.870894 -377.336043)
			(xy 332.886261 -377.283711) (xy 332.908921 -377.234098) (xy 332.93841 -377.188216) (xy 332.974129 -377.146998)
			(xy 333.015351 -377.111284) (xy 333.061237 -377.081799) (xy 333.110852 -377.059146) (xy 333.163186 -377.043785)
			(xy 333.217173 -377.036028) (xy 333.244444 -377.035568) (xy 334.108044 -377.035568) (xy 334.135313 -377.035998)
			(xy 334.189297 -377.043765) (xy 334.241625 -377.059135) (xy 334.291233 -377.081796) (xy 334.337112 -377.111285)
			(xy 334.378328 -377.147003) (xy 334.414041 -377.188223) (xy 334.443525 -377.234105) (xy 334.46618 -377.283716)
			(xy 334.481544 -377.336047) (xy 334.489306 -377.39003) (xy 334.489306 -377.44457) (xy 334.489306 -377.444571)
			(xy 339.670332 -377.444571) (xy 339.670332 -377.390029) (xy 339.678094 -377.336043) (xy 339.693461 -377.283711)
			(xy 339.716121 -377.234098) (xy 339.74561 -377.188216) (xy 339.781329 -377.146998) (xy 339.822551 -377.111284)
			(xy 339.868437 -377.081799) (xy 339.918052 -377.059146) (xy 339.970386 -377.043785) (xy 340.024373 -377.036028)
			(xy 340.051644 -377.035568) (xy 340.915244 -377.035568) (xy 340.942513 -377.035998) (xy 340.996497 -377.043765)
			(xy 341.048825 -377.059135) (xy 341.098433 -377.081796) (xy 341.144312 -377.111285) (xy 341.185528 -377.147003)
			(xy 341.221241 -377.188223) (xy 341.250725 -377.234105) (xy 341.27338 -377.283716) (xy 341.288744 -377.336047)
			(xy 341.296506 -377.39003) (xy 341.296506 -377.44457) (xy 341.296506 -377.444571) (xy 346.477532 -377.444571)
			(xy 346.477532 -377.390029) (xy 346.485294 -377.336043) (xy 346.500661 -377.283711) (xy 346.523321 -377.234098)
			(xy 346.55281 -377.188216) (xy 346.588529 -377.146998) (xy 346.629751 -377.111284) (xy 346.675637 -377.081799)
			(xy 346.725252 -377.059146) (xy 346.777586 -377.043785) (xy 346.831573 -377.036028) (xy 346.858844 -377.035568)
			(xy 347.722444 -377.035568) (xy 347.749713 -377.035998) (xy 347.803697 -377.043765) (xy 347.856025 -377.059135)
			(xy 347.905633 -377.081796) (xy 347.951512 -377.111285) (xy 347.992728 -377.147003) (xy 348.028441 -377.188223)
			(xy 348.057925 -377.234105) (xy 348.08058 -377.283716) (xy 348.095944 -377.336047) (xy 348.103706 -377.39003)
			(xy 348.103706 -377.44457) (xy 348.103706 -377.444571) (xy 353.284732 -377.444571) (xy 353.284732 -377.390029)
			(xy 353.292494 -377.336043) (xy 353.307861 -377.283711) (xy 353.330521 -377.234098) (xy 353.36001 -377.188216)
			(xy 353.395729 -377.146998) (xy 353.436951 -377.111284) (xy 353.482837 -377.081799) (xy 353.532452 -377.059146)
			(xy 353.584786 -377.043785) (xy 353.638773 -377.036028) (xy 353.666044 -377.035568) (xy 354.529644 -377.035568)
			(xy 354.556913 -377.035998) (xy 354.610897 -377.043765) (xy 354.663225 -377.059135) (xy 354.712833 -377.081796)
			(xy 354.758712 -377.111285) (xy 354.799928 -377.147003) (xy 354.835641 -377.188223) (xy 354.865125 -377.234105)
			(xy 354.88778 -377.283716) (xy 354.903144 -377.336047) (xy 354.910906 -377.39003) (xy 354.910906 -377.44457)
			(xy 354.910906 -377.444571) (xy 356.688332 -377.444571) (xy 356.688332 -377.390029) (xy 356.696094 -377.336043)
			(xy 356.711461 -377.283711) (xy 356.734121 -377.234098) (xy 356.76361 -377.188216) (xy 356.799329 -377.146998)
			(xy 356.840551 -377.111284) (xy 356.886437 -377.081799) (xy 356.936052 -377.059146) (xy 356.988386 -377.043785)
			(xy 357.042373 -377.036028) (xy 357.069644 -377.035568) (xy 357.933244 -377.035568) (xy 357.960513 -377.035998)
			(xy 358.014497 -377.043765) (xy 358.066825 -377.059135) (xy 358.116433 -377.081796) (xy 358.162312 -377.111285)
			(xy 358.203528 -377.147003) (xy 358.239241 -377.188223) (xy 358.268725 -377.234105) (xy 358.29138 -377.283716)
			(xy 358.306744 -377.336047) (xy 358.314506 -377.39003) (xy 358.314506 -377.444567) (xy 367.435654 -377.444567)
			(xy 367.435654 -377.390033) (xy 367.443415 -377.336054) (xy 367.458779 -377.28373) (xy 367.481433 -377.234124)
			(xy 367.510916 -377.188247) (xy 367.546627 -377.147033) (xy 367.587841 -377.11132) (xy 367.633717 -377.081837)
			(xy 367.683322 -377.059182) (xy 367.735647 -377.043817) (xy 367.789625 -377.036055) (xy 367.816892 -377.035568)
			(xy 368.680492 -377.035568) (xy 368.707766 -377.035971) (xy 368.761757 -377.043733) (xy 368.814095 -377.0591)
			(xy 368.863713 -377.081759) (xy 368.909602 -377.111248) (xy 368.950826 -377.146968) (xy 368.986547 -377.188192)
			(xy 369.016038 -377.23408) (xy 369.038698 -377.283697) (xy 369.054065 -377.336035) (xy 369.061828 -377.390026)
			(xy 369.061828 -377.444567) (xy 374.242854 -377.444567) (xy 374.242854 -377.390033) (xy 374.250615 -377.336054)
			(xy 374.265979 -377.28373) (xy 374.288633 -377.234124) (xy 374.318116 -377.188247) (xy 374.353827 -377.147033)
			(xy 374.395041 -377.11132) (xy 374.440917 -377.081837) (xy 374.490522 -377.059182) (xy 374.542847 -377.043817)
			(xy 374.596825 -377.036055) (xy 374.624092 -377.035568) (xy 375.487692 -377.035568) (xy 375.514966 -377.035971)
			(xy 375.568957 -377.043733) (xy 375.621295 -377.0591) (xy 375.670913 -377.081759) (xy 375.716802 -377.111248)
			(xy 375.758026 -377.146968) (xy 375.793747 -377.188192) (xy 375.823238 -377.23408) (xy 375.845898 -377.283697)
			(xy 375.861265 -377.336035) (xy 375.869028 -377.390026) (xy 375.869028 -377.444567) (xy 381.050054 -377.444567)
			(xy 381.050054 -377.390033) (xy 381.057815 -377.336054) (xy 381.073179 -377.28373) (xy 381.095833 -377.234124)
			(xy 381.125316 -377.188247) (xy 381.161027 -377.147033) (xy 381.202241 -377.11132) (xy 381.248117 -377.081837)
			(xy 381.297722 -377.059182) (xy 381.350047 -377.043817) (xy 381.404025 -377.036055) (xy 381.431292 -377.035568)
			(xy 382.294892 -377.035568) (xy 382.322166 -377.035971) (xy 382.376157 -377.043733) (xy 382.428495 -377.0591)
			(xy 382.478113 -377.081759) (xy 382.524002 -377.111248) (xy 382.565226 -377.146968) (xy 382.600947 -377.188192)
			(xy 382.630438 -377.23408) (xy 382.653098 -377.283697) (xy 382.668465 -377.336035) (xy 382.676228 -377.390026)
			(xy 382.676228 -377.444567) (xy 387.857254 -377.444567) (xy 387.857254 -377.390033) (xy 387.865015 -377.336054)
			(xy 387.880379 -377.28373) (xy 387.903033 -377.234124) (xy 387.932516 -377.188247) (xy 387.968227 -377.147033)
			(xy 388.009441 -377.11132) (xy 388.055317 -377.081837) (xy 388.104922 -377.059182) (xy 388.157247 -377.043817)
			(xy 388.211225 -377.036055) (xy 388.238492 -377.035568) (xy 389.102092 -377.035568) (xy 389.129366 -377.035971)
			(xy 389.183357 -377.043733) (xy 389.235695 -377.0591) (xy 389.285313 -377.081759) (xy 389.331202 -377.111248)
			(xy 389.372426 -377.146968) (xy 389.408147 -377.188192) (xy 389.437638 -377.23408) (xy 389.460298 -377.283697)
			(xy 389.475665 -377.336035) (xy 389.483428 -377.390026) (xy 389.483428 -377.444567) (xy 391.260854 -377.444567)
			(xy 391.260854 -377.390033) (xy 391.268615 -377.336054) (xy 391.283979 -377.28373) (xy 391.306633 -377.234124)
			(xy 391.336116 -377.188247) (xy 391.371827 -377.147033) (xy 391.413041 -377.11132) (xy 391.458917 -377.081837)
			(xy 391.508522 -377.059182) (xy 391.560847 -377.043817) (xy 391.614825 -377.036055) (xy 391.642092 -377.035568)
			(xy 392.505692 -377.035568) (xy 392.532966 -377.035971) (xy 392.586957 -377.043733) (xy 392.639295 -377.0591)
			(xy 392.688913 -377.081759) (xy 392.734802 -377.111248) (xy 392.776026 -377.146968) (xy 392.811747 -377.188192)
			(xy 392.841238 -377.23408) (xy 392.863898 -377.283697) (xy 392.879265 -377.336035) (xy 392.887028 -377.390026)
			(xy 392.887028 -377.444571) (xy 399.963332 -377.444571) (xy 399.963332 -377.390029) (xy 399.971094 -377.336043)
			(xy 399.986461 -377.283711) (xy 400.00912 -377.234099) (xy 400.038609 -377.188217) (xy 400.074328 -377.147)
			(xy 400.11555 -377.111285) (xy 400.161435 -377.081801) (xy 400.211049 -377.059147) (xy 400.263382 -377.043786)
			(xy 400.317369 -377.036029) (xy 400.34464 -377.035568) (xy 401.20824 -377.035568) (xy 401.23551 -377.035997)
			(xy 401.289493 -377.043764) (xy 401.341822 -377.059134) (xy 401.391431 -377.081794) (xy 401.437311 -377.111284)
			(xy 401.478527 -377.147002) (xy 401.51424 -377.188222) (xy 401.543725 -377.234104) (xy 401.56638 -377.283716)
			(xy 401.581744 -377.336046) (xy 401.589506 -377.39003) (xy 401.589506 -377.44457) (xy 401.589506 -377.444571)
			(xy 406.770532 -377.444571) (xy 406.770532 -377.390029) (xy 406.778294 -377.336043) (xy 406.793661 -377.283711)
			(xy 406.81632 -377.234099) (xy 406.845809 -377.188217) (xy 406.881528 -377.147) (xy 406.92275 -377.111285)
			(xy 406.968635 -377.081801) (xy 407.018249 -377.059147) (xy 407.070582 -377.043786) (xy 407.124569 -377.036029)
			(xy 407.15184 -377.035568) (xy 408.01544 -377.035568) (xy 408.04271 -377.035997) (xy 408.096693 -377.043764)
			(xy 408.149022 -377.059134) (xy 408.198631 -377.081794) (xy 408.244511 -377.111284) (xy 408.285727 -377.147002)
			(xy 408.32144 -377.188222) (xy 408.350925 -377.234104) (xy 408.37358 -377.283716) (xy 408.388944 -377.336046)
			(xy 408.396706 -377.39003) (xy 408.396706 -377.44457) (xy 408.396706 -377.444571) (xy 413.577732 -377.444571)
			(xy 413.577732 -377.390029) (xy 413.585494 -377.336043) (xy 413.600861 -377.283711) (xy 413.62352 -377.234099)
			(xy 413.653009 -377.188217) (xy 413.688728 -377.147) (xy 413.72995 -377.111285) (xy 413.775835 -377.081801)
			(xy 413.825449 -377.059147) (xy 413.877782 -377.043786) (xy 413.931769 -377.036029) (xy 413.95904 -377.035568)
			(xy 414.82264 -377.035568) (xy 414.84991 -377.035997) (xy 414.903893 -377.043764) (xy 414.956222 -377.059134)
			(xy 415.005831 -377.081794) (xy 415.051711 -377.111284) (xy 415.092927 -377.147002) (xy 415.12864 -377.188222)
			(xy 415.158125 -377.234104) (xy 415.18078 -377.283716) (xy 415.196144 -377.336046) (xy 415.203906 -377.39003)
			(xy 415.203906 -377.44457) (xy 415.203906 -377.444571) (xy 420.384932 -377.444571) (xy 420.384932 -377.390029)
			(xy 420.392694 -377.336043) (xy 420.408061 -377.283711) (xy 420.43072 -377.234099) (xy 420.460209 -377.188217)
			(xy 420.495928 -377.147) (xy 420.53715 -377.111285) (xy 420.583035 -377.081801) (xy 420.632649 -377.059147)
			(xy 420.684982 -377.043786) (xy 420.738969 -377.036029) (xy 420.76624 -377.035568) (xy 421.62984 -377.035568)
			(xy 421.65711 -377.035997) (xy 421.711093 -377.043764) (xy 421.763422 -377.059134) (xy 421.813031 -377.081794)
			(xy 421.858911 -377.111284) (xy 421.900127 -377.147002) (xy 421.93584 -377.188222) (xy 421.965325 -377.234104)
			(xy 421.98798 -377.283716) (xy 422.003344 -377.336046) (xy 422.011106 -377.39003) (xy 422.011106 -377.44457)
			(xy 422.011106 -377.444571) (xy 423.788532 -377.444571) (xy 423.788532 -377.390029) (xy 423.796294 -377.336043)
			(xy 423.811661 -377.283711) (xy 423.83432 -377.234099) (xy 423.863809 -377.188217) (xy 423.899528 -377.147)
			(xy 423.94075 -377.111285) (xy 423.986635 -377.081801) (xy 424.036249 -377.059147) (xy 424.088582 -377.043786)
			(xy 424.142569 -377.036029) (xy 424.16984 -377.035568) (xy 425.03344 -377.035568) (xy 425.06071 -377.035997)
			(xy 425.114693 -377.043764) (xy 425.167022 -377.059134) (xy 425.216631 -377.081794) (xy 425.262511 -377.111284)
			(xy 425.303727 -377.147002) (xy 425.33944 -377.188222) (xy 425.368925 -377.234104) (xy 425.39158 -377.283716)
			(xy 425.406944 -377.336046) (xy 425.414706 -377.39003) (xy 425.414706 -377.44457) (xy 425.406944 -377.498554)
			(xy 425.39158 -377.550884) (xy 425.368925 -377.600496) (xy 425.33944 -377.646378) (xy 425.303727 -377.687598)
			(xy 425.262511 -377.723316) (xy 425.216631 -377.752806) (xy 425.167022 -377.775466) (xy 425.114693 -377.790836)
			(xy 425.06071 -377.798603) (xy 425.03344 -377.799092) (xy 424.16984 -377.799092) (xy 424.142569 -377.798571)
			(xy 424.088582 -377.790814) (xy 424.036249 -377.775453) (xy 423.986635 -377.752799) (xy 423.94075 -377.723315)
			(xy 423.899528 -377.6876) (xy 423.863809 -377.646383) (xy 423.83432 -377.600501) (xy 423.811661 -377.550889)
			(xy 423.796294 -377.498557) (xy 423.788532 -377.444571) (xy 422.011106 -377.444571) (xy 422.003344 -377.498554)
			(xy 421.98798 -377.550884) (xy 421.965325 -377.600496) (xy 421.93584 -377.646378) (xy 421.900127 -377.687598)
			(xy 421.858911 -377.723316) (xy 421.813031 -377.752806) (xy 421.763422 -377.775466) (xy 421.711093 -377.790836)
			(xy 421.65711 -377.798603) (xy 421.62984 -377.799092) (xy 420.76624 -377.799092) (xy 420.738969 -377.798571)
			(xy 420.684982 -377.790814) (xy 420.632649 -377.775453) (xy 420.583035 -377.752799) (xy 420.53715 -377.723315)
			(xy 420.495928 -377.6876) (xy 420.460209 -377.646383) (xy 420.43072 -377.600501) (xy 420.408061 -377.550889)
			(xy 420.392694 -377.498557) (xy 420.384932 -377.444571) (xy 415.203906 -377.444571) (xy 415.196144 -377.498554)
			(xy 415.18078 -377.550884) (xy 415.158125 -377.600496) (xy 415.12864 -377.646378) (xy 415.092927 -377.687598)
			(xy 415.051711 -377.723316) (xy 415.005831 -377.752806) (xy 414.956222 -377.775466) (xy 414.903893 -377.790836)
			(xy 414.84991 -377.798603) (xy 414.82264 -377.799092) (xy 413.95904 -377.799092) (xy 413.931769 -377.798571)
			(xy 413.877782 -377.790814) (xy 413.825449 -377.775453) (xy 413.775835 -377.752799) (xy 413.72995 -377.723315)
			(xy 413.688728 -377.6876) (xy 413.653009 -377.646383) (xy 413.62352 -377.600501) (xy 413.600861 -377.550889)
			(xy 413.585494 -377.498557) (xy 413.577732 -377.444571) (xy 408.396706 -377.444571) (xy 408.388944 -377.498554)
			(xy 408.37358 -377.550884) (xy 408.350925 -377.600496) (xy 408.32144 -377.646378) (xy 408.285727 -377.687598)
			(xy 408.244511 -377.723316) (xy 408.198631 -377.752806) (xy 408.149022 -377.775466) (xy 408.096693 -377.790836)
			(xy 408.04271 -377.798603) (xy 408.01544 -377.799092) (xy 407.15184 -377.799092) (xy 407.124569 -377.798571)
			(xy 407.070582 -377.790814) (xy 407.018249 -377.775453) (xy 406.968635 -377.752799) (xy 406.92275 -377.723315)
			(xy 406.881528 -377.6876) (xy 406.845809 -377.646383) (xy 406.81632 -377.600501) (xy 406.793661 -377.550889)
			(xy 406.778294 -377.498557) (xy 406.770532 -377.444571) (xy 401.589506 -377.444571) (xy 401.581744 -377.498554)
			(xy 401.56638 -377.550884) (xy 401.543725 -377.600496) (xy 401.51424 -377.646378) (xy 401.478527 -377.687598)
			(xy 401.437311 -377.723316) (xy 401.391431 -377.752806) (xy 401.341822 -377.775466) (xy 401.289493 -377.790836)
			(xy 401.23551 -377.798603) (xy 401.20824 -377.799092) (xy 400.34464 -377.799092) (xy 400.317369 -377.798571)
			(xy 400.263382 -377.790814) (xy 400.211049 -377.775453) (xy 400.161435 -377.752799) (xy 400.11555 -377.723315)
			(xy 400.074328 -377.6876) (xy 400.038609 -377.646383) (xy 400.00912 -377.600501) (xy 399.986461 -377.550889)
			(xy 399.971094 -377.498557) (xy 399.963332 -377.444571) (xy 392.887028 -377.444571) (xy 392.887028 -377.444574)
			(xy 392.879265 -377.498565) (xy 392.863898 -377.550903) (xy 392.841238 -377.60052) (xy 392.811747 -377.646408)
			(xy 392.776026 -377.687632) (xy 392.734802 -377.723352) (xy 392.688913 -377.752841) (xy 392.639295 -377.7755)
			(xy 392.586957 -377.790867) (xy 392.532966 -377.798629) (xy 392.505692 -377.799092) (xy 391.642092 -377.799092)
			(xy 391.614825 -377.798545) (xy 391.560847 -377.790783) (xy 391.508522 -377.775418) (xy 391.458917 -377.752763)
			(xy 391.413041 -377.72328) (xy 391.371827 -377.687567) (xy 391.336116 -377.646353) (xy 391.306633 -377.600476)
			(xy 391.283979 -377.55087) (xy 391.268615 -377.498546) (xy 391.260854 -377.444567) (xy 389.483428 -377.444567)
			(xy 389.483428 -377.444574) (xy 389.475665 -377.498565) (xy 389.460298 -377.550903) (xy 389.437638 -377.60052)
			(xy 389.408147 -377.646408) (xy 389.372426 -377.687632) (xy 389.331202 -377.723352) (xy 389.285313 -377.752841)
			(xy 389.235695 -377.7755) (xy 389.183357 -377.790867) (xy 389.129366 -377.798629) (xy 389.102092 -377.799092)
			(xy 388.238492 -377.799092) (xy 388.211225 -377.798545) (xy 388.157247 -377.790783) (xy 388.104922 -377.775418)
			(xy 388.055317 -377.752763) (xy 388.009441 -377.72328) (xy 387.968227 -377.687567) (xy 387.932516 -377.646353)
			(xy 387.903033 -377.600476) (xy 387.880379 -377.55087) (xy 387.865015 -377.498546) (xy 387.857254 -377.444567)
			(xy 382.676228 -377.444567) (xy 382.676228 -377.444574) (xy 382.668465 -377.498565) (xy 382.653098 -377.550903)
			(xy 382.630438 -377.60052) (xy 382.600947 -377.646408) (xy 382.565226 -377.687632) (xy 382.524002 -377.723352)
			(xy 382.478113 -377.752841) (xy 382.428495 -377.7755) (xy 382.376157 -377.790867) (xy 382.322166 -377.798629)
			(xy 382.294892 -377.799092) (xy 381.431292 -377.799092) (xy 381.404025 -377.798545) (xy 381.350047 -377.790783)
			(xy 381.297722 -377.775418) (xy 381.248117 -377.752763) (xy 381.202241 -377.72328) (xy 381.161027 -377.687567)
			(xy 381.125316 -377.646353) (xy 381.095833 -377.600476) (xy 381.073179 -377.55087) (xy 381.057815 -377.498546)
			(xy 381.050054 -377.444567) (xy 375.869028 -377.444567) (xy 375.869028 -377.444574) (xy 375.861265 -377.498565)
			(xy 375.845898 -377.550903) (xy 375.823238 -377.60052) (xy 375.793747 -377.646408) (xy 375.758026 -377.687632)
			(xy 375.716802 -377.723352) (xy 375.670913 -377.752841) (xy 375.621295 -377.7755) (xy 375.568957 -377.790867)
			(xy 375.514966 -377.798629) (xy 375.487692 -377.799092) (xy 374.624092 -377.799092) (xy 374.596825 -377.798545)
			(xy 374.542847 -377.790783) (xy 374.490522 -377.775418) (xy 374.440917 -377.752763) (xy 374.395041 -377.72328)
			(xy 374.353827 -377.687567) (xy 374.318116 -377.646353) (xy 374.288633 -377.600476) (xy 374.265979 -377.55087)
			(xy 374.250615 -377.498546) (xy 374.242854 -377.444567) (xy 369.061828 -377.444567) (xy 369.061828 -377.444574)
			(xy 369.054065 -377.498565) (xy 369.038698 -377.550903) (xy 369.016038 -377.60052) (xy 368.986547 -377.646408)
			(xy 368.950826 -377.687632) (xy 368.909602 -377.723352) (xy 368.863713 -377.752841) (xy 368.814095 -377.7755)
			(xy 368.761757 -377.790867) (xy 368.707766 -377.798629) (xy 368.680492 -377.799092) (xy 367.816892 -377.799092)
			(xy 367.789625 -377.798545) (xy 367.735647 -377.790783) (xy 367.683322 -377.775418) (xy 367.633717 -377.752763)
			(xy 367.587841 -377.72328) (xy 367.546627 -377.687567) (xy 367.510916 -377.646353) (xy 367.481433 -377.600476)
			(xy 367.458779 -377.55087) (xy 367.443415 -377.498546) (xy 367.435654 -377.444567) (xy 358.314506 -377.444567)
			(xy 358.314506 -377.44457) (xy 358.306744 -377.498553) (xy 358.29138 -377.550884) (xy 358.268725 -377.600495)
			(xy 358.239241 -377.646377) (xy 358.203528 -377.687597) (xy 358.162312 -377.723315) (xy 358.116433 -377.752804)
			(xy 358.066825 -377.775465) (xy 358.014497 -377.790835) (xy 357.960513 -377.798602) (xy 357.933244 -377.799092)
			(xy 357.069644 -377.799092) (xy 357.042373 -377.798572) (xy 356.988386 -377.790815) (xy 356.936052 -377.775454)
			(xy 356.886437 -377.752801) (xy 356.840551 -377.723316) (xy 356.799329 -377.687602) (xy 356.76361 -377.646384)
			(xy 356.734121 -377.600502) (xy 356.711461 -377.550889) (xy 356.696094 -377.498557) (xy 356.688332 -377.444571)
			(xy 354.910906 -377.444571) (xy 354.903144 -377.498553) (xy 354.88778 -377.550884) (xy 354.865125 -377.600495)
			(xy 354.835641 -377.646377) (xy 354.799928 -377.687597) (xy 354.758712 -377.723315) (xy 354.712833 -377.752804)
			(xy 354.663225 -377.775465) (xy 354.610897 -377.790835) (xy 354.556913 -377.798602) (xy 354.529644 -377.799092)
			(xy 353.666044 -377.799092) (xy 353.638773 -377.798572) (xy 353.584786 -377.790815) (xy 353.532452 -377.775454)
			(xy 353.482837 -377.752801) (xy 353.436951 -377.723316) (xy 353.395729 -377.687602) (xy 353.36001 -377.646384)
			(xy 353.330521 -377.600502) (xy 353.307861 -377.550889) (xy 353.292494 -377.498557) (xy 353.284732 -377.444571)
			(xy 348.103706 -377.444571) (xy 348.095944 -377.498553) (xy 348.08058 -377.550884) (xy 348.057925 -377.600495)
			(xy 348.028441 -377.646377) (xy 347.992728 -377.687597) (xy 347.951512 -377.723315) (xy 347.905633 -377.752804)
			(xy 347.856025 -377.775465) (xy 347.803697 -377.790835) (xy 347.749713 -377.798602) (xy 347.722444 -377.799092)
			(xy 346.858844 -377.799092) (xy 346.831573 -377.798572) (xy 346.777586 -377.790815) (xy 346.725252 -377.775454)
			(xy 346.675637 -377.752801) (xy 346.629751 -377.723316) (xy 346.588529 -377.687602) (xy 346.55281 -377.646384)
			(xy 346.523321 -377.600502) (xy 346.500661 -377.550889) (xy 346.485294 -377.498557) (xy 346.477532 -377.444571)
			(xy 341.296506 -377.444571) (xy 341.288744 -377.498553) (xy 341.27338 -377.550884) (xy 341.250725 -377.600495)
			(xy 341.221241 -377.646377) (xy 341.185528 -377.687597) (xy 341.144312 -377.723315) (xy 341.098433 -377.752804)
			(xy 341.048825 -377.775465) (xy 340.996497 -377.790835) (xy 340.942513 -377.798602) (xy 340.915244 -377.799092)
			(xy 340.051644 -377.799092) (xy 340.024373 -377.798572) (xy 339.970386 -377.790815) (xy 339.918052 -377.775454)
			(xy 339.868437 -377.752801) (xy 339.822551 -377.723316) (xy 339.781329 -377.687602) (xy 339.74561 -377.646384)
			(xy 339.716121 -377.600502) (xy 339.693461 -377.550889) (xy 339.678094 -377.498557) (xy 339.670332 -377.444571)
			(xy 334.489306 -377.444571) (xy 334.481544 -377.498553) (xy 334.46618 -377.550884) (xy 334.443525 -377.600495)
			(xy 334.414041 -377.646377) (xy 334.378328 -377.687597) (xy 334.337112 -377.723315) (xy 334.291233 -377.752804)
			(xy 334.241625 -377.775465) (xy 334.189297 -377.790835) (xy 334.135313 -377.798602) (xy 334.108044 -377.799092)
			(xy 333.244444 -377.799092) (xy 333.217173 -377.798572) (xy 333.163186 -377.790815) (xy 333.110852 -377.775454)
			(xy 333.061237 -377.752801) (xy 333.015351 -377.723316) (xy 332.974129 -377.687602) (xy 332.93841 -377.646384)
			(xy 332.908921 -377.600502) (xy 332.886261 -377.550889) (xy 332.870894 -377.498557) (xy 332.863132 -377.444571)
			(xy 325.786828 -377.444571) (xy 325.786828 -377.444573) (xy 325.779066 -377.498565) (xy 325.763698 -377.550902)
			(xy 325.741038 -377.600519) (xy 325.711548 -377.646407) (xy 325.675827 -377.68763) (xy 325.634603 -377.72335)
			(xy 325.588716 -377.75284) (xy 325.539098 -377.775499) (xy 325.486761 -377.790866) (xy 325.432769 -377.798629)
			(xy 325.405496 -377.799092) (xy 324.541896 -377.799092) (xy 324.514629 -377.798545) (xy 324.46065 -377.790784)
			(xy 324.408325 -377.775419) (xy 324.358719 -377.752765) (xy 324.312842 -377.723281) (xy 324.271629 -377.687569)
			(xy 324.235917 -377.646354) (xy 324.206433 -377.600477) (xy 324.183779 -377.550871) (xy 324.168415 -377.498546)
			(xy 324.160654 -377.444567) (xy 322.383228 -377.444567) (xy 322.383228 -377.444573) (xy 322.375466 -377.498565)
			(xy 322.360098 -377.550902) (xy 322.337438 -377.600519) (xy 322.307948 -377.646407) (xy 322.272227 -377.68763)
			(xy 322.231003 -377.72335) (xy 322.185116 -377.75284) (xy 322.135498 -377.775499) (xy 322.083161 -377.790866)
			(xy 322.029169 -377.798629) (xy 322.001896 -377.799092) (xy 321.138296 -377.799092) (xy 321.111029 -377.798545)
			(xy 321.05705 -377.790784) (xy 321.004725 -377.775419) (xy 320.955119 -377.752765) (xy 320.909242 -377.723281)
			(xy 320.868029 -377.687569) (xy 320.832317 -377.646354) (xy 320.802833 -377.600477) (xy 320.780179 -377.550871)
			(xy 320.764815 -377.498546) (xy 320.757054 -377.444567) (xy 315.576028 -377.444567) (xy 315.576028 -377.444573)
			(xy 315.568266 -377.498565) (xy 315.552898 -377.550902) (xy 315.530238 -377.600519) (xy 315.500748 -377.646407)
			(xy 315.465027 -377.68763) (xy 315.423803 -377.72335) (xy 315.377916 -377.75284) (xy 315.328298 -377.775499)
			(xy 315.275961 -377.790866) (xy 315.221969 -377.798629) (xy 315.194696 -377.799092) (xy 314.331096 -377.799092)
			(xy 314.303829 -377.798545) (xy 314.24985 -377.790784) (xy 314.197525 -377.775419) (xy 314.147919 -377.752765)
			(xy 314.102042 -377.723281) (xy 314.060829 -377.687569) (xy 314.025117 -377.646354) (xy 313.995633 -377.600477)
			(xy 313.972979 -377.550871) (xy 313.957615 -377.498546) (xy 313.949854 -377.444567) (xy 308.768828 -377.444567)
			(xy 308.768828 -377.444573) (xy 308.761066 -377.498565) (xy 308.745698 -377.550902) (xy 308.723038 -377.600519)
			(xy 308.693548 -377.646407) (xy 308.657827 -377.68763) (xy 308.616603 -377.72335) (xy 308.570716 -377.75284)
			(xy 308.521098 -377.775499) (xy 308.468761 -377.790866) (xy 308.414769 -377.798629) (xy 308.387496 -377.799092)
			(xy 307.523896 -377.799092) (xy 307.496629 -377.798545) (xy 307.44265 -377.790784) (xy 307.390325 -377.775419)
			(xy 307.340719 -377.752765) (xy 307.294842 -377.723281) (xy 307.253629 -377.687569) (xy 307.217917 -377.646354)
			(xy 307.188433 -377.600477) (xy 307.165779 -377.550871) (xy 307.150415 -377.498546) (xy 307.142654 -377.444567)
			(xy 301.961628 -377.444567) (xy 301.961628 -377.444573) (xy 301.953866 -377.498565) (xy 301.938498 -377.550902)
			(xy 301.915838 -377.600519) (xy 301.886348 -377.646407) (xy 301.850627 -377.68763) (xy 301.809403 -377.72335)
			(xy 301.763516 -377.75284) (xy 301.713898 -377.775499) (xy 301.661561 -377.790866) (xy 301.607569 -377.798629)
			(xy 301.580296 -377.799092) (xy 300.716696 -377.799092) (xy 300.689429 -377.798545) (xy 300.63545 -377.790784)
			(xy 300.583125 -377.775419) (xy 300.533519 -377.752765) (xy 300.487642 -377.723281) (xy 300.446429 -377.687569)
			(xy 300.410717 -377.646354) (xy 300.381233 -377.600477) (xy 300.358579 -377.550871) (xy 300.343215 -377.498546)
			(xy 300.335454 -377.444567) (xy 200.859958 -377.444567) (xy 200.882666 -377.460737) (xy 200.946694 -377.516218)
			(xy 201.005159 -377.577533) (xy 201.05753 -377.644129) (xy 201.103333 -377.715401) (xy 201.142155 -377.790704)
			(xy 201.173643 -377.869356) (xy 201.197511 -377.950646) (xy 201.213545 -378.033836) (xy 201.221598 -378.118173)
			(xy 201.222102 -378.160534) (xy 201.221598 -378.202895) (xy 201.213545 -378.287232) (xy 201.197511 -378.370422)
			(xy 201.173643 -378.451712) (xy 201.142155 -378.530364) (xy 201.103333 -378.605667) (xy 201.05753 -378.676939)
			(xy 201.005159 -378.743535) (xy 200.946694 -378.80485) (xy 200.882666 -378.860331) (xy 200.813654 -378.909474)
			(xy 200.740284 -378.951834) (xy 200.663219 -378.987029) (xy 200.583157 -379.014738) (xy 200.500824 -379.034712)
			(xy 200.416965 -379.046769) (xy 200.33234 -379.050801) (xy 200.247715 -379.046769) (xy 200.163856 -379.034712)
			(xy 200.081523 -379.014738) (xy 200.001461 -378.987029) (xy 199.924396 -378.951834) (xy 199.851026 -378.909474)
			(xy 199.782014 -378.860331) (xy 199.717986 -378.80485) (xy 199.659521 -378.743535) (xy 199.60715 -378.676939)
			(xy 199.561347 -378.605667) (xy 199.522525 -378.530364) (xy 199.491037 -378.451712) (xy 199.467169 -378.370422)
			(xy 199.451135 -378.287232) (xy 199.443082 -378.202895) (xy 195.47531 -378.202895) (xy 195.462625 -378.219025)
			(xy 195.40416 -378.28034) (xy 195.340132 -378.335821) (xy 195.27112 -378.384964) (xy 195.19775 -378.427324)
			(xy 195.120685 -378.462519) (xy 195.040623 -378.490228) (xy 194.95829 -378.510202) (xy 194.874431 -378.522259)
			(xy 194.789806 -378.526291) (xy 194.705181 -378.522259) (xy 194.621322 -378.510202) (xy 194.538989 -378.490228)
			(xy 194.458927 -378.462519) (xy 194.381862 -378.427324) (xy 194.308492 -378.384964) (xy 194.23948 -378.335821)
			(xy 194.175452 -378.28034) (xy 194.116987 -378.219025) (xy 194.064616 -378.152429) (xy 194.018813 -378.081157)
			(xy 193.979991 -378.005854) (xy 193.948503 -377.927202) (xy 193.924635 -377.845912) (xy 193.908601 -377.762722)
			(xy 193.900548 -377.678385) (xy 181.319901 -377.678385) (xy 181.279884 -377.802486) (xy 181.217663 -377.969563)
			(xy 181.148062 -378.133704) (xy 181.071217 -378.29458) (xy 180.987283 -378.451874) (xy 180.896425 -378.605273)
			(xy 180.798823 -378.754472) (xy 180.694672 -378.899175) (xy 180.584179 -379.039095) (xy 180.467562 -379.173954)
			(xy 180.345053 -379.303484) (xy 180.216896 -379.427428) (xy 180.083345 -379.54554) (xy 179.944665 -379.657585)
			(xy 179.801131 -379.763342) (xy 179.653028 -379.862599) (xy 179.577684 -379.908367) (xy 298.633654 -379.908367)
			(xy 298.633654 -379.853833) (xy 298.641415 -379.799854) (xy 298.656779 -379.747529) (xy 298.679433 -379.697923)
			(xy 298.708917 -379.652046) (xy 298.744629 -379.610831) (xy 298.785842 -379.575119) (xy 298.831719 -379.545635)
			(xy 298.881325 -379.522981) (xy 298.93365 -379.507616) (xy 298.987629 -379.499855) (xy 299.014896 -379.499368)
			(xy 299.878496 -379.499368) (xy 299.905769 -379.499771) (xy 299.959761 -379.507534) (xy 300.012098 -379.522901)
			(xy 300.061716 -379.54556) (xy 300.107603 -379.57505) (xy 300.148827 -379.61077) (xy 300.184548 -379.651993)
			(xy 300.214038 -379.697881) (xy 300.236698 -379.747498) (xy 300.252066 -379.799835) (xy 300.259828 -379.853827)
			(xy 300.259828 -379.908367) (xy 305.440854 -379.908367) (xy 305.440854 -379.853833) (xy 305.448615 -379.799854)
			(xy 305.463979 -379.747529) (xy 305.486633 -379.697923) (xy 305.516117 -379.652046) (xy 305.551829 -379.610831)
			(xy 305.593042 -379.575119) (xy 305.638919 -379.545635) (xy 305.688525 -379.522981) (xy 305.74085 -379.507616)
			(xy 305.794829 -379.499855) (xy 305.822096 -379.499368) (xy 306.685696 -379.499368) (xy 306.712969 -379.499771)
			(xy 306.766961 -379.507534) (xy 306.819298 -379.522901) (xy 306.868916 -379.54556) (xy 306.914803 -379.57505)
			(xy 306.956027 -379.61077) (xy 306.991748 -379.651993) (xy 307.021238 -379.697881) (xy 307.043898 -379.747498)
			(xy 307.059266 -379.799835) (xy 307.067028 -379.853827) (xy 307.067028 -379.908367) (xy 312.248054 -379.908367)
			(xy 312.248054 -379.853833) (xy 312.255815 -379.799854) (xy 312.271179 -379.747529) (xy 312.293833 -379.697923)
			(xy 312.323317 -379.652046) (xy 312.359029 -379.610831) (xy 312.400242 -379.575119) (xy 312.446119 -379.545635)
			(xy 312.495725 -379.522981) (xy 312.54805 -379.507616) (xy 312.602029 -379.499855) (xy 312.629296 -379.499368)
			(xy 313.492896 -379.499368) (xy 313.520169 -379.499771) (xy 313.574161 -379.507534) (xy 313.626498 -379.522901)
			(xy 313.676116 -379.54556) (xy 313.722003 -379.57505) (xy 313.763227 -379.61077) (xy 313.798948 -379.651993)
			(xy 313.828438 -379.697881) (xy 313.851098 -379.747498) (xy 313.866466 -379.799835) (xy 313.874228 -379.853827)
			(xy 313.874228 -379.908367) (xy 319.055254 -379.908367) (xy 319.055254 -379.853833) (xy 319.063015 -379.799854)
			(xy 319.078379 -379.747529) (xy 319.101033 -379.697923) (xy 319.130517 -379.652046) (xy 319.166229 -379.610831)
			(xy 319.207442 -379.575119) (xy 319.253319 -379.545635) (xy 319.302925 -379.522981) (xy 319.35525 -379.507616)
			(xy 319.409229 -379.499855) (xy 319.436496 -379.499368) (xy 320.300096 -379.499368) (xy 320.327369 -379.499771)
			(xy 320.381361 -379.507534) (xy 320.433698 -379.522901) (xy 320.483316 -379.54556) (xy 320.529203 -379.57505)
			(xy 320.570427 -379.61077) (xy 320.606148 -379.651993) (xy 320.635638 -379.697881) (xy 320.658298 -379.747498)
			(xy 320.673666 -379.799835) (xy 320.681428 -379.853827) (xy 320.681428 -379.908371) (xy 331.161332 -379.908371)
			(xy 331.161332 -379.853829) (xy 331.169094 -379.799843) (xy 331.184461 -379.747511) (xy 331.207121 -379.697898)
			(xy 331.23661 -379.652016) (xy 331.272329 -379.610798) (xy 331.313551 -379.575084) (xy 331.359437 -379.545599)
			(xy 331.409052 -379.522946) (xy 331.461386 -379.507585) (xy 331.515373 -379.499828) (xy 331.542644 -379.499368)
			(xy 332.406244 -379.499368) (xy 332.433513 -379.499798) (xy 332.487497 -379.507565) (xy 332.539825 -379.522935)
			(xy 332.589433 -379.545596) (xy 332.635312 -379.575085) (xy 332.676528 -379.610803) (xy 332.712241 -379.652023)
			(xy 332.741725 -379.697905) (xy 332.76438 -379.747516) (xy 332.779744 -379.799847) (xy 332.787506 -379.85383)
			(xy 332.787506 -379.90837) (xy 332.787506 -379.908371) (xy 337.968532 -379.908371) (xy 337.968532 -379.853829)
			(xy 337.976294 -379.799843) (xy 337.991661 -379.747511) (xy 338.014321 -379.697898) (xy 338.04381 -379.652016)
			(xy 338.079529 -379.610798) (xy 338.120751 -379.575084) (xy 338.166637 -379.545599) (xy 338.216252 -379.522946)
			(xy 338.268586 -379.507585) (xy 338.322573 -379.499828) (xy 338.349844 -379.499368) (xy 339.213444 -379.499368)
			(xy 339.240713 -379.499798) (xy 339.294697 -379.507565) (xy 339.347025 -379.522935) (xy 339.396633 -379.545596)
			(xy 339.442512 -379.575085) (xy 339.483728 -379.610803) (xy 339.519441 -379.652023) (xy 339.548925 -379.697905)
			(xy 339.57158 -379.747516) (xy 339.586944 -379.799847) (xy 339.594706 -379.85383) (xy 339.594706 -379.90837)
			(xy 339.594706 -379.908371) (xy 344.775732 -379.908371) (xy 344.775732 -379.853829) (xy 344.783494 -379.799843)
			(xy 344.798861 -379.747511) (xy 344.821521 -379.697898) (xy 344.85101 -379.652016) (xy 344.886729 -379.610798)
			(xy 344.927951 -379.575084) (xy 344.973837 -379.545599) (xy 345.023452 -379.522946) (xy 345.075786 -379.507585)
			(xy 345.129773 -379.499828) (xy 345.157044 -379.499368) (xy 346.020644 -379.499368) (xy 346.047913 -379.499798)
			(xy 346.101897 -379.507565) (xy 346.154225 -379.522935) (xy 346.203833 -379.545596) (xy 346.249712 -379.575085)
			(xy 346.290928 -379.610803) (xy 346.326641 -379.652023) (xy 346.356125 -379.697905) (xy 346.37878 -379.747516)
			(xy 346.394144 -379.799847) (xy 346.401906 -379.85383) (xy 346.401906 -379.90837) (xy 346.401906 -379.908371)
			(xy 351.582932 -379.908371) (xy 351.582932 -379.853829) (xy 351.590694 -379.799843) (xy 351.606061 -379.747511)
			(xy 351.628721 -379.697898) (xy 351.65821 -379.652016) (xy 351.693929 -379.610798) (xy 351.735151 -379.575084)
			(xy 351.781037 -379.545599) (xy 351.830652 -379.522946) (xy 351.882986 -379.507585) (xy 351.936973 -379.499828)
			(xy 351.964244 -379.499368) (xy 352.827844 -379.499368) (xy 352.855113 -379.499798) (xy 352.909097 -379.507565)
			(xy 352.961425 -379.522935) (xy 353.011033 -379.545596) (xy 353.056912 -379.575085) (xy 353.098128 -379.610803)
			(xy 353.133841 -379.652023) (xy 353.163325 -379.697905) (xy 353.18598 -379.747516) (xy 353.201344 -379.799847)
			(xy 353.209106 -379.85383) (xy 353.209106 -379.908367) (xy 365.733854 -379.908367) (xy 365.733854 -379.853833)
			(xy 365.741615 -379.799854) (xy 365.756979 -379.74753) (xy 365.779633 -379.697924) (xy 365.809116 -379.652047)
			(xy 365.844827 -379.610833) (xy 365.886041 -379.57512) (xy 365.931917 -379.545637) (xy 365.981522 -379.522982)
			(xy 366.033847 -379.507617) (xy 366.087825 -379.499855) (xy 366.115092 -379.499368) (xy 366.978692 -379.499368)
			(xy 367.005966 -379.499771) (xy 367.059957 -379.507533) (xy 367.112295 -379.5229) (xy 367.161913 -379.545559)
			(xy 367.207802 -379.575048) (xy 367.249026 -379.610768) (xy 367.284747 -379.651992) (xy 367.314238 -379.69788)
			(xy 367.336898 -379.747497) (xy 367.352265 -379.799835) (xy 367.360028 -379.853826) (xy 367.360028 -379.908367)
			(xy 372.541054 -379.908367) (xy 372.541054 -379.853833) (xy 372.548815 -379.799854) (xy 372.564179 -379.74753)
			(xy 372.586833 -379.697924) (xy 372.616316 -379.652047) (xy 372.652027 -379.610833) (xy 372.693241 -379.57512)
			(xy 372.739117 -379.545637) (xy 372.788722 -379.522982) (xy 372.841047 -379.507617) (xy 372.895025 -379.499855)
			(xy 372.922292 -379.499368) (xy 373.785892 -379.499368) (xy 373.813166 -379.499771) (xy 373.867157 -379.507533)
			(xy 373.919495 -379.5229) (xy 373.969113 -379.545559) (xy 374.015002 -379.575048) (xy 374.056226 -379.610768)
			(xy 374.091947 -379.651992) (xy 374.121438 -379.69788) (xy 374.144098 -379.747497) (xy 374.159465 -379.799835)
			(xy 374.167228 -379.853826) (xy 374.167228 -379.908367) (xy 379.348254 -379.908367) (xy 379.348254 -379.853833)
			(xy 379.356015 -379.799854) (xy 379.371379 -379.74753) (xy 379.394033 -379.697924) (xy 379.423516 -379.652047)
			(xy 379.459227 -379.610833) (xy 379.500441 -379.57512) (xy 379.546317 -379.545637) (xy 379.595922 -379.522982)
			(xy 379.648247 -379.507617) (xy 379.702225 -379.499855) (xy 379.729492 -379.499368) (xy 380.593092 -379.499368)
			(xy 380.620366 -379.499771) (xy 380.674357 -379.507533) (xy 380.726695 -379.5229) (xy 380.776313 -379.545559)
			(xy 380.822202 -379.575048) (xy 380.863426 -379.610768) (xy 380.899147 -379.651992) (xy 380.928638 -379.69788)
			(xy 380.951298 -379.747497) (xy 380.966665 -379.799835) (xy 380.974428 -379.853826) (xy 380.974428 -379.908367)
			(xy 386.155454 -379.908367) (xy 386.155454 -379.853833) (xy 386.163215 -379.799854) (xy 386.178579 -379.74753)
			(xy 386.201233 -379.697924) (xy 386.230716 -379.652047) (xy 386.266427 -379.610833) (xy 386.307641 -379.57512)
			(xy 386.353517 -379.545637) (xy 386.403122 -379.522982) (xy 386.455447 -379.507617) (xy 386.509425 -379.499855)
			(xy 386.536692 -379.499368) (xy 387.400292 -379.499368) (xy 387.427566 -379.499771) (xy 387.481557 -379.507533)
			(xy 387.533895 -379.5229) (xy 387.583513 -379.545559) (xy 387.629402 -379.575048) (xy 387.670626 -379.610768)
			(xy 387.706347 -379.651992) (xy 387.735838 -379.69788) (xy 387.758498 -379.747497) (xy 387.773865 -379.799835)
			(xy 387.781628 -379.853826) (xy 387.781628 -379.908371) (xy 398.261532 -379.908371) (xy 398.261532 -379.853829)
			(xy 398.269294 -379.799843) (xy 398.284661 -379.747511) (xy 398.30732 -379.697899) (xy 398.336809 -379.652017)
			(xy 398.372528 -379.6108) (xy 398.41375 -379.575085) (xy 398.459635 -379.545601) (xy 398.509249 -379.522947)
			(xy 398.561582 -379.507586) (xy 398.615569 -379.499829) (xy 398.64284 -379.499368) (xy 399.50644 -379.499368)
			(xy 399.53371 -379.499797) (xy 399.587693 -379.507564) (xy 399.640022 -379.522934) (xy 399.689631 -379.545594)
			(xy 399.735511 -379.575084) (xy 399.776727 -379.610802) (xy 399.81244 -379.652022) (xy 399.841925 -379.697904)
			(xy 399.86458 -379.747516) (xy 399.879944 -379.799846) (xy 399.887706 -379.85383) (xy 399.887706 -379.90837)
			(xy 399.887706 -379.908371) (xy 405.068732 -379.908371) (xy 405.068732 -379.853829) (xy 405.076494 -379.799843)
			(xy 405.091861 -379.747511) (xy 405.11452 -379.697899) (xy 405.144009 -379.652017) (xy 405.179728 -379.6108)
			(xy 405.22095 -379.575085) (xy 405.266835 -379.545601) (xy 405.316449 -379.522947) (xy 405.368782 -379.507586)
			(xy 405.422769 -379.499829) (xy 405.45004 -379.499368) (xy 406.31364 -379.499368) (xy 406.34091 -379.499797)
			(xy 406.394893 -379.507564) (xy 406.447222 -379.522934) (xy 406.496831 -379.545594) (xy 406.542711 -379.575084)
			(xy 406.583927 -379.610802) (xy 406.61964 -379.652022) (xy 406.649125 -379.697904) (xy 406.67178 -379.747516)
			(xy 406.687144 -379.799846) (xy 406.694906 -379.85383) (xy 406.694906 -379.90837) (xy 406.694906 -379.908371)
			(xy 411.875932 -379.908371) (xy 411.875932 -379.853829) (xy 411.883694 -379.799843) (xy 411.899061 -379.747511)
			(xy 411.92172 -379.697899) (xy 411.951209 -379.652017) (xy 411.986928 -379.6108) (xy 412.02815 -379.575085)
			(xy 412.074035 -379.545601) (xy 412.123649 -379.522947) (xy 412.175982 -379.507586) (xy 412.229969 -379.499829)
			(xy 412.25724 -379.499368) (xy 413.12084 -379.499368) (xy 413.14811 -379.499797) (xy 413.202093 -379.507564)
			(xy 413.254422 -379.522934) (xy 413.304031 -379.545594) (xy 413.349911 -379.575084) (xy 413.391127 -379.610802)
			(xy 413.42684 -379.652022) (xy 413.456325 -379.697904) (xy 413.47898 -379.747516) (xy 413.494344 -379.799846)
			(xy 413.502106 -379.85383) (xy 413.502106 -379.90837) (xy 413.502106 -379.908371) (xy 418.683132 -379.908371)
			(xy 418.683132 -379.853829) (xy 418.690894 -379.799843) (xy 418.706261 -379.747511) (xy 418.72892 -379.697899)
			(xy 418.758409 -379.652017) (xy 418.794128 -379.6108) (xy 418.83535 -379.575085) (xy 418.881235 -379.545601)
			(xy 418.930849 -379.522947) (xy 418.983182 -379.507586) (xy 419.037169 -379.499829) (xy 419.06444 -379.499368)
			(xy 419.92804 -379.499368) (xy 419.95531 -379.499797) (xy 420.009293 -379.507564) (xy 420.061622 -379.522934)
			(xy 420.111231 -379.545594) (xy 420.157111 -379.575084) (xy 420.198327 -379.610802) (xy 420.23404 -379.652022)
			(xy 420.263525 -379.697904) (xy 420.28618 -379.747516) (xy 420.301544 -379.799846) (xy 420.309306 -379.85383)
			(xy 420.309306 -379.90837) (xy 420.301544 -379.962354) (xy 420.28618 -380.014684) (xy 420.263525 -380.064296)
			(xy 420.23404 -380.110178) (xy 420.198327 -380.151398) (xy 420.157111 -380.187116) (xy 420.111231 -380.216606)
			(xy 420.061622 -380.239266) (xy 420.009293 -380.254636) (xy 419.95531 -380.262403) (xy 419.92804 -380.262892)
			(xy 419.06444 -380.262892) (xy 419.037169 -380.262371) (xy 418.983182 -380.254614) (xy 418.930849 -380.239253)
			(xy 418.881235 -380.216599) (xy 418.83535 -380.187115) (xy 418.794128 -380.1514) (xy 418.758409 -380.110183)
			(xy 418.72892 -380.064301) (xy 418.706261 -380.014689) (xy 418.690894 -379.962357) (xy 418.683132 -379.908371)
			(xy 413.502106 -379.908371) (xy 413.494344 -379.962354) (xy 413.47898 -380.014684) (xy 413.456325 -380.064296)
			(xy 413.42684 -380.110178) (xy 413.391127 -380.151398) (xy 413.349911 -380.187116) (xy 413.304031 -380.216606)
			(xy 413.254422 -380.239266) (xy 413.202093 -380.254636) (xy 413.14811 -380.262403) (xy 413.12084 -380.262892)
			(xy 412.25724 -380.262892) (xy 412.229969 -380.262371) (xy 412.175982 -380.254614) (xy 412.123649 -380.239253)
			(xy 412.074035 -380.216599) (xy 412.02815 -380.187115) (xy 411.986928 -380.1514) (xy 411.951209 -380.110183)
			(xy 411.92172 -380.064301) (xy 411.899061 -380.014689) (xy 411.883694 -379.962357) (xy 411.875932 -379.908371)
			(xy 406.694906 -379.908371) (xy 406.687144 -379.962354) (xy 406.67178 -380.014684) (xy 406.649125 -380.064296)
			(xy 406.61964 -380.110178) (xy 406.583927 -380.151398) (xy 406.542711 -380.187116) (xy 406.496831 -380.216606)
			(xy 406.447222 -380.239266) (xy 406.394893 -380.254636) (xy 406.34091 -380.262403) (xy 406.31364 -380.262892)
			(xy 405.45004 -380.262892) (xy 405.422769 -380.262371) (xy 405.368782 -380.254614) (xy 405.316449 -380.239253)
			(xy 405.266835 -380.216599) (xy 405.22095 -380.187115) (xy 405.179728 -380.1514) (xy 405.144009 -380.110183)
			(xy 405.11452 -380.064301) (xy 405.091861 -380.014689) (xy 405.076494 -379.962357) (xy 405.068732 -379.908371)
			(xy 399.887706 -379.908371) (xy 399.879944 -379.962354) (xy 399.86458 -380.014684) (xy 399.841925 -380.064296)
			(xy 399.81244 -380.110178) (xy 399.776727 -380.151398) (xy 399.735511 -380.187116) (xy 399.689631 -380.216606)
			(xy 399.640022 -380.239266) (xy 399.587693 -380.254636) (xy 399.53371 -380.262403) (xy 399.50644 -380.262892)
			(xy 398.64284 -380.262892) (xy 398.615569 -380.262371) (xy 398.561582 -380.254614) (xy 398.509249 -380.239253)
			(xy 398.459635 -380.216599) (xy 398.41375 -380.187115) (xy 398.372528 -380.1514) (xy 398.336809 -380.110183)
			(xy 398.30732 -380.064301) (xy 398.284661 -380.014689) (xy 398.269294 -379.962357) (xy 398.261532 -379.908371)
			(xy 387.781628 -379.908371) (xy 387.781628 -379.908374) (xy 387.773865 -379.962365) (xy 387.758498 -380.014703)
			(xy 387.735838 -380.06432) (xy 387.706347 -380.110208) (xy 387.670626 -380.151432) (xy 387.629402 -380.187152)
			(xy 387.583513 -380.216641) (xy 387.533895 -380.2393) (xy 387.481557 -380.254667) (xy 387.427566 -380.262429)
			(xy 387.400292 -380.262892) (xy 386.536692 -380.262892) (xy 386.509425 -380.262345) (xy 386.455447 -380.254583)
			(xy 386.403122 -380.239218) (xy 386.353517 -380.216563) (xy 386.307641 -380.18708) (xy 386.266427 -380.151367)
			(xy 386.230716 -380.110153) (xy 386.201233 -380.064276) (xy 386.178579 -380.01467) (xy 386.163215 -379.962346)
			(xy 386.155454 -379.908367) (xy 380.974428 -379.908367) (xy 380.974428 -379.908374) (xy 380.966665 -379.962365)
			(xy 380.951298 -380.014703) (xy 380.928638 -380.06432) (xy 380.899147 -380.110208) (xy 380.863426 -380.151432)
			(xy 380.822202 -380.187152) (xy 380.776313 -380.216641) (xy 380.726695 -380.2393) (xy 380.674357 -380.254667)
			(xy 380.620366 -380.262429) (xy 380.593092 -380.262892) (xy 379.729492 -380.262892) (xy 379.702225 -380.262345)
			(xy 379.648247 -380.254583) (xy 379.595922 -380.239218) (xy 379.546317 -380.216563) (xy 379.500441 -380.18708)
			(xy 379.459227 -380.151367) (xy 379.423516 -380.110153) (xy 379.394033 -380.064276) (xy 379.371379 -380.01467)
			(xy 379.356015 -379.962346) (xy 379.348254 -379.908367) (xy 374.167228 -379.908367) (xy 374.167228 -379.908374)
			(xy 374.159465 -379.962365) (xy 374.144098 -380.014703) (xy 374.121438 -380.06432) (xy 374.091947 -380.110208)
			(xy 374.056226 -380.151432) (xy 374.015002 -380.187152) (xy 373.969113 -380.216641) (xy 373.919495 -380.2393)
			(xy 373.867157 -380.254667) (xy 373.813166 -380.262429) (xy 373.785892 -380.262892) (xy 372.922292 -380.262892)
			(xy 372.895025 -380.262345) (xy 372.841047 -380.254583) (xy 372.788722 -380.239218) (xy 372.739117 -380.216563)
			(xy 372.693241 -380.18708) (xy 372.652027 -380.151367) (xy 372.616316 -380.110153) (xy 372.586833 -380.064276)
			(xy 372.564179 -380.01467) (xy 372.548815 -379.962346) (xy 372.541054 -379.908367) (xy 367.360028 -379.908367)
			(xy 367.360028 -379.908374) (xy 367.352265 -379.962365) (xy 367.336898 -380.014703) (xy 367.314238 -380.06432)
			(xy 367.284747 -380.110208) (xy 367.249026 -380.151432) (xy 367.207802 -380.187152) (xy 367.161913 -380.216641)
			(xy 367.112295 -380.2393) (xy 367.059957 -380.254667) (xy 367.005966 -380.262429) (xy 366.978692 -380.262892)
			(xy 366.115092 -380.262892) (xy 366.087825 -380.262345) (xy 366.033847 -380.254583) (xy 365.981522 -380.239218)
			(xy 365.931917 -380.216563) (xy 365.886041 -380.18708) (xy 365.844827 -380.151367) (xy 365.809116 -380.110153)
			(xy 365.779633 -380.064276) (xy 365.756979 -380.01467) (xy 365.741615 -379.962346) (xy 365.733854 -379.908367)
			(xy 353.209106 -379.908367) (xy 353.209106 -379.90837) (xy 353.201344 -379.962353) (xy 353.18598 -380.014684)
			(xy 353.163325 -380.064295) (xy 353.133841 -380.110177) (xy 353.098128 -380.151397) (xy 353.056912 -380.187115)
			(xy 353.011033 -380.216604) (xy 352.961425 -380.239265) (xy 352.909097 -380.254635) (xy 352.855113 -380.262402)
			(xy 352.827844 -380.262892) (xy 351.964244 -380.262892) (xy 351.936973 -380.262372) (xy 351.882986 -380.254615)
			(xy 351.830652 -380.239254) (xy 351.781037 -380.216601) (xy 351.735151 -380.187116) (xy 351.693929 -380.151402)
			(xy 351.65821 -380.110184) (xy 351.628721 -380.064302) (xy 351.606061 -380.014689) (xy 351.590694 -379.962357)
			(xy 351.582932 -379.908371) (xy 346.401906 -379.908371) (xy 346.394144 -379.962353) (xy 346.37878 -380.014684)
			(xy 346.356125 -380.064295) (xy 346.326641 -380.110177) (xy 346.290928 -380.151397) (xy 346.249712 -380.187115)
			(xy 346.203833 -380.216604) (xy 346.154225 -380.239265) (xy 346.101897 -380.254635) (xy 346.047913 -380.262402)
			(xy 346.020644 -380.262892) (xy 345.157044 -380.262892) (xy 345.129773 -380.262372) (xy 345.075786 -380.254615)
			(xy 345.023452 -380.239254) (xy 344.973837 -380.216601) (xy 344.927951 -380.187116) (xy 344.886729 -380.151402)
			(xy 344.85101 -380.110184) (xy 344.821521 -380.064302) (xy 344.798861 -380.014689) (xy 344.783494 -379.962357)
			(xy 344.775732 -379.908371) (xy 339.594706 -379.908371) (xy 339.586944 -379.962353) (xy 339.57158 -380.014684)
			(xy 339.548925 -380.064295) (xy 339.519441 -380.110177) (xy 339.483728 -380.151397) (xy 339.442512 -380.187115)
			(xy 339.396633 -380.216604) (xy 339.347025 -380.239265) (xy 339.294697 -380.254635) (xy 339.240713 -380.262402)
			(xy 339.213444 -380.262892) (xy 338.349844 -380.262892) (xy 338.322573 -380.262372) (xy 338.268586 -380.254615)
			(xy 338.216252 -380.239254) (xy 338.166637 -380.216601) (xy 338.120751 -380.187116) (xy 338.079529 -380.151402)
			(xy 338.04381 -380.110184) (xy 338.014321 -380.064302) (xy 337.991661 -380.014689) (xy 337.976294 -379.962357)
			(xy 337.968532 -379.908371) (xy 332.787506 -379.908371) (xy 332.779744 -379.962353) (xy 332.76438 -380.014684)
			(xy 332.741725 -380.064295) (xy 332.712241 -380.110177) (xy 332.676528 -380.151397) (xy 332.635312 -380.187115)
			(xy 332.589433 -380.216604) (xy 332.539825 -380.239265) (xy 332.487497 -380.254635) (xy 332.433513 -380.262402)
			(xy 332.406244 -380.262892) (xy 331.542644 -380.262892) (xy 331.515373 -380.262372) (xy 331.461386 -380.254615)
			(xy 331.409052 -380.239254) (xy 331.359437 -380.216601) (xy 331.313551 -380.187116) (xy 331.272329 -380.151402)
			(xy 331.23661 -380.110184) (xy 331.207121 -380.064302) (xy 331.184461 -380.014689) (xy 331.169094 -379.962357)
			(xy 331.161332 -379.908371) (xy 320.681428 -379.908371) (xy 320.681428 -379.908373) (xy 320.673666 -379.962365)
			(xy 320.658298 -380.014702) (xy 320.635638 -380.064319) (xy 320.606148 -380.110207) (xy 320.570427 -380.15143)
			(xy 320.529203 -380.18715) (xy 320.483316 -380.21664) (xy 320.433698 -380.239299) (xy 320.381361 -380.254666)
			(xy 320.327369 -380.262429) (xy 320.300096 -380.262892) (xy 319.436496 -380.262892) (xy 319.409229 -380.262345)
			(xy 319.35525 -380.254584) (xy 319.302925 -380.239219) (xy 319.253319 -380.216565) (xy 319.207442 -380.187081)
			(xy 319.166229 -380.151369) (xy 319.130517 -380.110154) (xy 319.101033 -380.064277) (xy 319.078379 -380.014671)
			(xy 319.063015 -379.962346) (xy 319.055254 -379.908367) (xy 313.874228 -379.908367) (xy 313.874228 -379.908373)
			(xy 313.866466 -379.962365) (xy 313.851098 -380.014702) (xy 313.828438 -380.064319) (xy 313.798948 -380.110207)
			(xy 313.763227 -380.15143) (xy 313.722003 -380.18715) (xy 313.676116 -380.21664) (xy 313.626498 -380.239299)
			(xy 313.574161 -380.254666) (xy 313.520169 -380.262429) (xy 313.492896 -380.262892) (xy 312.629296 -380.262892)
			(xy 312.602029 -380.262345) (xy 312.54805 -380.254584) (xy 312.495725 -380.239219) (xy 312.446119 -380.216565)
			(xy 312.400242 -380.187081) (xy 312.359029 -380.151369) (xy 312.323317 -380.110154) (xy 312.293833 -380.064277)
			(xy 312.271179 -380.014671) (xy 312.255815 -379.962346) (xy 312.248054 -379.908367) (xy 307.067028 -379.908367)
			(xy 307.067028 -379.908373) (xy 307.059266 -379.962365) (xy 307.043898 -380.014702) (xy 307.021238 -380.064319)
			(xy 306.991748 -380.110207) (xy 306.956027 -380.15143) (xy 306.914803 -380.18715) (xy 306.868916 -380.21664)
			(xy 306.819298 -380.239299) (xy 306.766961 -380.254666) (xy 306.712969 -380.262429) (xy 306.685696 -380.262892)
			(xy 305.822096 -380.262892) (xy 305.794829 -380.262345) (xy 305.74085 -380.254584) (xy 305.688525 -380.239219)
			(xy 305.638919 -380.216565) (xy 305.593042 -380.187081) (xy 305.551829 -380.151369) (xy 305.516117 -380.110154)
			(xy 305.486633 -380.064277) (xy 305.463979 -380.014671) (xy 305.448615 -379.962346) (xy 305.440854 -379.908367)
			(xy 300.259828 -379.908367) (xy 300.259828 -379.908373) (xy 300.252066 -379.962365) (xy 300.236698 -380.014702)
			(xy 300.214038 -380.064319) (xy 300.184548 -380.110207) (xy 300.148827 -380.15143) (xy 300.107603 -380.18715)
			(xy 300.061716 -380.21664) (xy 300.012098 -380.239299) (xy 299.959761 -380.254666) (xy 299.905769 -380.262429)
			(xy 299.878496 -380.262892) (xy 299.014896 -380.262892) (xy 298.987629 -380.262345) (xy 298.93365 -380.254584)
			(xy 298.881325 -380.239219) (xy 298.831719 -380.216565) (xy 298.785842 -380.187081) (xy 298.744629 -380.151369)
			(xy 298.708917 -380.110154) (xy 298.679433 -380.064277) (xy 298.656779 -380.014671) (xy 298.641415 -379.962346)
			(xy 298.633654 -379.908367) (xy 179.577684 -379.908367) (xy 179.500651 -379.955161) (xy 179.344302 -380.040842)
			(xy 179.184291 -380.119474) (xy 179.020937 -380.1909) (xy 178.854562 -380.254978) (xy 178.685499 -380.31158)
			(xy 178.514082 -380.360596) (xy 178.340651 -380.401926) (xy 178.165551 -380.43549) (xy 177.989131 -380.46122)
			(xy 177.811739 -380.479066) (xy 177.633728 -380.488992) (xy 177.455451 -380.490978) (xy 177.277264 -380.485021)
			(xy 177.099518 -380.471131) (xy 176.922568 -380.449338) (xy 176.746764 -380.419684) (xy 176.572456 -380.382227)
			(xy 176.399989 -380.337043) (xy 176.229706 -380.284221) (xy 176.061945 -380.223865) (xy 175.89704 -380.156097)
			(xy 175.735317 -380.081049) (xy 175.577098 -379.998872) (xy 175.422697 -379.909729) (xy 175.27242 -379.813795)
			(xy 175.126565 -379.711263) (xy 174.985423 -379.602335) (xy 174.849274 -379.487228) (xy 174.718387 -379.36617)
			(xy 174.593023 -379.239401) (xy 174.47343 -379.107174) (xy 174.359847 -378.969751) (xy 174.252498 -378.827404)
			(xy 174.151597 -378.680416) (xy 174.057344 -378.52908) (xy 173.969926 -378.373695) (xy 173.889516 -378.21457)
			(xy 173.816275 -378.052021) (xy 173.750348 -377.886371) (xy 173.691865 -377.717949) (xy 173.640943 -377.547088)
			(xy 173.597683 -377.374129) (xy 173.562171 -377.199414) (xy 173.534477 -377.02329) (xy 173.514656 -376.846108)
			(xy 173.502748 -376.668219) (xy 173.498776 -376.489976) (xy 171.286932 -376.489976) (xy 171.286932 -376.956828)
			(xy 171.286446 -376.984079) (xy 171.27869 -377.038027) (xy 171.263335 -377.090322) (xy 171.240693 -377.139899)
			(xy 171.211227 -377.185749) (xy 171.175536 -377.22694) (xy 171.134345 -377.262631) (xy 171.088495 -377.292097)
			(xy 171.038918 -377.314739) (xy 170.986623 -377.330094) (xy 170.932675 -377.33785) (xy 170.878173 -377.33785)
			(xy 170.824225 -377.330094) (xy 170.77193 -377.314739) (xy 170.722353 -377.292097) (xy 170.676503 -377.262631)
			(xy 170.635312 -377.22694) (xy 170.599621 -377.185749) (xy 170.570155 -377.139899) (xy 170.547513 -377.090322)
			(xy 170.532158 -377.038027) (xy 170.524402 -376.984079) (xy 170.523916 -376.956828) (xy 141.418806 -376.956828)
			(xy 141.416303 -376.965354) (xy 141.393661 -377.014931) (xy 141.364195 -377.060781) (xy 141.328504 -377.101972)
			(xy 141.287313 -377.137663) (xy 141.241463 -377.167129) (xy 141.191886 -377.189771) (xy 141.139591 -377.205126)
			(xy 141.085643 -377.212882) (xy 141.031141 -377.212882) (xy 140.977193 -377.205126) (xy 140.924898 -377.189771)
			(xy 140.875321 -377.167129) (xy 140.829471 -377.137663) (xy 140.78828 -377.101972) (xy 140.752589 -377.060781)
			(xy 140.723123 -377.014931) (xy 140.700481 -376.965354) (xy 140.685126 -376.913059) (xy 140.67737 -376.859111)
			(xy 140.676884 -376.83186) (xy 138.759184 -376.83186) (xy 138.759184 -376.956828) (xy 138.758698 -376.984079)
			(xy 138.750942 -377.038027) (xy 138.735587 -377.090322) (xy 138.712945 -377.139899) (xy 138.683479 -377.185749)
			(xy 138.647788 -377.22694) (xy 138.606597 -377.262631) (xy 138.560747 -377.292097) (xy 138.51117 -377.314739)
			(xy 138.458875 -377.330094) (xy 138.404927 -377.33785) (xy 138.350425 -377.33785) (xy 138.296477 -377.330094)
			(xy 138.244182 -377.314739) (xy 138.194605 -377.292097) (xy 138.148755 -377.262631) (xy 138.107564 -377.22694)
			(xy 138.071873 -377.185749) (xy 138.042407 -377.139899) (xy 138.019765 -377.090322) (xy 138.00441 -377.038027)
			(xy 137.996654 -376.984079) (xy 137.996168 -376.956828) (xy 108.891058 -376.956828) (xy 108.888555 -376.965354)
			(xy 108.865913 -377.014931) (xy 108.836447 -377.060781) (xy 108.800756 -377.101972) (xy 108.759565 -377.137663)
			(xy 108.713715 -377.167129) (xy 108.664138 -377.189771) (xy 108.611843 -377.205126) (xy 108.557895 -377.212882)
			(xy 108.503393 -377.212882) (xy 108.449445 -377.205126) (xy 108.39715 -377.189771) (xy 108.347573 -377.167129)
			(xy 108.301723 -377.137663) (xy 108.260532 -377.101972) (xy 108.224841 -377.060781) (xy 108.195375 -377.014931)
			(xy 108.172733 -376.965354) (xy 108.157378 -376.913059) (xy 108.149622 -376.859111) (xy 108.149136 -376.83186)
			(xy 104.187244 -376.83186) (xy 104.187244 -376.956828) (xy 104.186758 -376.984097) (xy 104.178996 -377.038081)
			(xy 104.163631 -377.090411) (xy 104.140974 -377.140021) (xy 104.111488 -377.185902) (xy 104.075773 -377.227119)
			(xy 104.034556 -377.262834) (xy 103.988675 -377.29232) (xy 103.939065 -377.314977) (xy 103.886735 -377.330342)
			(xy 103.832751 -377.338104) (xy 103.778213 -377.338104) (xy 103.724229 -377.330342) (xy 103.671899 -377.314977)
			(xy 103.622289 -377.29232) (xy 103.576408 -377.262834) (xy 103.535191 -377.227119) (xy 103.499476 -377.185902)
			(xy 103.46999 -377.140021) (xy 103.447333 -377.090411) (xy 103.431968 -377.038081) (xy 103.424206 -376.984097)
			(xy 103.42372 -376.956828) (xy 74.319129 -376.956828) (xy 74.316599 -376.965443) (xy 74.293942 -377.015053)
			(xy 74.264456 -377.060934) (xy 74.228741 -377.102151) (xy 74.187524 -377.137866) (xy 74.141643 -377.167352)
			(xy 74.092033 -377.190009) (xy 74.039703 -377.205374) (xy 73.985719 -377.213136) (xy 73.931181 -377.213136)
			(xy 73.877197 -377.205374) (xy 73.824867 -377.190009) (xy 73.775257 -377.167352) (xy 73.729376 -377.137866)
			(xy 73.688159 -377.102151) (xy 73.652444 -377.060934) (xy 73.622958 -377.015053) (xy 73.600301 -376.965443)
			(xy 73.584936 -376.913113) (xy 73.577174 -376.859129) (xy 73.576688 -376.83186) (xy 71.659496 -376.83186)
			(xy 71.659496 -376.956828) (xy 71.65901 -376.984097) (xy 71.651248 -377.038081) (xy 71.635883 -377.090411)
			(xy 71.613226 -377.140021) (xy 71.58374 -377.185902) (xy 71.548025 -377.227119) (xy 71.506808 -377.262834)
			(xy 71.460927 -377.29232) (xy 71.411317 -377.314977) (xy 71.358987 -377.330342) (xy 71.305003 -377.338104)
			(xy 71.250465 -377.338104) (xy 71.196481 -377.330342) (xy 71.144151 -377.314977) (xy 71.094541 -377.29232)
			(xy 71.04866 -377.262834) (xy 71.007443 -377.227119) (xy 70.971728 -377.185902) (xy 70.942242 -377.140021)
			(xy 70.919585 -377.090411) (xy 70.90422 -377.038081) (xy 70.896458 -376.984097) (xy 70.895972 -376.956828)
			(xy 41.791381 -376.956828) (xy 41.788851 -376.965443) (xy 41.766194 -377.015053) (xy 41.736708 -377.060934)
			(xy 41.700993 -377.102151) (xy 41.659776 -377.137866) (xy 41.613895 -377.167352) (xy 41.564285 -377.190009)
			(xy 41.511955 -377.205374) (xy 41.457971 -377.213136) (xy 41.403433 -377.213136) (xy 41.349449 -377.205374)
			(xy 41.297119 -377.190009) (xy 41.247509 -377.167352) (xy 41.201628 -377.137866) (xy 41.160411 -377.102151)
			(xy 41.124696 -377.060934) (xy 41.09521 -377.015053) (xy 41.072553 -376.965443) (xy 41.057188 -376.913113)
			(xy 41.049426 -376.859129) (xy 41.04894 -376.83186) (xy 39.05568 -376.83186) (xy 39.046481 -376.93481)
			(xy 39.022717 -377.111506) (xy 38.991106 -377.286969) (xy 38.95171 -377.460849) (xy 38.904608 -377.632802)
			(xy 38.849892 -377.802486) (xy 38.787671 -377.969563) (xy 38.71807 -378.133704) (xy 38.641225 -378.29458)
			(xy 38.557291 -378.451874) (xy 38.466433 -378.605273) (xy 38.368831 -378.754472) (xy 38.26468 -378.899175)
			(xy 38.154187 -379.039095) (xy 38.03757 -379.173954) (xy 37.915061 -379.303484) (xy 37.786904 -379.427428)
			(xy 37.653353 -379.54554) (xy 37.514673 -379.657585) (xy 37.371139 -379.763342) (xy 37.223036 -379.862599)
			(xy 37.070659 -379.955161) (xy 36.91431 -380.040842) (xy 36.754299 -380.119474) (xy 36.590945 -380.1909)
			(xy 36.42457 -380.254978) (xy 36.255507 -380.31158) (xy 36.084678 -380.360428) (xy 70.895972 -380.360428)
			(xy 70.895972 -379.496828) (xy 70.896458 -379.469559) (xy 70.90422 -379.415575) (xy 70.919585 -379.363245)
			(xy 70.942242 -379.313635) (xy 70.971728 -379.267754) (xy 71.007443 -379.226537) (xy 71.04866 -379.190822)
			(xy 71.094541 -379.161336) (xy 71.144151 -379.138679) (xy 71.196481 -379.123314) (xy 71.250465 -379.115552)
			(xy 71.305003 -379.115552) (xy 71.358987 -379.123314) (xy 71.411317 -379.138679) (xy 71.460927 -379.161336)
			(xy 71.506808 -379.190822) (xy 71.548025 -379.226537) (xy 71.58374 -379.267754) (xy 71.613226 -379.313635)
			(xy 71.635883 -379.363245) (xy 71.651248 -379.415575) (xy 71.65901 -379.469559) (xy 71.659496 -379.496828)
			(xy 71.659496 -380.360428) (xy 103.42372 -380.360428) (xy 103.42372 -379.496828) (xy 103.424206 -379.469559)
			(xy 103.431968 -379.415575) (xy 103.447333 -379.363245) (xy 103.46999 -379.313635) (xy 103.499476 -379.267754)
			(xy 103.535191 -379.226537) (xy 103.576408 -379.190822) (xy 103.622289 -379.161336) (xy 103.671899 -379.138679)
			(xy 103.724229 -379.123314) (xy 103.778213 -379.115552) (xy 103.832751 -379.115552) (xy 103.886735 -379.123314)
			(xy 103.939065 -379.138679) (xy 103.988675 -379.161336) (xy 104.034556 -379.190822) (xy 104.075773 -379.226537)
			(xy 104.111488 -379.267754) (xy 104.140974 -379.313635) (xy 104.163631 -379.363245) (xy 104.178996 -379.415575)
			(xy 104.186758 -379.469559) (xy 104.187244 -379.496828) (xy 104.187244 -380.360428) (xy 137.996168 -380.360428)
			(xy 137.996168 -379.496828) (xy 137.996654 -379.469577) (xy 138.00441 -379.415629) (xy 138.019765 -379.363334)
			(xy 138.042407 -379.313757) (xy 138.071873 -379.267907) (xy 138.107564 -379.226716) (xy 138.148755 -379.191025)
			(xy 138.194605 -379.161559) (xy 138.244182 -379.138917) (xy 138.296477 -379.123562) (xy 138.350425 -379.115806)
			(xy 138.404927 -379.115806) (xy 138.458875 -379.123562) (xy 138.51117 -379.138917) (xy 138.560747 -379.161559)
			(xy 138.606597 -379.191025) (xy 138.647788 -379.226716) (xy 138.683479 -379.267907) (xy 138.712945 -379.313757)
			(xy 138.735587 -379.363334) (xy 138.750942 -379.415629) (xy 138.758698 -379.469577) (xy 138.759184 -379.496828)
			(xy 138.759184 -380.360428) (xy 170.523916 -380.360428) (xy 170.523916 -379.496828) (xy 170.524402 -379.469577)
			(xy 170.532158 -379.415629) (xy 170.547513 -379.363334) (xy 170.570155 -379.313757) (xy 170.599621 -379.267907)
			(xy 170.635312 -379.226716) (xy 170.676503 -379.191025) (xy 170.722353 -379.161559) (xy 170.77193 -379.138917)
			(xy 170.824225 -379.123562) (xy 170.878173 -379.115806) (xy 170.932675 -379.115806) (xy 170.986623 -379.123562)
			(xy 171.038918 -379.138917) (xy 171.088495 -379.161559) (xy 171.134345 -379.191025) (xy 171.175536 -379.226716)
			(xy 171.211227 -379.267907) (xy 171.240693 -379.313757) (xy 171.263335 -379.363334) (xy 171.27869 -379.415629)
			(xy 171.286446 -379.469577) (xy 171.286932 -379.496828) (xy 171.286932 -380.360428) (xy 171.286446 -380.387679)
			(xy 171.27869 -380.441627) (xy 171.263335 -380.493922) (xy 171.240693 -380.543499) (xy 171.211227 -380.589349)
			(xy 171.175536 -380.63054) (xy 171.134345 -380.666231) (xy 171.088495 -380.695697) (xy 171.038918 -380.718339)
			(xy 170.986623 -380.733694) (xy 170.932675 -380.74145) (xy 170.878173 -380.74145) (xy 170.824225 -380.733694)
			(xy 170.77193 -380.718339) (xy 170.722353 -380.695697) (xy 170.676503 -380.666231) (xy 170.635312 -380.63054)
			(xy 170.599621 -380.589349) (xy 170.570155 -380.543499) (xy 170.547513 -380.493922) (xy 170.532158 -380.441627)
			(xy 170.524402 -380.387679) (xy 170.523916 -380.360428) (xy 138.759184 -380.360428) (xy 138.758698 -380.387679)
			(xy 138.750942 -380.441627) (xy 138.735587 -380.493922) (xy 138.712945 -380.543499) (xy 138.683479 -380.589349)
			(xy 138.647788 -380.63054) (xy 138.606597 -380.666231) (xy 138.560747 -380.695697) (xy 138.51117 -380.718339)
			(xy 138.458875 -380.733694) (xy 138.404927 -380.74145) (xy 138.350425 -380.74145) (xy 138.296477 -380.733694)
			(xy 138.244182 -380.718339) (xy 138.194605 -380.695697) (xy 138.148755 -380.666231) (xy 138.107564 -380.63054)
			(xy 138.071873 -380.589349) (xy 138.042407 -380.543499) (xy 138.019765 -380.493922) (xy 138.00441 -380.441627)
			(xy 137.996654 -380.387679) (xy 137.996168 -380.360428) (xy 104.187244 -380.360428) (xy 104.186758 -380.387697)
			(xy 104.178996 -380.441681) (xy 104.163631 -380.494011) (xy 104.140974 -380.543621) (xy 104.111488 -380.589502)
			(xy 104.075773 -380.630719) (xy 104.034556 -380.666434) (xy 103.988675 -380.69592) (xy 103.939065 -380.718577)
			(xy 103.886735 -380.733942) (xy 103.832751 -380.741704) (xy 103.778213 -380.741704) (xy 103.724229 -380.733942)
			(xy 103.671899 -380.718577) (xy 103.622289 -380.69592) (xy 103.576408 -380.666434) (xy 103.535191 -380.630719)
			(xy 103.499476 -380.589502) (xy 103.46999 -380.543621) (xy 103.447333 -380.494011) (xy 103.431968 -380.441681)
			(xy 103.424206 -380.387697) (xy 103.42372 -380.360428) (xy 71.659496 -380.360428) (xy 71.65901 -380.387697)
			(xy 71.651248 -380.441681) (xy 71.635883 -380.494011) (xy 71.613226 -380.543621) (xy 71.58374 -380.589502)
			(xy 71.548025 -380.630719) (xy 71.506808 -380.666434) (xy 71.460927 -380.69592) (xy 71.411317 -380.718577)
			(xy 71.358987 -380.733942) (xy 71.305003 -380.741704) (xy 71.250465 -380.741704) (xy 71.196481 -380.733942)
			(xy 71.144151 -380.718577) (xy 71.094541 -380.69592) (xy 71.04866 -380.666434) (xy 71.007443 -380.630719)
			(xy 70.971728 -380.589502) (xy 70.942242 -380.543621) (xy 70.919585 -380.494011) (xy 70.90422 -380.441681)
			(xy 70.896458 -380.387697) (xy 70.895972 -380.360428) (xy 36.084678 -380.360428) (xy 36.08409 -380.360596)
			(xy 35.910659 -380.401926) (xy 35.735559 -380.43549) (xy 35.559139 -380.46122) (xy 35.381747 -380.479066)
			(xy 35.203736 -380.488992) (xy 35.025459 -380.490978) (xy 34.847272 -380.485021) (xy 34.669526 -380.471131)
			(xy 34.492576 -380.449338) (xy 34.316772 -380.419684) (xy 34.142464 -380.382227) (xy 33.969997 -380.337043)
			(xy 33.799714 -380.284221) (xy 33.631953 -380.223865) (xy 33.467048 -380.156097) (xy 33.305325 -380.081049)
			(xy 33.147106 -379.998872) (xy 32.992705 -379.909729) (xy 32.842428 -379.813795) (xy 32.696573 -379.711263)
			(xy 32.555431 -379.602335) (xy 32.419282 -379.487228) (xy 32.288395 -379.36617) (xy 32.163031 -379.239401)
			(xy 32.043438 -379.107174) (xy 31.929855 -378.969751) (xy 31.822506 -378.827404) (xy 31.721605 -378.680416)
			(xy 31.627352 -378.52908) (xy 31.539934 -378.373695) (xy 31.459524 -378.21457) (xy 31.386283 -378.052021)
			(xy 31.320356 -377.886371) (xy 31.261873 -377.717949) (xy 31.210951 -377.547088) (xy 31.167691 -377.374129)
			(xy 31.132179 -377.199414) (xy 31.104485 -377.02329) (xy 31.084664 -376.846108) (xy 31.072756 -376.668219)
			(xy 31.068784 -376.489976) (xy 2.509012 -376.489976) (xy 2.509012 -382.36906) (xy 41.04894 -382.36906)
			(xy 41.04894 -381.50546) (xy 41.049426 -381.478191) (xy 41.057188 -381.424207) (xy 41.072553 -381.371877)
			(xy 41.09521 -381.322267) (xy 41.124696 -381.276386) (xy 41.160411 -381.235169) (xy 41.201628 -381.199454)
			(xy 41.247509 -381.169968) (xy 41.297119 -381.147311) (xy 41.349449 -381.131946) (xy 41.403433 -381.124184)
			(xy 41.457971 -381.124184) (xy 41.511955 -381.131946) (xy 41.564285 -381.147311) (xy 41.613895 -381.169968)
			(xy 41.659776 -381.199454) (xy 41.700993 -381.235169) (xy 41.736708 -381.276386) (xy 41.766194 -381.322267)
			(xy 41.788851 -381.371877) (xy 41.804216 -381.424207) (xy 41.811978 -381.478191) (xy 41.812464 -381.50546)
			(xy 41.812464 -382.36906) (xy 73.576688 -382.36906) (xy 73.576688 -381.50546) (xy 73.577174 -381.478191)
			(xy 73.584936 -381.424207) (xy 73.600301 -381.371877) (xy 73.622958 -381.322267) (xy 73.652444 -381.276386)
			(xy 73.688159 -381.235169) (xy 73.729376 -381.199454) (xy 73.775257 -381.169968) (xy 73.824867 -381.147311)
			(xy 73.877197 -381.131946) (xy 73.931181 -381.124184) (xy 73.985719 -381.124184) (xy 74.039703 -381.131946)
			(xy 74.092033 -381.147311) (xy 74.141643 -381.169968) (xy 74.187524 -381.199454) (xy 74.228741 -381.235169)
			(xy 74.264456 -381.276386) (xy 74.293942 -381.322267) (xy 74.316599 -381.371877) (xy 74.331964 -381.424207)
			(xy 74.339726 -381.478191) (xy 74.340212 -381.50546) (xy 74.340212 -382.36906) (xy 108.149136 -382.36906)
			(xy 108.149136 -381.50546) (xy 108.149622 -381.478209) (xy 108.157378 -381.424261) (xy 108.172733 -381.371966)
			(xy 108.195375 -381.322389) (xy 108.224841 -381.276539) (xy 108.260532 -381.235348) (xy 108.301723 -381.199657)
			(xy 108.347573 -381.170191) (xy 108.39715 -381.147549) (xy 108.449445 -381.132194) (xy 108.503393 -381.124438)
			(xy 108.557895 -381.124438) (xy 108.611843 -381.132194) (xy 108.664138 -381.147549) (xy 108.713715 -381.170191)
			(xy 108.759565 -381.199657) (xy 108.800756 -381.235348) (xy 108.836447 -381.276539) (xy 108.865913 -381.322389)
			(xy 108.888555 -381.371966) (xy 108.90391 -381.424261) (xy 108.911666 -381.478209) (xy 108.912152 -381.50546)
			(xy 108.912152 -382.36906) (xy 140.676884 -382.36906) (xy 140.676884 -381.50546) (xy 140.67737 -381.478209)
			(xy 140.685126 -381.424261) (xy 140.700481 -381.371966) (xy 140.723123 -381.322389) (xy 140.752589 -381.276539)
			(xy 140.78828 -381.235348) (xy 140.829471 -381.199657) (xy 140.875321 -381.170191) (xy 140.924898 -381.147549)
			(xy 140.977193 -381.132194) (xy 141.031141 -381.124438) (xy 141.085643 -381.124438) (xy 141.139591 -381.132194)
			(xy 141.191886 -381.147549) (xy 141.241463 -381.170191) (xy 141.287313 -381.199657) (xy 141.328504 -381.235348)
			(xy 141.364195 -381.276539) (xy 141.393661 -381.322389) (xy 141.416303 -381.371966) (xy 141.431658 -381.424261)
			(xy 141.439414 -381.478209) (xy 141.4399 -381.50546) (xy 141.4399 -382.36906) (xy 141.439414 -382.396311)
			(xy 141.431658 -382.450259) (xy 141.416303 -382.502554) (xy 141.393661 -382.552131) (xy 141.364195 -382.597981)
			(xy 141.328504 -382.639172) (xy 141.287313 -382.674863) (xy 141.241463 -382.704329) (xy 141.191886 -382.726971)
			(xy 141.139591 -382.742326) (xy 141.085643 -382.750082) (xy 141.031141 -382.750082) (xy 140.977193 -382.742326)
			(xy 140.924898 -382.726971) (xy 140.875321 -382.704329) (xy 140.829471 -382.674863) (xy 140.78828 -382.639172)
			(xy 140.752589 -382.597981) (xy 140.723123 -382.552131) (xy 140.700481 -382.502554) (xy 140.685126 -382.450259)
			(xy 140.67737 -382.396311) (xy 140.676884 -382.36906) (xy 108.912152 -382.36906) (xy 108.911666 -382.396311)
			(xy 108.90391 -382.450259) (xy 108.888555 -382.502554) (xy 108.865913 -382.552131) (xy 108.836447 -382.597981)
			(xy 108.800756 -382.639172) (xy 108.759565 -382.674863) (xy 108.713715 -382.704329) (xy 108.664138 -382.726971)
			(xy 108.611843 -382.742326) (xy 108.557895 -382.750082) (xy 108.503393 -382.750082) (xy 108.449445 -382.742326)
			(xy 108.39715 -382.726971) (xy 108.347573 -382.704329) (xy 108.301723 -382.674863) (xy 108.260532 -382.639172)
			(xy 108.224841 -382.597981) (xy 108.195375 -382.552131) (xy 108.172733 -382.502554) (xy 108.157378 -382.450259)
			(xy 108.149622 -382.396311) (xy 108.149136 -382.36906) (xy 74.340212 -382.36906) (xy 74.339726 -382.396329)
			(xy 74.331964 -382.450313) (xy 74.316599 -382.502643) (xy 74.293942 -382.552253) (xy 74.264456 -382.598134)
			(xy 74.228741 -382.639351) (xy 74.187524 -382.675066) (xy 74.141643 -382.704552) (xy 74.092033 -382.727209)
			(xy 74.039703 -382.742574) (xy 73.985719 -382.750336) (xy 73.931181 -382.750336) (xy 73.877197 -382.742574)
			(xy 73.824867 -382.727209) (xy 73.775257 -382.704552) (xy 73.729376 -382.675066) (xy 73.688159 -382.639351)
			(xy 73.652444 -382.598134) (xy 73.622958 -382.552253) (xy 73.600301 -382.502643) (xy 73.584936 -382.450313)
			(xy 73.577174 -382.396329) (xy 73.576688 -382.36906) (xy 41.812464 -382.36906) (xy 41.811978 -382.396329)
			(xy 41.804216 -382.450313) (xy 41.788851 -382.502643) (xy 41.766194 -382.552253) (xy 41.736708 -382.598134)
			(xy 41.700993 -382.639351) (xy 41.659776 -382.675066) (xy 41.613895 -382.704552) (xy 41.564285 -382.727209)
			(xy 41.511955 -382.742574) (xy 41.457971 -382.750336) (xy 41.403433 -382.750336) (xy 41.349449 -382.742574)
			(xy 41.297119 -382.727209) (xy 41.247509 -382.704552) (xy 41.201628 -382.675066) (xy 41.160411 -382.639351)
			(xy 41.124696 -382.598134) (xy 41.09521 -382.552253) (xy 41.072553 -382.502643) (xy 41.057188 -382.450313)
			(xy 41.049426 -382.396329) (xy 41.04894 -382.36906) (xy 2.509012 -382.36906) (xy 2.509012 -384.869944)
			(xy 287.06878 -384.869944) (xy 287.072752 -384.691701) (xy 287.08466 -384.513812) (xy 287.104481 -384.33663)
			(xy 287.132175 -384.160506) (xy 287.167687 -383.985791) (xy 287.210947 -383.812832) (xy 287.261869 -383.641971)
			(xy 287.320352 -383.473549) (xy 287.386279 -383.307899) (xy 287.45952 -383.14535) (xy 287.53993 -382.986225)
			(xy 287.627348 -382.83084) (xy 287.721601 -382.679504) (xy 287.822502 -382.532516) (xy 287.929851 -382.390169)
			(xy 288.043434 -382.252746) (xy 288.163027 -382.120519) (xy 288.288391 -381.99375) (xy 288.419278 -381.872692)
			(xy 288.555427 -381.757585) (xy 288.696569 -381.648657) (xy 288.842424 -381.546125) (xy 288.992701 -381.450191)
			(xy 289.147102 -381.361048) (xy 289.305321 -381.278871) (xy 289.467044 -381.203823) (xy 289.631949 -381.136055)
			(xy 289.79971 -381.075699) (xy 289.969993 -381.022877) (xy 290.14246 -380.977693) (xy 290.316768 -380.940236)
			(xy 290.492572 -380.910582) (xy 290.669522 -380.888789) (xy 290.847268 -380.874899) (xy 291.025455 -380.868942)
			(xy 291.203732 -380.870928) (xy 291.381743 -380.880854) (xy 291.559135 -380.8987) (xy 291.735555 -380.92443)
			(xy 291.910655 -380.957994) (xy 292.084086 -380.999324) (xy 292.255503 -381.04834) (xy 292.424566 -381.104942)
			(xy 292.590941 -381.16902) (xy 292.754295 -381.240446) (xy 292.914306 -381.319078) (xy 293.070655 -381.404759)
			(xy 293.223032 -381.497321) (xy 293.371135 -381.596578) (xy 293.514669 -381.702335) (xy 293.653349 -381.81438)
			(xy 293.7869 -381.932492) (xy 293.915057 -382.056436) (xy 294.037566 -382.185966) (xy 294.154183 -382.320825)
			(xy 294.194727 -382.372167) (xy 303.739054 -382.372167) (xy 303.739054 -382.317633) (xy 303.746815 -382.263654)
			(xy 303.762179 -382.211329) (xy 303.784833 -382.161723) (xy 303.814317 -382.115846) (xy 303.850029 -382.074631)
			(xy 303.891242 -382.038919) (xy 303.937119 -382.009435) (xy 303.986725 -381.986781) (xy 304.03905 -381.971416)
			(xy 304.093029 -381.963655) (xy 304.120296 -381.963168) (xy 304.983896 -381.963168) (xy 305.011169 -381.963571)
			(xy 305.065161 -381.971334) (xy 305.117498 -381.986701) (xy 305.167116 -382.00936) (xy 305.213003 -382.03885)
			(xy 305.254227 -382.07457) (xy 305.289948 -382.115793) (xy 305.319438 -382.161681) (xy 305.342098 -382.211298)
			(xy 305.357466 -382.263635) (xy 305.365228 -382.317627) (xy 305.365228 -382.372167) (xy 310.546254 -382.372167)
			(xy 310.546254 -382.317633) (xy 310.554015 -382.263654) (xy 310.569379 -382.211329) (xy 310.592033 -382.161723)
			(xy 310.621517 -382.115846) (xy 310.657229 -382.074631) (xy 310.698442 -382.038919) (xy 310.744319 -382.009435)
			(xy 310.793925 -381.986781) (xy 310.84625 -381.971416) (xy 310.900229 -381.963655) (xy 310.927496 -381.963168)
			(xy 311.791096 -381.963168) (xy 311.818369 -381.963571) (xy 311.872361 -381.971334) (xy 311.924698 -381.986701)
			(xy 311.974316 -382.00936) (xy 312.020203 -382.03885) (xy 312.061427 -382.07457) (xy 312.097148 -382.115793)
			(xy 312.126638 -382.161681) (xy 312.149298 -382.211298) (xy 312.164666 -382.263635) (xy 312.172428 -382.317627)
			(xy 312.172428 -382.372167) (xy 317.353454 -382.372167) (xy 317.353454 -382.317633) (xy 317.361215 -382.263654)
			(xy 317.376579 -382.211329) (xy 317.399233 -382.161723) (xy 317.428717 -382.115846) (xy 317.464429 -382.074631)
			(xy 317.505642 -382.038919) (xy 317.551519 -382.009435) (xy 317.601125 -381.986781) (xy 317.65345 -381.971416)
			(xy 317.707429 -381.963655) (xy 317.734696 -381.963168) (xy 318.598296 -381.963168) (xy 318.625569 -381.963571)
			(xy 318.679561 -381.971334) (xy 318.731898 -381.986701) (xy 318.781516 -382.00936) (xy 318.827403 -382.03885)
			(xy 318.868627 -382.07457) (xy 318.904348 -382.115793) (xy 318.933838 -382.161681) (xy 318.956498 -382.211298)
			(xy 318.971866 -382.263635) (xy 318.979628 -382.317627) (xy 318.979628 -382.372171) (xy 336.266732 -382.372171)
			(xy 336.266732 -382.317629) (xy 336.274494 -382.263643) (xy 336.289861 -382.211311) (xy 336.312521 -382.161698)
			(xy 336.34201 -382.115816) (xy 336.377729 -382.074598) (xy 336.418951 -382.038884) (xy 336.464837 -382.009399)
			(xy 336.514452 -381.986746) (xy 336.566786 -381.971385) (xy 336.620773 -381.963628) (xy 336.648044 -381.963168)
			(xy 337.511644 -381.963168) (xy 337.538913 -381.963598) (xy 337.592897 -381.971365) (xy 337.645225 -381.986735)
			(xy 337.694833 -382.009396) (xy 337.740712 -382.038885) (xy 337.781928 -382.074603) (xy 337.817641 -382.115823)
			(xy 337.847125 -382.161705) (xy 337.86978 -382.211316) (xy 337.885144 -382.263647) (xy 337.892906 -382.31763)
			(xy 337.892906 -382.37217) (xy 337.892906 -382.372171) (xy 343.073932 -382.372171) (xy 343.073932 -382.317629)
			(xy 343.081694 -382.263643) (xy 343.097061 -382.211311) (xy 343.119721 -382.161698) (xy 343.14921 -382.115816)
			(xy 343.184929 -382.074598) (xy 343.226151 -382.038884) (xy 343.272037 -382.009399) (xy 343.321652 -381.986746)
			(xy 343.373986 -381.971385) (xy 343.427973 -381.963628) (xy 343.455244 -381.963168) (xy 344.318844 -381.963168)
			(xy 344.346113 -381.963598) (xy 344.400097 -381.971365) (xy 344.452425 -381.986735) (xy 344.502033 -382.009396)
			(xy 344.547912 -382.038885) (xy 344.589128 -382.074603) (xy 344.624841 -382.115823) (xy 344.654325 -382.161705)
			(xy 344.67698 -382.211316) (xy 344.692344 -382.263647) (xy 344.700106 -382.31763) (xy 344.700106 -382.37217)
			(xy 344.700106 -382.372171) (xy 349.881132 -382.372171) (xy 349.881132 -382.317629) (xy 349.888894 -382.263643)
			(xy 349.904261 -382.211311) (xy 349.926921 -382.161698) (xy 349.95641 -382.115816) (xy 349.992129 -382.074598)
			(xy 350.033351 -382.038884) (xy 350.079237 -382.009399) (xy 350.128852 -381.986746) (xy 350.181186 -381.971385)
			(xy 350.235173 -381.963628) (xy 350.262444 -381.963168) (xy 351.126044 -381.963168) (xy 351.153313 -381.963598)
			(xy 351.207297 -381.971365) (xy 351.259625 -381.986735) (xy 351.309233 -382.009396) (xy 351.355112 -382.038885)
			(xy 351.396328 -382.074603) (xy 351.432041 -382.115823) (xy 351.461525 -382.161705) (xy 351.48418 -382.211316)
			(xy 351.499544 -382.263647) (xy 351.507306 -382.31763) (xy 351.507306 -382.372167) (xy 370.839254 -382.372167)
			(xy 370.839254 -382.317633) (xy 370.847015 -382.263654) (xy 370.862379 -382.21133) (xy 370.885033 -382.161724)
			(xy 370.914516 -382.115847) (xy 370.950227 -382.074633) (xy 370.991441 -382.03892) (xy 371.037317 -382.009437)
			(xy 371.086922 -381.986782) (xy 371.139247 -381.971417) (xy 371.193225 -381.963655) (xy 371.220492 -381.963168)
			(xy 372.084092 -381.963168) (xy 372.111366 -381.963571) (xy 372.165357 -381.971333) (xy 372.217695 -381.9867)
			(xy 372.267313 -382.009359) (xy 372.313202 -382.038848) (xy 372.354426 -382.074568) (xy 372.390147 -382.115792)
			(xy 372.419638 -382.16168) (xy 372.442298 -382.211297) (xy 372.457665 -382.263635) (xy 372.465428 -382.317626)
			(xy 372.465428 -382.372167) (xy 377.646454 -382.372167) (xy 377.646454 -382.317633) (xy 377.654215 -382.263654)
			(xy 377.669579 -382.21133) (xy 377.692233 -382.161724) (xy 377.721716 -382.115847) (xy 377.757427 -382.074633)
			(xy 377.798641 -382.03892) (xy 377.844517 -382.009437) (xy 377.894122 -381.986782) (xy 377.946447 -381.971417)
			(xy 378.000425 -381.963655) (xy 378.027692 -381.963168) (xy 378.891292 -381.963168) (xy 378.918566 -381.963571)
			(xy 378.972557 -381.971333) (xy 379.024895 -381.9867) (xy 379.074513 -382.009359) (xy 379.120402 -382.038848)
			(xy 379.161626 -382.074568) (xy 379.197347 -382.115792) (xy 379.226838 -382.16168) (xy 379.249498 -382.211297)
			(xy 379.264865 -382.263635) (xy 379.272628 -382.317626) (xy 379.272628 -382.372167) (xy 384.453654 -382.372167)
			(xy 384.453654 -382.317633) (xy 384.461415 -382.263654) (xy 384.476779 -382.21133) (xy 384.499433 -382.161724)
			(xy 384.528916 -382.115847) (xy 384.564627 -382.074633) (xy 384.605841 -382.03892) (xy 384.651717 -382.009437)
			(xy 384.701322 -381.986782) (xy 384.753647 -381.971417) (xy 384.807625 -381.963655) (xy 384.834892 -381.963168)
			(xy 385.698492 -381.963168) (xy 385.725766 -381.963571) (xy 385.779757 -381.971333) (xy 385.832095 -381.9867)
			(xy 385.881713 -382.009359) (xy 385.927602 -382.038848) (xy 385.968826 -382.074568) (xy 386.004547 -382.115792)
			(xy 386.034038 -382.16168) (xy 386.056698 -382.211297) (xy 386.072065 -382.263635) (xy 386.079828 -382.317626)
			(xy 386.079828 -382.372171) (xy 403.366932 -382.372171) (xy 403.366932 -382.317629) (xy 403.374694 -382.263643)
			(xy 403.390061 -382.211311) (xy 403.41272 -382.161699) (xy 403.442209 -382.115817) (xy 403.477928 -382.0746)
			(xy 403.51915 -382.038885) (xy 403.565035 -382.009401) (xy 403.614649 -381.986747) (xy 403.666982 -381.971386)
			(xy 403.720969 -381.963629) (xy 403.74824 -381.963168) (xy 404.61184 -381.963168) (xy 404.63911 -381.963597)
			(xy 404.693093 -381.971364) (xy 404.745422 -381.986734) (xy 404.795031 -382.009394) (xy 404.840911 -382.038884)
			(xy 404.882127 -382.074602) (xy 404.91784 -382.115822) (xy 404.947325 -382.161704) (xy 404.96998 -382.211316)
			(xy 404.985344 -382.263646) (xy 404.993106 -382.31763) (xy 404.993106 -382.37217) (xy 404.993106 -382.372171)
			(xy 410.174132 -382.372171) (xy 410.174132 -382.317629) (xy 410.181894 -382.263643) (xy 410.197261 -382.211311)
			(xy 410.21992 -382.161699) (xy 410.249409 -382.115817) (xy 410.285128 -382.0746) (xy 410.32635 -382.038885)
			(xy 410.372235 -382.009401) (xy 410.421849 -381.986747) (xy 410.474182 -381.971386) (xy 410.528169 -381.963629)
			(xy 410.55544 -381.963168) (xy 411.41904 -381.963168) (xy 411.44631 -381.963597) (xy 411.500293 -381.971364)
			(xy 411.552622 -381.986734) (xy 411.602231 -382.009394) (xy 411.648111 -382.038884) (xy 411.689327 -382.074602)
			(xy 411.72504 -382.115822) (xy 411.754525 -382.161704) (xy 411.77718 -382.211316) (xy 411.792544 -382.263646)
			(xy 411.800306 -382.31763) (xy 411.800306 -382.37217) (xy 411.800306 -382.372171) (xy 416.981332 -382.372171)
			(xy 416.981332 -382.317629) (xy 416.989094 -382.263643) (xy 417.004461 -382.211311) (xy 417.02712 -382.161699)
			(xy 417.056609 -382.115817) (xy 417.092328 -382.0746) (xy 417.13355 -382.038885) (xy 417.179435 -382.009401)
			(xy 417.229049 -381.986747) (xy 417.281382 -381.971386) (xy 417.335369 -381.963629) (xy 417.36264 -381.963168)
			(xy 418.22624 -381.963168) (xy 418.25351 -381.963597) (xy 418.307493 -381.971364) (xy 418.359822 -381.986734)
			(xy 418.409431 -382.009394) (xy 418.455311 -382.038884) (xy 418.496527 -382.074602) (xy 418.53224 -382.115822)
			(xy 418.561725 -382.161704) (xy 418.58438 -382.211316) (xy 418.599744 -382.263646) (xy 418.607506 -382.31763)
			(xy 418.607506 -382.37217) (xy 418.599744 -382.426154) (xy 418.58438 -382.478484) (xy 418.561725 -382.528096)
			(xy 418.53224 -382.573978) (xy 418.496527 -382.615198) (xy 418.455311 -382.650916) (xy 418.409431 -382.680406)
			(xy 418.359822 -382.703066) (xy 418.307493 -382.718436) (xy 418.25351 -382.726203) (xy 418.22624 -382.726692)
			(xy 417.36264 -382.726692) (xy 417.335369 -382.726171) (xy 417.281382 -382.718414) (xy 417.229049 -382.703053)
			(xy 417.179435 -382.680399) (xy 417.13355 -382.650915) (xy 417.092328 -382.6152) (xy 417.056609 -382.573983)
			(xy 417.02712 -382.528101) (xy 417.004461 -382.478489) (xy 416.989094 -382.426157) (xy 416.981332 -382.372171)
			(xy 411.800306 -382.372171) (xy 411.792544 -382.426154) (xy 411.77718 -382.478484) (xy 411.754525 -382.528096)
			(xy 411.72504 -382.573978) (xy 411.689327 -382.615198) (xy 411.648111 -382.650916) (xy 411.602231 -382.680406)
			(xy 411.552622 -382.703066) (xy 411.500293 -382.718436) (xy 411.44631 -382.726203) (xy 411.41904 -382.726692)
			(xy 410.55544 -382.726692) (xy 410.528169 -382.726171) (xy 410.474182 -382.718414) (xy 410.421849 -382.703053)
			(xy 410.372235 -382.680399) (xy 410.32635 -382.650915) (xy 410.285128 -382.6152) (xy 410.249409 -382.573983)
			(xy 410.21992 -382.528101) (xy 410.197261 -382.478489) (xy 410.181894 -382.426157) (xy 410.174132 -382.372171)
			(xy 404.993106 -382.372171) (xy 404.985344 -382.426154) (xy 404.96998 -382.478484) (xy 404.947325 -382.528096)
			(xy 404.91784 -382.573978) (xy 404.882127 -382.615198) (xy 404.840911 -382.650916) (xy 404.795031 -382.680406)
			(xy 404.745422 -382.703066) (xy 404.693093 -382.718436) (xy 404.63911 -382.726203) (xy 404.61184 -382.726692)
			(xy 403.74824 -382.726692) (xy 403.720969 -382.726171) (xy 403.666982 -382.718414) (xy 403.614649 -382.703053)
			(xy 403.565035 -382.680399) (xy 403.51915 -382.650915) (xy 403.477928 -382.6152) (xy 403.442209 -382.573983)
			(xy 403.41272 -382.528101) (xy 403.390061 -382.478489) (xy 403.374694 -382.426157) (xy 403.366932 -382.372171)
			(xy 386.079828 -382.372171) (xy 386.079828 -382.372174) (xy 386.072065 -382.426165) (xy 386.056698 -382.478503)
			(xy 386.034038 -382.52812) (xy 386.004547 -382.574008) (xy 385.968826 -382.615232) (xy 385.927602 -382.650952)
			(xy 385.881713 -382.680441) (xy 385.832095 -382.7031) (xy 385.779757 -382.718467) (xy 385.725766 -382.726229)
			(xy 385.698492 -382.726692) (xy 384.834892 -382.726692) (xy 384.807625 -382.726145) (xy 384.753647 -382.718383)
			(xy 384.701322 -382.703018) (xy 384.651717 -382.680363) (xy 384.605841 -382.65088) (xy 384.564627 -382.615167)
			(xy 384.528916 -382.573953) (xy 384.499433 -382.528076) (xy 384.476779 -382.47847) (xy 384.461415 -382.426146)
			(xy 384.453654 -382.372167) (xy 379.272628 -382.372167) (xy 379.272628 -382.372174) (xy 379.264865 -382.426165)
			(xy 379.249498 -382.478503) (xy 379.226838 -382.52812) (xy 379.197347 -382.574008) (xy 379.161626 -382.615232)
			(xy 379.120402 -382.650952) (xy 379.074513 -382.680441) (xy 379.024895 -382.7031) (xy 378.972557 -382.718467)
			(xy 378.918566 -382.726229) (xy 378.891292 -382.726692) (xy 378.027692 -382.726692) (xy 378.000425 -382.726145)
			(xy 377.946447 -382.718383) (xy 377.894122 -382.703018) (xy 377.844517 -382.680363) (xy 377.798641 -382.65088)
			(xy 377.757427 -382.615167) (xy 377.721716 -382.573953) (xy 377.692233 -382.528076) (xy 377.669579 -382.47847)
			(xy 377.654215 -382.426146) (xy 377.646454 -382.372167) (xy 372.465428 -382.372167) (xy 372.465428 -382.372174)
			(xy 372.457665 -382.426165) (xy 372.442298 -382.478503) (xy 372.419638 -382.52812) (xy 372.390147 -382.574008)
			(xy 372.354426 -382.615232) (xy 372.313202 -382.650952) (xy 372.267313 -382.680441) (xy 372.217695 -382.7031)
			(xy 372.165357 -382.718467) (xy 372.111366 -382.726229) (xy 372.084092 -382.726692) (xy 371.220492 -382.726692)
			(xy 371.193225 -382.726145) (xy 371.139247 -382.718383) (xy 371.086922 -382.703018) (xy 371.037317 -382.680363)
			(xy 370.991441 -382.65088) (xy 370.950227 -382.615167) (xy 370.914516 -382.573953) (xy 370.885033 -382.528076)
			(xy 370.862379 -382.47847) (xy 370.847015 -382.426146) (xy 370.839254 -382.372167) (xy 351.507306 -382.372167)
			(xy 351.507306 -382.37217) (xy 351.499544 -382.426153) (xy 351.48418 -382.478484) (xy 351.461525 -382.528095)
			(xy 351.432041 -382.573977) (xy 351.396328 -382.615197) (xy 351.355112 -382.650915) (xy 351.309233 -382.680404)
			(xy 351.259625 -382.703065) (xy 351.207297 -382.718435) (xy 351.153313 -382.726202) (xy 351.126044 -382.726692)
			(xy 350.262444 -382.726692) (xy 350.235173 -382.726172) (xy 350.181186 -382.718415) (xy 350.128852 -382.703054)
			(xy 350.079237 -382.680401) (xy 350.033351 -382.650916) (xy 349.992129 -382.615202) (xy 349.95641 -382.573984)
			(xy 349.926921 -382.528102) (xy 349.904261 -382.478489) (xy 349.888894 -382.426157) (xy 349.881132 -382.372171)
			(xy 344.700106 -382.372171) (xy 344.692344 -382.426153) (xy 344.67698 -382.478484) (xy 344.654325 -382.528095)
			(xy 344.624841 -382.573977) (xy 344.589128 -382.615197) (xy 344.547912 -382.650915) (xy 344.502033 -382.680404)
			(xy 344.452425 -382.703065) (xy 344.400097 -382.718435) (xy 344.346113 -382.726202) (xy 344.318844 -382.726692)
			(xy 343.455244 -382.726692) (xy 343.427973 -382.726172) (xy 343.373986 -382.718415) (xy 343.321652 -382.703054)
			(xy 343.272037 -382.680401) (xy 343.226151 -382.650916) (xy 343.184929 -382.615202) (xy 343.14921 -382.573984)
			(xy 343.119721 -382.528102) (xy 343.097061 -382.478489) (xy 343.081694 -382.426157) (xy 343.073932 -382.372171)
			(xy 337.892906 -382.372171) (xy 337.885144 -382.426153) (xy 337.86978 -382.478484) (xy 337.847125 -382.528095)
			(xy 337.817641 -382.573977) (xy 337.781928 -382.615197) (xy 337.740712 -382.650915) (xy 337.694833 -382.680404)
			(xy 337.645225 -382.703065) (xy 337.592897 -382.718435) (xy 337.538913 -382.726202) (xy 337.511644 -382.726692)
			(xy 336.648044 -382.726692) (xy 336.620773 -382.726172) (xy 336.566786 -382.718415) (xy 336.514452 -382.703054)
			(xy 336.464837 -382.680401) (xy 336.418951 -382.650916) (xy 336.377729 -382.615202) (xy 336.34201 -382.573984)
			(xy 336.312521 -382.528102) (xy 336.289861 -382.478489) (xy 336.274494 -382.426157) (xy 336.266732 -382.372171)
			(xy 318.979628 -382.372171) (xy 318.979628 -382.372173) (xy 318.971866 -382.426165) (xy 318.956498 -382.478502)
			(xy 318.933838 -382.528119) (xy 318.904348 -382.574007) (xy 318.868627 -382.61523) (xy 318.827403 -382.65095)
			(xy 318.781516 -382.68044) (xy 318.731898 -382.703099) (xy 318.679561 -382.718466) (xy 318.625569 -382.726229)
			(xy 318.598296 -382.726692) (xy 317.734696 -382.726692) (xy 317.707429 -382.726145) (xy 317.65345 -382.718384)
			(xy 317.601125 -382.703019) (xy 317.551519 -382.680365) (xy 317.505642 -382.650881) (xy 317.464429 -382.615169)
			(xy 317.428717 -382.573954) (xy 317.399233 -382.528077) (xy 317.376579 -382.478471) (xy 317.361215 -382.426146)
			(xy 317.353454 -382.372167) (xy 312.172428 -382.372167) (xy 312.172428 -382.372173) (xy 312.164666 -382.426165)
			(xy 312.149298 -382.478502) (xy 312.126638 -382.528119) (xy 312.097148 -382.574007) (xy 312.061427 -382.61523)
			(xy 312.020203 -382.65095) (xy 311.974316 -382.68044) (xy 311.924698 -382.703099) (xy 311.872361 -382.718466)
			(xy 311.818369 -382.726229) (xy 311.791096 -382.726692) (xy 310.927496 -382.726692) (xy 310.900229 -382.726145)
			(xy 310.84625 -382.718384) (xy 310.793925 -382.703019) (xy 310.744319 -382.680365) (xy 310.698442 -382.650881)
			(xy 310.657229 -382.615169) (xy 310.621517 -382.573954) (xy 310.592033 -382.528077) (xy 310.569379 -382.478471)
			(xy 310.554015 -382.426146) (xy 310.546254 -382.372167) (xy 305.365228 -382.372167) (xy 305.365228 -382.372173)
			(xy 305.357466 -382.426165) (xy 305.342098 -382.478502) (xy 305.319438 -382.528119) (xy 305.289948 -382.574007)
			(xy 305.254227 -382.61523) (xy 305.213003 -382.65095) (xy 305.167116 -382.68044) (xy 305.117498 -382.703099)
			(xy 305.065161 -382.718466) (xy 305.011169 -382.726229) (xy 304.983896 -382.726692) (xy 304.120296 -382.726692)
			(xy 304.093029 -382.726145) (xy 304.03905 -382.718384) (xy 303.986725 -382.703019) (xy 303.937119 -382.680365)
			(xy 303.891242 -382.650881) (xy 303.850029 -382.615169) (xy 303.814317 -382.573954) (xy 303.784833 -382.528077)
			(xy 303.762179 -382.478471) (xy 303.746815 -382.426146) (xy 303.739054 -382.372167) (xy 294.194727 -382.372167)
			(xy 294.264676 -382.460745) (xy 294.368827 -382.605448) (xy 294.466429 -382.754647) (xy 294.557287 -382.908046)
			(xy 294.641221 -383.06534) (xy 294.718066 -383.226216) (xy 294.787667 -383.390357) (xy 294.849888 -383.557434)
			(xy 294.904604 -383.727118) (xy 294.951706 -383.899071) (xy 294.991102 -384.072951) (xy 295.022713 -384.248414)
			(xy 295.046477 -384.42511) (xy 295.062345 -384.60269) (xy 295.070287 -384.7808) (xy 295.070784 -384.869944)
			(xy 295.070287 -384.959088) (xy 295.062345 -385.137198) (xy 295.055495 -385.21386) (xy 297.048936 -385.21386)
			(xy 297.048936 -384.35026) (xy 297.049422 -384.323009) (xy 297.057178 -384.269061) (xy 297.072533 -384.216766)
			(xy 297.095175 -384.167189) (xy 297.124641 -384.121339) (xy 297.160332 -384.080148) (xy 297.201523 -384.044457)
			(xy 297.247373 -384.014991) (xy 297.29695 -383.992349) (xy 297.349245 -383.976994) (xy 297.403193 -383.969238)
			(xy 297.457695 -383.969238) (xy 297.511643 -383.976994) (xy 297.563938 -383.992349) (xy 297.613515 -384.014991)
			(xy 297.659365 -384.044457) (xy 297.700556 -384.080148) (xy 297.736247 -384.121339) (xy 297.765713 -384.167189)
			(xy 297.788355 -384.216766) (xy 297.80371 -384.269061) (xy 297.811466 -384.323009) (xy 297.811952 -384.35026)
			(xy 297.811952 -385.21386) (xy 297.811466 -385.241111) (xy 297.80371 -385.295059) (xy 297.790858 -385.338828)
			(xy 326.895968 -385.338828) (xy 326.895968 -384.475228) (xy 326.896454 -384.447977) (xy 326.90421 -384.394029)
			(xy 326.919565 -384.341734) (xy 326.942207 -384.292157) (xy 326.971673 -384.246307) (xy 327.007364 -384.205116)
			(xy 327.048555 -384.169425) (xy 327.094405 -384.139959) (xy 327.143982 -384.117317) (xy 327.196277 -384.101962)
			(xy 327.250225 -384.094206) (xy 327.304727 -384.094206) (xy 327.358675 -384.101962) (xy 327.41097 -384.117317)
			(xy 327.460547 -384.139959) (xy 327.506397 -384.169425) (xy 327.547588 -384.205116) (xy 327.583279 -384.246307)
			(xy 327.612745 -384.292157) (xy 327.635387 -384.341734) (xy 327.650742 -384.394029) (xy 327.658498 -384.447977)
			(xy 327.658984 -384.475228) (xy 327.658984 -385.21386) (xy 329.576684 -385.21386) (xy 329.576684 -384.35026)
			(xy 329.57717 -384.323009) (xy 329.584926 -384.269061) (xy 329.600281 -384.216766) (xy 329.622923 -384.167189)
			(xy 329.652389 -384.121339) (xy 329.68808 -384.080148) (xy 329.729271 -384.044457) (xy 329.775121 -384.014991)
			(xy 329.824698 -383.992349) (xy 329.876993 -383.976994) (xy 329.930941 -383.969238) (xy 329.985443 -383.969238)
			(xy 330.039391 -383.976994) (xy 330.091686 -383.992349) (xy 330.141263 -384.014991) (xy 330.187113 -384.044457)
			(xy 330.228304 -384.080148) (xy 330.263995 -384.121339) (xy 330.293461 -384.167189) (xy 330.316103 -384.216766)
			(xy 330.331458 -384.269061) (xy 330.339214 -384.323009) (xy 330.3397 -384.35026) (xy 330.3397 -385.21386)
			(xy 330.339214 -385.241111) (xy 330.331458 -385.295059) (xy 330.318606 -385.338828) (xy 359.423716 -385.338828)
			(xy 359.423716 -384.475228) (xy 359.424202 -384.447977) (xy 359.431958 -384.394029) (xy 359.447313 -384.341734)
			(xy 359.469955 -384.292157) (xy 359.499421 -384.246307) (xy 359.535112 -384.205116) (xy 359.576303 -384.169425)
			(xy 359.622153 -384.139959) (xy 359.67173 -384.117317) (xy 359.724025 -384.101962) (xy 359.777973 -384.094206)
			(xy 359.832475 -384.094206) (xy 359.886423 -384.101962) (xy 359.938718 -384.117317) (xy 359.988295 -384.139959)
			(xy 360.034145 -384.169425) (xy 360.075336 -384.205116) (xy 360.111027 -384.246307) (xy 360.140493 -384.292157)
			(xy 360.163135 -384.341734) (xy 360.17849 -384.394029) (xy 360.186246 -384.447977) (xy 360.186732 -384.475228)
			(xy 360.186732 -385.21386) (xy 364.149132 -385.21386) (xy 364.149132 -384.35026) (xy 364.149618 -384.323009)
			(xy 364.157374 -384.269061) (xy 364.172729 -384.216766) (xy 364.195371 -384.167189) (xy 364.224837 -384.121339)
			(xy 364.260528 -384.080148) (xy 364.301719 -384.044457) (xy 364.347569 -384.014991) (xy 364.397146 -383.992349)
			(xy 364.449441 -383.976994) (xy 364.503389 -383.969238) (xy 364.557891 -383.969238) (xy 364.611839 -383.976994)
			(xy 364.664134 -383.992349) (xy 364.713711 -384.014991) (xy 364.759561 -384.044457) (xy 364.800752 -384.080148)
			(xy 364.836443 -384.121339) (xy 364.865909 -384.167189) (xy 364.888551 -384.216766) (xy 364.903906 -384.269061)
			(xy 364.911662 -384.323009) (xy 364.912148 -384.35026) (xy 364.912148 -385.21386) (xy 364.911662 -385.241111)
			(xy 364.903906 -385.295059) (xy 364.891054 -385.338828) (xy 393.996164 -385.338828) (xy 393.996164 -384.475228)
			(xy 393.99665 -384.447977) (xy 394.004406 -384.394029) (xy 394.019761 -384.341734) (xy 394.042403 -384.292157)
			(xy 394.071869 -384.246307) (xy 394.10756 -384.205116) (xy 394.148751 -384.169425) (xy 394.194601 -384.139959)
			(xy 394.244178 -384.117317) (xy 394.296473 -384.101962) (xy 394.350421 -384.094206) (xy 394.404923 -384.094206)
			(xy 394.458871 -384.101962) (xy 394.511166 -384.117317) (xy 394.560743 -384.139959) (xy 394.606593 -384.169425)
			(xy 394.647784 -384.205116) (xy 394.683475 -384.246307) (xy 394.712941 -384.292157) (xy 394.735583 -384.341734)
			(xy 394.750938 -384.394029) (xy 394.758694 -384.447977) (xy 394.75918 -384.475228) (xy 394.75918 -385.21386)
			(xy 396.67688 -385.21386) (xy 396.67688 -384.35026) (xy 396.677366 -384.323009) (xy 396.685122 -384.269061)
			(xy 396.700477 -384.216766) (xy 396.723119 -384.167189) (xy 396.752585 -384.121339) (xy 396.788276 -384.080148)
			(xy 396.829467 -384.044457) (xy 396.875317 -384.014991) (xy 396.924894 -383.992349) (xy 396.977189 -383.976994)
			(xy 397.031137 -383.969238) (xy 397.085639 -383.969238) (xy 397.139587 -383.976994) (xy 397.191882 -383.992349)
			(xy 397.241459 -384.014991) (xy 397.287309 -384.044457) (xy 397.3285 -384.080148) (xy 397.364191 -384.121339)
			(xy 397.393657 -384.167189) (xy 397.416299 -384.216766) (xy 397.431654 -384.269061) (xy 397.43941 -384.323009)
			(xy 397.439896 -384.35026) (xy 397.439896 -385.21386) (xy 397.43941 -385.241111) (xy 397.431654 -385.295059)
			(xy 397.418802 -385.338828) (xy 426.523912 -385.338828) (xy 426.523912 -384.475228) (xy 426.524398 -384.447977)
			(xy 426.532154 -384.394029) (xy 426.547509 -384.341734) (xy 426.570151 -384.292157) (xy 426.599617 -384.246307)
			(xy 426.635308 -384.205116) (xy 426.676499 -384.169425) (xy 426.722349 -384.139959) (xy 426.771926 -384.117317)
			(xy 426.824221 -384.101962) (xy 426.878169 -384.094206) (xy 426.932671 -384.094206) (xy 426.986619 -384.101962)
			(xy 427.038914 -384.117317) (xy 427.088491 -384.139959) (xy 427.134341 -384.169425) (xy 427.175532 -384.205116)
			(xy 427.211223 -384.246307) (xy 427.240689 -384.292157) (xy 427.263331 -384.341734) (xy 427.278686 -384.394029)
			(xy 427.286442 -384.447977) (xy 427.286928 -384.475228) (xy 427.286928 -384.869944) (xy 429.498772 -384.869944)
			(xy 429.502744 -384.691701) (xy 429.514652 -384.513812) (xy 429.534473 -384.33663) (xy 429.562167 -384.160506)
			(xy 429.597679 -383.985791) (xy 429.640939 -383.812832) (xy 429.691861 -383.641971) (xy 429.750344 -383.473549)
			(xy 429.816271 -383.307899) (xy 429.889512 -383.14535) (xy 429.969922 -382.986225) (xy 430.05734 -382.83084)
			(xy 430.151593 -382.679504) (xy 430.252494 -382.532516) (xy 430.359843 -382.390169) (xy 430.473426 -382.252746)
			(xy 430.593019 -382.120519) (xy 430.718383 -381.99375) (xy 430.84927 -381.872692) (xy 430.985419 -381.757585)
			(xy 431.126561 -381.648657) (xy 431.272416 -381.546125) (xy 431.422693 -381.450191) (xy 431.577094 -381.361048)
			(xy 431.735313 -381.278871) (xy 431.897036 -381.203823) (xy 432.061941 -381.136055) (xy 432.229702 -381.075699)
			(xy 432.399985 -381.022877) (xy 432.572452 -380.977693) (xy 432.74676 -380.940236) (xy 432.922564 -380.910582)
			(xy 433.099514 -380.888789) (xy 433.27726 -380.874899) (xy 433.455447 -380.868942) (xy 433.633724 -380.870928)
			(xy 433.811735 -380.880854) (xy 433.989127 -380.8987) (xy 434.165547 -380.92443) (xy 434.340647 -380.957994)
			(xy 434.514078 -380.999324) (xy 434.685495 -381.04834) (xy 434.854558 -381.104942) (xy 435.020933 -381.16902)
			(xy 435.184287 -381.240446) (xy 435.344298 -381.319078) (xy 435.500647 -381.404759) (xy 435.653024 -381.497321)
			(xy 435.801127 -381.596578) (xy 435.944661 -381.702335) (xy 436.083341 -381.81438) (xy 436.216892 -381.932492)
			(xy 436.345049 -382.056436) (xy 436.467558 -382.185966) (xy 436.584175 -382.320825) (xy 436.694668 -382.460745)
			(xy 436.798819 -382.605448) (xy 436.896421 -382.754647) (xy 436.987279 -382.908046) (xy 437.071213 -383.06534)
			(xy 437.148058 -383.226216) (xy 437.217659 -383.390357) (xy 437.27988 -383.557434) (xy 437.334596 -383.727118)
			(xy 437.381698 -383.899071) (xy 437.421094 -384.072951) (xy 437.452705 -384.248414) (xy 437.476469 -384.42511)
			(xy 437.492337 -384.60269) (xy 437.500279 -384.7808) (xy 437.500776 -384.869944) (xy 437.500279 -384.959088)
			(xy 437.492337 -385.137198) (xy 437.476469 -385.314778) (xy 437.452705 -385.491474) (xy 437.421094 -385.666937)
			(xy 437.381698 -385.840817) (xy 437.334596 -386.01277) (xy 437.27988 -386.182454) (xy 437.217659 -386.349531)
			(xy 437.148058 -386.513672) (xy 437.071213 -386.674548) (xy 436.987279 -386.831842) (xy 436.896421 -386.985241)
			(xy 436.798819 -387.13444) (xy 436.694668 -387.279143) (xy 436.584175 -387.419063) (xy 436.467558 -387.553922)
			(xy 436.345049 -387.683452) (xy 436.216892 -387.807396) (xy 436.083341 -387.925508) (xy 435.944661 -388.037553)
			(xy 435.801127 -388.14331) (xy 435.653024 -388.242567) (xy 435.500647 -388.335129) (xy 435.344298 -388.42081)
			(xy 435.184287 -388.499442) (xy 435.020933 -388.570868) (xy 434.854558 -388.634946) (xy 434.685495 -388.691548)
			(xy 434.514078 -388.740564) (xy 434.340647 -388.781894) (xy 434.165547 -388.815458) (xy 433.989127 -388.841188)
			(xy 433.811735 -388.859034) (xy 433.633724 -388.86896) (xy 433.455447 -388.870946) (xy 433.27726 -388.864989)
			(xy 433.099514 -388.851099) (xy 432.922564 -388.829306) (xy 432.74676 -388.799652) (xy 432.572452 -388.762195)
			(xy 432.399985 -388.717011) (xy 432.229702 -388.664189) (xy 432.061941 -388.603833) (xy 431.897036 -388.536065)
			(xy 431.735313 -388.461017) (xy 431.577094 -388.37884) (xy 431.422693 -388.289697) (xy 431.272416 -388.193763)
			(xy 431.126561 -388.091231) (xy 430.985419 -387.982303) (xy 430.84927 -387.867196) (xy 430.718383 -387.746138)
			(xy 430.593019 -387.619369) (xy 430.473426 -387.487142) (xy 430.359843 -387.349719) (xy 430.252494 -387.207372)
			(xy 430.151593 -387.060384) (xy 430.05734 -386.909048) (xy 429.969922 -386.753663) (xy 429.889512 -386.594538)
			(xy 429.816271 -386.431989) (xy 429.750344 -386.266339) (xy 429.691861 -386.097917) (xy 429.640939 -385.927056)
			(xy 429.597679 -385.754097) (xy 429.562167 -385.579382) (xy 429.534473 -385.403258) (xy 429.514652 -385.226076)
			(xy 429.502744 -385.048187) (xy 429.498772 -384.869944) (xy 427.286928 -384.869944) (xy 427.286928 -385.338828)
			(xy 427.286442 -385.366079) (xy 427.278686 -385.420027) (xy 427.263331 -385.472322) (xy 427.240689 -385.521899)
			(xy 427.211223 -385.567749) (xy 427.175532 -385.60894) (xy 427.134341 -385.644631) (xy 427.088491 -385.674097)
			(xy 427.038914 -385.696739) (xy 426.986619 -385.712094) (xy 426.932671 -385.71985) (xy 426.878169 -385.71985)
			(xy 426.824221 -385.712094) (xy 426.771926 -385.696739) (xy 426.722349 -385.674097) (xy 426.676499 -385.644631)
			(xy 426.635308 -385.60894) (xy 426.599617 -385.567749) (xy 426.570151 -385.521899) (xy 426.547509 -385.472322)
			(xy 426.532154 -385.420027) (xy 426.524398 -385.366079) (xy 426.523912 -385.338828) (xy 397.418802 -385.338828)
			(xy 397.416299 -385.347354) (xy 397.393657 -385.396931) (xy 397.364191 -385.442781) (xy 397.3285 -385.483972)
			(xy 397.287309 -385.519663) (xy 397.241459 -385.549129) (xy 397.191882 -385.571771) (xy 397.139587 -385.587126)
			(xy 397.085639 -385.594882) (xy 397.031137 -385.594882) (xy 396.977189 -385.587126) (xy 396.924894 -385.571771)
			(xy 396.875317 -385.549129) (xy 396.829467 -385.519663) (xy 396.788276 -385.483972) (xy 396.752585 -385.442781)
			(xy 396.723119 -385.396931) (xy 396.700477 -385.347354) (xy 396.685122 -385.295059) (xy 396.677366 -385.241111)
			(xy 396.67688 -385.21386) (xy 394.75918 -385.21386) (xy 394.75918 -385.338828) (xy 394.758694 -385.366079)
			(xy 394.750938 -385.420027) (xy 394.735583 -385.472322) (xy 394.712941 -385.521899) (xy 394.683475 -385.567749)
			(xy 394.647784 -385.60894) (xy 394.606593 -385.644631) (xy 394.560743 -385.674097) (xy 394.511166 -385.696739)
			(xy 394.458871 -385.712094) (xy 394.404923 -385.71985) (xy 394.350421 -385.71985) (xy 394.296473 -385.712094)
			(xy 394.244178 -385.696739) (xy 394.194601 -385.674097) (xy 394.148751 -385.644631) (xy 394.10756 -385.60894)
			(xy 394.071869 -385.567749) (xy 394.042403 -385.521899) (xy 394.019761 -385.472322) (xy 394.004406 -385.420027)
			(xy 393.99665 -385.366079) (xy 393.996164 -385.338828) (xy 364.891054 -385.338828) (xy 364.888551 -385.347354)
			(xy 364.865909 -385.396931) (xy 364.836443 -385.442781) (xy 364.800752 -385.483972) (xy 364.759561 -385.519663)
			(xy 364.713711 -385.549129) (xy 364.664134 -385.571771) (xy 364.611839 -385.587126) (xy 364.557891 -385.594882)
			(xy 364.503389 -385.594882) (xy 364.449441 -385.587126) (xy 364.397146 -385.571771) (xy 364.347569 -385.549129)
			(xy 364.301719 -385.519663) (xy 364.260528 -385.483972) (xy 364.224837 -385.442781) (xy 364.195371 -385.396931)
			(xy 364.172729 -385.347354) (xy 364.157374 -385.295059) (xy 364.149618 -385.241111) (xy 364.149132 -385.21386)
			(xy 360.186732 -385.21386) (xy 360.186732 -385.338828) (xy 360.186246 -385.366079) (xy 360.17849 -385.420027)
			(xy 360.163135 -385.472322) (xy 360.140493 -385.521899) (xy 360.111027 -385.567749) (xy 360.075336 -385.60894)
			(xy 360.034145 -385.644631) (xy 359.988295 -385.674097) (xy 359.938718 -385.696739) (xy 359.886423 -385.712094)
			(xy 359.832475 -385.71985) (xy 359.777973 -385.71985) (xy 359.724025 -385.712094) (xy 359.67173 -385.696739)
			(xy 359.622153 -385.674097) (xy 359.576303 -385.644631) (xy 359.535112 -385.60894) (xy 359.499421 -385.567749)
			(xy 359.469955 -385.521899) (xy 359.447313 -385.472322) (xy 359.431958 -385.420027) (xy 359.424202 -385.366079)
			(xy 359.423716 -385.338828) (xy 330.318606 -385.338828) (xy 330.316103 -385.347354) (xy 330.293461 -385.396931)
			(xy 330.263995 -385.442781) (xy 330.228304 -385.483972) (xy 330.187113 -385.519663) (xy 330.141263 -385.549129)
			(xy 330.091686 -385.571771) (xy 330.039391 -385.587126) (xy 329.985443 -385.594882) (xy 329.930941 -385.594882)
			(xy 329.876993 -385.587126) (xy 329.824698 -385.571771) (xy 329.775121 -385.549129) (xy 329.729271 -385.519663)
			(xy 329.68808 -385.483972) (xy 329.652389 -385.442781) (xy 329.622923 -385.396931) (xy 329.600281 -385.347354)
			(xy 329.584926 -385.295059) (xy 329.57717 -385.241111) (xy 329.576684 -385.21386) (xy 327.658984 -385.21386)
			(xy 327.658984 -385.338828) (xy 327.658498 -385.366079) (xy 327.650742 -385.420027) (xy 327.635387 -385.472322)
			(xy 327.612745 -385.521899) (xy 327.583279 -385.567749) (xy 327.547588 -385.60894) (xy 327.506397 -385.644631)
			(xy 327.460547 -385.674097) (xy 327.41097 -385.696739) (xy 327.358675 -385.712094) (xy 327.304727 -385.71985)
			(xy 327.250225 -385.71985) (xy 327.196277 -385.712094) (xy 327.143982 -385.696739) (xy 327.094405 -385.674097)
			(xy 327.048555 -385.644631) (xy 327.007364 -385.60894) (xy 326.971673 -385.567749) (xy 326.942207 -385.521899)
			(xy 326.919565 -385.472322) (xy 326.90421 -385.420027) (xy 326.896454 -385.366079) (xy 326.895968 -385.338828)
			(xy 297.790858 -385.338828) (xy 297.788355 -385.347354) (xy 297.765713 -385.396931) (xy 297.736247 -385.442781)
			(xy 297.700556 -385.483972) (xy 297.659365 -385.519663) (xy 297.613515 -385.549129) (xy 297.563938 -385.571771)
			(xy 297.511643 -385.587126) (xy 297.457695 -385.594882) (xy 297.403193 -385.594882) (xy 297.349245 -385.587126)
			(xy 297.29695 -385.571771) (xy 297.247373 -385.549129) (xy 297.201523 -385.519663) (xy 297.160332 -385.483972)
			(xy 297.124641 -385.442781) (xy 297.095175 -385.396931) (xy 297.072533 -385.347354) (xy 297.057178 -385.295059)
			(xy 297.049422 -385.241111) (xy 297.048936 -385.21386) (xy 295.055495 -385.21386) (xy 295.046477 -385.314778)
			(xy 295.022713 -385.491474) (xy 294.991102 -385.666937) (xy 294.951706 -385.840817) (xy 294.904604 -386.01277)
			(xy 294.849888 -386.182454) (xy 294.787667 -386.349531) (xy 294.718066 -386.513672) (xy 294.641221 -386.674548)
			(xy 294.557287 -386.831842) (xy 294.466429 -386.985241) (xy 294.368827 -387.13444) (xy 294.264676 -387.279143)
			(xy 294.154183 -387.419063) (xy 294.037566 -387.553922) (xy 293.915057 -387.683452) (xy 293.7869 -387.807396)
			(xy 293.653349 -387.925508) (xy 293.514669 -388.037553) (xy 293.371135 -388.14331) (xy 293.223032 -388.242567)
			(xy 293.070655 -388.335129) (xy 292.914306 -388.42081) (xy 292.754295 -388.499442) (xy 292.590941 -388.570868)
			(xy 292.424566 -388.634946) (xy 292.255503 -388.691548) (xy 292.084086 -388.740564) (xy 292.076264 -388.742428)
			(xy 326.895968 -388.742428) (xy 326.895968 -387.878828) (xy 326.896454 -387.851577) (xy 326.90421 -387.797629)
			(xy 326.919565 -387.745334) (xy 326.942207 -387.695757) (xy 326.971673 -387.649907) (xy 327.007364 -387.608716)
			(xy 327.048555 -387.573025) (xy 327.094405 -387.543559) (xy 327.143982 -387.520917) (xy 327.196277 -387.505562)
			(xy 327.250225 -387.497806) (xy 327.304727 -387.497806) (xy 327.358675 -387.505562) (xy 327.41097 -387.520917)
			(xy 327.460547 -387.543559) (xy 327.506397 -387.573025) (xy 327.547588 -387.608716) (xy 327.583279 -387.649907)
			(xy 327.612745 -387.695757) (xy 327.635387 -387.745334) (xy 327.650742 -387.797629) (xy 327.658498 -387.851577)
			(xy 327.658984 -387.878828) (xy 327.658984 -388.742428) (xy 359.423716 -388.742428) (xy 359.423716 -387.878828)
			(xy 359.424202 -387.851577) (xy 359.431958 -387.797629) (xy 359.447313 -387.745334) (xy 359.469955 -387.695757)
			(xy 359.499421 -387.649907) (xy 359.535112 -387.608716) (xy 359.576303 -387.573025) (xy 359.622153 -387.543559)
			(xy 359.67173 -387.520917) (xy 359.724025 -387.505562) (xy 359.777973 -387.497806) (xy 359.832475 -387.497806)
			(xy 359.886423 -387.505562) (xy 359.938718 -387.520917) (xy 359.988295 -387.543559) (xy 360.034145 -387.573025)
			(xy 360.075336 -387.608716) (xy 360.111027 -387.649907) (xy 360.140493 -387.695757) (xy 360.163135 -387.745334)
			(xy 360.17849 -387.797629) (xy 360.186246 -387.851577) (xy 360.186732 -387.878828) (xy 360.186732 -388.742428)
			(xy 393.996164 -388.742428) (xy 393.996164 -387.878828) (xy 393.99665 -387.851577) (xy 394.004406 -387.797629)
			(xy 394.019761 -387.745334) (xy 394.042403 -387.695757) (xy 394.071869 -387.649907) (xy 394.10756 -387.608716)
			(xy 394.148751 -387.573025) (xy 394.194601 -387.543559) (xy 394.244178 -387.520917) (xy 394.296473 -387.505562)
			(xy 394.350421 -387.497806) (xy 394.404923 -387.497806) (xy 394.458871 -387.505562) (xy 394.511166 -387.520917)
			(xy 394.560743 -387.543559) (xy 394.606593 -387.573025) (xy 394.647784 -387.608716) (xy 394.683475 -387.649907)
			(xy 394.712941 -387.695757) (xy 394.735583 -387.745334) (xy 394.750938 -387.797629) (xy 394.758694 -387.851577)
			(xy 394.75918 -387.878828) (xy 394.75918 -388.742428) (xy 426.523912 -388.742428) (xy 426.523912 -387.878828)
			(xy 426.524398 -387.851577) (xy 426.532154 -387.797629) (xy 426.547509 -387.745334) (xy 426.570151 -387.695757)
			(xy 426.599617 -387.649907) (xy 426.635308 -387.608716) (xy 426.676499 -387.573025) (xy 426.722349 -387.543559)
			(xy 426.771926 -387.520917) (xy 426.824221 -387.505562) (xy 426.878169 -387.497806) (xy 426.932671 -387.497806)
			(xy 426.986619 -387.505562) (xy 427.038914 -387.520917) (xy 427.088491 -387.543559) (xy 427.134341 -387.573025)
			(xy 427.175532 -387.608716) (xy 427.211223 -387.649907) (xy 427.240689 -387.695757) (xy 427.263331 -387.745334)
			(xy 427.278686 -387.797629) (xy 427.286442 -387.851577) (xy 427.286928 -387.878828) (xy 427.286928 -388.742428)
			(xy 427.286442 -388.769679) (xy 427.278686 -388.823627) (xy 427.263331 -388.875922) (xy 427.240689 -388.925499)
			(xy 427.211223 -388.971349) (xy 427.175532 -389.01254) (xy 427.134341 -389.048231) (xy 427.088491 -389.077697)
			(xy 427.038914 -389.100339) (xy 426.986619 -389.115694) (xy 426.932671 -389.12345) (xy 426.878169 -389.12345)
			(xy 426.824221 -389.115694) (xy 426.771926 -389.100339) (xy 426.722349 -389.077697) (xy 426.676499 -389.048231)
			(xy 426.635308 -389.01254) (xy 426.599617 -388.971349) (xy 426.570151 -388.925499) (xy 426.547509 -388.875922)
			(xy 426.532154 -388.823627) (xy 426.524398 -388.769679) (xy 426.523912 -388.742428) (xy 394.75918 -388.742428)
			(xy 394.758694 -388.769679) (xy 394.750938 -388.823627) (xy 394.735583 -388.875922) (xy 394.712941 -388.925499)
			(xy 394.683475 -388.971349) (xy 394.647784 -389.01254) (xy 394.606593 -389.048231) (xy 394.560743 -389.077697)
			(xy 394.511166 -389.100339) (xy 394.458871 -389.115694) (xy 394.404923 -389.12345) (xy 394.350421 -389.12345)
			(xy 394.296473 -389.115694) (xy 394.244178 -389.100339) (xy 394.194601 -389.077697) (xy 394.148751 -389.048231)
			(xy 394.10756 -389.01254) (xy 394.071869 -388.971349) (xy 394.042403 -388.925499) (xy 394.019761 -388.875922)
			(xy 394.004406 -388.823627) (xy 393.99665 -388.769679) (xy 393.996164 -388.742428) (xy 360.186732 -388.742428)
			(xy 360.186246 -388.769679) (xy 360.17849 -388.823627) (xy 360.163135 -388.875922) (xy 360.140493 -388.925499)
			(xy 360.111027 -388.971349) (xy 360.075336 -389.01254) (xy 360.034145 -389.048231) (xy 359.988295 -389.077697)
			(xy 359.938718 -389.100339) (xy 359.886423 -389.115694) (xy 359.832475 -389.12345) (xy 359.777973 -389.12345)
			(xy 359.724025 -389.115694) (xy 359.67173 -389.100339) (xy 359.622153 -389.077697) (xy 359.576303 -389.048231)
			(xy 359.535112 -389.01254) (xy 359.499421 -388.971349) (xy 359.469955 -388.925499) (xy 359.447313 -388.875922)
			(xy 359.431958 -388.823627) (xy 359.424202 -388.769679) (xy 359.423716 -388.742428) (xy 327.658984 -388.742428)
			(xy 327.658498 -388.769679) (xy 327.650742 -388.823627) (xy 327.635387 -388.875922) (xy 327.612745 -388.925499)
			(xy 327.583279 -388.971349) (xy 327.547588 -389.01254) (xy 327.506397 -389.048231) (xy 327.460547 -389.077697)
			(xy 327.41097 -389.100339) (xy 327.358675 -389.115694) (xy 327.304727 -389.12345) (xy 327.250225 -389.12345)
			(xy 327.196277 -389.115694) (xy 327.143982 -389.100339) (xy 327.094405 -389.077697) (xy 327.048555 -389.048231)
			(xy 327.007364 -389.01254) (xy 326.971673 -388.971349) (xy 326.942207 -388.925499) (xy 326.919565 -388.875922)
			(xy 326.90421 -388.823627) (xy 326.896454 -388.769679) (xy 326.895968 -388.742428) (xy 292.076264 -388.742428)
			(xy 291.910655 -388.781894) (xy 291.735555 -388.815458) (xy 291.559135 -388.841188) (xy 291.381743 -388.859034)
			(xy 291.203732 -388.86896) (xy 291.025455 -388.870946) (xy 290.847268 -388.864989) (xy 290.669522 -388.851099)
			(xy 290.492572 -388.829306) (xy 290.316768 -388.799652) (xy 290.14246 -388.762195) (xy 289.969993 -388.717011)
			(xy 289.79971 -388.664189) (xy 289.631949 -388.603833) (xy 289.467044 -388.536065) (xy 289.305321 -388.461017)
			(xy 289.147102 -388.37884) (xy 288.992701 -388.289697) (xy 288.842424 -388.193763) (xy 288.696569 -388.091231)
			(xy 288.555427 -387.982303) (xy 288.419278 -387.867196) (xy 288.288391 -387.746138) (xy 288.163027 -387.619369)
			(xy 288.043434 -387.487142) (xy 287.929851 -387.349719) (xy 287.822502 -387.207372) (xy 287.721601 -387.060384)
			(xy 287.627348 -386.909048) (xy 287.53993 -386.753663) (xy 287.45952 -386.594538) (xy 287.386279 -386.431989)
			(xy 287.320352 -386.266339) (xy 287.261869 -386.097917) (xy 287.210947 -385.927056) (xy 287.167687 -385.754097)
			(xy 287.132175 -385.579382) (xy 287.104481 -385.403258) (xy 287.08466 -385.226076) (xy 287.072752 -385.048187)
			(xy 287.06878 -384.869944) (xy 2.509012 -384.869944) (xy 2.509012 -385.310888) (xy 47.485808 -385.310888)
			(xy 47.485808 -385.31038) (xy 47.486221 -385.286373) (xy 47.493739 -385.238951) (xy 47.508587 -385.19329)
			(xy 47.530398 -385.150515) (xy 47.558635 -385.111682) (xy 47.592603 -385.077747) (xy 47.631463 -385.049546)
			(xy 47.674258 -385.027775) (xy 47.719933 -385.012971) (xy 47.767362 -385.005498) (xy 47.79137 -385.005072)
			(xy 47.815305 -385.005523) (xy 47.862591 -385.012984) (xy 47.908134 -385.027728) (xy 47.950821 -385.049394)
			(xy 47.989606 -385.077452) (xy 48.023541 -385.111216) (xy 48.051795 -385.149858) (xy 48.06315 -385.170934)
			(xy 48.063658 -385.17195) (xy 48.143964 -385.310888) (xy 48.685704 -385.310888) (xy 48.685704 -385.31038)
			(xy 48.686121 -385.286373) (xy 48.693639 -385.238951) (xy 48.708486 -385.193291) (xy 48.730297 -385.150516)
			(xy 48.758534 -385.111683) (xy 48.792501 -385.077748) (xy 48.831361 -385.049548) (xy 48.874155 -385.027777)
			(xy 48.91983 -385.012972) (xy 48.967259 -385.005498) (xy 48.991266 -385.005072) (xy 49.015201 -385.005526)
			(xy 49.062486 -385.012986) (xy 49.10803 -385.02773) (xy 49.150716 -385.049395) (xy 49.189502 -385.077453)
			(xy 49.223437 -385.111216) (xy 49.251691 -385.149859) (xy 49.263046 -385.170934) (xy 49.263554 -385.17195)
			(xy 49.34386 -385.310888) (xy 49.8856 -385.310888) (xy 49.8856 -385.31038) (xy 49.886021 -385.286373)
			(xy 49.893539 -385.238952) (xy 49.908386 -385.193291) (xy 49.930196 -385.150518) (xy 49.958433 -385.111685)
			(xy 49.992399 -385.07775) (xy 50.031259 -385.049549) (xy 50.074052 -385.027778) (xy 50.119727 -385.012973)
			(xy 50.167155 -385.005499) (xy 50.191162 -385.005072) (xy 50.215097 -385.005529) (xy 50.262382 -385.012989)
			(xy 50.307925 -385.027732) (xy 50.350612 -385.049397) (xy 50.389397 -385.077454) (xy 50.423333 -385.111217)
			(xy 50.451587 -385.149859) (xy 50.462942 -385.170934) (xy 50.46345 -385.17195) (xy 50.543756 -385.310888)
			(xy 51.086004 -385.310888) (xy 51.086004 -385.31038) (xy 51.086444 -385.286388) (xy 51.093954 -385.238994)
			(xy 51.108785 -385.193359) (xy 51.130572 -385.150605) (xy 51.158779 -385.111786) (xy 51.192711 -385.077858)
			(xy 51.231533 -385.049655) (xy 51.274288 -385.027872) (xy 51.319925 -385.013046) (xy 51.36732 -385.005542)
			(xy 51.391312 -385.005072) (xy 51.415246 -385.00557) (xy 51.462529 -385.013022) (xy 51.508071 -385.027757)
			(xy 51.550758 -385.049416) (xy 51.589544 -385.077467) (xy 51.62348 -385.111224) (xy 51.651736 -385.149861)
			(xy 51.663092 -385.170934) (xy 51.6636 -385.17195) (xy 51.743906 -385.310888) (xy 52.2859 -385.310888)
			(xy 52.2859 -385.31038) (xy 52.286344 -385.286388) (xy 52.293854 -385.238995) (xy 52.308684 -385.19336)
			(xy 52.330471 -385.150606) (xy 52.358677 -385.111788) (xy 52.392609 -385.077859) (xy 52.43143 -385.049656)
			(xy 52.474186 -385.027873) (xy 52.519822 -385.013047) (xy 52.567216 -385.005542) (xy 52.591208 -385.005072)
			(xy 52.615141 -385.005573) (xy 52.662424 -385.013024) (xy 52.707967 -385.027759) (xy 52.750653 -385.049417)
			(xy 52.789439 -385.077468) (xy 52.823376 -385.111224) (xy 52.851632 -385.149861) (xy 52.862988 -385.170934)
			(xy 52.863496 -385.17195) (xy 52.943802 -385.310888) (xy 53.485796 -385.310888) (xy 53.485796 -385.31038)
			(xy 53.486221 -385.286373) (xy 53.493738 -385.238952) (xy 53.508585 -385.193292) (xy 53.530396 -385.150519)
			(xy 53.558632 -385.111686) (xy 53.592598 -385.077751) (xy 53.631456 -385.04955) (xy 53.67425 -385.027779)
			(xy 53.719923 -385.012973) (xy 53.767351 -385.005499) (xy 53.791358 -385.005072) (xy 53.815293 -385.005532)
			(xy 53.862578 -385.012992) (xy 53.908121 -385.027734) (xy 53.950807 -385.049398) (xy 53.989593 -385.077455)
			(xy 54.023528 -385.111217) (xy 54.051783 -385.149859) (xy 54.063138 -385.170934) (xy 54.063646 -385.17195)
			(xy 54.143952 -385.310888) (xy 54.685692 -385.310888) (xy 54.685692 -385.31038) (xy 54.686121 -385.286374)
			(xy 54.693638 -385.238953) (xy 54.708485 -385.193293) (xy 54.730295 -385.15052) (xy 54.758531 -385.111687)
			(xy 54.792496 -385.077752) (xy 54.831354 -385.049552) (xy 54.874147 -385.02778) (xy 54.91982 -385.012974)
			(xy 54.967247 -385.005499) (xy 54.991254 -385.005072) (xy 55.015189 -385.005536) (xy 55.062474 -385.012994)
			(xy 55.108017 -385.027736) (xy 55.150703 -385.0494) (xy 55.189489 -385.077456) (xy 55.223424 -385.111218)
			(xy 55.251679 -385.149859) (xy 55.263034 -385.170934) (xy 55.263542 -385.17195) (xy 55.343848 -385.310888)
			(xy 55.885588 -385.310888) (xy 55.885588 -385.31038) (xy 55.886021 -385.286374) (xy 55.893538 -385.238954)
			(xy 55.908385 -385.193294) (xy 55.930194 -385.150521) (xy 55.95843 -385.111689) (xy 55.992394 -385.077754)
			(xy 56.031252 -385.049553) (xy 56.074044 -385.027781) (xy 56.119717 -385.012975) (xy 56.167143 -385.0055)
			(xy 56.19115 -385.005072) (xy 56.215085 -385.005539) (xy 56.262369 -385.012997) (xy 56.307912 -385.027738)
			(xy 56.350599 -385.049401) (xy 56.389384 -385.077457) (xy 56.42332 -385.111218) (xy 56.451575 -385.149859)
			(xy 56.46293 -385.170934) (xy 56.463438 -385.17195) (xy 56.543744 -385.310888) (xy 57.085992 -385.310888)
			(xy 57.085992 -385.31038) (xy 57.086444 -385.286388) (xy 57.093953 -385.238996) (xy 57.108783 -385.193362)
			(xy 57.130569 -385.150609) (xy 57.158775 -385.11179) (xy 57.192706 -385.077862) (xy 57.231526 -385.049659)
			(xy 57.27428 -385.027876) (xy 57.319915 -385.013049) (xy 57.367308 -385.005543) (xy 57.3913 -385.005072)
			(xy 57.391554 -385.005072) (xy 57.415489 -385.005536) (xy 57.462774 -385.012994) (xy 57.508317 -385.027736)
			(xy 57.551003 -385.0494) (xy 57.589789 -385.077456) (xy 57.623724 -385.111218) (xy 57.651979 -385.149859)
			(xy 57.663334 -385.170934) (xy 57.663842 -385.17195) (xy 57.744148 -385.310888) (xy 58.285888 -385.310888)
			(xy 58.285888 -385.31038) (xy 58.286344 -385.286388) (xy 58.293853 -385.238996) (xy 58.308683 -385.193362)
			(xy 58.330469 -385.15061) (xy 58.358674 -385.111792) (xy 58.392604 -385.077863) (xy 58.431424 -385.04966)
			(xy 58.474177 -385.027877) (xy 58.519812 -385.013049) (xy 58.567204 -385.005543) (xy 58.591196 -385.005072)
			(xy 58.59145 -385.005072) (xy 58.615385 -385.005539) (xy 58.662669 -385.012997) (xy 58.708212 -385.027738)
			(xy 58.750899 -385.049401) (xy 58.789684 -385.077457) (xy 58.82362 -385.111218) (xy 58.851875 -385.149859)
			(xy 58.86323 -385.170934) (xy 58.863738 -385.17195) (xy 58.944044 -385.310888) (xy 59.485784 -385.310888)
			(xy 59.485784 -385.31038) (xy 59.486221 -385.286374) (xy 59.493738 -385.238954) (xy 59.508584 -385.193295)
			(xy 59.530394 -385.150522) (xy 59.558628 -385.11169) (xy 59.592593 -385.077755) (xy 59.63145 -385.049554)
			(xy 59.674241 -385.027782) (xy 59.719913 -385.012976) (xy 59.76734 -385.0055) (xy 59.791346 -385.005072)
			(xy 59.7916 -385.005072) (xy 59.815533 -385.00558) (xy 59.862816 -385.01303) (xy 59.908358 -385.027764)
			(xy 59.951044 -385.04942) (xy 59.989831 -385.07747) (xy 60.023768 -385.111226) (xy 60.052024 -385.149862)
			(xy 60.06338 -385.170934) (xy 60.063888 -385.17195) (xy 60.144194 -385.310888) (xy 60.68568 -385.310888)
			(xy 60.68568 -385.31038) (xy 60.686121 -385.286374) (xy 60.693638 -385.238955) (xy 60.708484 -385.193296)
			(xy 60.730293 -385.150524) (xy 60.758527 -385.111692) (xy 60.792491 -385.077757) (xy 60.831347 -385.049556)
			(xy 60.874139 -385.027783) (xy 60.91981 -385.012977) (xy 60.967236 -385.0055) (xy 60.991242 -385.005072)
			(xy 60.991496 -385.005072) (xy 61.015432 -385.005502) (xy 61.062718 -385.012966) (xy 61.108262 -385.027714)
			(xy 61.150949 -385.049384) (xy 61.189734 -385.077445) (xy 61.223668 -385.111212) (xy 61.251922 -385.149857)
			(xy 61.263276 -385.170934) (xy 61.263784 -385.17195) (xy 61.34409 -385.310888) (xy 61.885576 -385.310888)
			(xy 61.885576 -385.31038) (xy 61.886021 -385.286374) (xy 61.893538 -385.238955) (xy 61.908383 -385.193297)
			(xy 61.930192 -385.150525) (xy 61.958426 -385.111693) (xy 61.992389 -385.077758) (xy 62.031245 -385.049557)
			(xy 62.074036 -385.027785) (xy 62.119707 -385.012977) (xy 62.167132 -385.0055) (xy 62.191138 -385.005072)
			(xy 62.191392 -385.005072) (xy 62.215328 -385.005505) (xy 62.262614 -385.012969) (xy 62.308158 -385.027716)
			(xy 62.350844 -385.049385) (xy 62.38963 -385.077446) (xy 62.423564 -385.111212) (xy 62.451818 -385.149857)
			(xy 62.463172 -385.170934) (xy 62.46368 -385.17195) (xy 62.543986 -385.310888) (xy 63.08598 -385.310888)
			(xy 63.08598 -385.31038) (xy 63.086444 -385.286389) (xy 63.093953 -385.238998) (xy 63.108782 -385.193364)
			(xy 63.130567 -385.150612) (xy 63.158771 -385.111795) (xy 63.192701 -385.077866) (xy 63.231519 -385.049663)
			(xy 63.274272 -385.027879) (xy 63.319905 -385.013051) (xy 63.367297 -385.005543) (xy 63.391288 -385.005072)
			(xy 63.391542 -385.005072) (xy 63.415476 -385.005545) (xy 63.462761 -385.013002) (xy 63.508303 -385.027742)
			(xy 63.55099 -385.049404) (xy 63.589776 -385.077459) (xy 63.623712 -385.11122) (xy 63.651967 -385.14986)
			(xy 63.663322 -385.170934) (xy 63.66383 -385.17195) (xy 63.744136 -385.310888) (xy 64.285876 -385.310888)
			(xy 64.285876 -385.31038) (xy 64.286344 -385.286389) (xy 64.293853 -385.238998) (xy 64.308682 -385.193365)
			(xy 64.330467 -385.150614) (xy 64.35867 -385.111796) (xy 64.392599 -385.077868) (xy 64.431417 -385.049664)
			(xy 64.474169 -385.02788) (xy 64.519802 -385.013052) (xy 64.567193 -385.005544) (xy 64.591184 -385.005072)
			(xy 64.591438 -385.005072) (xy 64.615372 -385.005549) (xy 64.662656 -385.013005) (xy 64.708199 -385.027744)
			(xy 64.750886 -385.049406) (xy 64.789672 -385.07746) (xy 64.823607 -385.11122) (xy 64.851863 -385.14986)
			(xy 64.863218 -385.170934) (xy 64.863726 -385.17195) (xy 64.944032 -385.310888) (xy 65.485772 -385.310888)
			(xy 65.485772 -385.31038) (xy 65.486221 -385.286375) (xy 65.493738 -385.238956) (xy 65.508583 -385.193298)
			(xy 65.530391 -385.150526) (xy 65.558625 -385.111694) (xy 65.592588 -385.07776) (xy 65.631443 -385.049558)
			(xy 65.674233 -385.027786) (xy 65.719903 -385.012978) (xy 65.767328 -385.005501) (xy 65.791334 -385.005072)
			(xy 65.791588 -385.005072) (xy 65.815524 -385.005508) (xy 65.86281 -385.012972) (xy 65.908353 -385.027718)
			(xy 65.95104 -385.049387) (xy 65.989825 -385.077447) (xy 66.02376 -385.111213) (xy 66.052014 -385.149858)
			(xy 66.063368 -385.170934) (xy 66.063876 -385.17195) (xy 66.144182 -385.310888) (xy 80.013556 -385.310888)
			(xy 80.013556 -385.31038) (xy 80.014021 -385.286375) (xy 80.021537 -385.238958) (xy 80.036382 -385.193302)
			(xy 80.058188 -385.150531) (xy 80.08642 -385.1117) (xy 80.120381 -385.077765) (xy 80.159234 -385.049564)
			(xy 80.202022 -385.02779) (xy 80.24769 -385.012981) (xy 80.295113 -385.005502) (xy 80.319118 -385.005072)
			(xy 80.343052 -385.005565) (xy 80.390335 -385.013018) (xy 80.435877 -385.027754) (xy 80.478564 -385.049413)
			(xy 80.51735 -385.077465) (xy 80.551287 -385.111223) (xy 80.579542 -385.149861) (xy 80.590898 -385.170934)
			(xy 80.591406 -385.17195) (xy 80.671712 -385.310888) (xy 81.213452 -385.310888) (xy 81.213452 -385.31038)
			(xy 81.213921 -385.286376) (xy 81.221437 -385.238959) (xy 81.236281 -385.193303) (xy 81.258088 -385.150532)
			(xy 81.286319 -385.111701) (xy 81.320279 -385.077767) (xy 81.359132 -385.049565) (xy 81.401919 -385.027792)
			(xy 81.447587 -385.012982) (xy 81.495009 -385.005502) (xy 81.519014 -385.005072) (xy 81.542948 -385.005568)
			(xy 81.590231 -385.013021) (xy 81.635773 -385.027756) (xy 81.67846 -385.049415) (xy 81.717246 -385.077466)
			(xy 81.751182 -385.111224) (xy 81.779438 -385.149861) (xy 81.790794 -385.170934) (xy 81.791302 -385.17195)
			(xy 81.871608 -385.310888) (xy 82.413348 -385.310888) (xy 82.413348 -385.31038) (xy 82.413821 -385.286376)
			(xy 82.421337 -385.238959) (xy 82.436181 -385.193304) (xy 82.457987 -385.150533) (xy 82.486218 -385.111702)
			(xy 82.520178 -385.077768) (xy 82.55903 -385.049567) (xy 82.601816 -385.027793) (xy 82.647483 -385.012983)
			(xy 82.694905 -385.005502) (xy 82.71891 -385.005072) (xy 82.742843 -385.005571) (xy 82.790127 -385.013023)
			(xy 82.835669 -385.027758) (xy 82.878355 -385.049416) (xy 82.917142 -385.077467) (xy 82.951078 -385.111224)
			(xy 82.979334 -385.149861) (xy 82.99069 -385.170934) (xy 82.991198 -385.17195) (xy 83.071504 -385.310888)
			(xy 83.613752 -385.310888) (xy 83.613752 -385.31038) (xy 83.614244 -385.28639) (xy 83.621752 -385.239002)
			(xy 83.63658 -385.193371) (xy 83.658362 -385.150621) (xy 83.686563 -385.111804) (xy 83.720489 -385.077876)
			(xy 83.759304 -385.049673) (xy 83.802052 -385.027887) (xy 83.847682 -385.013057) (xy 83.89507 -385.005546)
			(xy 83.91906 -385.005072) (xy 83.942995 -385.005531) (xy 83.99028 -385.01299) (xy 84.035823 -385.027733)
			(xy 84.07851 -385.049398) (xy 84.117295 -385.077455) (xy 84.151231 -385.111217) (xy 84.179485 -385.149859)
			(xy 84.19084 -385.170934) (xy 84.191348 -385.17195) (xy 84.271654 -385.310888) (xy 84.813648 -385.310888)
			(xy 84.813648 -385.31038) (xy 84.814144 -385.28639) (xy 84.821652 -385.239002) (xy 84.836479 -385.193372)
			(xy 84.858261 -385.150622) (xy 84.886462 -385.111805) (xy 84.920387 -385.077878) (xy 84.959201 -385.049674)
			(xy 85.001949 -385.027888) (xy 85.047579 -385.013057) (xy 85.094966 -385.005546) (xy 85.118956 -385.005072)
			(xy 85.142891 -385.005534) (xy 85.190176 -385.012993) (xy 85.235719 -385.027735) (xy 85.278405 -385.049399)
			(xy 85.317191 -385.077456) (xy 85.351126 -385.111218) (xy 85.379381 -385.149859) (xy 85.390736 -385.170934)
			(xy 85.391244 -385.17195) (xy 85.47155 -385.310888) (xy 86.013544 -385.310888) (xy 86.013544 -385.31038)
			(xy 86.01402 -385.286376) (xy 86.021537 -385.23896) (xy 86.03638 -385.193304) (xy 86.058186 -385.150534)
			(xy 86.086417 -385.111704) (xy 86.120376 -385.07777) (xy 86.159227 -385.049568) (xy 86.202014 -385.027794)
			(xy 86.24768 -385.012984) (xy 86.295102 -385.005503) (xy 86.319106 -385.005072) (xy 86.343039 -385.005575)
			(xy 86.390322 -385.013026) (xy 86.435864 -385.02776) (xy 86.478551 -385.049418) (xy 86.517337 -385.077468)
			(xy 86.551274 -385.111225) (xy 86.57953 -385.149861) (xy 86.590886 -385.170934) (xy 86.591394 -385.17195)
			(xy 86.6717 -385.310888) (xy 87.21344 -385.310888) (xy 87.21344 -385.31038) (xy 87.213821 -385.286371)
			(xy 87.22134 -385.238946) (xy 87.23619 -385.193282) (xy 87.258004 -385.150506) (xy 87.286245 -385.111671)
			(xy 87.320216 -385.077735) (xy 87.359081 -385.049535) (xy 87.40188 -385.027766) (xy 87.44756 -385.012965)
			(xy 87.494993 -385.005496) (xy 87.519002 -385.005072) (xy 87.542935 -385.005578) (xy 87.590218 -385.013028)
			(xy 87.63576 -385.027763) (xy 87.678447 -385.04942) (xy 87.717233 -385.077469) (xy 87.75117 -385.111225)
			(xy 87.779426 -385.149861) (xy 87.790782 -385.170934) (xy 87.79129 -385.17195) (xy 87.871596 -385.310888)
			(xy 88.413336 -385.310888) (xy 88.413336 -385.31038) (xy 88.413721 -385.286371) (xy 88.42124 -385.238947)
			(xy 88.436089 -385.193283) (xy 88.457903 -385.150507) (xy 88.486144 -385.111672) (xy 88.520115 -385.077737)
			(xy 88.558979 -385.049537) (xy 88.601777 -385.027767) (xy 88.647456 -385.012965) (xy 88.694889 -385.005496)
			(xy 88.718898 -385.005072) (xy 88.742834 -385.0055) (xy 88.790121 -385.012965) (xy 88.835664 -385.027713)
			(xy 88.878351 -385.049383) (xy 88.917136 -385.077445) (xy 88.95107 -385.111212) (xy 88.979324 -385.149857)
			(xy 88.990678 -385.170934) (xy 88.991186 -385.17195) (xy 89.071492 -385.310888) (xy 89.61374 -385.310888)
			(xy 89.61374 -385.31038) (xy 89.61412 -385.286384) (xy 89.621631 -385.238983) (xy 89.636465 -385.193341)
			(xy 89.658257 -385.150582) (xy 89.68647 -385.111758) (xy 89.72041 -385.077826) (xy 89.75924 -385.049622)
			(xy 89.802004 -385.027839) (xy 89.847649 -385.013015) (xy 89.895052 -385.005515) (xy 89.919048 -385.005072)
			(xy 89.942983 -385.005541) (xy 89.990267 -385.012998) (xy 90.03581 -385.027739) (xy 90.078497 -385.049402)
			(xy 90.117282 -385.077458) (xy 90.151218 -385.111219) (xy 90.179473 -385.149859) (xy 90.190828 -385.170934)
			(xy 90.191336 -385.17195) (xy 90.271642 -385.310888) (xy 90.813636 -385.310888) (xy 90.813636 -385.31038)
			(xy 90.81402 -385.286384) (xy 90.821531 -385.238984) (xy 90.836365 -385.193342) (xy 90.858157 -385.150583)
			(xy 90.886369 -385.111759) (xy 90.920308 -385.077828) (xy 90.959138 -385.049623) (xy 91.001901 -385.02784)
			(xy 91.047546 -385.013016) (xy 91.094948 -385.005515) (xy 91.118944 -385.005072) (xy 91.142878 -385.005544)
			(xy 91.190163 -385.013001) (xy 91.235706 -385.027741) (xy 91.278392 -385.049404) (xy 91.317178 -385.077459)
			(xy 91.351114 -385.111219) (xy 91.379369 -385.14986) (xy 91.390724 -385.170934) (xy 91.391232 -385.17195)
			(xy 91.471538 -385.310888) (xy 92.013532 -385.310888) (xy 92.013532 -385.31038) (xy 92.013921 -385.286372)
			(xy 92.02144 -385.238947) (xy 92.036289 -385.193284) (xy 92.058102 -385.150508) (xy 92.086342 -385.111674)
			(xy 92.120313 -385.077738) (xy 92.159176 -385.049538) (xy 92.201975 -385.027769) (xy 92.247653 -385.012966)
			(xy 92.295085 -385.005496) (xy 92.319094 -385.005072) (xy 92.34303 -385.005503) (xy 92.390316 -385.012968)
			(xy 92.43586 -385.027715) (xy 92.478547 -385.049385) (xy 92.517332 -385.077446) (xy 92.551266 -385.111212)
			(xy 92.57952 -385.149857) (xy 92.590874 -385.170934) (xy 92.591382 -385.17195) (xy 92.671688 -385.310888)
			(xy 93.213428 -385.310888) (xy 93.213428 -385.31038) (xy 93.213821 -385.286372) (xy 93.221339 -385.238948)
			(xy 93.236188 -385.193285) (xy 93.258002 -385.150509) (xy 93.286241 -385.111675) (xy 93.320211 -385.07774)
			(xy 93.359074 -385.049539) (xy 93.401872 -385.02777) (xy 93.44755 -385.012967) (xy 93.494981 -385.005497)
			(xy 93.51899 -385.005072) (xy 93.542926 -385.005506) (xy 93.590212 -385.01297) (xy 93.635756 -385.027717)
			(xy 93.678442 -385.049386) (xy 93.717227 -385.077447) (xy 93.751162 -385.111213) (xy 93.779416 -385.149857)
			(xy 93.79077 -385.170934) (xy 93.791278 -385.17195) (xy 93.871584 -385.310888) (xy 94.413324 -385.310888)
			(xy 94.413324 -385.31038) (xy 94.413721 -385.286372) (xy 94.421239 -385.238948) (xy 94.436088 -385.193286)
			(xy 94.457901 -385.15051) (xy 94.48614 -385.111676) (xy 94.520109 -385.077741) (xy 94.558972 -385.049541)
			(xy 94.601769 -385.027771) (xy 94.647446 -385.012968) (xy 94.694878 -385.005497) (xy 94.718886 -385.005072)
			(xy 94.742822 -385.00551) (xy 94.790108 -385.012973) (xy 94.835651 -385.027719) (xy 94.878338 -385.049388)
			(xy 94.917123 -385.077448) (xy 94.951058 -385.111213) (xy 94.979312 -385.149858) (xy 94.990666 -385.170934)
			(xy 94.991174 -385.17195) (xy 95.07148 -385.310888) (xy 95.613728 -385.310888) (xy 95.613728 -385.31038)
			(xy 95.61412 -385.286385) (xy 95.621631 -385.238985) (xy 95.636464 -385.193344) (xy 95.658255 -385.150585)
			(xy 95.686467 -385.111762) (xy 95.720405 -385.07783) (xy 95.759233 -385.049626) (xy 95.801996 -385.027843)
			(xy 95.847639 -385.013018) (xy 95.89504 -385.005515) (xy 95.919036 -385.005072) (xy 95.94297 -385.00555)
			(xy 95.990254 -385.013006) (xy 96.035797 -385.027745) (xy 96.078484 -385.049407) (xy 96.117269 -385.077461)
			(xy 96.151205 -385.11122) (xy 96.179461 -385.14986) (xy 96.190816 -385.170934) (xy 96.191324 -385.17195)
			(xy 96.27163 -385.310888) (xy 96.813624 -385.310888) (xy 96.813624 -385.31038) (xy 96.81402 -385.286385)
			(xy 96.821531 -385.238985) (xy 96.836364 -385.193345) (xy 96.858154 -385.150586) (xy 96.886366 -385.111764)
			(xy 96.920303 -385.077832) (xy 96.959131 -385.049627) (xy 97.001893 -385.027844) (xy 97.047536 -385.013018)
			(xy 97.094937 -385.005516) (xy 97.118932 -385.005072) (xy 97.142866 -385.005554) (xy 97.19015 -385.013009)
			(xy 97.235693 -385.027747) (xy 97.278379 -385.049408) (xy 97.317165 -385.077462) (xy 97.351101 -385.111221)
			(xy 97.379357 -385.14986) (xy 97.390712 -385.170934) (xy 97.39122 -385.17195) (xy 97.471526 -385.310888)
			(xy 98.01352 -385.310888) (xy 98.01352 -385.31038) (xy 98.013921 -385.286372) (xy 98.021439 -385.238949)
			(xy 98.036288 -385.193287) (xy 98.0581 -385.150512) (xy 98.086339 -385.111678) (xy 98.120308 -385.077742)
			(xy 98.15917 -385.049542) (xy 98.201966 -385.027772) (xy 98.247643 -385.012969) (xy 98.295074 -385.005497)
			(xy 98.319082 -385.005072) (xy 98.343018 -385.005513) (xy 98.390303 -385.012976) (xy 98.435847 -385.027721)
			(xy 98.478534 -385.049389) (xy 98.517319 -385.077449) (xy 98.551254 -385.111214) (xy 98.579508 -385.149858)
			(xy 98.590862 -385.170934) (xy 98.59137 -385.17195) (xy 98.671676 -385.310888) (xy 114.586004 -385.310888)
			(xy 114.586004 -385.31038) (xy 114.586444 -385.286388) (xy 114.593954 -385.238994) (xy 114.608785 -385.193359)
			(xy 114.630572 -385.150605) (xy 114.658779 -385.111786) (xy 114.692711 -385.077858) (xy 114.731533 -385.049655)
			(xy 114.774288 -385.027872) (xy 114.819925 -385.013046) (xy 114.86732 -385.005542) (xy 114.891312 -385.005072)
			(xy 114.915246 -385.00557) (xy 114.962529 -385.013022) (xy 115.008071 -385.027757) (xy 115.050758 -385.049416)
			(xy 115.089544 -385.077467) (xy 115.12348 -385.111224) (xy 115.151736 -385.149861) (xy 115.163092 -385.170934)
			(xy 115.1636 -385.17195) (xy 115.243906 -385.310888) (xy 115.7859 -385.310888) (xy 115.7859 -385.31038)
			(xy 115.786344 -385.286388) (xy 115.793854 -385.238995) (xy 115.808684 -385.19336) (xy 115.830471 -385.150606)
			(xy 115.858677 -385.111788) (xy 115.892609 -385.077859) (xy 115.93143 -385.049656) (xy 115.974186 -385.027873)
			(xy 116.019822 -385.013047) (xy 116.067216 -385.005542) (xy 116.091208 -385.005072) (xy 116.115141 -385.005573)
			(xy 116.162424 -385.013024) (xy 116.207967 -385.027759) (xy 116.250653 -385.049417) (xy 116.289439 -385.077468)
			(xy 116.323376 -385.111224) (xy 116.351632 -385.149861) (xy 116.362988 -385.170934) (xy 116.363496 -385.17195)
			(xy 116.443802 -385.310888) (xy 116.985796 -385.310888) (xy 116.985796 -385.31038) (xy 116.986244 -385.286388)
			(xy 116.993753 -385.238995) (xy 117.008584 -385.193361) (xy 117.03037 -385.150608) (xy 117.058576 -385.111789)
			(xy 117.092507 -385.077861) (xy 117.131328 -385.049658) (xy 117.174083 -385.027875) (xy 117.219719 -385.013048)
			(xy 117.267112 -385.005542) (xy 117.291104 -385.005072) (xy 117.315037 -385.005576) (xy 117.36232 -385.013027)
			(xy 117.407862 -385.027762) (xy 117.450549 -385.049419) (xy 117.489335 -385.077469) (xy 117.523272 -385.111225)
			(xy 117.551528 -385.149861) (xy 117.562884 -385.170934) (xy 117.563392 -385.17195) (xy 117.643698 -385.310888)
			(xy 118.185692 -385.310888) (xy 118.185692 -385.31038) (xy 118.186121 -385.286374) (xy 118.193638 -385.238953)
			(xy 118.208485 -385.193293) (xy 118.230295 -385.15052) (xy 118.258531 -385.111687) (xy 118.292496 -385.077752)
			(xy 118.331354 -385.049552) (xy 118.374147 -385.02778) (xy 118.41982 -385.012974) (xy 118.467247 -385.005499)
			(xy 118.491254 -385.005072) (xy 118.515189 -385.005536) (xy 118.562474 -385.012994) (xy 118.608017 -385.027736)
			(xy 118.650703 -385.0494) (xy 118.689489 -385.077456) (xy 118.723424 -385.111218) (xy 118.751679 -385.149859)
			(xy 118.763034 -385.170934) (xy 118.763542 -385.17195) (xy 118.843848 -385.310888) (xy 119.385588 -385.310888)
			(xy 119.385588 -385.31038) (xy 119.386021 -385.286374) (xy 119.393538 -385.238954) (xy 119.408385 -385.193294)
			(xy 119.430194 -385.150521) (xy 119.45843 -385.111689) (xy 119.492394 -385.077754) (xy 119.531252 -385.049553)
			(xy 119.574044 -385.027781) (xy 119.619717 -385.012975) (xy 119.667143 -385.0055) (xy 119.69115 -385.005072)
			(xy 119.715085 -385.005539) (xy 119.762369 -385.012997) (xy 119.807912 -385.027738) (xy 119.850599 -385.049401)
			(xy 119.889384 -385.077457) (xy 119.92332 -385.111218) (xy 119.951575 -385.149859) (xy 119.96293 -385.170934)
			(xy 119.963438 -385.17195) (xy 120.043744 -385.310888) (xy 120.585992 -385.310888) (xy 120.585992 -385.31038)
			(xy 120.586444 -385.286388) (xy 120.593953 -385.238996) (xy 120.608783 -385.193362) (xy 120.630569 -385.150609)
			(xy 120.658775 -385.11179) (xy 120.692706 -385.077862) (xy 120.731526 -385.049659) (xy 120.77428 -385.027876)
			(xy 120.819915 -385.013049) (xy 120.867308 -385.005543) (xy 120.8913 -385.005072) (xy 120.915233 -385.00558)
			(xy 120.962516 -385.01303) (xy 121.008058 -385.027764) (xy 121.050744 -385.04942) (xy 121.089531 -385.07747)
			(xy 121.123468 -385.111226) (xy 121.151724 -385.149862) (xy 121.16308 -385.170934) (xy 121.163588 -385.17195)
			(xy 121.243894 -385.310888) (xy 121.785888 -385.310888) (xy 121.785888 -385.31038) (xy 121.786344 -385.286388)
			(xy 121.793853 -385.238996) (xy 121.808683 -385.193362) (xy 121.830469 -385.15061) (xy 121.858674 -385.111792)
			(xy 121.892604 -385.077863) (xy 121.931424 -385.04966) (xy 121.974177 -385.027877) (xy 122.019812 -385.013049)
			(xy 122.067204 -385.005543) (xy 122.091196 -385.005072) (xy 122.115132 -385.005502) (xy 122.162418 -385.012966)
			(xy 122.207962 -385.027714) (xy 122.250649 -385.049384) (xy 122.289434 -385.077445) (xy 122.323368 -385.111212)
			(xy 122.351622 -385.149857) (xy 122.362976 -385.170934) (xy 122.363484 -385.17195) (xy 122.44379 -385.310888)
			(xy 122.985784 -385.310888) (xy 122.985784 -385.31038) (xy 122.986244 -385.286389) (xy 122.993753 -385.238997)
			(xy 123.008583 -385.193363) (xy 123.030368 -385.150611) (xy 123.058573 -385.111793) (xy 123.092502 -385.077865)
			(xy 123.131321 -385.049662) (xy 123.174074 -385.027878) (xy 123.219709 -385.01305) (xy 123.267101 -385.005543)
			(xy 123.291092 -385.005072) (xy 123.315028 -385.005505) (xy 123.362314 -385.012969) (xy 123.407858 -385.027716)
			(xy 123.450544 -385.049385) (xy 123.48933 -385.077446) (xy 123.523264 -385.111212) (xy 123.551518 -385.149857)
			(xy 123.562872 -385.170934) (xy 123.56338 -385.17195) (xy 123.643686 -385.310888) (xy 124.18568 -385.310888)
			(xy 124.18568 -385.31038) (xy 124.186121 -385.286374) (xy 124.193638 -385.238955) (xy 124.208484 -385.193296)
			(xy 124.230293 -385.150524) (xy 124.258527 -385.111692) (xy 124.292491 -385.077757) (xy 124.331347 -385.049556)
			(xy 124.374139 -385.027783) (xy 124.41981 -385.012977) (xy 124.467236 -385.0055) (xy 124.491242 -385.005072)
			(xy 124.515176 -385.005545) (xy 124.562461 -385.013002) (xy 124.608003 -385.027742) (xy 124.65069 -385.049404)
			(xy 124.689476 -385.077459) (xy 124.723412 -385.11122) (xy 124.751667 -385.14986) (xy 124.763022 -385.170934)
			(xy 124.76353 -385.17195) (xy 124.843836 -385.310888) (xy 125.385576 -385.310888) (xy 125.385576 -385.31038)
			(xy 125.386021 -385.286374) (xy 125.393538 -385.238955) (xy 125.408383 -385.193297) (xy 125.430192 -385.150525)
			(xy 125.458426 -385.111693) (xy 125.492389 -385.077758) (xy 125.531245 -385.049557) (xy 125.574036 -385.027785)
			(xy 125.619707 -385.012977) (xy 125.667132 -385.0055) (xy 125.691138 -385.005072) (xy 125.715072 -385.005549)
			(xy 125.762356 -385.013005) (xy 125.807899 -385.027744) (xy 125.850586 -385.049406) (xy 125.889372 -385.07746)
			(xy 125.923307 -385.11122) (xy 125.951563 -385.14986) (xy 125.962918 -385.170934) (xy 125.963426 -385.17195)
			(xy 126.043732 -385.310888) (xy 126.58598 -385.310888) (xy 126.58598 -385.31038) (xy 126.586444 -385.286389)
			(xy 126.593953 -385.238998) (xy 126.608782 -385.193364) (xy 126.630567 -385.150612) (xy 126.658771 -385.111795)
			(xy 126.692701 -385.077866) (xy 126.731519 -385.049663) (xy 126.774272 -385.027879) (xy 126.819905 -385.013051)
			(xy 126.867297 -385.005543) (xy 126.891288 -385.005072) (xy 126.915224 -385.005508) (xy 126.96251 -385.012972)
			(xy 127.008053 -385.027718) (xy 127.05074 -385.049387) (xy 127.089525 -385.077447) (xy 127.12346 -385.111213)
			(xy 127.151714 -385.149858) (xy 127.163068 -385.170934) (xy 127.163576 -385.17195) (xy 127.243882 -385.310888)
			(xy 127.785876 -385.310888) (xy 127.785876 -385.31038) (xy 127.786344 -385.286389) (xy 127.793853 -385.238998)
			(xy 127.808682 -385.193365) (xy 127.830467 -385.150614) (xy 127.85867 -385.111796) (xy 127.892599 -385.077868)
			(xy 127.931417 -385.049664) (xy 127.974169 -385.02788) (xy 128.019802 -385.013052) (xy 128.067193 -385.005544)
			(xy 128.091184 -385.005072) (xy 128.11512 -385.005511) (xy 128.162406 -385.012974) (xy 128.207949 -385.02772)
			(xy 128.250636 -385.049388) (xy 128.289421 -385.077448) (xy 128.323356 -385.111214) (xy 128.35161 -385.149858)
			(xy 128.362964 -385.170934) (xy 128.363472 -385.17195) (xy 128.443778 -385.310888) (xy 128.985772 -385.310888)
			(xy 128.985772 -385.31038) (xy 128.986244 -385.286389) (xy 128.993753 -385.238999) (xy 129.008581 -385.193366)
			(xy 129.030366 -385.150615) (xy 129.058569 -385.111797) (xy 129.092497 -385.077869) (xy 129.131315 -385.049666)
			(xy 129.174066 -385.027881) (xy 129.219699 -385.013053) (xy 129.267089 -385.005544) (xy 129.29108 -385.005072)
			(xy 129.315016 -385.005515) (xy 129.362301 -385.012977) (xy 129.407845 -385.027722) (xy 129.450531 -385.04939)
			(xy 129.489317 -385.077449) (xy 129.523252 -385.111214) (xy 129.551506 -385.149858) (xy 129.56286 -385.170934)
			(xy 129.563368 -385.17195) (xy 129.643674 -385.310888) (xy 130.185668 -385.310888) (xy 130.185668 -385.31038)
			(xy 130.186121 -385.286375) (xy 130.193637 -385.238957) (xy 130.208483 -385.193299) (xy 130.230291 -385.150527)
			(xy 130.258524 -385.111696) (xy 130.292486 -385.077761) (xy 130.331341 -385.04956) (xy 130.37413 -385.027787)
			(xy 130.4198 -385.012979) (xy 130.467224 -385.005501) (xy 130.49123 -385.005072) (xy 130.515164 -385.005555)
			(xy 130.562448 -385.01301) (xy 130.60799 -385.027748) (xy 130.650677 -385.049409) (xy 130.689463 -385.077462)
			(xy 130.723399 -385.111221) (xy 130.751655 -385.14986) (xy 130.76301 -385.170934) (xy 130.763518 -385.17195)
			(xy 130.843824 -385.310888) (xy 131.385564 -385.310888) (xy 131.385564 -385.31038) (xy 131.386021 -385.286375)
			(xy 131.393537 -385.238957) (xy 131.408382 -385.1933) (xy 131.43019 -385.150528) (xy 131.458422 -385.111697)
			(xy 131.492384 -385.077762) (xy 131.531239 -385.049561) (xy 131.574027 -385.027788) (xy 131.619697 -385.01298)
			(xy 131.667121 -385.005501) (xy 131.691126 -385.005072) (xy 131.71506 -385.005558) (xy 131.762344 -385.013013)
			(xy 131.807886 -385.02775) (xy 131.850573 -385.04941) (xy 131.889359 -385.077463) (xy 131.923295 -385.111222)
			(xy 131.951551 -385.14986) (xy 131.962906 -385.170934) (xy 131.963414 -385.17195) (xy 132.04372 -385.310888)
			(xy 132.585968 -385.310888) (xy 132.585968 -385.31038) (xy 132.586444 -385.286389) (xy 132.593952 -385.238999)
			(xy 132.608781 -385.193367) (xy 132.630565 -385.150616) (xy 132.658768 -385.111799) (xy 132.692696 -385.077871)
			(xy 132.731513 -385.049667) (xy 132.774263 -385.027883) (xy 132.819895 -385.013053) (xy 132.867285 -385.005544)
			(xy 132.891276 -385.005072) (xy 132.915211 -385.005518) (xy 132.962497 -385.01298) (xy 133.00804 -385.027724)
			(xy 133.050727 -385.049391) (xy 133.089512 -385.07745) (xy 133.123447 -385.111215) (xy 133.151701 -385.149858)
			(xy 133.163056 -385.170934) (xy 133.163564 -385.17195) (xy 133.24387 -385.310888) (xy 147.113752 -385.310888)
			(xy 147.113752 -385.31038) (xy 147.114244 -385.28639) (xy 147.121752 -385.239002) (xy 147.13658 -385.193371)
			(xy 147.158362 -385.150621) (xy 147.186563 -385.111804) (xy 147.220489 -385.077876) (xy 147.259304 -385.049673)
			(xy 147.302052 -385.027887) (xy 147.347682 -385.013057) (xy 147.39507 -385.005546) (xy 147.41906 -385.005072)
			(xy 147.442995 -385.005531) (xy 147.49028 -385.01299) (xy 147.535823 -385.027733) (xy 147.57851 -385.049398)
			(xy 147.617295 -385.077455) (xy 147.651231 -385.111217) (xy 147.679485 -385.149859) (xy 147.69084 -385.170934)
			(xy 147.691348 -385.17195) (xy 147.771654 -385.310888) (xy 148.313648 -385.310888) (xy 148.313648 -385.31038)
			(xy 148.314144 -385.28639) (xy 148.321652 -385.239002) (xy 148.336479 -385.193372) (xy 148.358261 -385.150622)
			(xy 148.386462 -385.111805) (xy 148.420387 -385.077878) (xy 148.459201 -385.049674) (xy 148.501949 -385.027888)
			(xy 148.547579 -385.013057) (xy 148.594966 -385.005546) (xy 148.618956 -385.005072) (xy 148.642891 -385.005534)
			(xy 148.690176 -385.012993) (xy 148.735719 -385.027735) (xy 148.778405 -385.049399) (xy 148.817191 -385.077456)
			(xy 148.851126 -385.111218) (xy 148.879381 -385.149859) (xy 148.890736 -385.170934) (xy 148.891244 -385.17195)
			(xy 148.97155 -385.310888) (xy 149.513544 -385.310888) (xy 149.513544 -385.31038) (xy 149.514044 -385.286391)
			(xy 149.521552 -385.239003) (xy 149.536379 -385.193373) (xy 149.558161 -385.150623) (xy 149.586361 -385.111807)
			(xy 149.620286 -385.077879) (xy 149.659099 -385.049675) (xy 149.701847 -385.02789) (xy 149.747476 -385.013058)
			(xy 149.794863 -385.005546) (xy 149.818852 -385.005072) (xy 149.842787 -385.005537) (xy 149.890071 -385.012995)
			(xy 149.935614 -385.027737) (xy 149.978301 -385.049401) (xy 150.017087 -385.077457) (xy 150.051022 -385.111218)
			(xy 150.079277 -385.149859) (xy 150.090632 -385.170934) (xy 150.09114 -385.17195) (xy 150.171446 -385.310888)
			(xy 150.71344 -385.310888) (xy 150.71344 -385.31038) (xy 150.713821 -385.286371) (xy 150.72134 -385.238946)
			(xy 150.73619 -385.193282) (xy 150.758004 -385.150506) (xy 150.786245 -385.111671) (xy 150.820216 -385.077735)
			(xy 150.859081 -385.049535) (xy 150.90188 -385.027766) (xy 150.94756 -385.012965) (xy 150.994993 -385.005496)
			(xy 151.019002 -385.005072) (xy 151.042935 -385.005578) (xy 151.090218 -385.013028) (xy 151.13576 -385.027763)
			(xy 151.178447 -385.04942) (xy 151.217233 -385.077469) (xy 151.25117 -385.111225) (xy 151.279426 -385.149861)
			(xy 151.290782 -385.170934) (xy 151.29129 -385.17195) (xy 151.371596 -385.310888) (xy 151.913336 -385.310888)
			(xy 151.913336 -385.31038) (xy 151.913721 -385.286371) (xy 151.92124 -385.238947) (xy 151.936089 -385.193283)
			(xy 151.957903 -385.150507) (xy 151.986144 -385.111672) (xy 152.020115 -385.077737) (xy 152.058979 -385.049537)
			(xy 152.101777 -385.027767) (xy 152.147456 -385.012965) (xy 152.194889 -385.005496) (xy 152.218898 -385.005072)
			(xy 152.242834 -385.0055) (xy 152.290121 -385.012965) (xy 152.335664 -385.027713) (xy 152.378351 -385.049383)
			(xy 152.417136 -385.077445) (xy 152.45107 -385.111212) (xy 152.479324 -385.149857) (xy 152.490678 -385.170934)
			(xy 152.491186 -385.17195) (xy 152.571492 -385.310888) (xy 153.11374 -385.310888) (xy 153.11374 -385.31038)
			(xy 153.11412 -385.286384) (xy 153.121631 -385.238983) (xy 153.136465 -385.193341) (xy 153.158257 -385.150582)
			(xy 153.18647 -385.111758) (xy 153.22041 -385.077826) (xy 153.25924 -385.049622) (xy 153.302004 -385.027839)
			(xy 153.347649 -385.013015) (xy 153.395052 -385.005515) (xy 153.419048 -385.005072) (xy 153.442983 -385.005541)
			(xy 153.490267 -385.012998) (xy 153.53581 -385.027739) (xy 153.578497 -385.049402) (xy 153.617282 -385.077458)
			(xy 153.651218 -385.111219) (xy 153.679473 -385.149859) (xy 153.690828 -385.170934) (xy 153.691336 -385.17195)
			(xy 153.771642 -385.310888) (xy 154.313636 -385.310888) (xy 154.313636 -385.31038) (xy 154.31402 -385.286384)
			(xy 154.321531 -385.238984) (xy 154.336365 -385.193342) (xy 154.358157 -385.150583) (xy 154.386369 -385.111759)
			(xy 154.420308 -385.077828) (xy 154.459138 -385.049623) (xy 154.501901 -385.02784) (xy 154.547546 -385.013016)
			(xy 154.594948 -385.005515) (xy 154.618944 -385.005072) (xy 154.642878 -385.005544) (xy 154.690163 -385.013001)
			(xy 154.735706 -385.027741) (xy 154.778392 -385.049404) (xy 154.817178 -385.077459) (xy 154.851114 -385.111219)
			(xy 154.879369 -385.14986) (xy 154.890724 -385.170934) (xy 154.891232 -385.17195) (xy 154.971538 -385.310888)
			(xy 155.513532 -385.310888) (xy 155.513532 -385.31038) (xy 155.51392 -385.286384) (xy 155.521431 -385.238984)
			(xy 155.536265 -385.193343) (xy 155.558056 -385.150584) (xy 155.586268 -385.111761) (xy 155.620206 -385.077829)
			(xy 155.659035 -385.049624) (xy 155.701798 -385.027842) (xy 155.747443 -385.013017) (xy 155.794844 -385.005515)
			(xy 155.81884 -385.005072) (xy 155.842774 -385.005547) (xy 155.890059 -385.013003) (xy 155.935601 -385.027743)
			(xy 155.978288 -385.049405) (xy 156.017074 -385.07746) (xy 156.05101 -385.11122) (xy 156.079265 -385.14986)
			(xy 156.09062 -385.170934) (xy 156.091128 -385.17195) (xy 156.171434 -385.310888) (xy 156.713428 -385.310888)
			(xy 156.713428 -385.31038) (xy 156.713821 -385.286372) (xy 156.721339 -385.238948) (xy 156.736188 -385.193285)
			(xy 156.758002 -385.150509) (xy 156.786241 -385.111675) (xy 156.820211 -385.07774) (xy 156.859074 -385.049539)
			(xy 156.901872 -385.02777) (xy 156.94755 -385.012967) (xy 156.994981 -385.005497) (xy 157.01899 -385.005072)
			(xy 157.042926 -385.005506) (xy 157.090212 -385.01297) (xy 157.135756 -385.027717) (xy 157.178442 -385.049386)
			(xy 157.217227 -385.077447) (xy 157.251162 -385.111213) (xy 157.279416 -385.149857) (xy 157.29077 -385.170934)
			(xy 157.291278 -385.17195) (xy 157.371584 -385.310888) (xy 157.913324 -385.310888) (xy 157.913324 -385.31038)
			(xy 157.913721 -385.286372) (xy 157.921239 -385.238948) (xy 157.936088 -385.193286) (xy 157.957901 -385.15051)
			(xy 157.98614 -385.111676) (xy 158.020109 -385.077741) (xy 158.058972 -385.049541) (xy 158.101769 -385.027771)
			(xy 158.147446 -385.012968) (xy 158.194878 -385.005497) (xy 158.218886 -385.005072) (xy 158.242822 -385.00551)
			(xy 158.290108 -385.012973) (xy 158.335651 -385.027719) (xy 158.378338 -385.049388) (xy 158.417123 -385.077448)
			(xy 158.451058 -385.111213) (xy 158.479312 -385.149858) (xy 158.490666 -385.170934) (xy 158.491174 -385.17195)
			(xy 158.57148 -385.310888) (xy 159.113728 -385.310888) (xy 159.113728 -385.31038) (xy 159.11412 -385.286385)
			(xy 159.121631 -385.238985) (xy 159.136464 -385.193344) (xy 159.158255 -385.150585) (xy 159.186467 -385.111762)
			(xy 159.220405 -385.07783) (xy 159.259233 -385.049626) (xy 159.301996 -385.027843) (xy 159.347639 -385.013018)
			(xy 159.39504 -385.005515) (xy 159.419036 -385.005072) (xy 159.44297 -385.00555) (xy 159.490254 -385.013006)
			(xy 159.535797 -385.027745) (xy 159.578484 -385.049407) (xy 159.617269 -385.077461) (xy 159.651205 -385.11122)
			(xy 159.679461 -385.14986) (xy 159.690816 -385.170934) (xy 159.691324 -385.17195) (xy 159.77163 -385.310888)
			(xy 160.313624 -385.310888) (xy 160.313624 -385.31038) (xy 160.31402 -385.286385) (xy 160.321531 -385.238985)
			(xy 160.336364 -385.193345) (xy 160.358154 -385.150586) (xy 160.386366 -385.111764) (xy 160.420303 -385.077832)
			(xy 160.459131 -385.049627) (xy 160.501893 -385.027844) (xy 160.547536 -385.013018) (xy 160.594937 -385.005516)
			(xy 160.618932 -385.005072) (xy 160.642866 -385.005554) (xy 160.69015 -385.013009) (xy 160.735693 -385.027747)
			(xy 160.778379 -385.049408) (xy 160.817165 -385.077462) (xy 160.851101 -385.111221) (xy 160.879357 -385.14986)
			(xy 160.890712 -385.170934) (xy 160.89122 -385.17195) (xy 160.971526 -385.310888) (xy 161.51352 -385.310888)
			(xy 161.51352 -385.31038) (xy 161.51392 -385.286385) (xy 161.52143 -385.238986) (xy 161.536263 -385.193346)
			(xy 161.558054 -385.150588) (xy 161.586265 -385.111765) (xy 161.620201 -385.077833) (xy 161.659029 -385.049629)
			(xy 161.70179 -385.027845) (xy 161.747433 -385.013019) (xy 161.794833 -385.005516) (xy 161.818828 -385.005072)
			(xy 161.842762 -385.005557) (xy 161.890046 -385.013011) (xy 161.935588 -385.027749) (xy 161.978275 -385.04941)
			(xy 162.017061 -385.077463) (xy 162.050997 -385.111222) (xy 162.079253 -385.14986) (xy 162.090608 -385.170934)
			(xy 162.091116 -385.17195) (xy 162.171422 -385.310888) (xy 162.713416 -385.310888) (xy 162.713416 -385.31038)
			(xy 162.713821 -385.286372) (xy 162.721339 -385.238949) (xy 162.736187 -385.193288) (xy 162.757999 -385.150513)
			(xy 162.786238 -385.111679) (xy 162.820206 -385.077744) (xy 162.859067 -385.049543) (xy 162.901864 -385.027773)
			(xy 162.94754 -385.012969) (xy 162.99497 -385.005497) (xy 163.018978 -385.005072) (xy 163.042913 -385.005516)
			(xy 163.090199 -385.012978) (xy 163.135743 -385.027723) (xy 163.178429 -385.049391) (xy 163.217215 -385.07745)
			(xy 163.251149 -385.111214) (xy 163.279404 -385.149858) (xy 163.290758 -385.170934) (xy 163.291266 -385.17195)
			(xy 163.371572 -385.310888) (xy 163.913312 -385.310888) (xy 163.913312 -385.31038) (xy 163.913721 -385.286373)
			(xy 163.921239 -385.23895) (xy 163.936087 -385.193289) (xy 163.957899 -385.150514) (xy 163.986137 -385.111681)
			(xy 164.020104 -385.077745) (xy 164.058965 -385.049545) (xy 164.101761 -385.027774) (xy 164.147436 -385.01297)
			(xy 164.194866 -385.005498) (xy 164.218874 -385.005072) (xy 164.242809 -385.005519) (xy 164.290095 -385.012981)
			(xy 164.335638 -385.027726) (xy 164.378325 -385.049392) (xy 164.41711 -385.077451) (xy 164.451045 -385.111215)
			(xy 164.479299 -385.149858) (xy 164.490654 -385.170934) (xy 164.491162 -385.17195) (xy 164.571468 -385.310888)
			(xy 165.113716 -385.310888) (xy 165.113716 -385.31038) (xy 165.11412 -385.286385) (xy 165.12163 -385.238987)
			(xy 165.136463 -385.193347) (xy 165.158253 -385.150589) (xy 165.186463 -385.111766) (xy 165.2204 -385.077835)
			(xy 165.259226 -385.04963) (xy 165.301987 -385.027846) (xy 165.347629 -385.01302) (xy 165.395029 -385.005516)
			(xy 165.419024 -385.005072) (xy 165.442958 -385.00556) (xy 165.490242 -385.013014) (xy 165.535784 -385.027751)
			(xy 165.578471 -385.049411) (xy 165.617257 -385.077464) (xy 165.651193 -385.111222) (xy 165.679449 -385.14986)
			(xy 165.690804 -385.170934) (xy 165.691312 -385.17195) (xy 166.083742 -385.850892) (xy 166.096567 -385.874224)
			(xy 166.114787 -385.924247) (xy 166.124047 -385.976673) (xy 166.124636 -386.003292) (xy 166.124154 -386.027296)
			(xy 166.116641 -386.074713) (xy 166.1018 -386.12037) (xy 166.079996 -386.163141) (xy 166.051766 -386.201973)
			(xy 166.017807 -386.235908) (xy 165.978955 -386.26411) (xy 165.936168 -386.285883) (xy 165.890501 -386.300692)
			(xy 165.843079 -386.308171) (xy 165.819074 -386.3086) (xy 165.795499 -386.308227) (xy 165.74891 -386.300982)
			(xy 165.703991 -386.286652) (xy 165.661813 -386.26558) (xy 165.62338 -386.238267) (xy 165.589609 -386.205365)
			(xy 165.561304 -386.167657) (xy 165.549834 -386.147056) (xy 165.549326 -386.146294) (xy 165.151562 -385.457954)
			(xy 165.139704 -385.435268) (xy 165.122846 -385.38694) (xy 165.114266 -385.33648) (xy 165.113716 -385.310888)
			(xy 164.571468 -385.310888) (xy 164.883592 -385.850892) (xy 164.896342 -385.874249) (xy 164.914451 -385.924281)
			(xy 164.923654 -385.976688) (xy 164.924232 -386.003292) (xy 164.92373 -386.027282) (xy 164.916226 -386.074671)
			(xy 164.901401 -386.120303) (xy 164.879621 -386.163054) (xy 164.851421 -386.201871) (xy 164.817496 -386.2358)
			(xy 164.778681 -386.264004) (xy 164.735932 -386.285789) (xy 164.690302 -386.300618) (xy 164.642914 -386.308128)
			(xy 164.618924 -386.3086) (xy 164.595351 -386.308187) (xy 164.548763 -386.300949) (xy 164.503845 -386.286627)
			(xy 164.461667 -386.265561) (xy 164.423233 -386.238255) (xy 164.389461 -386.205358) (xy 164.361155 -386.167655)
			(xy 164.349684 -386.147056) (xy 164.349176 -386.146294) (xy 163.951412 -385.457954) (xy 163.939479 -385.435295)
			(xy 163.922547 -385.386965) (xy 163.913895 -385.336491) (xy 163.913312 -385.310888) (xy 163.371572 -385.310888)
			(xy 163.683696 -385.850892) (xy 163.696446 -385.874249) (xy 163.714555 -385.924281) (xy 163.723758 -385.976688)
			(xy 163.724336 -386.003292) (xy 163.72383 -386.027282) (xy 163.716326 -386.07467) (xy 163.701501 -386.120302)
			(xy 163.679721 -386.163053) (xy 163.651522 -386.20187) (xy 163.617597 -386.235798) (xy 163.578783 -386.264002)
			(xy 163.536035 -386.285788) (xy 163.490405 -386.300618) (xy 163.443018 -386.308127) (xy 163.419028 -386.3086)
			(xy 163.395455 -386.308184) (xy 163.348868 -386.300946) (xy 163.30395 -386.286625) (xy 163.261771 -386.26556)
			(xy 163.223338 -386.238254) (xy 163.189565 -386.205357) (xy 163.161259 -386.167654) (xy 163.149788 -386.147056)
			(xy 163.14928 -386.146294) (xy 162.751516 -385.457954) (xy 162.739583 -385.435294) (xy 162.722652 -385.386965)
			(xy 162.713999 -385.336491) (xy 162.713416 -385.310888) (xy 162.171422 -385.310888) (xy 162.483546 -385.850892)
			(xy 162.496371 -385.874224) (xy 162.514591 -385.924247) (xy 162.523851 -385.976673) (xy 162.52444 -386.003292)
			(xy 162.523954 -386.027296) (xy 162.516441 -386.074713) (xy 162.5016 -386.120369) (xy 162.479796 -386.16314)
			(xy 162.451567 -386.201972) (xy 162.417609 -386.235907) (xy 162.378757 -386.264108) (xy 162.335971 -386.285882)
			(xy 162.290304 -386.300691) (xy 162.242882 -386.30817) (xy 162.218878 -386.3086) (xy 162.195303 -386.308224)
			(xy 162.148714 -386.300979) (xy 162.103795 -386.28665) (xy 162.061617 -386.265579) (xy 162.023184 -386.238266)
			(xy 161.989413 -386.205364) (xy 161.961108 -386.167657) (xy 161.949638 -386.147056) (xy 161.94913 -386.146294)
			(xy 161.551366 -385.457954) (xy 161.539508 -385.435268) (xy 161.52265 -385.38694) (xy 161.51407 -385.33648)
			(xy 161.51352 -385.310888) (xy 160.971526 -385.310888) (xy 161.28365 -385.850892) (xy 161.296476 -385.874224)
			(xy 161.314695 -385.924247) (xy 161.323955 -385.976673) (xy 161.324544 -386.003292) (xy 161.324054 -386.027296)
			(xy 161.316541 -386.074712) (xy 161.301701 -386.120368) (xy 161.279897 -386.163139) (xy 161.251669 -386.20197)
			(xy 161.21771 -386.235905) (xy 161.17886 -386.264107) (xy 161.136074 -386.285881) (xy 161.090407 -386.30069)
			(xy 161.042986 -386.30817) (xy 161.018982 -386.3086) (xy 160.995407 -386.308221) (xy 160.948819 -386.300977)
			(xy 160.9039 -386.286648) (xy 160.861721 -386.265577) (xy 160.823288 -386.238265) (xy 160.789517 -386.205364)
			(xy 160.761212 -386.167657) (xy 160.749742 -386.147056) (xy 160.749234 -386.146294) (xy 160.35147 -385.457954)
			(xy 160.339612 -385.435268) (xy 160.322755 -385.386939) (xy 160.314174 -385.33648) (xy 160.313624 -385.310888)
			(xy 159.77163 -385.310888) (xy 160.083754 -385.850892) (xy 160.09658 -385.874224) (xy 160.114799 -385.924247)
			(xy 160.124059 -385.976673) (xy 160.124648 -386.003292) (xy 160.124154 -386.027296) (xy 160.116641 -386.074711)
			(xy 160.101801 -386.120367) (xy 160.079998 -386.163138) (xy 160.05177 -386.201969) (xy 160.017812 -386.235904)
			(xy 159.978962 -386.264106) (xy 159.936177 -386.28588) (xy 159.890511 -386.30069) (xy 159.84309 -386.30817)
			(xy 159.819086 -386.3086) (xy 159.795512 -386.308217) (xy 159.748923 -386.300974) (xy 159.704004 -386.286646)
			(xy 159.661826 -386.265576) (xy 159.623393 -386.238264) (xy 159.589621 -386.205363) (xy 159.561316 -386.167656)
			(xy 159.549846 -386.147056) (xy 159.549338 -386.146294) (xy 159.151574 -385.457954) (xy 159.139717 -385.435268)
			(xy 159.122859 -385.386939) (xy 159.114278 -385.336479) (xy 159.113728 -385.310888) (xy 158.57148 -385.310888)
			(xy 158.883604 -385.850892) (xy 158.896355 -385.874249) (xy 158.914464 -385.924281) (xy 158.923666 -385.976688)
			(xy 158.924244 -386.003292) (xy 158.92373 -386.027281) (xy 158.916226 -386.074669) (xy 158.901402 -386.1203)
			(xy 158.879623 -386.16305) (xy 158.851424 -386.201867) (xy 158.817501 -386.235796) (xy 158.778688 -386.264)
			(xy 158.735941 -386.285785) (xy 158.690312 -386.300616) (xy 158.642925 -386.308127) (xy 158.618936 -386.3086)
			(xy 158.595363 -386.308177) (xy 158.548776 -386.300941) (xy 158.503858 -386.286621) (xy 158.46168 -386.265557)
			(xy 158.423246 -386.238252) (xy 158.389474 -386.205356) (xy 158.361167 -386.167654) (xy 158.349696 -386.147056)
			(xy 158.349188 -386.146294) (xy 157.951424 -385.457954) (xy 157.939492 -385.435294) (xy 157.92256 -385.386965)
			(xy 157.913907 -385.336491) (xy 157.913324 -385.310888) (xy 157.371584 -385.310888) (xy 157.683708 -385.850892)
			(xy 157.696459 -385.874248) (xy 157.714568 -385.924281) (xy 157.72377 -385.976688) (xy 157.724348 -386.003292)
			(xy 157.72383 -386.027281) (xy 157.716326 -386.074669) (xy 157.701503 -386.120299) (xy 157.679724 -386.163049)
			(xy 157.651525 -386.201866) (xy 157.617603 -386.235794) (xy 157.57879 -386.263998) (xy 157.536043 -386.285784)
			(xy 157.490415 -386.300615) (xy 157.443029 -386.308126) (xy 157.41904 -386.3086) (xy 157.395467 -386.308174)
			(xy 157.34888 -386.300939) (xy 157.303963 -386.286618) (xy 157.261784 -386.265555) (xy 157.223351 -386.238251)
			(xy 157.189578 -386.205355) (xy 157.161271 -386.167654) (xy 157.1498 -386.147056) (xy 157.149292 -386.146294)
			(xy 156.751528 -385.457954) (xy 156.739596 -385.435294) (xy 156.722664 -385.386965) (xy 156.714011 -385.336491)
			(xy 156.713428 -385.310888) (xy 156.171434 -385.310888) (xy 156.483558 -385.850892) (xy 156.496384 -385.874224)
			(xy 156.514604 -385.924247) (xy 156.523863 -385.976673) (xy 156.524452 -386.003292) (xy 156.523954 -386.027295)
			(xy 156.516442 -386.074711) (xy 156.501601 -386.120366) (xy 156.479799 -386.163137) (xy 156.451571 -386.201968)
			(xy 156.417614 -386.235902) (xy 156.378764 -386.264104) (xy 156.335979 -386.285879) (xy 156.290314 -386.300689)
			(xy 156.242894 -386.308169) (xy 156.21889 -386.3086) (xy 156.195316 -386.308214) (xy 156.148727 -386.300971)
			(xy 156.103808 -386.286644) (xy 156.06163 -386.265574) (xy 156.023197 -386.238263) (xy 155.989426 -386.205363)
			(xy 155.96112 -386.167656) (xy 155.94965 -386.147056) (xy 155.949142 -386.146294) (xy 155.551378 -385.457954)
			(xy 155.539521 -385.435268) (xy 155.522663 -385.386939) (xy 155.514082 -385.336479) (xy 155.513532 -385.310888)
			(xy 154.971538 -385.310888) (xy 155.283662 -385.850892) (xy 155.296489 -385.874224) (xy 155.314708 -385.924247)
			(xy 155.323967 -385.976673) (xy 155.324556 -386.003292) (xy 155.324054 -386.027295) (xy 155.316542 -386.07471)
			(xy 155.301702 -386.120365) (xy 155.279899 -386.163135) (xy 155.251672 -386.201966) (xy 155.217715 -386.235901)
			(xy 155.178866 -386.264103) (xy 155.136082 -386.285878) (xy 155.090417 -386.300688) (xy 155.042998 -386.308169)
			(xy 155.018994 -386.3086) (xy 154.99542 -386.308211) (xy 154.948831 -386.300969) (xy 154.903913 -386.286642)
			(xy 154.861734 -386.265573) (xy 154.823301 -386.238262) (xy 154.78953 -386.205362) (xy 154.761224 -386.167656)
			(xy 154.749754 -386.147056) (xy 154.749246 -386.146294) (xy 154.351482 -385.457954) (xy 154.339625 -385.435268)
			(xy 154.322767 -385.386939) (xy 154.314186 -385.336479) (xy 154.313636 -385.310888) (xy 153.771642 -385.310888)
			(xy 154.083766 -385.850892) (xy 154.096593 -385.874223) (xy 154.114812 -385.924247) (xy 154.124071 -385.976673)
			(xy 154.12466 -386.003292) (xy 154.124253 -386.0273) (xy 154.116738 -386.074724) (xy 154.101893 -386.120388)
			(xy 154.080082 -386.163164) (xy 154.051844 -386.201999) (xy 154.017875 -386.235935) (xy 153.979013 -386.264136)
			(xy 153.936216 -386.285905) (xy 153.890538 -386.300707) (xy 153.843106 -386.308176) (xy 153.819098 -386.3086)
			(xy 153.795524 -386.308208) (xy 153.748936 -386.300966) (xy 153.704017 -386.28664) (xy 153.661839 -386.265571)
			(xy 153.623406 -386.238261) (xy 153.589634 -386.205361) (xy 153.561328 -386.167656) (xy 153.549858 -386.147056)
			(xy 153.54935 -386.146294) (xy 153.151586 -385.457954) (xy 153.13973 -385.435267) (xy 153.122871 -385.386939)
			(xy 153.11429 -385.336479) (xy 153.11374 -385.310888) (xy 152.571492 -385.310888) (xy 152.883616 -385.850892)
			(xy 152.896368 -385.874248) (xy 152.914476 -385.924281) (xy 152.923678 -385.976688) (xy 152.924256 -386.003292)
			(xy 152.92373 -386.027281) (xy 152.916227 -386.074667) (xy 152.901403 -386.120297) (xy 152.879625 -386.163047)
			(xy 152.851428 -386.201863) (xy 152.817506 -386.235791) (xy 152.778694 -386.263996) (xy 152.735949 -386.285782)
			(xy 152.690322 -386.300614) (xy 152.642937 -386.308126) (xy 152.618948 -386.3086) (xy 152.595375 -386.308168)
			(xy 152.548789 -386.300933) (xy 152.503871 -386.286614) (xy 152.461693 -386.265552) (xy 152.423259 -386.238248)
			(xy 152.389486 -386.205354) (xy 152.361179 -386.167654) (xy 152.349708 -386.147056) (xy 152.3492 -386.146294)
			(xy 151.951436 -385.457954) (xy 151.939505 -385.435294) (xy 151.922572 -385.386964) (xy 151.913919 -385.336491)
			(xy 151.913336 -385.310888) (xy 151.371596 -385.310888) (xy 151.68372 -385.850892) (xy 151.696472 -385.874248)
			(xy 151.71458 -385.924281) (xy 151.723782 -385.976688) (xy 151.72436 -386.003292) (xy 151.723954 -386.027287)
			(xy 151.716447 -386.074687) (xy 151.701617 -386.120329) (xy 151.679828 -386.163088) (xy 151.651618 -386.201912)
			(xy 151.617682 -386.235844) (xy 151.578854 -386.264049) (xy 151.536092 -386.285832) (xy 151.490448 -386.300657)
			(xy 151.443047 -386.308157) (xy 151.419052 -386.3086) (xy 151.395479 -386.308164) (xy 151.348893 -386.300931)
			(xy 151.303976 -386.286612) (xy 151.261797 -386.265551) (xy 151.223364 -386.238247) (xy 151.189591 -386.205354)
			(xy 151.161283 -386.167653) (xy 151.149812 -386.147056) (xy 151.149304 -386.146294) (xy 150.75154 -385.457954)
			(xy 150.739609 -385.435293) (xy 150.722676 -385.386964) (xy 150.714023 -385.336491) (xy 150.71344 -385.310888)
			(xy 150.171446 -385.310888) (xy 150.48357 -385.850892) (xy 150.496397 -385.874223) (xy 150.514616 -385.924247)
			(xy 150.523875 -385.976673) (xy 150.524464 -386.003292) (xy 150.524053 -386.0273) (xy 150.516539 -386.074724)
			(xy 150.501693 -386.120387) (xy 150.479883 -386.163163) (xy 150.451645 -386.201998) (xy 150.417677 -386.235934)
			(xy 150.378815 -386.264134) (xy 150.336018 -386.285904) (xy 150.290341 -386.300706) (xy 150.24291 -386.308176)
			(xy 150.218902 -386.3086) (xy 150.195328 -386.308205) (xy 150.14874 -386.300963) (xy 150.103821 -386.286638)
			(xy 150.061643 -386.26557) (xy 150.02321 -386.23826) (xy 149.989438 -386.205361) (xy 149.961133 -386.167656)
			(xy 149.949662 -386.147056) (xy 149.949154 -386.146294) (xy 149.55139 -385.457954) (xy 149.539534 -385.435267)
			(xy 149.522675 -385.386939) (xy 149.514094 -385.336479) (xy 149.513544 -385.310888) (xy 148.97155 -385.310888)
			(xy 149.283674 -385.850892) (xy 149.296501 -385.874223) (xy 149.31472 -385.924247) (xy 149.323979 -385.976673)
			(xy 149.324568 -386.003292) (xy 149.324153 -386.0273) (xy 149.316639 -386.074723) (xy 149.301793 -386.120386)
			(xy 149.279983 -386.163162) (xy 149.251746 -386.201996) (xy 149.217779 -386.235932) (xy 149.178917 -386.264133)
			(xy 149.136121 -386.285903) (xy 149.090445 -386.300706) (xy 149.043014 -386.308176) (xy 149.019006 -386.3086)
			(xy 148.995432 -386.308201) (xy 148.948844 -386.300961) (xy 148.903926 -386.286636) (xy 148.861747 -386.265568)
			(xy 148.823314 -386.238259) (xy 148.789542 -386.20536) (xy 148.761237 -386.167655) (xy 148.749766 -386.147056)
			(xy 148.749258 -386.146294) (xy 148.351494 -385.457954) (xy 148.339638 -385.435267) (xy 148.322779 -385.386939)
			(xy 148.314198 -385.336479) (xy 148.313648 -385.310888) (xy 147.771654 -385.310888) (xy 148.083778 -385.850892)
			(xy 148.096606 -385.874223) (xy 148.114824 -385.924247) (xy 148.124083 -385.976673) (xy 148.124672 -386.003292)
			(xy 148.124253 -386.027299) (xy 148.116739 -386.074723) (xy 148.101894 -386.120385) (xy 148.080084 -386.163161)
			(xy 148.051848 -386.201995) (xy 148.01788 -386.235931) (xy 147.97902 -386.264132) (xy 147.936224 -386.285902)
			(xy 147.890548 -386.300705) (xy 147.843118 -386.308175) (xy 147.81911 -386.3086) (xy 147.795536 -386.308198)
			(xy 147.748948 -386.300958) (xy 147.70403 -386.286634) (xy 147.661852 -386.265566) (xy 147.623418 -386.238258)
			(xy 147.589647 -386.20536) (xy 147.561341 -386.167655) (xy 147.54987 -386.147056) (xy 147.549362 -386.146294)
			(xy 147.151598 -385.457954) (xy 147.139742 -385.435267) (xy 147.122883 -385.386939) (xy 147.114302 -385.336479)
			(xy 147.113752 -385.310888) (xy 133.24387 -385.310888) (xy 133.555994 -385.850892) (xy 133.568823 -385.874222)
			(xy 133.587041 -385.924246) (xy 133.596299 -385.976673) (xy 133.596888 -386.003292) (xy 133.596453 -386.027299)
			(xy 133.588939 -386.07472) (xy 133.574095 -386.120381) (xy 133.552287 -386.163156) (xy 133.524052 -386.20199)
			(xy 133.490087 -386.235925) (xy 133.451229 -386.264126) (xy 133.408435 -386.285897) (xy 133.362761 -386.300702)
			(xy 133.315333 -386.308174) (xy 133.291326 -386.3086) (xy 133.267753 -386.308185) (xy 133.221165 -386.300948)
			(xy 133.176247 -386.286626) (xy 133.134069 -386.26556) (xy 133.095636 -386.238254) (xy 133.061863 -386.205357)
			(xy 133.033557 -386.167655) (xy 133.022086 -386.147056) (xy 133.021578 -386.146294) (xy 132.623814 -385.457954)
			(xy 132.611952 -385.43527) (xy 132.595097 -385.38694) (xy 132.586517 -385.33648) (xy 132.585968 -385.310888)
			(xy 132.04372 -385.310888) (xy 132.355844 -385.850892) (xy 132.368598 -385.874247) (xy 132.386705 -385.92428)
			(xy 132.395906 -385.976688) (xy 132.396484 -386.003292) (xy 132.396054 -386.027286) (xy 132.388548 -386.074684)
			(xy 132.373719 -386.120323) (xy 132.351933 -386.163081) (xy 132.323725 -386.201904) (xy 132.289792 -386.235836)
			(xy 132.250967 -386.264041) (xy 132.208208 -386.285825) (xy 132.162568 -386.300652) (xy 132.11517 -386.308156)
			(xy 132.091176 -386.3086) (xy 132.067601 -386.308226) (xy 132.021012 -386.30098) (xy 131.976093 -386.286651)
			(xy 131.933915 -386.265579) (xy 131.895482 -386.238267) (xy 131.861711 -386.205365) (xy 131.833406 -386.167657)
			(xy 131.821936 -386.147056) (xy 131.821428 -386.146294) (xy 131.423664 -385.457954) (xy 131.411735 -385.435292)
			(xy 131.394801 -385.386964) (xy 131.386148 -385.336491) (xy 131.385564 -385.310888) (xy 130.843824 -385.310888)
			(xy 131.155948 -385.850892) (xy 131.168702 -385.874247) (xy 131.186809 -385.92428) (xy 131.19601 -385.976688)
			(xy 131.196588 -386.003292) (xy 131.196154 -386.027286) (xy 131.188648 -386.074683) (xy 131.17382 -386.120322)
			(xy 131.152033 -386.16308) (xy 131.123826 -386.201902) (xy 131.089893 -386.235834) (xy 131.05107 -386.26404)
			(xy 131.008311 -386.285824) (xy 130.962671 -386.300651) (xy 130.915274 -386.308155) (xy 130.89128 -386.3086)
			(xy 130.867705 -386.308222) (xy 130.821116 -386.300978) (xy 130.776197 -386.286649) (xy 130.734019 -386.265578)
			(xy 130.695586 -386.238266) (xy 130.661815 -386.205364) (xy 130.63351 -386.167657) (xy 130.62204 -386.147056)
			(xy 130.621532 -386.146294) (xy 130.223768 -385.457954) (xy 130.211839 -385.435292) (xy 130.194906 -385.386964)
			(xy 130.186252 -385.336491) (xy 130.185668 -385.310888) (xy 129.643674 -385.310888) (xy 129.955798 -385.850892)
			(xy 129.968619 -385.874226) (xy 129.986842 -385.924248) (xy 129.996103 -385.976674) (xy 129.996692 -386.003292)
			(xy 129.996253 -386.027298) (xy 129.98874 -386.07472) (xy 129.973896 -386.12038) (xy 129.952088 -386.163155)
			(xy 129.923853 -386.201988) (xy 129.889889 -386.235924) (xy 129.851031 -386.264125) (xy 129.808238 -386.285896)
			(xy 129.762564 -386.300701) (xy 129.715137 -386.308174) (xy 129.69113 -386.3086) (xy 129.667557 -386.308182)
			(xy 129.62097 -386.300945) (xy 129.576052 -386.286624) (xy 129.533873 -386.265559) (xy 129.49544 -386.238253)
			(xy 129.461668 -386.205357) (xy 129.433361 -386.167654) (xy 129.42189 -386.147056) (xy 129.421382 -386.146294)
			(xy 129.023618 -385.457954) (xy 129.011756 -385.43527) (xy 128.994901 -385.38694) (xy 128.986321 -385.33648)
			(xy 128.985772 -385.310888) (xy 128.443778 -385.310888) (xy 128.755902 -385.850892) (xy 128.768724 -385.874226)
			(xy 128.786946 -385.924248) (xy 128.796207 -385.976674) (xy 128.796796 -386.003292) (xy 128.796353 -386.027298)
			(xy 128.78884 -386.074719) (xy 128.773996 -386.120379) (xy 128.752188 -386.163153) (xy 128.723955 -386.201987)
			(xy 128.68999 -386.235922) (xy 128.651133 -386.264123) (xy 128.608341 -386.285895) (xy 128.562668 -386.3007)
			(xy 128.515241 -386.308174) (xy 128.491234 -386.3086) (xy 128.467661 -386.308179) (xy 128.421074 -386.300942)
			(xy 128.376156 -386.286622) (xy 128.333978 -386.265557) (xy 128.295544 -386.238252) (xy 128.261772 -386.205356)
			(xy 128.233465 -386.167654) (xy 128.221994 -386.147056) (xy 128.221486 -386.146294) (xy 127.823722 -385.457954)
			(xy 127.811861 -385.43527) (xy 127.795005 -385.38694) (xy 127.786426 -385.33648) (xy 127.785876 -385.310888)
			(xy 127.243882 -385.310888) (xy 127.556006 -385.850892) (xy 127.568828 -385.874226) (xy 127.58705 -385.924248)
			(xy 127.596311 -385.976674) (xy 127.5969 -386.003292) (xy 127.596454 -386.027298) (xy 127.58894 -386.074718)
			(xy 127.574096 -386.120378) (xy 127.552289 -386.163152) (xy 127.524056 -386.201985) (xy 127.490092 -386.235921)
			(xy 127.451235 -386.264122) (xy 127.408443 -386.285894) (xy 127.362771 -386.300699) (xy 127.315344 -386.308173)
			(xy 127.291338 -386.3086) (xy 127.267765 -386.308176) (xy 127.221178 -386.30094) (xy 127.17626 -386.28662)
			(xy 127.134082 -386.265556) (xy 127.095648 -386.238251) (xy 127.061876 -386.205356) (xy 127.033569 -386.167654)
			(xy 127.022098 -386.147056) (xy 127.02159 -386.146294) (xy 126.623826 -385.457954) (xy 126.611965 -385.43527)
			(xy 126.595109 -385.38694) (xy 126.58653 -385.33648) (xy 126.58598 -385.310888) (xy 126.043732 -385.310888)
			(xy 126.355856 -385.850892) (xy 126.368611 -385.874246) (xy 126.386717 -385.92428) (xy 126.395918 -385.976688)
			(xy 126.396496 -386.003292) (xy 126.396054 -386.027286) (xy 126.388548 -386.074682) (xy 126.37372 -386.12032)
			(xy 126.351935 -386.163077) (xy 126.323729 -386.2019) (xy 126.289797 -386.235831) (xy 126.250974 -386.264037)
			(xy 126.208217 -386.285822) (xy 126.162578 -386.300649) (xy 126.115182 -386.308155) (xy 126.091188 -386.3086)
			(xy 126.067614 -386.308216) (xy 126.021025 -386.300973) (xy 125.976106 -386.286645) (xy 125.933928 -386.265575)
			(xy 125.895495 -386.238264) (xy 125.861723 -386.205363) (xy 125.833418 -386.167656) (xy 125.821948 -386.147056)
			(xy 125.82144 -386.146294) (xy 125.423676 -385.457954) (xy 125.41174 -385.435296) (xy 125.39481 -385.386965)
			(xy 125.386159 -385.336492) (xy 125.385576 -385.310888) (xy 124.843836 -385.310888) (xy 125.15596 -385.850892)
			(xy 125.168715 -385.874246) (xy 125.186821 -385.92428) (xy 125.196022 -385.976688) (xy 125.1966 -386.003292)
			(xy 125.196154 -386.027285) (xy 125.188649 -386.074681) (xy 125.173821 -386.12032) (xy 125.152036 -386.163076)
			(xy 125.12383 -386.201898) (xy 125.089898 -386.23583) (xy 125.051076 -386.264036) (xy 125.00832 -386.285821)
			(xy 124.962681 -386.300649) (xy 124.915285 -386.308154) (xy 124.891292 -386.3086) (xy 124.867718 -386.308213)
			(xy 124.821129 -386.30097) (xy 124.77621 -386.286643) (xy 124.734032 -386.265573) (xy 124.695599 -386.238263)
			(xy 124.661828 -386.205362) (xy 124.633522 -386.167656) (xy 124.622052 -386.147056) (xy 124.621544 -386.146294)
			(xy 124.22378 -385.457954) (xy 124.211844 -385.435296) (xy 124.194915 -385.386965) (xy 124.186263 -385.336492)
			(xy 124.18568 -385.310888) (xy 123.643686 -385.310888) (xy 123.95581 -385.850892) (xy 123.968632 -385.874226)
			(xy 123.986854 -385.924248) (xy 123.996115 -385.976673) (xy 123.996704 -386.003292) (xy 123.996254 -386.027298)
			(xy 123.98874 -386.074718) (xy 123.973897 -386.120377) (xy 123.95209 -386.163151) (xy 123.923857 -386.201984)
			(xy 123.889894 -386.23592) (xy 123.851037 -386.264121) (xy 123.808246 -386.285893) (xy 123.762574 -386.300698)
			(xy 123.715148 -386.308173) (xy 123.691142 -386.3086) (xy 123.667569 -386.308172) (xy 123.620983 -386.300937)
			(xy 123.576065 -386.286617) (xy 123.533886 -386.265554) (xy 123.495453 -386.23825) (xy 123.46168 -386.205355)
			(xy 123.433373 -386.167654) (xy 123.421902 -386.147056) (xy 123.421394 -386.146294) (xy 123.02363 -385.457954)
			(xy 123.011769 -385.43527) (xy 122.994913 -385.38694) (xy 122.986334 -385.33648) (xy 122.985784 -385.310888)
			(xy 122.44379 -385.310888) (xy 122.755914 -385.850892) (xy 122.768737 -385.874226) (xy 122.786958 -385.924248)
			(xy 122.796219 -385.976673) (xy 122.796808 -386.003292) (xy 122.796354 -386.027298) (xy 122.78884 -386.074717)
			(xy 122.773997 -386.120377) (xy 122.752191 -386.16315) (xy 122.723958 -386.201983) (xy 122.689995 -386.235918)
			(xy 122.65114 -386.264119) (xy 122.608349 -386.285891) (xy 122.562678 -386.300698) (xy 122.515252 -386.308173)
			(xy 122.491246 -386.3086) (xy 122.467673 -386.308169) (xy 122.421087 -386.300935) (xy 122.376169 -386.286615)
			(xy 122.333991 -386.265553) (xy 122.295557 -386.238249) (xy 122.261784 -386.205355) (xy 122.233477 -386.167654)
			(xy 122.222006 -386.147056) (xy 122.221498 -386.146294) (xy 121.823734 -385.457954) (xy 121.811874 -385.43527)
			(xy 121.795018 -385.38694) (xy 121.786438 -385.33648) (xy 121.785888 -385.310888) (xy 121.243894 -385.310888)
			(xy 121.556018 -385.850892) (xy 121.568841 -385.874226) (xy 121.587062 -385.924248) (xy 121.596323 -385.976673)
			(xy 121.596912 -386.003292) (xy 121.596454 -386.027297) (xy 121.58894 -386.074717) (xy 121.574098 -386.120376)
			(xy 121.552291 -386.163149) (xy 121.524059 -386.201981) (xy 121.490097 -386.235917) (xy 121.451242 -386.264118)
			(xy 121.408452 -386.28589) (xy 121.362781 -386.300697) (xy 121.315356 -386.308172) (xy 121.29135 -386.3086)
			(xy 121.267777 -386.308166) (xy 121.221191 -386.300932) (xy 121.176273 -386.286613) (xy 121.134095 -386.265551)
			(xy 121.095661 -386.238248) (xy 121.061888 -386.205354) (xy 121.033581 -386.167653) (xy 121.02211 -386.147056)
			(xy 121.021602 -386.146294) (xy 120.623838 -385.457954) (xy 120.611978 -385.435269) (xy 120.595122 -385.38694)
			(xy 120.586542 -385.33648) (xy 120.585992 -385.310888) (xy 120.043744 -385.310888) (xy 120.355868 -385.850892)
			(xy 120.368624 -385.874246) (xy 120.38673 -385.92428) (xy 120.39593 -385.976688) (xy 120.396508 -386.003292)
			(xy 120.396054 -386.027285) (xy 120.388549 -386.07468) (xy 120.373721 -386.120318) (xy 120.351937 -386.163074)
			(xy 120.323732 -386.201896) (xy 120.289802 -386.235827) (xy 120.250981 -386.264033) (xy 120.208225 -386.285818)
			(xy 120.162588 -386.300647) (xy 120.115193 -386.308154) (xy 120.0912 -386.3086) (xy 120.067626 -386.308206)
			(xy 120.021038 -386.300965) (xy 119.976119 -386.286639) (xy 119.933941 -386.26557) (xy 119.895508 -386.238261)
			(xy 119.861736 -386.205361) (xy 119.83343 -386.167656) (xy 119.82196 -386.147056) (xy 119.821452 -386.146294)
			(xy 119.423688 -385.457954) (xy 119.411753 -385.435296) (xy 119.394823 -385.386965) (xy 119.386171 -385.336491)
			(xy 119.385588 -385.310888) (xy 118.843848 -385.310888) (xy 119.155972 -385.850892) (xy 119.168728 -385.874246)
			(xy 119.186834 -385.92428) (xy 119.196034 -385.976688) (xy 119.196612 -386.003292) (xy 119.196154 -386.027285)
			(xy 119.188649 -386.07468) (xy 119.173822 -386.120317) (xy 119.152038 -386.163073) (xy 119.123834 -386.201894)
			(xy 119.089903 -386.235826) (xy 119.051083 -386.264032) (xy 119.008328 -386.285817) (xy 118.962691 -386.300646)
			(xy 118.915297 -386.308154) (xy 118.891304 -386.3086) (xy 118.86773 -386.308203) (xy 118.821142 -386.300962)
			(xy 118.776223 -386.286637) (xy 118.734045 -386.265569) (xy 118.695612 -386.23826) (xy 118.66184 -386.205361)
			(xy 118.633535 -386.167656) (xy 118.622064 -386.147056) (xy 118.621556 -386.146294) (xy 118.223792 -385.457954)
			(xy 118.211857 -385.435295) (xy 118.194927 -385.386965) (xy 118.186275 -385.336491) (xy 118.185692 -385.310888)
			(xy 117.643698 -385.310888) (xy 117.955822 -385.850892) (xy 117.968645 -385.874225) (xy 117.986866 -385.924248)
			(xy 117.996127 -385.976673) (xy 117.996716 -386.003292) (xy 117.996254 -386.027297) (xy 117.98874 -386.074716)
			(xy 117.973898 -386.120375) (xy 117.952092 -386.163147) (xy 117.92386 -386.20198) (xy 117.889899 -386.235915)
			(xy 117.851044 -386.264117) (xy 117.808254 -386.285889) (xy 117.762584 -386.300696) (xy 117.71516 -386.308172)
			(xy 117.691154 -386.3086) (xy 117.667582 -386.308163) (xy 117.620995 -386.300929) (xy 117.576078 -386.286611)
			(xy 117.533899 -386.26555) (xy 117.495466 -386.238247) (xy 117.461693 -386.205353) (xy 117.433385 -386.167653)
			(xy 117.421914 -386.147056) (xy 117.421406 -386.146294) (xy 117.023642 -385.457954) (xy 117.011782 -385.435269)
			(xy 116.994926 -385.38694) (xy 116.986346 -385.33648) (xy 116.985796 -385.310888) (xy 116.443802 -385.310888)
			(xy 116.755926 -385.850892) (xy 116.76875 -385.874225) (xy 116.786971 -385.924247) (xy 116.796231 -385.976673)
			(xy 116.79682 -386.003292) (xy 116.796354 -386.027297) (xy 116.788841 -386.074716) (xy 116.773998 -386.120374)
			(xy 116.752193 -386.163146) (xy 116.723962 -386.201979) (xy 116.69 -386.235914) (xy 116.651146 -386.264115)
			(xy 116.608357 -386.285888) (xy 116.562688 -386.300695) (xy 116.515263 -386.308172) (xy 116.491258 -386.3086)
			(xy 116.467686 -386.308159) (xy 116.4211 -386.300927) (xy 116.376182 -386.286609) (xy 116.334004 -386.265548)
			(xy 116.29557 -386.238246) (xy 116.261797 -386.205353) (xy 116.23349 -386.167653) (xy 116.222018 -386.147056)
			(xy 116.22151 -386.146294) (xy 115.823746 -385.457954) (xy 115.811886 -385.435269) (xy 115.79503 -385.38694)
			(xy 115.78645 -385.33648) (xy 115.7859 -385.310888) (xy 115.243906 -385.310888) (xy 115.55603 -385.850892)
			(xy 115.568854 -385.874225) (xy 115.587075 -385.924247) (xy 115.596335 -385.976673) (xy 115.596924 -386.003292)
			(xy 115.596454 -386.027297) (xy 115.588941 -386.074715) (xy 115.574099 -386.120373) (xy 115.552294 -386.163145)
			(xy 115.524063 -386.201977) (xy 115.490102 -386.235912) (xy 115.451249 -386.264114) (xy 115.40846 -386.285887)
			(xy 115.362791 -386.300694) (xy 115.315367 -386.308172) (xy 115.291362 -386.3086) (xy 115.26779 -386.308156)
			(xy 115.221204 -386.300924) (xy 115.176286 -386.286607) (xy 115.134108 -386.265547) (xy 115.095674 -386.238245)
			(xy 115.061901 -386.205352) (xy 115.033594 -386.167653) (xy 115.022122 -386.147056) (xy 115.021614 -386.146294)
			(xy 114.62385 -385.457954) (xy 114.611991 -385.435269) (xy 114.595134 -385.38694) (xy 114.586554 -385.33648)
			(xy 114.586004 -385.310888) (xy 98.671676 -385.310888) (xy 98.9838 -385.850892) (xy 98.99655 -385.874249)
			(xy 99.01466 -385.924281) (xy 99.023862 -385.976688) (xy 99.02444 -386.003292) (xy 99.02393 -386.027281)
			(xy 99.016426 -386.07467) (xy 99.001602 -386.120301) (xy 98.979822 -386.163051) (xy 98.951623 -386.201869)
			(xy 98.917699 -386.235797) (xy 98.878886 -386.264001) (xy 98.836138 -386.285787) (xy 98.790509 -386.300617)
			(xy 98.743121 -386.308127) (xy 98.719132 -386.3086) (xy 98.695559 -386.30818) (xy 98.648972 -386.300944)
			(xy 98.604054 -386.286623) (xy 98.561875 -386.265558) (xy 98.523442 -386.238253) (xy 98.48967 -386.205357)
			(xy 98.461363 -386.167654) (xy 98.449892 -386.147056) (xy 98.449384 -386.146294) (xy 98.05162 -385.457954)
			(xy 98.039687 -385.435294) (xy 98.022756 -385.386965) (xy 98.014103 -385.336491) (xy 98.01352 -385.310888)
			(xy 97.471526 -385.310888) (xy 97.78365 -385.850892) (xy 97.796476 -385.874224) (xy 97.814695 -385.924247)
			(xy 97.823955 -385.976673) (xy 97.824544 -386.003292) (xy 97.824054 -386.027296) (xy 97.816541 -386.074712)
			(xy 97.801701 -386.120368) (xy 97.779897 -386.163139) (xy 97.751669 -386.20197) (xy 97.71771 -386.235905)
			(xy 97.67886 -386.264107) (xy 97.636074 -386.285881) (xy 97.590407 -386.30069) (xy 97.542986 -386.30817)
			(xy 97.518982 -386.3086) (xy 97.495407 -386.308221) (xy 97.448819 -386.300977) (xy 97.4039 -386.286648)
			(xy 97.361721 -386.265577) (xy 97.323288 -386.238265) (xy 97.289517 -386.205364) (xy 97.261212 -386.167657)
			(xy 97.249742 -386.147056) (xy 97.249234 -386.146294) (xy 96.85147 -385.457954) (xy 96.839612 -385.435268)
			(xy 96.822755 -385.386939) (xy 96.814174 -385.33648) (xy 96.813624 -385.310888) (xy 96.27163 -385.310888)
			(xy 96.583754 -385.850892) (xy 96.59658 -385.874224) (xy 96.614799 -385.924247) (xy 96.624059 -385.976673)
			(xy 96.624648 -386.003292) (xy 96.624154 -386.027296) (xy 96.616641 -386.074711) (xy 96.601801 -386.120367)
			(xy 96.579998 -386.163138) (xy 96.55177 -386.201969) (xy 96.517812 -386.235904) (xy 96.478962 -386.264106)
			(xy 96.436177 -386.28588) (xy 96.390511 -386.30069) (xy 96.34309 -386.30817) (xy 96.319086 -386.3086)
			(xy 96.295512 -386.308217) (xy 96.248923 -386.300974) (xy 96.204004 -386.286646) (xy 96.161826 -386.265576)
			(xy 96.123393 -386.238264) (xy 96.089621 -386.205363) (xy 96.061316 -386.167656) (xy 96.049846 -386.147056)
			(xy 96.049338 -386.146294) (xy 95.651574 -385.457954) (xy 95.639717 -385.435268) (xy 95.622859 -385.386939)
			(xy 95.614278 -385.336479) (xy 95.613728 -385.310888) (xy 95.07148 -385.310888) (xy 95.383604 -385.850892)
			(xy 95.396355 -385.874249) (xy 95.414464 -385.924281) (xy 95.423666 -385.976688) (xy 95.424244 -386.003292)
			(xy 95.42373 -386.027281) (xy 95.416226 -386.074669) (xy 95.401402 -386.1203) (xy 95.379623 -386.16305)
			(xy 95.351424 -386.201867) (xy 95.317501 -386.235796) (xy 95.278688 -386.264) (xy 95.235941 -386.285785)
			(xy 95.190312 -386.300616) (xy 95.142925 -386.308127) (xy 95.118936 -386.3086) (xy 95.095363 -386.308177)
			(xy 95.048776 -386.300941) (xy 95.003858 -386.286621) (xy 94.96168 -386.265557) (xy 94.923246 -386.238252)
			(xy 94.889474 -386.205356) (xy 94.861167 -386.167654) (xy 94.849696 -386.147056) (xy 94.849188 -386.146294)
			(xy 94.451424 -385.457954) (xy 94.439492 -385.435294) (xy 94.42256 -385.386965) (xy 94.413907 -385.336491)
			(xy 94.413324 -385.310888) (xy 93.871584 -385.310888) (xy 94.183708 -385.850892) (xy 94.196459 -385.874248)
			(xy 94.214568 -385.924281) (xy 94.22377 -385.976688) (xy 94.224348 -386.003292) (xy 94.22383 -386.027281)
			(xy 94.216326 -386.074669) (xy 94.201503 -386.120299) (xy 94.179724 -386.163049) (xy 94.151525 -386.201866)
			(xy 94.117603 -386.235794) (xy 94.07879 -386.263998) (xy 94.036043 -386.285784) (xy 93.990415 -386.300615)
			(xy 93.943029 -386.308126) (xy 93.91904 -386.3086) (xy 93.895467 -386.308174) (xy 93.84888 -386.300939)
			(xy 93.803963 -386.286618) (xy 93.761784 -386.265555) (xy 93.723351 -386.238251) (xy 93.689578 -386.205355)
			(xy 93.661271 -386.167654) (xy 93.6498 -386.147056) (xy 93.649292 -386.146294) (xy 93.251528 -385.457954)
			(xy 93.239596 -385.435294) (xy 93.222664 -385.386965) (xy 93.214011 -385.336491) (xy 93.213428 -385.310888)
			(xy 92.671688 -385.310888) (xy 92.983812 -385.850892) (xy 92.996563 -385.874248) (xy 93.014672 -385.924281)
			(xy 93.023874 -385.976688) (xy 93.024452 -386.003292) (xy 93.02393 -386.027281) (xy 93.016427 -386.074668)
			(xy 93.001603 -386.120298) (xy 92.979824 -386.163048) (xy 92.951627 -386.201865) (xy 92.917704 -386.235793)
			(xy 92.878892 -386.263997) (xy 92.836146 -386.285783) (xy 92.790519 -386.300614) (xy 92.743133 -386.308126)
			(xy 92.719144 -386.3086) (xy 92.695571 -386.308171) (xy 92.648985 -386.300936) (xy 92.604067 -386.286616)
			(xy 92.561889 -386.265554) (xy 92.523455 -386.238249) (xy 92.489682 -386.205355) (xy 92.461375 -386.167654)
			(xy 92.449904 -386.147056) (xy 92.449396 -386.146294) (xy 92.051632 -385.457954) (xy 92.0397 -385.435294)
			(xy 92.022768 -385.386965) (xy 92.014115 -385.336491) (xy 92.013532 -385.310888) (xy 91.471538 -385.310888)
			(xy 91.783662 -385.850892) (xy 91.796489 -385.874224) (xy 91.814708 -385.924247) (xy 91.823967 -385.976673)
			(xy 91.824556 -386.003292) (xy 91.824054 -386.027295) (xy 91.816542 -386.07471) (xy 91.801702 -386.120365)
			(xy 91.779899 -386.163135) (xy 91.751672 -386.201966) (xy 91.717715 -386.235901) (xy 91.678866 -386.264103)
			(xy 91.636082 -386.285878) (xy 91.590417 -386.300688) (xy 91.542998 -386.308169) (xy 91.518994 -386.3086)
			(xy 91.49542 -386.308211) (xy 91.448831 -386.300969) (xy 91.403913 -386.286642) (xy 91.361734 -386.265573)
			(xy 91.323301 -386.238262) (xy 91.28953 -386.205362) (xy 91.261224 -386.167656) (xy 91.249754 -386.147056)
			(xy 91.249246 -386.146294) (xy 90.851482 -385.457954) (xy 90.839625 -385.435268) (xy 90.822767 -385.386939)
			(xy 90.814186 -385.336479) (xy 90.813636 -385.310888) (xy 90.271642 -385.310888) (xy 90.583766 -385.850892)
			(xy 90.596593 -385.874223) (xy 90.614812 -385.924247) (xy 90.624071 -385.976673) (xy 90.62466 -386.003292)
			(xy 90.624253 -386.0273) (xy 90.616738 -386.074724) (xy 90.601893 -386.120388) (xy 90.580082 -386.163164)
			(xy 90.551844 -386.201999) (xy 90.517875 -386.235935) (xy 90.479013 -386.264136) (xy 90.436216 -386.285905)
			(xy 90.390538 -386.300707) (xy 90.343106 -386.308176) (xy 90.319098 -386.3086) (xy 90.295524 -386.308208)
			(xy 90.248936 -386.300966) (xy 90.204017 -386.28664) (xy 90.161839 -386.265571) (xy 90.123406 -386.238261)
			(xy 90.089634 -386.205361) (xy 90.061328 -386.167656) (xy 90.049858 -386.147056) (xy 90.04935 -386.146294)
			(xy 89.651586 -385.457954) (xy 89.63973 -385.435267) (xy 89.622871 -385.386939) (xy 89.61429 -385.336479)
			(xy 89.61374 -385.310888) (xy 89.071492 -385.310888) (xy 89.383616 -385.850892) (xy 89.396368 -385.874248)
			(xy 89.414476 -385.924281) (xy 89.423678 -385.976688) (xy 89.424256 -386.003292) (xy 89.42373 -386.027281)
			(xy 89.416227 -386.074667) (xy 89.401403 -386.120297) (xy 89.379625 -386.163047) (xy 89.351428 -386.201863)
			(xy 89.317506 -386.235791) (xy 89.278694 -386.263996) (xy 89.235949 -386.285782) (xy 89.190322 -386.300614)
			(xy 89.142937 -386.308126) (xy 89.118948 -386.3086) (xy 89.095375 -386.308168) (xy 89.048789 -386.300933)
			(xy 89.003871 -386.286614) (xy 88.961693 -386.265552) (xy 88.923259 -386.238248) (xy 88.889486 -386.205354)
			(xy 88.861179 -386.167654) (xy 88.849708 -386.147056) (xy 88.8492 -386.146294) (xy 88.451436 -385.457954)
			(xy 88.439505 -385.435294) (xy 88.422572 -385.386964) (xy 88.413919 -385.336491) (xy 88.413336 -385.310888)
			(xy 87.871596 -385.310888) (xy 88.18372 -385.850892) (xy 88.196472 -385.874248) (xy 88.21458 -385.924281)
			(xy 88.223782 -385.976688) (xy 88.22436 -386.003292) (xy 88.223954 -386.027287) (xy 88.216447 -386.074687)
			(xy 88.201617 -386.120329) (xy 88.179828 -386.163088) (xy 88.151618 -386.201912) (xy 88.117682 -386.235844)
			(xy 88.078854 -386.264049) (xy 88.036092 -386.285832) (xy 87.990448 -386.300657) (xy 87.943047 -386.308157)
			(xy 87.919052 -386.3086) (xy 87.895479 -386.308164) (xy 87.848893 -386.300931) (xy 87.803976 -386.286612)
			(xy 87.761797 -386.265551) (xy 87.723364 -386.238247) (xy 87.689591 -386.205354) (xy 87.661283 -386.167653)
			(xy 87.649812 -386.147056) (xy 87.649304 -386.146294) (xy 87.25154 -385.457954) (xy 87.239609 -385.435293)
			(xy 87.222676 -385.386964) (xy 87.214023 -385.336491) (xy 87.21344 -385.310888) (xy 86.6717 -385.310888)
			(xy 86.983824 -385.850892) (xy 86.996576 -385.874248) (xy 87.014684 -385.92428) (xy 87.023886 -385.976688)
			(xy 87.024464 -386.003292) (xy 87.024054 -386.027287) (xy 87.016547 -386.074687) (xy 87.001717 -386.120328)
			(xy 86.979929 -386.163087) (xy 86.951719 -386.201911) (xy 86.917783 -386.235843) (xy 86.878956 -386.264048)
			(xy 86.836195 -386.285831) (xy 86.790552 -386.300656) (xy 86.743151 -386.308157) (xy 86.719156 -386.3086)
			(xy 86.695584 -386.308161) (xy 86.648997 -386.300928) (xy 86.60408 -386.28661) (xy 86.561902 -386.265549)
			(xy 86.523468 -386.238246) (xy 86.489695 -386.205353) (xy 86.461387 -386.167653) (xy 86.449916 -386.147056)
			(xy 86.449408 -386.146294) (xy 86.051644 -385.457954) (xy 86.039713 -385.435293) (xy 86.02278 -385.386964)
			(xy 86.014127 -385.336491) (xy 86.013544 -385.310888) (xy 85.47155 -385.310888) (xy 85.783674 -385.850892)
			(xy 85.796501 -385.874223) (xy 85.81472 -385.924247) (xy 85.823979 -385.976673) (xy 85.824568 -386.003292)
			(xy 85.824153 -386.0273) (xy 85.816639 -386.074723) (xy 85.801793 -386.120386) (xy 85.779983 -386.163162)
			(xy 85.751746 -386.201996) (xy 85.717779 -386.235932) (xy 85.678917 -386.264133) (xy 85.636121 -386.285903)
			(xy 85.590445 -386.300706) (xy 85.543014 -386.308176) (xy 85.519006 -386.3086) (xy 85.495432 -386.308201)
			(xy 85.448844 -386.300961) (xy 85.403926 -386.286636) (xy 85.361747 -386.265568) (xy 85.323314 -386.238259)
			(xy 85.289542 -386.20536) (xy 85.261237 -386.167655) (xy 85.249766 -386.147056) (xy 85.249258 -386.146294)
			(xy 84.851494 -385.457954) (xy 84.839638 -385.435267) (xy 84.822779 -385.386939) (xy 84.814198 -385.336479)
			(xy 84.813648 -385.310888) (xy 84.271654 -385.310888) (xy 84.583778 -385.850892) (xy 84.596606 -385.874223)
			(xy 84.614824 -385.924247) (xy 84.624083 -385.976673) (xy 84.624672 -386.003292) (xy 84.624253 -386.027299)
			(xy 84.616739 -386.074723) (xy 84.601894 -386.120385) (xy 84.580084 -386.163161) (xy 84.551848 -386.201995)
			(xy 84.51788 -386.235931) (xy 84.47902 -386.264132) (xy 84.436224 -386.285902) (xy 84.390548 -386.300705)
			(xy 84.343118 -386.308175) (xy 84.31911 -386.3086) (xy 84.295536 -386.308198) (xy 84.248948 -386.300958)
			(xy 84.20403 -386.286634) (xy 84.161852 -386.265566) (xy 84.123418 -386.238258) (xy 84.089647 -386.20536)
			(xy 84.061341 -386.167655) (xy 84.04987 -386.147056) (xy 84.049362 -386.146294) (xy 83.651598 -385.457954)
			(xy 83.639742 -385.435267) (xy 83.622883 -385.386939) (xy 83.614302 -385.336479) (xy 83.613752 -385.310888)
			(xy 83.071504 -385.310888) (xy 83.383628 -385.850892) (xy 83.396381 -385.874247) (xy 83.414488 -385.92428)
			(xy 83.42369 -385.976688) (xy 83.424268 -386.003292) (xy 83.423854 -386.027287) (xy 83.416348 -386.074686)
			(xy 83.401518 -386.120327) (xy 83.37973 -386.163086) (xy 83.351521 -386.201909) (xy 83.317585 -386.235841)
			(xy 83.278758 -386.264047) (xy 83.235997 -386.28583) (xy 83.190355 -386.300655) (xy 83.142955 -386.308157)
			(xy 83.11896 -386.3086) (xy 83.095388 -386.308158) (xy 83.048802 -386.300925) (xy 83.003884 -386.286608)
			(xy 82.961706 -386.265548) (xy 82.923272 -386.238245) (xy 82.889499 -386.205353) (xy 82.861192 -386.167653)
			(xy 82.84972 -386.147056) (xy 82.849212 -386.146294) (xy 82.451448 -385.457954) (xy 82.439517 -385.435293)
			(xy 82.422585 -385.386964) (xy 82.413931 -385.336491) (xy 82.413348 -385.310888) (xy 81.871608 -385.310888)
			(xy 82.183732 -385.850892) (xy 82.196485 -385.874247) (xy 82.214593 -385.92428) (xy 82.223794 -385.976688)
			(xy 82.224372 -386.003292) (xy 82.223954 -386.027287) (xy 82.216448 -386.074685) (xy 82.201618 -386.120326)
			(xy 82.179831 -386.163085) (xy 82.151622 -386.201908) (xy 82.117687 -386.23584) (xy 82.078861 -386.264045)
			(xy 82.0361 -386.285829) (xy 81.990458 -386.300654) (xy 81.943059 -386.308156) (xy 81.919064 -386.3086)
			(xy 81.895492 -386.308155) (xy 81.848906 -386.300923) (xy 81.803989 -386.286606) (xy 81.76181 -386.265546)
			(xy 81.723376 -386.238244) (xy 81.689603 -386.205352) (xy 81.661296 -386.167653) (xy 81.649824 -386.147056)
			(xy 81.649316 -386.146294) (xy 81.251552 -385.457954) (xy 81.239622 -385.435293) (xy 81.222689 -385.386964)
			(xy 81.214035 -385.336491) (xy 81.213452 -385.310888) (xy 80.671712 -385.310888) (xy 80.983836 -385.850892)
			(xy 80.996589 -385.874247) (xy 81.014697 -385.92428) (xy 81.023898 -385.976688) (xy 81.024476 -386.003292)
			(xy 81.024054 -386.027287) (xy 81.016548 -386.074685) (xy 81.001718 -386.120325) (xy 80.979931 -386.163083)
			(xy 80.951723 -386.201907) (xy 80.917788 -386.235839) (xy 80.878963 -386.264044) (xy 80.836203 -386.285828)
			(xy 80.790561 -386.300653) (xy 80.743163 -386.308156) (xy 80.719168 -386.3086) (xy 80.695596 -386.308151)
			(xy 80.64901 -386.30092) (xy 80.604093 -386.286604) (xy 80.561915 -386.265545) (xy 80.523481 -386.238243)
			(xy 80.489707 -386.205351) (xy 80.4614 -386.167653) (xy 80.449928 -386.147056) (xy 80.44942 -386.146294)
			(xy 80.051656 -385.457954) (xy 80.039726 -385.435293) (xy 80.022793 -385.386964) (xy 80.014139 -385.336491)
			(xy 80.013556 -385.310888) (xy 66.144182 -385.310888) (xy 66.456306 -385.850892) (xy 66.469128 -385.874226)
			(xy 66.48735 -385.924248) (xy 66.496611 -385.976674) (xy 66.4972 -386.003292) (xy 66.496754 -386.027298)
			(xy 66.48924 -386.074718) (xy 66.474396 -386.120378) (xy 66.452589 -386.163152) (xy 66.424356 -386.201985)
			(xy 66.390392 -386.235921) (xy 66.351535 -386.264122) (xy 66.308743 -386.285894) (xy 66.263071 -386.300699)
			(xy 66.215644 -386.308173) (xy 66.191638 -386.3086) (xy 66.191384 -386.3086) (xy 66.16781 -386.308219)
			(xy 66.121221 -386.300975) (xy 66.076302 -386.286647) (xy 66.034123 -386.265576) (xy 65.995691 -386.238265)
			(xy 65.961919 -386.205363) (xy 65.933614 -386.167656) (xy 65.922144 -386.147056) (xy 65.921636 -386.146294)
			(xy 65.523872 -385.457954) (xy 65.511936 -385.435296) (xy 65.495006 -385.386965) (xy 65.486355 -385.336492)
			(xy 65.485772 -385.310888) (xy 64.944032 -385.310888) (xy 65.256156 -385.850892) (xy 65.268911 -385.874246)
			(xy 65.287017 -385.92428) (xy 65.296218 -385.976688) (xy 65.296796 -386.003292) (xy 65.296354 -386.027286)
			(xy 65.288848 -386.074682) (xy 65.27402 -386.12032) (xy 65.252235 -386.163077) (xy 65.224029 -386.2019)
			(xy 65.190097 -386.235831) (xy 65.151274 -386.264037) (xy 65.108517 -386.285822) (xy 65.062878 -386.300649)
			(xy 65.015482 -386.308155) (xy 64.991488 -386.3086) (xy 64.991234 -386.3086) (xy 64.967661 -386.308179)
			(xy 64.921074 -386.300942) (xy 64.876156 -386.286622) (xy 64.833978 -386.265557) (xy 64.795544 -386.238252)
			(xy 64.761772 -386.205356) (xy 64.733465 -386.167654) (xy 64.721994 -386.147056) (xy 64.721486 -386.146294)
			(xy 64.323722 -385.457954) (xy 64.311861 -385.43527) (xy 64.295005 -385.38694) (xy 64.286426 -385.33648)
			(xy 64.285876 -385.310888) (xy 63.744136 -385.310888) (xy 64.05626 -385.850892) (xy 64.069015 -385.874246)
			(xy 64.087121 -385.92428) (xy 64.096322 -385.976688) (xy 64.0969 -386.003292) (xy 64.096454 -386.027285)
			(xy 64.088949 -386.074681) (xy 64.074121 -386.12032) (xy 64.052336 -386.163076) (xy 64.02413 -386.201898)
			(xy 63.990198 -386.23583) (xy 63.951376 -386.264036) (xy 63.90862 -386.285821) (xy 63.862981 -386.300649)
			(xy 63.815585 -386.308154) (xy 63.791592 -386.3086) (xy 63.791338 -386.3086) (xy 63.767765 -386.308176)
			(xy 63.721178 -386.30094) (xy 63.67626 -386.28662) (xy 63.634082 -386.265556) (xy 63.595648 -386.238251)
			(xy 63.561876 -386.205356) (xy 63.533569 -386.167654) (xy 63.522098 -386.147056) (xy 63.52159 -386.146294)
			(xy 63.123826 -385.457954) (xy 63.111965 -385.43527) (xy 63.095109 -385.38694) (xy 63.08653 -385.33648)
			(xy 63.08598 -385.310888) (xy 62.543986 -385.310888) (xy 62.85611 -385.850892) (xy 62.868932 -385.874226)
			(xy 62.887154 -385.924248) (xy 62.896415 -385.976673) (xy 62.897004 -386.003292) (xy 62.896554 -386.027298)
			(xy 62.88904 -386.074718) (xy 62.874197 -386.120377) (xy 62.85239 -386.163151) (xy 62.824157 -386.201984)
			(xy 62.790194 -386.23592) (xy 62.751337 -386.264121) (xy 62.708546 -386.285893) (xy 62.662874 -386.300698)
			(xy 62.615448 -386.308173) (xy 62.591442 -386.3086) (xy 62.591188 -386.3086) (xy 62.567614 -386.308216)
			(xy 62.521025 -386.300973) (xy 62.476106 -386.286645) (xy 62.433928 -386.265575) (xy 62.395495 -386.238264)
			(xy 62.361723 -386.205363) (xy 62.333418 -386.167656) (xy 62.321948 -386.147056) (xy 62.32144 -386.146294)
			(xy 61.923676 -385.457954) (xy 61.91174 -385.435296) (xy 61.89481 -385.386965) (xy 61.886159 -385.336492)
			(xy 61.885576 -385.310888) (xy 61.34409 -385.310888) (xy 61.656214 -385.850892) (xy 61.669037 -385.874226)
			(xy 61.687258 -385.924248) (xy 61.696519 -385.976673) (xy 61.697108 -386.003292) (xy 61.696654 -386.027298)
			(xy 61.68914 -386.074717) (xy 61.674297 -386.120377) (xy 61.652491 -386.16315) (xy 61.624258 -386.201983)
			(xy 61.590295 -386.235918) (xy 61.55144 -386.264119) (xy 61.508649 -386.285891) (xy 61.462978 -386.300698)
			(xy 61.415552 -386.308173) (xy 61.391546 -386.3086) (xy 61.391292 -386.3086) (xy 61.367718 -386.308213)
			(xy 61.321129 -386.30097) (xy 61.27621 -386.286643) (xy 61.234032 -386.265573) (xy 61.195599 -386.238263)
			(xy 61.161828 -386.205362) (xy 61.133522 -386.167656) (xy 61.122052 -386.147056) (xy 61.121544 -386.146294)
			(xy 60.72378 -385.457954) (xy 60.711844 -385.435296) (xy 60.694915 -385.386965) (xy 60.686263 -385.336492)
			(xy 60.68568 -385.310888) (xy 60.144194 -385.310888) (xy 60.456318 -385.850892) (xy 60.469141 -385.874226)
			(xy 60.487362 -385.924248) (xy 60.496623 -385.976673) (xy 60.497212 -386.003292) (xy 60.496754 -386.027297)
			(xy 60.48924 -386.074717) (xy 60.474398 -386.120376) (xy 60.452591 -386.163149) (xy 60.424359 -386.201981)
			(xy 60.390397 -386.235917) (xy 60.351542 -386.264118) (xy 60.308752 -386.28589) (xy 60.263081 -386.300697)
			(xy 60.215656 -386.308172) (xy 60.19165 -386.3086) (xy 60.191396 -386.3086) (xy 60.167822 -386.308209)
			(xy 60.121233 -386.300967) (xy 60.076315 -386.286641) (xy 60.034136 -386.265572) (xy 59.995703 -386.238262)
			(xy 59.961932 -386.205362) (xy 59.933626 -386.167656) (xy 59.922156 -386.147056) (xy 59.921648 -386.146294)
			(xy 59.523884 -385.457954) (xy 59.511948 -385.435296) (xy 59.495019 -385.386965) (xy 59.486367 -385.336492)
			(xy 59.485784 -385.310888) (xy 58.944044 -385.310888) (xy 59.256168 -385.850892) (xy 59.268924 -385.874246)
			(xy 59.28703 -385.92428) (xy 59.29623 -385.976688) (xy 59.296808 -386.003292) (xy 59.296354 -386.027285)
			(xy 59.288849 -386.07468) (xy 59.274021 -386.120318) (xy 59.252237 -386.163074) (xy 59.224032 -386.201896)
			(xy 59.190102 -386.235827) (xy 59.151281 -386.264033) (xy 59.108525 -386.285818) (xy 59.062888 -386.300647)
			(xy 59.015493 -386.308154) (xy 58.9915 -386.3086) (xy 58.991246 -386.3086) (xy 58.967673 -386.308169)
			(xy 58.921087 -386.300935) (xy 58.876169 -386.286615) (xy 58.833991 -386.265553) (xy 58.795557 -386.238249)
			(xy 58.761784 -386.205355) (xy 58.733477 -386.167654) (xy 58.722006 -386.147056) (xy 58.721498 -386.146294)
			(xy 58.323734 -385.457954) (xy 58.311874 -385.43527) (xy 58.295018 -385.38694) (xy 58.286438 -385.33648)
			(xy 58.285888 -385.310888) (xy 57.744148 -385.310888) (xy 58.056272 -385.850892) (xy 58.069028 -385.874246)
			(xy 58.087134 -385.92428) (xy 58.096334 -385.976688) (xy 58.096912 -386.003292) (xy 58.096454 -386.027285)
			(xy 58.088949 -386.07468) (xy 58.074122 -386.120317) (xy 58.052338 -386.163073) (xy 58.024134 -386.201894)
			(xy 57.990203 -386.235826) (xy 57.951383 -386.264032) (xy 57.908628 -386.285817) (xy 57.862991 -386.300646)
			(xy 57.815597 -386.308154) (xy 57.791604 -386.3086) (xy 57.79135 -386.3086) (xy 57.767777 -386.308166)
			(xy 57.721191 -386.300932) (xy 57.676273 -386.286613) (xy 57.634095 -386.265551) (xy 57.595661 -386.238248)
			(xy 57.561888 -386.205354) (xy 57.533581 -386.167653) (xy 57.52211 -386.147056) (xy 57.521602 -386.146294)
			(xy 57.123838 -385.457954) (xy 57.111978 -385.435269) (xy 57.095122 -385.38694) (xy 57.086542 -385.33648)
			(xy 57.085992 -385.310888) (xy 56.543744 -385.310888) (xy 56.855868 -385.850892) (xy 56.868624 -385.874246)
			(xy 56.88673 -385.92428) (xy 56.89593 -385.976688) (xy 56.896508 -386.003292) (xy 56.896054 -386.027285)
			(xy 56.888549 -386.07468) (xy 56.873721 -386.120318) (xy 56.851937 -386.163074) (xy 56.823732 -386.201896)
			(xy 56.789802 -386.235827) (xy 56.750981 -386.264033) (xy 56.708225 -386.285818) (xy 56.662588 -386.300647)
			(xy 56.615193 -386.308154) (xy 56.5912 -386.3086) (xy 56.567626 -386.308206) (xy 56.521038 -386.300965)
			(xy 56.476119 -386.286639) (xy 56.433941 -386.26557) (xy 56.395508 -386.238261) (xy 56.361736 -386.205361)
			(xy 56.33343 -386.167656) (xy 56.32196 -386.147056) (xy 56.321452 -386.146294) (xy 55.923688 -385.457954)
			(xy 55.911753 -385.435296) (xy 55.894823 -385.386965) (xy 55.886171 -385.336491) (xy 55.885588 -385.310888)
			(xy 55.343848 -385.310888) (xy 55.655972 -385.850892) (xy 55.668728 -385.874246) (xy 55.686834 -385.92428)
			(xy 55.696034 -385.976688) (xy 55.696612 -386.003292) (xy 55.696154 -386.027285) (xy 55.688649 -386.07468)
			(xy 55.673822 -386.120317) (xy 55.652038 -386.163073) (xy 55.623834 -386.201894) (xy 55.589903 -386.235826)
			(xy 55.551083 -386.264032) (xy 55.508328 -386.285817) (xy 55.462691 -386.300646) (xy 55.415297 -386.308154)
			(xy 55.391304 -386.3086) (xy 55.36773 -386.308203) (xy 55.321142 -386.300962) (xy 55.276223 -386.286637)
			(xy 55.234045 -386.265569) (xy 55.195612 -386.23826) (xy 55.16184 -386.205361) (xy 55.133535 -386.167656)
			(xy 55.122064 -386.147056) (xy 55.121556 -386.146294) (xy 54.723792 -385.457954) (xy 54.711857 -385.435295)
			(xy 54.694927 -385.386965) (xy 54.686275 -385.336491) (xy 54.685692 -385.310888) (xy 54.143952 -385.310888)
			(xy 54.456076 -385.850892) (xy 54.468824 -385.87425) (xy 54.486935 -385.924281) (xy 54.496138 -385.976688)
			(xy 54.496716 -386.003292) (xy 54.49623 -386.027283) (xy 54.488725 -386.074673) (xy 54.4739 -386.120306)
			(xy 54.452118 -386.163059) (xy 54.423916 -386.201877) (xy 54.389989 -386.235806) (xy 54.351172 -386.264009)
			(xy 54.308421 -386.285793) (xy 54.262789 -386.300622) (xy 54.215399 -386.308129) (xy 54.191408 -386.3086)
			(xy 54.167834 -386.3082) (xy 54.121246 -386.30096) (xy 54.076328 -386.286635) (xy 54.034149 -386.265567)
			(xy 53.995716 -386.238259) (xy 53.961944 -386.20536) (xy 53.933639 -386.167655) (xy 53.922168 -386.147056)
			(xy 53.92166 -386.146294) (xy 53.523896 -385.457954) (xy 53.511961 -385.435295) (xy 53.495031 -385.386965)
			(xy 53.486379 -385.336491) (xy 53.485796 -385.310888) (xy 52.943802 -385.310888) (xy 53.255926 -385.850892)
			(xy 53.26875 -385.874225) (xy 53.286971 -385.924247) (xy 53.296231 -385.976673) (xy 53.29682 -386.003292)
			(xy 53.296354 -386.027297) (xy 53.288841 -386.074716) (xy 53.273998 -386.120374) (xy 53.252193 -386.163146)
			(xy 53.223962 -386.201979) (xy 53.19 -386.235914) (xy 53.151146 -386.264115) (xy 53.108357 -386.285888)
			(xy 53.062688 -386.300695) (xy 53.015263 -386.308172) (xy 52.991258 -386.3086) (xy 52.967686 -386.308159)
			(xy 52.9211 -386.300927) (xy 52.876182 -386.286609) (xy 52.834004 -386.265548) (xy 52.79557 -386.238246)
			(xy 52.761797 -386.205353) (xy 52.73349 -386.167653) (xy 52.722018 -386.147056) (xy 52.72151 -386.146294)
			(xy 52.323746 -385.457954) (xy 52.311886 -385.435269) (xy 52.29503 -385.38694) (xy 52.28645 -385.33648)
			(xy 52.2859 -385.310888) (xy 51.743906 -385.310888) (xy 52.05603 -385.850892) (xy 52.068854 -385.874225)
			(xy 52.087075 -385.924247) (xy 52.096335 -385.976673) (xy 52.096924 -386.003292) (xy 52.096454 -386.027297)
			(xy 52.088941 -386.074715) (xy 52.074099 -386.120373) (xy 52.052294 -386.163145) (xy 52.024063 -386.201977)
			(xy 51.990102 -386.235912) (xy 51.951249 -386.264114) (xy 51.90846 -386.285887) (xy 51.862791 -386.300694)
			(xy 51.815367 -386.308172) (xy 51.791362 -386.3086) (xy 51.76779 -386.308156) (xy 51.721204 -386.300924)
			(xy 51.676286 -386.286607) (xy 51.634108 -386.265547) (xy 51.595674 -386.238245) (xy 51.561901 -386.205352)
			(xy 51.533594 -386.167653) (xy 51.522122 -386.147056) (xy 51.521614 -386.146294) (xy 51.12385 -385.457954)
			(xy 51.111991 -385.435269) (xy 51.095134 -385.38694) (xy 51.086554 -385.33648) (xy 51.086004 -385.310888)
			(xy 50.543756 -385.310888) (xy 50.85588 -385.850892) (xy 50.868629 -385.87425) (xy 50.886739 -385.924281)
			(xy 50.895942 -385.976688) (xy 50.89652 -386.003292) (xy 50.89603 -386.027282) (xy 50.888526 -386.074673)
			(xy 50.8737 -386.120306) (xy 50.851918 -386.163057) (xy 50.823717 -386.201876) (xy 50.789791 -386.235804)
			(xy 50.750974 -386.264008) (xy 50.708224 -386.285792) (xy 50.662592 -386.300621) (xy 50.615202 -386.308128)
			(xy 50.591212 -386.3086) (xy 50.567638 -386.308197) (xy 50.521051 -386.300957) (xy 50.476132 -386.286633)
			(xy 50.433954 -386.265566) (xy 50.395521 -386.238258) (xy 50.361749 -386.205359) (xy 50.333443 -386.167655)
			(xy 50.321972 -386.147056) (xy 50.321464 -386.146294) (xy 49.9237 -385.457954) (xy 49.911766 -385.435295)
			(xy 49.894835 -385.386965) (xy 49.886183 -385.336491) (xy 49.8856 -385.310888) (xy 49.34386 -385.310888)
			(xy 49.655984 -385.850892) (xy 49.668733 -385.874249) (xy 49.686843 -385.924281) (xy 49.696046 -385.976688)
			(xy 49.696624 -386.003292) (xy 49.69613 -386.027282) (xy 49.688626 -386.074672) (xy 49.6738 -386.120305)
			(xy 49.652019 -386.163056) (xy 49.623818 -386.201874) (xy 49.589892 -386.235803) (xy 49.551077 -386.264007)
			(xy 49.508327 -386.285791) (xy 49.462695 -386.30062) (xy 49.415306 -386.308128) (xy 49.391316 -386.3086)
			(xy 49.367742 -386.308193) (xy 49.321155 -386.300954) (xy 49.276236 -386.286631) (xy 49.234058 -386.265564)
			(xy 49.195625 -386.238257) (xy 49.161853 -386.205359) (xy 49.133547 -386.167655) (xy 49.122076 -386.147056)
			(xy 49.121568 -386.146294) (xy 48.723804 -385.457954) (xy 48.71187 -385.435295) (xy 48.694939 -385.386965)
			(xy 48.686287 -385.336491) (xy 48.685704 -385.310888) (xy 48.143964 -385.310888) (xy 48.456088 -385.850892)
			(xy 48.468837 -385.874249) (xy 48.486947 -385.924281) (xy 48.49615 -385.976688) (xy 48.496728 -386.003292)
			(xy 48.49623 -386.027282) (xy 48.488726 -386.074672) (xy 48.473901 -386.120304) (xy 48.45212 -386.163055)
			(xy 48.42392 -386.201873) (xy 48.389994 -386.235801) (xy 48.351179 -386.264005) (xy 48.30843 -386.28579)
			(xy 48.262799 -386.300619) (xy 48.21541 -386.308128) (xy 48.19142 -386.3086) (xy 48.167847 -386.30819)
			(xy 48.121259 -386.300952) (xy 48.076341 -386.286629) (xy 48.034162 -386.265563) (xy 47.995729 -386.238256)
			(xy 47.961957 -386.205358) (xy 47.933651 -386.167655) (xy 47.92218 -386.147056) (xy 47.921672 -386.146294)
			(xy 47.523908 -385.457954) (xy 47.511974 -385.435295) (xy 47.495043 -385.386965) (xy 47.486391 -385.336491)
			(xy 47.485808 -385.310888) (xy 2.509012 -385.310888) (xy 2.509012 -387.789674) (xy 40.901112 -387.789674)
			(xy 40.901112 -386.926074) (xy 40.901598 -386.898805) (xy 40.90936 -386.844821) (xy 40.924725 -386.792491)
			(xy 40.947382 -386.742881) (xy 40.976868 -386.697) (xy 41.012583 -386.655783) (xy 41.0538 -386.620068)
			(xy 41.099681 -386.590582) (xy 41.149291 -386.567925) (xy 41.201621 -386.55256) (xy 41.255605 -386.544798)
			(xy 41.310143 -386.544798) (xy 41.364127 -386.55256) (xy 41.416457 -386.567925) (xy 41.466067 -386.590582)
			(xy 41.511948 -386.620068) (xy 41.553165 -386.655783) (xy 41.58888 -386.697) (xy 41.618366 -386.742881)
			(xy 41.641023 -386.792491) (xy 41.656388 -386.844821) (xy 41.66415 -386.898805) (xy 41.664636 -386.926074)
			(xy 41.664636 -387.789674) (xy 73.42886 -387.789674) (xy 73.42886 -386.926074) (xy 73.429346 -386.898805)
			(xy 73.437108 -386.844821) (xy 73.452473 -386.792491) (xy 73.47513 -386.742881) (xy 73.504616 -386.697)
			(xy 73.540331 -386.655783) (xy 73.581548 -386.620068) (xy 73.627429 -386.590582) (xy 73.677039 -386.567925)
			(xy 73.729369 -386.55256) (xy 73.783353 -386.544798) (xy 73.837891 -386.544798) (xy 73.891875 -386.55256)
			(xy 73.944205 -386.567925) (xy 73.993815 -386.590582) (xy 74.039696 -386.620068) (xy 74.080913 -386.655783)
			(xy 74.116628 -386.697) (xy 74.146114 -386.742881) (xy 74.168771 -386.792491) (xy 74.184136 -386.844821)
			(xy 74.191898 -386.898805) (xy 74.192384 -386.926074) (xy 74.192384 -387.789674) (xy 108.001308 -387.789674)
			(xy 108.001308 -386.926074) (xy 108.001794 -386.898823) (xy 108.00955 -386.844875) (xy 108.024905 -386.79258)
			(xy 108.047547 -386.743003) (xy 108.077013 -386.697153) (xy 108.112704 -386.655962) (xy 108.153895 -386.620271)
			(xy 108.199745 -386.590805) (xy 108.249322 -386.568163) (xy 108.301617 -386.552808) (xy 108.355565 -386.545052)
			(xy 108.410067 -386.545052) (xy 108.464015 -386.552808) (xy 108.51631 -386.568163) (xy 108.565887 -386.590805)
			(xy 108.611737 -386.620271) (xy 108.652928 -386.655962) (xy 108.688619 -386.697153) (xy 108.718085 -386.743003)
			(xy 108.740727 -386.79258) (xy 108.756082 -386.844875) (xy 108.763838 -386.898823) (xy 108.764324 -386.926074)
			(xy 108.764324 -387.789674) (xy 140.529056 -387.789674) (xy 140.529056 -386.926074) (xy 140.529542 -386.898823)
			(xy 140.537298 -386.844875) (xy 140.552653 -386.79258) (xy 140.575295 -386.743003) (xy 140.604761 -386.697153)
			(xy 140.640452 -386.655962) (xy 140.681643 -386.620271) (xy 140.727493 -386.590805) (xy 140.77707 -386.568163)
			(xy 140.829365 -386.552808) (xy 140.883313 -386.545052) (xy 140.937815 -386.545052) (xy 140.991763 -386.552808)
			(xy 141.044058 -386.568163) (xy 141.093635 -386.590805) (xy 141.139485 -386.620271) (xy 141.180676 -386.655962)
			(xy 141.216367 -386.697153) (xy 141.245833 -386.743003) (xy 141.268475 -386.79258) (xy 141.28383 -386.844875)
			(xy 141.291586 -386.898823) (xy 141.292072 -386.926074) (xy 141.292072 -387.789674) (xy 141.291586 -387.816925)
			(xy 141.28383 -387.870873) (xy 141.268475 -387.923168) (xy 141.245833 -387.972745) (xy 141.216367 -388.018595)
			(xy 141.180676 -388.059786) (xy 141.139485 -388.095477) (xy 141.093635 -388.124943) (xy 141.044058 -388.147585)
			(xy 140.991763 -388.16294) (xy 140.937815 -388.170696) (xy 140.883313 -388.170696) (xy 140.829365 -388.16294)
			(xy 140.77707 -388.147585) (xy 140.727493 -388.124943) (xy 140.681643 -388.095477) (xy 140.640452 -388.059786)
			(xy 140.604761 -388.018595) (xy 140.575295 -387.972745) (xy 140.552653 -387.923168) (xy 140.537298 -387.870873)
			(xy 140.529542 -387.816925) (xy 140.529056 -387.789674) (xy 108.764324 -387.789674) (xy 108.763838 -387.816925)
			(xy 108.756082 -387.870873) (xy 108.740727 -387.923168) (xy 108.718085 -387.972745) (xy 108.688619 -388.018595)
			(xy 108.652928 -388.059786) (xy 108.611737 -388.095477) (xy 108.565887 -388.124943) (xy 108.51631 -388.147585)
			(xy 108.464015 -388.16294) (xy 108.410067 -388.170696) (xy 108.355565 -388.170696) (xy 108.301617 -388.16294)
			(xy 108.249322 -388.147585) (xy 108.199745 -388.124943) (xy 108.153895 -388.095477) (xy 108.112704 -388.059786)
			(xy 108.077013 -388.018595) (xy 108.047547 -387.972745) (xy 108.024905 -387.923168) (xy 108.00955 -387.870873)
			(xy 108.001794 -387.816925) (xy 108.001308 -387.789674) (xy 74.192384 -387.789674) (xy 74.191898 -387.816943)
			(xy 74.184136 -387.870927) (xy 74.168771 -387.923257) (xy 74.146114 -387.972867) (xy 74.116628 -388.018748)
			(xy 74.080913 -388.059965) (xy 74.039696 -388.09568) (xy 73.993815 -388.125166) (xy 73.944205 -388.147823)
			(xy 73.891875 -388.163188) (xy 73.837891 -388.17095) (xy 73.783353 -388.17095) (xy 73.729369 -388.163188)
			(xy 73.677039 -388.147823) (xy 73.627429 -388.125166) (xy 73.581548 -388.09568) (xy 73.540331 -388.059965)
			(xy 73.504616 -388.018748) (xy 73.47513 -387.972867) (xy 73.452473 -387.923257) (xy 73.437108 -387.870927)
			(xy 73.429346 -387.816943) (xy 73.42886 -387.789674) (xy 41.664636 -387.789674) (xy 41.66415 -387.816943)
			(xy 41.656388 -387.870927) (xy 41.641023 -387.923257) (xy 41.618366 -387.972867) (xy 41.58888 -388.018748)
			(xy 41.553165 -388.059965) (xy 41.511948 -388.09568) (xy 41.466067 -388.125166) (xy 41.416457 -388.147823)
			(xy 41.364127 -388.163188) (xy 41.310143 -388.17095) (xy 41.255605 -388.17095) (xy 41.201621 -388.163188)
			(xy 41.149291 -388.147823) (xy 41.099681 -388.125166) (xy 41.0538 -388.09568) (xy 41.012583 -388.059965)
			(xy 40.976868 -388.018748) (xy 40.947382 -387.972867) (xy 40.924725 -387.923257) (xy 40.90936 -387.870927)
			(xy 40.901598 -387.816943) (xy 40.901112 -387.789674) (xy 2.509012 -387.789674) (xy 2.509012 -388.797976)
			(xy 47.486325 -388.797976) (xy 47.486573 -388.747043) (xy 47.495267 -388.696858) (xy 47.512163 -388.648809)
			(xy 47.536795 -388.604229) (xy 47.56848 -388.564351) (xy 47.60634 -388.530281) (xy 47.649327 -388.502963)
			(xy 47.696249 -388.483153) (xy 47.745807 -388.471399) (xy 47.796628 -388.468029) (xy 47.847305 -388.473134)
			(xy 47.896432 -388.486573) (xy 47.942651 -388.507975) (xy 47.984679 -388.536747) (xy 48.021353 -388.57209)
			(xy 48.051657 -388.613027) (xy 48.063658 -388.635494) (xy 48.064166 -388.636764) (xy 48.15733 -388.797975)
			(xy 48.686228 -388.797975) (xy 48.686477 -388.747043) (xy 48.69517 -388.696859) (xy 48.712067 -388.648811)
			(xy 48.736698 -388.604231) (xy 48.768383 -388.564354) (xy 48.806242 -388.530284) (xy 48.849228 -388.502966)
			(xy 48.89615 -388.483156) (xy 48.945707 -388.471403) (xy 48.996528 -388.468032) (xy 49.047203 -388.473137)
			(xy 49.09633 -388.486576) (xy 49.142548 -388.507978) (xy 49.184575 -388.536748) (xy 49.221249 -388.572091)
			(xy 49.251553 -388.613027) (xy 49.263554 -388.635494) (xy 49.264062 -388.636764) (xy 49.330245 -388.751287)
			(xy 49.885901 -388.751287) (xy 49.893233 -388.703732) (xy 49.907928 -388.657914) (xy 49.929622 -388.614966)
			(xy 49.95778 -388.575949) (xy 49.991706 -388.541827) (xy 50.03056 -388.513445) (xy 50.073382 -388.491502)
			(xy 50.119114 -388.476543) (xy 50.166626 -388.468937) (xy 50.214742 -388.468871) (xy 50.262274 -388.476348)
			(xy 50.308047 -388.491183) (xy 50.350929 -388.513008) (xy 50.389861 -388.541284) (xy 50.423879 -388.575313)
			(xy 50.452143 -388.614254) (xy 50.46345 -388.635494) (xy 50.463958 -388.636764) (xy 50.53014 -388.751285)
			(xy 51.086146 -388.751285) (xy 51.093477 -388.703739) (xy 51.10817 -388.657929) (xy 51.129861 -388.614989)
			(xy 51.158013 -388.575979) (xy 51.191932 -388.541863) (xy 51.230779 -388.513485) (xy 51.273593 -388.491546)
			(xy 51.319317 -388.476589) (xy 51.366819 -388.468982) (xy 51.414927 -388.468915) (xy 51.462451 -388.476388)
			(xy 51.508216 -388.491218) (xy 51.551092 -388.513037) (xy 51.590018 -388.541306) (xy 51.624032 -388.575327)
			(xy 51.652294 -388.614258) (xy 51.6636 -388.635494) (xy 51.664108 -388.636764) (xy 51.730289 -388.751284)
			(xy 52.286049 -388.751284) (xy 52.293381 -388.703739) (xy 52.308073 -388.65793) (xy 52.329764 -388.614991)
			(xy 52.357916 -388.575981) (xy 52.391834 -388.541866) (xy 52.43068 -388.513488) (xy 52.473494 -388.49155)
			(xy 52.519217 -388.476592) (xy 52.566719 -388.468986) (xy 52.614826 -388.468918) (xy 52.662349 -388.476392)
			(xy 52.708114 -388.491221) (xy 52.750989 -388.513039) (xy 52.789914 -388.541308) (xy 52.823928 -388.575328)
			(xy 52.85219 -388.614259) (xy 52.863496 -388.635494) (xy 52.864004 -388.636764) (xy 52.930187 -388.751287)
			(xy 53.486104 -388.751287) (xy 53.493436 -388.703733) (xy 53.508131 -388.657915) (xy 53.529825 -388.614968)
			(xy 53.557983 -388.575951) (xy 53.591908 -388.54183) (xy 53.630761 -388.513448) (xy 53.673583 -388.491506)
			(xy 53.719314 -388.476547) (xy 53.766825 -388.468941) (xy 53.814941 -388.468875) (xy 53.862473 -388.476351)
			(xy 53.908245 -388.491185) (xy 53.951126 -388.51301) (xy 53.990057 -388.541286) (xy 54.024075 -388.575314)
			(xy 54.052339 -388.614254) (xy 54.063646 -388.635494) (xy 54.064154 -388.636764) (xy 54.130337 -388.751286)
			(xy 54.686008 -388.751286) (xy 54.69334 -388.703733) (xy 54.708035 -388.657917) (xy 54.729728 -388.61497)
			(xy 54.757886 -388.575954) (xy 54.79181 -388.541833) (xy 54.830663 -388.513451) (xy 54.873484 -388.491509)
			(xy 54.919215 -388.476551) (xy 54.966725 -388.468944) (xy 55.01484 -388.468878) (xy 55.062371 -388.476355)
			(xy 55.108142 -388.491188) (xy 55.151023 -388.513012) (xy 55.189954 -388.541288) (xy 55.223971 -388.575315)
			(xy 55.252235 -388.614254) (xy 55.263542 -388.635494) (xy 55.26405 -388.636764) (xy 55.330233 -388.751286)
			(xy 55.885912 -388.751286) (xy 55.893244 -388.703734) (xy 55.907938 -388.657918) (xy 55.929632 -388.614971)
			(xy 55.957788 -388.575956) (xy 55.991712 -388.541836) (xy 56.030564 -388.513454) (xy 56.073385 -388.491513)
			(xy 56.119115 -388.476554) (xy 56.166624 -388.468948) (xy 56.214739 -388.468882) (xy 56.262269 -388.476358)
			(xy 56.30804 -388.491191) (xy 56.35092 -388.513015) (xy 56.38985 -388.54129) (xy 56.423868 -388.575317)
			(xy 56.452131 -388.614255) (xy 56.463438 -388.635494) (xy 56.463946 -388.636764) (xy 56.530127 -388.751284)
			(xy 57.086156 -388.751284) (xy 57.093488 -388.70374) (xy 57.10818 -388.657933) (xy 57.12987 -388.614994)
			(xy 57.158021 -388.575986) (xy 57.191939 -388.541872) (xy 57.230784 -388.513495) (xy 57.273596 -388.491557)
			(xy 57.319317 -388.476599) (xy 57.366818 -388.468993) (xy 57.414924 -388.468925) (xy 57.462446 -388.476398)
			(xy 57.508209 -388.491226) (xy 57.551083 -388.513044) (xy 57.590007 -388.541311) (xy 57.624021 -388.57533)
			(xy 57.652282 -388.614259) (xy 57.663588 -388.635494) (xy 57.664096 -388.636764) (xy 57.730277 -388.751284)
			(xy 58.28606 -388.751284) (xy 58.293391 -388.703741) (xy 58.308083 -388.657934) (xy 58.329773 -388.614996)
			(xy 58.357924 -388.575988) (xy 58.391841 -388.541874) (xy 58.430685 -388.513498) (xy 58.473497 -388.49156)
			(xy 58.519217 -388.476603) (xy 58.566717 -388.468997) (xy 58.614822 -388.468929) (xy 58.662344 -388.476401)
			(xy 58.708107 -388.491229) (xy 58.75098 -388.513046) (xy 58.789904 -388.541313) (xy 58.823917 -388.575331)
			(xy 58.852178 -388.61426) (xy 58.863484 -388.635494) (xy 58.863992 -388.636764) (xy 58.930175 -388.751286)
			(xy 59.486115 -388.751286) (xy 59.493447 -388.703734) (xy 59.508141 -388.657919) (xy 59.529835 -388.614973)
			(xy 59.557991 -388.575958) (xy 59.591914 -388.541839) (xy 59.630766 -388.513457) (xy 59.673585 -388.491516)
			(xy 59.719315 -388.476558) (xy 59.766824 -388.468952) (xy 59.814937 -388.468885) (xy 59.862467 -388.476361)
			(xy 59.908237 -388.491194) (xy 59.951117 -388.513017) (xy 59.990047 -388.541291) (xy 60.024064 -388.575318)
			(xy 60.052327 -388.614255) (xy 60.063634 -388.635494) (xy 60.064142 -388.636764) (xy 60.130325 -388.751286)
			(xy 60.686019 -388.751286) (xy 60.693351 -388.703735) (xy 60.708045 -388.65792) (xy 60.729738 -388.614975)
			(xy 60.757893 -388.575961) (xy 60.791816 -388.541841) (xy 60.830667 -388.513461) (xy 60.873486 -388.49152)
			(xy 60.919215 -388.476561) (xy 60.966723 -388.468955) (xy 61.014836 -388.468889) (xy 61.062365 -388.476364)
			(xy 61.108135 -388.491197) (xy 61.151014 -388.513019) (xy 61.189943 -388.541293) (xy 61.22396 -388.575319)
			(xy 61.252223 -388.614255) (xy 61.26353 -388.635494) (xy 61.264038 -388.636764) (xy 61.330221 -388.751286)
			(xy 61.885922 -388.751286) (xy 61.893254 -388.703735) (xy 61.907948 -388.657921) (xy 61.929641 -388.614977)
			(xy 61.957796 -388.575963) (xy 61.991718 -388.541844) (xy 62.030569 -388.513464) (xy 62.073387 -388.491523)
			(xy 62.119115 -388.476565) (xy 62.166623 -388.468959) (xy 62.214735 -388.468892) (xy 62.262263 -388.476368)
			(xy 62.308032 -388.4912) (xy 62.350911 -388.513022) (xy 62.38984 -388.541295) (xy 62.423856 -388.57532)
			(xy 62.452119 -388.614256) (xy 62.463426 -388.635494) (xy 62.463934 -388.636764) (xy 62.530115 -388.751284)
			(xy 63.086167 -388.751284) (xy 63.093498 -388.703742) (xy 63.10819 -388.657936) (xy 63.129879 -388.615)
			(xy 63.158029 -388.575993) (xy 63.191945 -388.54188) (xy 63.230788 -388.513504) (xy 63.273598 -388.491567)
			(xy 63.319318 -388.47661) (xy 63.366816 -388.469004) (xy 63.41492 -388.468936) (xy 63.46244 -388.476408)
			(xy 63.508202 -388.491235) (xy 63.551074 -388.513051) (xy 63.589997 -388.541317) (xy 63.624009 -388.575333)
			(xy 63.65227 -388.61426) (xy 63.663576 -388.635494) (xy 63.664084 -388.636764) (xy 63.757251 -388.797979)
			(xy 64.286112 -388.797979) (xy 64.286361 -388.747044) (xy 64.295054 -388.696856) (xy 64.311952 -388.648805)
			(xy 64.336585 -388.604222) (xy 64.368271 -388.564342) (xy 64.406133 -388.530271) (xy 64.449122 -388.502951)
			(xy 64.496047 -388.48314) (xy 64.545608 -388.471387) (xy 64.596432 -388.468016) (xy 64.647111 -388.473122)
			(xy 64.696241 -388.486563) (xy 64.742461 -388.507967) (xy 64.784491 -388.53674) (xy 64.821166 -388.572086)
			(xy 64.851471 -388.613026) (xy 64.863472 -388.635494) (xy 64.86398 -388.636764) (xy 64.930163 -388.751286)
			(xy 65.486126 -388.751286) (xy 65.493458 -388.703736) (xy 65.508151 -388.657923) (xy 65.529844 -388.614979)
			(xy 65.557999 -388.575966) (xy 65.59192 -388.541847) (xy 65.63077 -388.513467) (xy 65.673588 -388.491527)
			(xy 65.719316 -388.476569) (xy 65.766822 -388.468962) (xy 65.814934 -388.468896) (xy 65.862461 -388.476371)
			(xy 65.90823 -388.491202) (xy 65.951108 -388.513024) (xy 65.990037 -388.541297) (xy 66.024053 -388.575321)
			(xy 66.052315 -388.614256) (xy 66.063622 -388.635494) (xy 66.06413 -388.636764) (xy 66.130312 -388.751285)
			(xy 80.01394 -388.751285) (xy 80.021272 -388.703738) (xy 80.035965 -388.657927) (xy 80.057656 -388.614986)
			(xy 80.085809 -388.575975) (xy 80.119729 -388.541859) (xy 80.158577 -388.51348) (xy 80.201392 -388.491541)
			(xy 80.247116 -388.476583) (xy 80.29462 -388.468977) (xy 80.342729 -388.46891) (xy 80.390254 -388.476384)
			(xy 80.43602 -388.491214) (xy 80.478896 -388.513033) (xy 80.517823 -388.541304) (xy 80.551837 -388.575325)
			(xy 80.5801 -388.614258) (xy 80.591406 -388.635494) (xy 80.591914 -388.636764) (xy 80.658096 -388.751285)
			(xy 81.213844 -388.751285) (xy 81.221175 -388.703738) (xy 81.235868 -388.657929) (xy 81.257559 -388.614988)
			(xy 81.285712 -388.575977) (xy 81.319631 -388.541862) (xy 81.358478 -388.513483) (xy 81.401293 -388.491544)
			(xy 81.447017 -388.476587) (xy 81.49452 -388.46898) (xy 81.542628 -388.468913) (xy 81.590152 -388.476387)
			(xy 81.635918 -388.491217) (xy 81.678793 -388.513036) (xy 81.717719 -388.541305) (xy 81.751734 -388.575326)
			(xy 81.779996 -388.614258) (xy 81.791302 -388.635494) (xy 81.79181 -388.636764) (xy 81.857992 -388.751285)
			(xy 82.413748 -388.751285) (xy 82.421079 -388.703739) (xy 82.435771 -388.65793) (xy 82.457462 -388.61499)
			(xy 82.485615 -388.57598) (xy 82.519533 -388.541864) (xy 82.55838 -388.513487) (xy 82.601194 -388.491548)
			(xy 82.646917 -388.47659) (xy 82.694419 -388.468984) (xy 82.742527 -388.468917) (xy 82.79005 -388.47639)
			(xy 82.835815 -388.491219) (xy 82.87869 -388.513038) (xy 82.917616 -388.541307) (xy 82.95163 -388.575327)
			(xy 82.979892 -388.614258) (xy 82.991198 -388.635494) (xy 82.991706 -388.636764) (xy 83.057889 -388.751287)
			(xy 83.613803 -388.751287) (xy 83.621135 -388.703732) (xy 83.635829 -388.657915) (xy 83.657524 -388.614967)
			(xy 83.685682 -388.57595) (xy 83.719607 -388.541829) (xy 83.75846 -388.513446) (xy 83.801282 -388.491504)
			(xy 83.847014 -388.476545) (xy 83.894525 -388.468939) (xy 83.942642 -388.468873) (xy 83.990174 -388.47635)
			(xy 84.035946 -388.491184) (xy 84.078828 -388.513009) (xy 84.117759 -388.541285) (xy 84.151777 -388.575314)
			(xy 84.180041 -388.614254) (xy 84.191348 -388.635494) (xy 84.191856 -388.636764) (xy 84.258039 -388.751287)
			(xy 84.813706 -388.751287) (xy 84.821038 -388.703733) (xy 84.835733 -388.657916) (xy 84.857427 -388.614969)
			(xy 84.885584 -388.575952) (xy 84.919509 -388.541831) (xy 84.958362 -388.513449) (xy 85.001183 -388.491508)
			(xy 85.046914 -388.476549) (xy 85.094425 -388.468942) (xy 85.14254 -388.468877) (xy 85.190072 -388.476353)
			(xy 85.235844 -388.491187) (xy 85.278725 -388.513011) (xy 85.317655 -388.541287) (xy 85.351673 -388.575315)
			(xy 85.379937 -388.614254) (xy 85.391244 -388.635494) (xy 85.391752 -388.636764) (xy 85.457933 -388.751284)
			(xy 86.013951 -388.751284) (xy 86.021282 -388.703739) (xy 86.035975 -388.657931) (xy 86.057665 -388.614992)
			(xy 86.085817 -388.575982) (xy 86.119735 -388.541867) (xy 86.158581 -388.51349) (xy 86.201394 -388.491551)
			(xy 86.247117 -388.476594) (xy 86.294619 -388.468988) (xy 86.342725 -388.46892) (xy 86.390248 -388.476393)
			(xy 86.436013 -388.491222) (xy 86.478887 -388.513041) (xy 86.517813 -388.541309) (xy 86.551826 -388.575329)
			(xy 86.580088 -388.614259) (xy 86.591394 -388.635494) (xy 86.591902 -388.636764) (xy 86.658083 -388.751284)
			(xy 87.213855 -388.751284) (xy 87.221186 -388.70374) (xy 87.235878 -388.657932) (xy 87.257568 -388.614993)
			(xy 87.28572 -388.575985) (xy 87.319638 -388.54187) (xy 87.358483 -388.513493) (xy 87.401295 -388.491555)
			(xy 87.447017 -388.476598) (xy 87.494518 -388.468991) (xy 87.542624 -388.468924) (xy 87.590147 -388.476397)
			(xy 87.63591 -388.491225) (xy 87.678784 -388.513043) (xy 87.717709 -388.541311) (xy 87.751722 -388.57533)
			(xy 87.779984 -388.614259) (xy 87.79129 -388.635494) (xy 87.791798 -388.636764) (xy 87.857979 -388.751284)
			(xy 88.413758 -388.751284) (xy 88.42109 -388.70374) (xy 88.435782 -388.657933) (xy 88.457471 -388.614995)
			(xy 88.485623 -388.575987) (xy 88.51954 -388.541873) (xy 88.558384 -388.513496) (xy 88.601196 -388.491558)
			(xy 88.646917 -388.476601) (xy 88.694418 -388.468995) (xy 88.742523 -388.468927) (xy 88.790045 -388.4764)
			(xy 88.835808 -388.491228) (xy 88.878681 -388.513045) (xy 88.917606 -388.541312) (xy 88.951619 -388.575331)
			(xy 88.97988 -388.614259) (xy 88.991186 -388.635494) (xy 88.991694 -388.636764) (xy 89.057877 -388.751286)
			(xy 89.613813 -388.751286) (xy 89.621145 -388.703734) (xy 89.63584 -388.657918) (xy 89.657533 -388.614972)
			(xy 89.68569 -388.575957) (xy 89.719613 -388.541837) (xy 89.758465 -388.513456) (xy 89.801285 -388.491515)
			(xy 89.847015 -388.476556) (xy 89.894524 -388.46895) (xy 89.942638 -388.468884) (xy 89.990168 -388.476359)
			(xy 90.035939 -388.491192) (xy 90.078819 -388.513016) (xy 90.117749 -388.54129) (xy 90.151766 -388.575317)
			(xy 90.180029 -388.614255) (xy 90.191336 -388.635494) (xy 90.191844 -388.636764) (xy 90.258027 -388.751286)
			(xy 90.813717 -388.751286) (xy 90.821049 -388.703734) (xy 90.835743 -388.65792) (xy 90.857436 -388.614974)
			(xy 90.885592 -388.57596) (xy 90.919515 -388.54184) (xy 90.958366 -388.513459) (xy 91.001186 -388.491518)
			(xy 91.046915 -388.47656) (xy 91.094423 -388.468953) (xy 91.142537 -388.468887) (xy 91.190066 -388.476363)
			(xy 91.235836 -388.491195) (xy 91.278716 -388.513018) (xy 91.317645 -388.541292) (xy 91.351662 -388.575318)
			(xy 91.379925 -388.614255) (xy 91.391232 -388.635494) (xy 91.39174 -388.636764) (xy 91.457921 -388.751284)
			(xy 92.013962 -388.751284) (xy 92.021293 -388.703741) (xy 92.035985 -388.657935) (xy 92.057674 -388.614997)
			(xy 92.085825 -388.575989) (xy 92.119742 -388.541876) (xy 92.158586 -388.5135) (xy 92.201397 -388.491562)
			(xy 92.247118 -388.476605) (xy 92.294617 -388.468999) (xy 92.342722 -388.468931) (xy 92.390243 -388.476403)
			(xy 92.436005 -388.491231) (xy 92.478878 -388.513048) (xy 92.517802 -388.541314) (xy 92.551815 -388.575332)
			(xy 92.580076 -388.61426) (xy 92.591382 -388.635494) (xy 92.59189 -388.636764) (xy 92.658071 -388.751284)
			(xy 93.213865 -388.751284) (xy 93.221197 -388.703741) (xy 93.235888 -388.657936) (xy 93.257577 -388.614999)
			(xy 93.285728 -388.575992) (xy 93.319644 -388.541879) (xy 93.358487 -388.513503) (xy 93.401298 -388.491565)
			(xy 93.447018 -388.476609) (xy 93.494517 -388.469002) (xy 93.542621 -388.468934) (xy 93.590141 -388.476406)
			(xy 93.635903 -388.491234) (xy 93.678775 -388.51305) (xy 93.717699 -388.541316) (xy 93.751711 -388.575333)
			(xy 93.779972 -388.61426) (xy 93.791278 -388.635494) (xy 93.791786 -388.636764) (xy 93.884953 -388.797979)
			(xy 94.413811 -388.797979) (xy 94.414059 -388.747044) (xy 94.422753 -388.696855) (xy 94.43965 -388.648804)
			(xy 94.464283 -388.604221) (xy 94.49597 -388.564341) (xy 94.533833 -388.530269) (xy 94.576822 -388.502949)
			(xy 94.623747 -388.483138) (xy 94.673308 -388.471385) (xy 94.724132 -388.468014) (xy 94.774811 -388.47312)
			(xy 94.823942 -388.486562) (xy 94.870162 -388.507966) (xy 94.912192 -388.536739) (xy 94.948868 -388.572086)
			(xy 94.979173 -388.613025) (xy 94.991174 -388.635494) (xy 94.991682 -388.636764) (xy 95.057865 -388.751286)
			(xy 95.613824 -388.751286) (xy 95.621156 -388.703735) (xy 95.63585 -388.657922) (xy 95.657542 -388.614978)
			(xy 95.685697 -388.575964) (xy 95.719619 -388.541846) (xy 95.75847 -388.513466) (xy 95.801288 -388.491525)
			(xy 95.847015 -388.476567) (xy 95.894522 -388.468961) (xy 95.942634 -388.468894) (xy 95.990162 -388.476369)
			(xy 96.035931 -388.491201) (xy 96.07881 -388.513023) (xy 96.117738 -388.541296) (xy 96.151754 -388.57532)
			(xy 96.180017 -388.614256) (xy 96.191324 -388.635494) (xy 96.191832 -388.636764) (xy 96.258014 -388.751285)
			(xy 96.813728 -388.751285) (xy 96.821059 -388.703736) (xy 96.835753 -388.657923) (xy 96.857445 -388.61498)
			(xy 96.8856 -388.575967) (xy 96.919522 -388.541849) (xy 96.958371 -388.513469) (xy 97.001189 -388.491529)
			(xy 97.046916 -388.476571) (xy 97.094422 -388.468964) (xy 97.142533 -388.468898) (xy 97.19006 -388.476372)
			(xy 97.235829 -388.491204) (xy 97.278707 -388.513025) (xy 97.317635 -388.541297) (xy 97.351651 -388.575321)
			(xy 97.379913 -388.614256) (xy 97.39122 -388.635494) (xy 97.391728 -388.636764) (xy 97.484894 -388.797978)
			(xy 98.014014 -388.797978) (xy 98.014263 -388.747044) (xy 98.022956 -388.696856) (xy 98.039853 -388.648805)
			(xy 98.064486 -388.604223) (xy 98.096173 -388.564344) (xy 98.134034 -388.530272) (xy 98.177023 -388.502953)
			(xy 98.223948 -388.483142) (xy 98.273508 -388.471388) (xy 98.324331 -388.468018) (xy 98.37501 -388.473124)
			(xy 98.424139 -388.486565) (xy 98.470359 -388.507968) (xy 98.512389 -388.536741) (xy 98.549064 -388.572087)
			(xy 98.579369 -388.613026) (xy 98.59137 -388.635494) (xy 98.591878 -388.636764) (xy 98.65806 -388.751285)
			(xy 114.586146 -388.751285) (xy 114.593477 -388.703739) (xy 114.60817 -388.657929) (xy 114.629861 -388.614989)
			(xy 114.658013 -388.575979) (xy 114.691932 -388.541863) (xy 114.730779 -388.513485) (xy 114.773593 -388.491546)
			(xy 114.819317 -388.476589) (xy 114.866819 -388.468982) (xy 114.914927 -388.468915) (xy 114.962451 -388.476388)
			(xy 115.008216 -388.491218) (xy 115.051092 -388.513037) (xy 115.090018 -388.541306) (xy 115.124032 -388.575327)
			(xy 115.152294 -388.614258) (xy 115.1636 -388.635494) (xy 115.164108 -388.636764) (xy 115.230289 -388.751284)
			(xy 115.786049 -388.751284) (xy 115.793381 -388.703739) (xy 115.808073 -388.65793) (xy 115.829764 -388.614991)
			(xy 115.857916 -388.575981) (xy 115.891834 -388.541866) (xy 115.93068 -388.513488) (xy 115.973494 -388.49155)
			(xy 116.019217 -388.476592) (xy 116.066719 -388.468986) (xy 116.114826 -388.468918) (xy 116.162349 -388.476392)
			(xy 116.208114 -388.491221) (xy 116.250989 -388.513039) (xy 116.289914 -388.541308) (xy 116.323928 -388.575328)
			(xy 116.35219 -388.614259) (xy 116.363496 -388.635494) (xy 116.364004 -388.636764) (xy 116.430185 -388.751284)
			(xy 116.985953 -388.751284) (xy 116.993284 -388.70374) (xy 117.007977 -388.657932) (xy 117.029667 -388.614992)
			(xy 117.057819 -388.575983) (xy 117.091737 -388.541869) (xy 117.130582 -388.513491) (xy 117.173395 -388.491553)
			(xy 117.219117 -388.476596) (xy 117.266618 -388.468989) (xy 117.314725 -388.468922) (xy 117.362247 -388.476395)
			(xy 117.408011 -388.491224) (xy 117.450886 -388.513042) (xy 117.489811 -388.54131) (xy 117.523824 -388.575329)
			(xy 117.552086 -388.614259) (xy 117.563392 -388.635494) (xy 117.5639 -388.636764) (xy 117.630083 -388.751286)
			(xy 118.186008 -388.751286) (xy 118.19334 -388.703733) (xy 118.208035 -388.657917) (xy 118.229728 -388.61497)
			(xy 118.257886 -388.575954) (xy 118.29181 -388.541833) (xy 118.330663 -388.513451) (xy 118.373484 -388.491509)
			(xy 118.419215 -388.476551) (xy 118.466725 -388.468944) (xy 118.51484 -388.468878) (xy 118.562371 -388.476355)
			(xy 118.608142 -388.491188) (xy 118.651023 -388.513012) (xy 118.689954 -388.541288) (xy 118.723971 -388.575315)
			(xy 118.752235 -388.614254) (xy 118.763542 -388.635494) (xy 118.76405 -388.636764) (xy 118.830233 -388.751286)
			(xy 119.385912 -388.751286) (xy 119.393244 -388.703734) (xy 119.407938 -388.657918) (xy 119.429632 -388.614971)
			(xy 119.457788 -388.575956) (xy 119.491712 -388.541836) (xy 119.530564 -388.513454) (xy 119.573385 -388.491513)
			(xy 119.619115 -388.476554) (xy 119.666624 -388.468948) (xy 119.714739 -388.468882) (xy 119.762269 -388.476358)
			(xy 119.80804 -388.491191) (xy 119.85092 -388.513015) (xy 119.88985 -388.54129) (xy 119.923868 -388.575317)
			(xy 119.952131 -388.614255) (xy 119.963438 -388.635494) (xy 119.963946 -388.636764) (xy 120.030127 -388.751284)
			(xy 120.586156 -388.751284) (xy 120.593488 -388.70374) (xy 120.60818 -388.657933) (xy 120.62987 -388.614994)
			(xy 120.658021 -388.575986) (xy 120.691939 -388.541872) (xy 120.730784 -388.513495) (xy 120.773596 -388.491557)
			(xy 120.819317 -388.476599) (xy 120.866818 -388.468993) (xy 120.914924 -388.468925) (xy 120.962446 -388.476398)
			(xy 121.008209 -388.491226) (xy 121.051083 -388.513044) (xy 121.090007 -388.541311) (xy 121.124021 -388.57533)
			(xy 121.152282 -388.614259) (xy 121.163588 -388.635494) (xy 121.164096 -388.636764) (xy 121.230277 -388.751284)
			(xy 121.78606 -388.751284) (xy 121.793391 -388.703741) (xy 121.808083 -388.657934) (xy 121.829773 -388.614996)
			(xy 121.857924 -388.575988) (xy 121.891841 -388.541874) (xy 121.930685 -388.513498) (xy 121.973497 -388.49156)
			(xy 122.019217 -388.476603) (xy 122.066717 -388.468997) (xy 122.114822 -388.468929) (xy 122.162344 -388.476401)
			(xy 122.208107 -388.491229) (xy 122.25098 -388.513046) (xy 122.289904 -388.541313) (xy 122.323917 -388.575331)
			(xy 122.352178 -388.61426) (xy 122.363484 -388.635494) (xy 122.363992 -388.636764) (xy 122.430173 -388.751284)
			(xy 122.985964 -388.751284) (xy 122.993295 -388.703741) (xy 123.007987 -388.657935) (xy 123.029676 -388.614998)
			(xy 123.057827 -388.575991) (xy 123.091743 -388.541877) (xy 123.130587 -388.513501) (xy 123.173398 -388.491564)
			(xy 123.219118 -388.476607) (xy 123.266617 -388.469) (xy 123.314721 -388.468932) (xy 123.362242 -388.476405)
			(xy 123.408004 -388.491232) (xy 123.450877 -388.513049) (xy 123.4898 -388.541315) (xy 123.523813 -388.575332)
			(xy 123.552074 -388.61426) (xy 123.56338 -388.635494) (xy 123.563888 -388.636764) (xy 123.630071 -388.751286)
			(xy 124.186019 -388.751286) (xy 124.193351 -388.703735) (xy 124.208045 -388.65792) (xy 124.229738 -388.614975)
			(xy 124.257893 -388.575961) (xy 124.291816 -388.541841) (xy 124.330667 -388.513461) (xy 124.373486 -388.49152)
			(xy 124.419215 -388.476561) (xy 124.466723 -388.468955) (xy 124.514836 -388.468889) (xy 124.562365 -388.476364)
			(xy 124.608135 -388.491197) (xy 124.651014 -388.513019) (xy 124.689943 -388.541293) (xy 124.72396 -388.575319)
			(xy 124.752223 -388.614255) (xy 124.76353 -388.635494) (xy 124.764038 -388.636764) (xy 124.830221 -388.751286)
			(xy 125.385922 -388.751286) (xy 125.393254 -388.703735) (xy 125.407948 -388.657921) (xy 125.429641 -388.614977)
			(xy 125.457796 -388.575963) (xy 125.491718 -388.541844) (xy 125.530569 -388.513464) (xy 125.573387 -388.491523)
			(xy 125.619115 -388.476565) (xy 125.666623 -388.468959) (xy 125.714735 -388.468892) (xy 125.762263 -388.476368)
			(xy 125.808032 -388.4912) (xy 125.850911 -388.513022) (xy 125.88984 -388.541295) (xy 125.923856 -388.57532)
			(xy 125.952119 -388.614256) (xy 125.963426 -388.635494) (xy 125.963934 -388.636764) (xy 126.030115 -388.751284)
			(xy 126.586167 -388.751284) (xy 126.593498 -388.703742) (xy 126.60819 -388.657936) (xy 126.629879 -388.615)
			(xy 126.658029 -388.575993) (xy 126.691945 -388.54188) (xy 126.730788 -388.513504) (xy 126.773598 -388.491567)
			(xy 126.819318 -388.47661) (xy 126.866816 -388.469004) (xy 126.91492 -388.468936) (xy 126.96244 -388.476408)
			(xy 127.008202 -388.491235) (xy 127.051074 -388.513051) (xy 127.089997 -388.541317) (xy 127.124009 -388.575333)
			(xy 127.15227 -388.61426) (xy 127.163576 -388.635494) (xy 127.164084 -388.636764) (xy 127.257251 -388.797979)
			(xy 127.786112 -388.797979) (xy 127.786361 -388.747044) (xy 127.795054 -388.696856) (xy 127.811952 -388.648805)
			(xy 127.836585 -388.604222) (xy 127.868271 -388.564342) (xy 127.906133 -388.530271) (xy 127.949122 -388.502951)
			(xy 127.996047 -388.48314) (xy 128.045608 -388.471387) (xy 128.096432 -388.468016) (xy 128.147111 -388.473122)
			(xy 128.196241 -388.486563) (xy 128.242461 -388.507967) (xy 128.284491 -388.53674) (xy 128.321166 -388.572086)
			(xy 128.351471 -388.613026) (xy 128.363472 -388.635494) (xy 128.36398 -388.636764) (xy 128.457146 -388.797978)
			(xy 128.986016 -388.797978) (xy 128.986265 -388.747044) (xy 128.994958 -388.696856) (xy 129.011855 -388.648806)
			(xy 129.036488 -388.604224) (xy 129.068174 -388.564345) (xy 129.106035 -388.530274) (xy 129.149024 -388.502955)
			(xy 129.195948 -388.483144) (xy 129.245508 -388.47139) (xy 129.296331 -388.46802) (xy 129.347009 -388.473125)
			(xy 129.396138 -388.486566) (xy 129.442358 -388.507969) (xy 129.484387 -388.536742) (xy 129.521062 -388.572087)
			(xy 129.551367 -388.613026) (xy 129.563368 -388.635494) (xy 129.563876 -388.636764) (xy 129.630058 -388.751285)
			(xy 130.18603 -388.751285) (xy 130.193361 -388.703736) (xy 130.208055 -388.657924) (xy 130.229747 -388.614981)
			(xy 130.257901 -388.575968) (xy 130.291823 -388.54185) (xy 130.330672 -388.51347) (xy 130.373489 -388.49153)
			(xy 130.419216 -388.476572) (xy 130.466722 -388.468966) (xy 130.514833 -388.468899) (xy 130.56236 -388.476374)
			(xy 130.608128 -388.491205) (xy 130.651005 -388.513026) (xy 130.689933 -388.541298) (xy 130.723949 -388.575322)
			(xy 130.752211 -388.614256) (xy 130.763518 -388.635494) (xy 130.764026 -388.636764) (xy 130.830208 -388.751285)
			(xy 131.385933 -388.751285) (xy 131.393265 -388.703737) (xy 131.407958 -388.657925) (xy 131.42965 -388.614982)
			(xy 131.457804 -388.57597) (xy 131.491725 -388.541853) (xy 131.530573 -388.513474) (xy 131.57339 -388.491534)
			(xy 131.619116 -388.476576) (xy 131.666621 -388.46897) (xy 131.714731 -388.468903) (xy 131.762258 -388.476377)
			(xy 131.808025 -388.491208) (xy 131.850902 -388.513029) (xy 131.88983 -388.5413) (xy 131.923845 -388.575323)
			(xy 131.952107 -388.614257) (xy 131.963414 -388.635494) (xy 131.963922 -388.636764) (xy 132.057087 -388.797977)
			(xy 132.586219 -388.797977) (xy 132.586468 -388.747044) (xy 132.595161 -388.696857) (xy 132.612058 -388.648807)
			(xy 132.636691 -388.604226) (xy 132.668376 -388.564348) (xy 132.706237 -388.530277) (xy 132.749225 -388.502958)
			(xy 132.796148 -388.483147) (xy 132.845708 -388.471394) (xy 132.89653 -388.468023) (xy 132.947207 -388.473129)
			(xy 132.996336 -388.486569) (xy 133.042555 -388.507972) (xy 133.084584 -388.536744) (xy 133.121258 -388.572088)
			(xy 133.151563 -388.613026) (xy 133.163564 -388.635494) (xy 133.164072 -388.636764) (xy 133.243924 -388.77494)
			(xy 147.113752 -388.77494) (xy 147.113752 -388.774432) (xy 147.114292 -388.750444) (xy 147.121792 -388.703057)
			(xy 147.136613 -388.657427) (xy 147.158389 -388.614677) (xy 147.186584 -388.57586) (xy 147.220505 -388.541931)
			(xy 147.259315 -388.513726) (xy 147.30206 -388.49194) (xy 147.347687 -388.477109) (xy 147.395072 -388.469598)
			(xy 147.41906 -388.469124) (xy 147.442996 -388.469555) (xy 147.490284 -388.477016) (xy 147.535829 -388.491761)
			(xy 147.578517 -388.51343) (xy 147.617303 -388.541492) (xy 147.651236 -388.57526) (xy 147.679488 -388.613908)
			(xy 147.69084 -388.634986) (xy 147.691348 -388.636002) (xy 147.771654 -388.77494) (xy 148.313648 -388.77494)
			(xy 148.313648 -388.774432) (xy 148.314192 -388.750444) (xy 148.321692 -388.703057) (xy 148.336512 -388.657428)
			(xy 148.358288 -388.614678) (xy 148.386483 -388.575861) (xy 148.420403 -388.541933) (xy 148.459213 -388.513728)
			(xy 148.501957 -388.491941) (xy 148.547583 -388.47711) (xy 148.594968 -388.469598) (xy 148.618956 -388.469124)
			(xy 148.642892 -388.469558) (xy 148.69018 -388.477018) (xy 148.735725 -388.491763) (xy 148.778413 -388.513431)
			(xy 148.817198 -388.541493) (xy 148.851132 -388.575261) (xy 148.879383 -388.613908) (xy 148.890736 -388.634986)
			(xy 148.891244 -388.636002) (xy 148.97155 -388.77494) (xy 149.513544 -388.77494) (xy 149.513544 -388.774432)
			(xy 149.514092 -388.750444) (xy 149.521592 -388.703058) (xy 149.536412 -388.657429) (xy 149.558187 -388.614679)
			(xy 149.586382 -388.575862) (xy 149.620301 -388.541934) (xy 149.659111 -388.513729) (xy 149.701855 -388.491943)
			(xy 149.74748 -388.477111) (xy 149.794864 -388.469598) (xy 149.818852 -388.469124) (xy 149.842788 -388.469561)
			(xy 149.890076 -388.477021) (xy 149.935621 -388.491765) (xy 149.978308 -388.513433) (xy 150.017094 -388.541494)
			(xy 150.051028 -388.575261) (xy 150.079279 -388.613908) (xy 150.090632 -388.634986) (xy 150.09114 -388.636002)
			(xy 150.171446 -388.77494) (xy 150.71344 -388.77494) (xy 150.71344 -388.774432) (xy 150.713869 -388.750425)
			(xy 150.72138 -388.703001) (xy 150.736223 -388.657338) (xy 150.75803 -388.614562) (xy 150.786266 -388.575726)
			(xy 150.820232 -388.54179) (xy 150.859092 -388.513589) (xy 150.901888 -388.491819) (xy 150.947564 -388.477017)
			(xy 150.994994 -388.469548) (xy 151.019002 -388.469124) (xy 151.042937 -388.469602) (xy 151.090222 -388.477054)
			(xy 151.135766 -388.491791) (xy 151.178454 -388.513452) (xy 151.21724 -388.541507) (xy 151.251175 -388.575268)
			(xy 151.279429 -388.61391) (xy 151.290782 -388.634986) (xy 151.29129 -388.636002) (xy 151.371596 -388.77494)
			(xy 151.913336 -388.77494) (xy 151.913336 -388.774432) (xy 151.913769 -388.750425) (xy 151.92128 -388.703002)
			(xy 151.936122 -388.657339) (xy 151.95793 -388.614563) (xy 151.986164 -388.575728) (xy 152.02013 -388.541791)
			(xy 152.05899 -388.51359) (xy 152.101785 -388.49182) (xy 152.147461 -388.477018) (xy 152.19489 -388.469548)
			(xy 152.218898 -388.469124) (xy 152.242835 -388.469524) (xy 152.290125 -388.476991) (xy 152.335671 -388.491741)
			(xy 152.378358 -388.513415) (xy 152.417143 -388.541482) (xy 152.451076 -388.575255) (xy 152.479326 -388.613906)
			(xy 152.490678 -388.634986) (xy 152.491186 -388.636002) (xy 152.571492 -388.77494) (xy 153.11374 -388.77494)
			(xy 153.11374 -388.774432) (xy 153.114168 -388.750437) (xy 153.121671 -388.703038) (xy 153.136498 -388.657397)
			(xy 153.158284 -388.614638) (xy 153.186491 -388.575814) (xy 153.220426 -388.541881) (xy 153.259251 -388.513676)
			(xy 153.302012 -388.491892) (xy 153.347654 -388.477068) (xy 153.395053 -388.469567) (xy 153.419048 -388.469124)
			(xy 153.442984 -388.469565) (xy 153.490271 -388.477024) (xy 153.535816 -388.491767) (xy 153.578504 -388.513434)
			(xy 153.61729 -388.541495) (xy 153.651224 -388.575262) (xy 153.679475 -388.613908) (xy 153.690828 -388.634986)
			(xy 153.691336 -388.636002) (xy 153.771642 -388.77494) (xy 154.313636 -388.77494) (xy 154.313636 -388.774432)
			(xy 154.314068 -388.750438) (xy 154.321571 -388.703039) (xy 154.336398 -388.657398) (xy 154.358183 -388.614639)
			(xy 154.38639 -388.575815) (xy 154.420324 -388.541882) (xy 154.459149 -388.513677) (xy 154.501909 -388.491893)
			(xy 154.547551 -388.477068) (xy 154.59495 -388.469567) (xy 154.618944 -388.469124) (xy 154.64288 -388.469568)
			(xy 154.690167 -388.477026) (xy 154.735712 -388.491769) (xy 154.7784 -388.513436) (xy 154.817185 -388.541496)
			(xy 154.851119 -388.575262) (xy 154.879371 -388.613909) (xy 154.890724 -388.634986) (xy 154.891232 -388.636002)
			(xy 154.971538 -388.77494) (xy 155.513532 -388.77494) (xy 155.513532 -388.774432) (xy 155.513968 -388.750438)
			(xy 155.521471 -388.703039) (xy 155.536298 -388.657399) (xy 155.558083 -388.61464) (xy 155.586289 -388.575816)
			(xy 155.620222 -388.541884) (xy 155.659047 -388.513678) (xy 155.701806 -388.491895) (xy 155.747447 -388.477069)
			(xy 155.794846 -388.469567) (xy 155.81884 -388.469124) (xy 155.842776 -388.469571) (xy 155.890063 -388.477029)
			(xy 155.935608 -388.491771) (xy 155.978295 -388.513437) (xy 156.017081 -388.541497) (xy 156.051015 -388.575263)
			(xy 156.079267 -388.613909) (xy 156.09062 -388.634986) (xy 156.091128 -388.636002) (xy 156.171434 -388.77494)
			(xy 156.713428 -388.77494) (xy 156.713428 -388.774432) (xy 156.713869 -388.750425) (xy 156.72138 -388.703003)
			(xy 156.736222 -388.657341) (xy 156.758028 -388.614565) (xy 156.786262 -388.575731) (xy 156.820227 -388.541794)
			(xy 156.859086 -388.513593) (xy 156.90188 -388.491823) (xy 156.947554 -388.477019) (xy 156.994983 -388.469549)
			(xy 157.01899 -388.469124) (xy 157.042927 -388.46953) (xy 157.090216 -388.476996) (xy 157.135762 -388.491746)
			(xy 157.17845 -388.513419) (xy 157.217235 -388.541484) (xy 157.251168 -388.575256) (xy 157.279418 -388.613907)
			(xy 157.29077 -388.634986) (xy 157.291278 -388.636002) (xy 157.371584 -388.77494) (xy 157.913324 -388.77494)
			(xy 157.913324 -388.774432) (xy 157.913769 -388.750425) (xy 157.92128 -388.703004) (xy 157.936121 -388.657342)
			(xy 157.957927 -388.614567) (xy 157.986161 -388.575732) (xy 158.020125 -388.541796) (xy 158.058983 -388.513595)
			(xy 158.101777 -388.491824) (xy 158.147451 -388.47702) (xy 158.194879 -388.469549) (xy 158.218886 -388.469124)
			(xy 158.242823 -388.469534) (xy 158.290112 -388.476998) (xy 158.335657 -388.491748) (xy 158.378345 -388.51342)
			(xy 158.41713 -388.541485) (xy 158.451064 -388.575256) (xy 158.479314 -388.613907) (xy 158.490666 -388.634986)
			(xy 158.491174 -388.636002) (xy 158.57148 -388.77494) (xy 159.113728 -388.77494) (xy 159.113728 -388.774432)
			(xy 159.114168 -388.750438) (xy 159.121671 -388.70304) (xy 159.136497 -388.6574) (xy 159.158282 -388.614641)
			(xy 159.186488 -388.575818) (xy 159.220421 -388.541885) (xy 159.259245 -388.51368) (xy 159.302004 -388.491896)
			(xy 159.347644 -388.47707) (xy 159.395042 -388.469568) (xy 159.419036 -388.469124) (xy 159.442972 -388.469574)
			(xy 159.490258 -388.477031) (xy 159.535803 -388.491773) (xy 159.578491 -388.513439) (xy 159.617277 -388.541498)
			(xy 159.651211 -388.575264) (xy 159.679463 -388.613909) (xy 159.690816 -388.634986) (xy 159.691324 -388.636002)
			(xy 159.77163 -388.77494) (xy 160.313624 -388.77494) (xy 160.313624 -388.774432) (xy 160.314068 -388.750438)
			(xy 160.321571 -388.703041) (xy 160.336397 -388.657401) (xy 160.358181 -388.614643) (xy 160.386387 -388.575819)
			(xy 160.420319 -388.541887) (xy 160.459143 -388.513681) (xy 160.501901 -388.491897) (xy 160.547541 -388.477071)
			(xy 160.594938 -388.469568) (xy 160.618932 -388.469124) (xy 160.642868 -388.469578) (xy 160.690154 -388.477034)
			(xy 160.735699 -388.491775) (xy 160.778387 -388.51344) (xy 160.817172 -388.541499) (xy 160.851107 -388.575264)
			(xy 160.879359 -388.613909) (xy 160.890712 -388.634986) (xy 160.89122 -388.636002) (xy 160.971526 -388.77494)
			(xy 161.51352 -388.77494) (xy 161.51352 -388.774432) (xy 161.513968 -388.750438) (xy 161.521471 -388.703041)
			(xy 161.536297 -388.657402) (xy 161.55808 -388.614644) (xy 161.586286 -388.57582) (xy 161.620217 -388.541888)
			(xy 161.65904 -388.513682) (xy 161.701798 -388.491898) (xy 161.747437 -388.477072) (xy 161.794834 -388.469568)
			(xy 161.818828 -388.469124) (xy 161.842763 -388.469581) (xy 161.89005 -388.477037) (xy 161.935595 -388.491777)
			(xy 161.978282 -388.513442) (xy 162.017068 -388.5415) (xy 162.051003 -388.575265) (xy 162.079255 -388.613909)
			(xy 162.090608 -388.634986) (xy 162.091116 -388.636002) (xy 162.171422 -388.77494) (xy 162.713416 -388.77494)
			(xy 162.713416 -388.774432) (xy 162.713869 -388.750426) (xy 162.721379 -388.703005) (xy 162.73622 -388.657344)
			(xy 162.758026 -388.614569) (xy 162.786259 -388.575735) (xy 162.820222 -388.541799) (xy 162.859079 -388.513597)
			(xy 162.901871 -388.491826) (xy 162.947544 -388.477022) (xy 162.994971 -388.469549) (xy 163.018978 -388.469124)
			(xy 163.042915 -388.46954) (xy 163.090203 -388.477004) (xy 163.135749 -388.491752) (xy 163.178437 -388.513423)
			(xy 163.217222 -388.541487) (xy 163.251155 -388.575258) (xy 163.279406 -388.613907) (xy 163.290758 -388.634986)
			(xy 163.291266 -388.636002) (xy 163.371572 -388.77494) (xy 163.913312 -388.77494) (xy 163.913312 -388.774432)
			(xy 163.913769 -388.750426) (xy 163.921279 -388.703005) (xy 163.93612 -388.657345) (xy 163.957925 -388.61457)
			(xy 163.986157 -388.575736) (xy 164.02012 -388.5418) (xy 164.058977 -388.513599) (xy 164.101769 -388.491827)
			(xy 164.147441 -388.477023) (xy 164.194868 -388.46955) (xy 164.218874 -388.469124) (xy 164.242811 -388.469543)
			(xy 164.290099 -388.477006) (xy 164.335644 -388.491754) (xy 164.378332 -388.513425) (xy 164.417118 -388.541488)
			(xy 164.451051 -388.575258) (xy 164.479302 -388.613907) (xy 164.490654 -388.634986) (xy 164.491162 -388.636002)
			(xy 164.571468 -388.77494) (xy 165.113716 -388.77494) (xy 165.113716 -388.774432) (xy 165.114168 -388.750439)
			(xy 165.121671 -388.703042) (xy 165.136496 -388.657403) (xy 165.15828 -388.614645) (xy 165.186484 -388.575822)
			(xy 165.220416 -388.54189) (xy 165.259238 -388.513684) (xy 165.301995 -388.491899) (xy 165.347634 -388.477072)
			(xy 165.395031 -388.469568) (xy 165.419024 -388.469124) (xy 165.442959 -388.469584) (xy 165.490246 -388.477039)
			(xy 165.53579 -388.491779) (xy 165.578478 -388.513444) (xy 165.617264 -388.541501) (xy 165.651198 -388.575265)
			(xy 165.679451 -388.61391) (xy 165.690804 -388.634986) (xy 165.691312 -388.636002) (xy 165.744132 -388.727385)
			(xy 193.900548 -388.727385) (xy 193.900548 -388.642663) (xy 193.908601 -388.558326) (xy 193.924635 -388.475136)
			(xy 193.948503 -388.393846) (xy 193.979991 -388.315194) (xy 194.018813 -388.239891) (xy 194.064616 -388.168619)
			(xy 194.116987 -388.102023) (xy 194.175452 -388.040708) (xy 194.23948 -387.985227) (xy 194.308492 -387.936084)
			(xy 194.381862 -387.893724) (xy 194.458927 -387.858529) (xy 194.538989 -387.83082) (xy 194.621322 -387.810846)
			(xy 194.705181 -387.798789) (xy 194.789806 -387.794758) (xy 194.874431 -387.798789) (xy 194.95829 -387.810846)
			(xy 195.040623 -387.83082) (xy 195.120685 -387.858529) (xy 195.19775 -387.893724) (xy 195.27112 -387.936084)
			(xy 195.340132 -387.985227) (xy 195.40416 -388.040708) (xy 195.462625 -388.102023) (xy 195.514996 -388.168619)
			(xy 195.560799 -388.239891) (xy 195.599621 -388.315194) (xy 195.631109 -388.393846) (xy 195.654977 -388.475136)
			(xy 195.671011 -388.558326) (xy 195.679064 -388.642663) (xy 195.679568 -388.685024) (xy 195.679064 -388.727385)
			(xy 195.671011 -388.811722) (xy 195.654977 -388.894912) (xy 195.631109 -388.976202) (xy 195.599621 -389.054854)
			(xy 195.560799 -389.130157) (xy 195.514996 -389.201429) (xy 195.462625 -389.268025) (xy 195.40416 -389.32934)
			(xy 195.355765 -389.371275) (xy 238.989866 -389.371275) (xy 238.989866 -389.286553) (xy 238.997919 -389.202216)
			(xy 239.013953 -389.119026) (xy 239.037821 -389.037736) (xy 239.069309 -388.959084) (xy 239.108131 -388.883781)
			(xy 239.153934 -388.812509) (xy 239.206305 -388.745913) (xy 239.26477 -388.684598) (xy 239.328798 -388.629117)
			(xy 239.39781 -388.579974) (xy 239.47118 -388.537614) (xy 239.548245 -388.502419) (xy 239.628307 -388.47471)
			(xy 239.71064 -388.454736) (xy 239.794499 -388.442679) (xy 239.879124 -388.438648) (xy 239.963749 -388.442679)
			(xy 240.047608 -388.454736) (xy 240.129941 -388.47471) (xy 240.210003 -388.502419) (xy 240.287068 -388.537614)
			(xy 240.360438 -388.579974) (xy 240.42945 -388.629117) (xy 240.493478 -388.684598) (xy 240.551943 -388.745913)
			(xy 240.604314 -388.812509) (xy 240.650117 -388.883781) (xy 240.688939 -388.959084) (xy 240.720427 -389.037736)
			(xy 240.744295 -389.119026) (xy 240.760329 -389.202216) (xy 240.768382 -389.286553) (xy 240.768792 -389.321)
			(xy 241.768928 -389.321) (xy 241.772957 -389.236403) (xy 241.78501 -389.152572) (xy 241.804978 -389.070266)
			(xy 241.832678 -388.990231) (xy 241.867861 -388.913191) (xy 241.910207 -388.839845) (xy 241.959334 -388.770856)
			(xy 242.014797 -388.706849) (xy 242.076092 -388.648404) (xy 242.142665 -388.59605) (xy 242.213914 -388.550261)
			(xy 242.289192 -388.511453) (xy 242.367819 -388.479975) (xy 242.449081 -388.456114) (xy 242.532244 -388.440086)
			(xy 242.616553 -388.432036) (xy 242.6589 -388.431532) (xy 242.659408 -388.431532) (xy 242.70574 -388.432135)
			(xy 242.797898 -388.441807) (xy 242.888552 -388.461003) (xy 242.976721 -388.489516) (xy 243.019326 -388.507732)
			(xy 243.029268 -388.511538) (xy 243.050532 -388.511538) (xy 243.060474 -388.507732) (xy 243.103108 -388.489501)
			(xy 243.191337 -388.460969) (xy 243.282057 -388.441775) (xy 243.374282 -388.432129) (xy 243.420646 -388.431532)
			(xy 243.421154 -388.431532) (xy 243.467518 -388.432123) (xy 243.559741 -388.441782) (xy 243.65046 -388.460978)
			(xy 243.738691 -388.489505) (xy 243.781326 -388.507732) (xy 243.791268 -388.511538) (xy 243.812532 -388.511538)
			(xy 243.822474 -388.507732) (xy 243.861902 -388.4908) (xy 243.943323 -388.463701) (xy 243.985034 -388.45363)
			(xy 243.999004 -388.450328) (xy 244.018816 -388.431024) (xy 244.049296 -388.31647) (xy 244.041422 -388.289292)
			(xy 244.031008 -388.279894) (xy 244.001154 -388.251861) (xy 243.946161 -388.191171) (xy 243.89698 -388.125683)
			(xy 243.854027 -388.055951) (xy 243.817668 -387.982565) (xy 243.788209 -387.906147) (xy 243.7659 -387.827344)
			(xy 243.75093 -387.746825) (xy 243.743427 -387.66527) (xy 243.742972 -387.62432) (xy 243.743564 -387.577925)
			(xy 243.753206 -387.485637) (xy 243.7724 -387.394853) (xy 243.800936 -387.306559) (xy 243.819172 -387.263894)
			(xy 243.822967 -387.253948) (xy 243.822974 -387.232688) (xy 243.819172 -387.222746) (xy 243.800933 -387.180082)
			(xy 243.772387 -387.09179) (xy 243.753193 -387.001006) (xy 243.743558 -386.908716) (xy 243.742972 -386.86232)
			(xy 243.743564 -386.815925) (xy 243.753206 -386.723637) (xy 243.7724 -386.632853) (xy 243.800936 -386.544559)
			(xy 243.819172 -386.501894) (xy 243.822967 -386.491948) (xy 243.822974 -386.470688) (xy 243.819172 -386.460746)
			(xy 243.800955 -386.418141) (xy 243.772437 -386.329974) (xy 243.753242 -386.239319) (xy 243.743581 -386.14716)
			(xy 243.742972 -386.100828) (xy 243.742972 -386.10032) (xy 243.743476 -386.057972) (xy 243.751527 -385.973658)
			(xy 243.767556 -385.890492) (xy 243.791417 -385.809225) (xy 243.822896 -385.730595) (xy 243.861707 -385.655314)
			(xy 243.907497 -385.584062) (xy 243.959853 -385.517486) (xy 244.018301 -385.456188) (xy 244.082311 -385.400723)
			(xy 244.151303 -385.351594) (xy 244.224653 -385.309245) (xy 244.301696 -385.274061) (xy 244.381735 -385.246359)
			(xy 244.464044 -385.226391) (xy 244.547879 -385.214338) (xy 244.63248 -385.210308) (xy 244.717081 -385.214338)
			(xy 244.800916 -385.226391) (xy 244.883225 -385.246359) (xy 244.963264 -385.274061) (xy 245.040307 -385.309245)
			(xy 245.113657 -385.351594) (xy 245.182649 -385.400723) (xy 245.246659 -385.456188) (xy 245.305107 -385.517486)
			(xy 245.357463 -385.584062) (xy 245.403253 -385.655314) (xy 245.442064 -385.730595) (xy 245.473543 -385.809225)
			(xy 245.497404 -385.890492) (xy 245.513433 -385.973658) (xy 245.521484 -386.057972) (xy 245.521988 -386.10032)
			(xy 245.521988 -386.100828) (xy 245.521391 -386.14716) (xy 245.511717 -386.239318) (xy 245.492519 -386.329972)
			(xy 245.464005 -386.418141) (xy 245.445788 -386.460746) (xy 245.441972 -386.470685) (xy 245.44198 -386.491951)
			(xy 245.445788 -386.501894) (xy 245.464038 -386.544554) (xy 245.492581 -386.632847) (xy 245.511773 -386.723633)
			(xy 245.521404 -386.815924) (xy 245.521988 -386.86232) (xy 245.521379 -386.908715) (xy 245.511742 -387.001003)
			(xy 245.492553 -387.091786) (xy 245.464022 -387.180081) (xy 245.445788 -387.222746) (xy 245.441972 -387.232685)
			(xy 245.44198 -387.253951) (xy 245.445788 -387.263894) (xy 245.464015 -387.306495) (xy 245.492532 -387.394663)
			(xy 245.511723 -387.485319) (xy 245.521381 -387.57748) (xy 245.521988 -387.623812) (xy 245.521988 -387.62432)
			(xy 249.677936 -387.62432) (xy 249.677936 -387.623812) (xy 249.678545 -387.57748) (xy 249.688215 -387.485322)
			(xy 249.70741 -387.394668) (xy 249.735921 -387.306499) (xy 249.754136 -387.263894) (xy 249.757932 -387.253949)
			(xy 249.75794 -387.232688) (xy 249.754136 -387.222746) (xy 249.735901 -387.18008) (xy 249.707353 -387.091789)
			(xy 249.688158 -387.001005) (xy 249.678522 -386.908716) (xy 249.677936 -386.86232) (xy 249.678522 -386.815924)
			(xy 249.688166 -386.723636) (xy 249.707361 -386.632852) (xy 249.735898 -386.544559) (xy 249.754136 -386.501894)
			(xy 249.757932 -386.491949) (xy 249.75794 -386.470688) (xy 249.754136 -386.460746) (xy 249.735917 -386.418142)
			(xy 249.707399 -386.329975) (xy 249.688206 -386.23932) (xy 249.678545 -386.14716) (xy 249.677936 -386.100828)
			(xy 249.677936 -386.10032) (xy 249.67844 -386.057972) (xy 249.686491 -385.973658) (xy 249.70252 -385.890492)
			(xy 249.726381 -385.809225) (xy 249.75786 -385.730595) (xy 249.796671 -385.655314) (xy 249.842461 -385.584062)
			(xy 249.894817 -385.517486) (xy 249.953265 -385.456188) (xy 250.017275 -385.400723) (xy 250.086267 -385.351594)
			(xy 250.159617 -385.309245) (xy 250.23666 -385.274061) (xy 250.316699 -385.246359) (xy 250.399008 -385.226391)
			(xy 250.482843 -385.214338) (xy 250.567444 -385.210308) (xy 250.652045 -385.214338) (xy 250.73588 -385.226391)
			(xy 250.818189 -385.246359) (xy 250.898228 -385.274061) (xy 250.975271 -385.309245) (xy 251.048621 -385.351594)
			(xy 251.117613 -385.400723) (xy 251.181623 -385.456188) (xy 251.240071 -385.517486) (xy 251.292427 -385.584062)
			(xy 251.338217 -385.655314) (xy 251.377028 -385.730595) (xy 251.408507 -385.809225) (xy 251.432368 -385.890492)
			(xy 251.448397 -385.973658) (xy 251.456448 -386.057972) (xy 251.456952 -386.10032) (xy 251.456952 -386.100828)
			(xy 251.456349 -386.14716) (xy 251.446676 -386.239318) (xy 251.42748 -386.329972) (xy 251.398967 -386.418141)
			(xy 251.380752 -386.460746) (xy 251.376932 -386.470684) (xy 251.37694 -386.491952) (xy 251.380752 -386.501894)
			(xy 251.399 -386.544555) (xy 251.427544 -386.632848) (xy 251.446736 -386.723633) (xy 251.456368 -386.815924)
			(xy 251.456952 -386.86232) (xy 251.456346 -386.908715) (xy 251.446708 -387.001003) (xy 251.427519 -387.091787)
			(xy 251.398987 -387.180081) (xy 251.380752 -387.222746) (xy 251.376932 -387.232684) (xy 251.37694 -387.253952)
			(xy 251.380752 -387.263894) (xy 251.399 -387.306555) (xy 251.427544 -387.394848) (xy 251.446736 -387.485633)
			(xy 251.456368 -387.577924) (xy 251.456952 -387.62432) (xy 255.6129 -387.62432) (xy 255.6129 -387.623812)
			(xy 255.613512 -387.57748) (xy 255.623182 -387.485323) (xy 255.642376 -387.394668) (xy 255.670886 -387.3065)
			(xy 255.6891 -387.263894) (xy 255.692893 -387.253948) (xy 255.692901 -387.232688) (xy 255.6891 -387.222746)
			(xy 255.670862 -387.180081) (xy 255.642316 -387.09179) (xy 255.623121 -387.001005) (xy 255.613486 -386.908716)
			(xy 255.6129 -386.86232) (xy 255.613489 -386.815925) (xy 255.623132 -386.723636) (xy 255.642326 -386.632853)
			(xy 255.670863 -386.544559) (xy 255.6891 -386.501894) (xy 255.692893 -386.491948) (xy 255.692901 -386.470688)
			(xy 255.6891 -386.460746) (xy 255.670885 -386.41814) (xy 255.642365 -386.329974) (xy 255.623171 -386.239319)
			(xy 255.613509 -386.14716) (xy 255.6129 -386.100828) (xy 255.6129 -386.10032) (xy 255.613404 -386.057972)
			(xy 255.621455 -385.973658) (xy 255.637484 -385.890492) (xy 255.661345 -385.809225) (xy 255.692824 -385.730595)
			(xy 255.731635 -385.655314) (xy 255.777425 -385.584062) (xy 255.829781 -385.517486) (xy 255.888229 -385.456188)
			(xy 255.952239 -385.400723) (xy 256.021231 -385.351594) (xy 256.094581 -385.309245) (xy 256.171624 -385.274061)
			(xy 256.251663 -385.246359) (xy 256.333972 -385.226391) (xy 256.417807 -385.214338) (xy 256.502408 -385.210308)
			(xy 256.587009 -385.214338) (xy 256.670844 -385.226391) (xy 256.753153 -385.246359) (xy 256.833192 -385.274061)
			(xy 256.910235 -385.309245) (xy 256.983585 -385.351594) (xy 257.052577 -385.400723) (xy 257.116587 -385.456188)
			(xy 257.175035 -385.517486) (xy 257.227391 -385.584062) (xy 257.273181 -385.655314) (xy 257.311992 -385.730595)
			(xy 257.343471 -385.809225) (xy 257.367332 -385.890492) (xy 257.383361 -385.973658) (xy 257.391412 -386.057972)
			(xy 257.391916 -386.10032) (xy 257.391916 -386.100828) (xy 257.391316 -386.14716) (xy 257.381643 -386.239318)
			(xy 257.362446 -386.329972) (xy 257.333932 -386.418141) (xy 257.315716 -386.460746) (xy 257.311898 -386.470685)
			(xy 257.311906 -386.491952) (xy 257.315716 -386.501894) (xy 257.333968 -386.544553) (xy 257.36251 -386.632847)
			(xy 257.381701 -386.723633) (xy 257.391332 -386.815924) (xy 257.391916 -386.86232) (xy 257.391304 -386.908715)
			(xy 257.381668 -387.001002) (xy 257.36248 -387.091786) (xy 257.33395 -387.18008) (xy 257.315716 -387.222746)
			(xy 257.311898 -387.232685) (xy 257.311906 -387.253952) (xy 257.315716 -387.263894) (xy 257.333945 -387.306494)
			(xy 257.362461 -387.394663) (xy 257.381651 -387.485319) (xy 257.391309 -387.57748) (xy 257.391916 -387.623812)
			(xy 257.391916 -387.62432) (xy 257.391412 -387.666668) (xy 257.383361 -387.750982) (xy 257.367332 -387.834148)
			(xy 257.343471 -387.915415) (xy 257.311992 -387.994045) (xy 257.273181 -388.069326) (xy 257.227391 -388.140578)
			(xy 257.175035 -388.207154) (xy 257.116587 -388.268452) (xy 257.052577 -388.323917) (xy 256.983585 -388.373046)
			(xy 256.910235 -388.415395) (xy 256.833192 -388.450579) (xy 256.753153 -388.478281) (xy 256.670844 -388.498249)
			(xy 256.587009 -388.510302) (xy 256.502408 -388.514333) (xy 256.417807 -388.510302) (xy 256.333972 -388.498249)
			(xy 256.251663 -388.478281) (xy 256.171624 -388.450579) (xy 256.094581 -388.415395) (xy 256.021231 -388.373046)
			(xy 255.952239 -388.323917) (xy 255.888229 -388.268452) (xy 255.829781 -388.207154) (xy 255.777425 -388.140578)
			(xy 255.731635 -388.069326) (xy 255.692824 -387.994045) (xy 255.661345 -387.915415) (xy 255.637484 -387.834148)
			(xy 255.621455 -387.750982) (xy 255.613404 -387.666668) (xy 255.6129 -387.62432) (xy 251.456952 -387.62432)
			(xy 251.456512 -387.665188) (xy 251.449014 -387.746579) (xy 251.434085 -387.82694) (xy 251.411848 -387.905592)
			(xy 251.382493 -387.981875) (xy 251.346266 -388.055144) (xy 251.303472 -388.124781) (xy 251.254472 -388.190201)
			(xy 251.19968 -388.250852) (xy 251.169932 -388.278878) (xy 251.159518 -388.28853) (xy 251.151644 -388.315708)
			(xy 251.182378 -388.430008) (xy 251.202698 -388.449566) (xy 251.216668 -388.452614) (xy 251.259507 -388.462746)
			(xy 251.343101 -388.490352) (xy 251.383546 -388.507732) (xy 251.393488 -388.511538) (xy 251.414752 -388.511538)
			(xy 251.424694 -388.507732) (xy 251.467325 -388.489494) (xy 251.555555 -388.460964) (xy 251.646276 -388.441772)
			(xy 251.738502 -388.432127) (xy 251.784866 -388.431532) (xy 251.785374 -388.431532) (xy 251.831737 -388.432151)
			(xy 251.92396 -388.441802) (xy 252.014679 -388.46099) (xy 252.10291 -388.489509) (xy 252.145546 -388.507732)
			(xy 252.155488 -388.511538) (xy 252.176752 -388.511538) (xy 252.186694 -388.507732) (xy 252.229325 -388.489494)
			(xy 252.317555 -388.460964) (xy 252.408276 -388.441772) (xy 252.500502 -388.432127) (xy 252.546866 -388.431532)
			(xy 252.547374 -388.431532) (xy 252.593737 -388.432151) (xy 252.68596 -388.441802) (xy 252.776679 -388.46099)
			(xy 252.86491 -388.489509) (xy 252.907546 -388.507732) (xy 252.917488 -388.511538) (xy 252.938752 -388.511538)
			(xy 252.948694 -388.507732) (xy 252.991325 -388.489494) (xy 253.079555 -388.460964) (xy 253.170276 -388.441772)
			(xy 253.262502 -388.432127) (xy 253.308866 -388.431532) (xy 253.309374 -388.431532) (xy 253.355737 -388.432151)
			(xy 253.44796 -388.441802) (xy 253.538679 -388.46099) (xy 253.62691 -388.489509) (xy 253.669546 -388.507732)
			(xy 253.679488 -388.511538) (xy 253.700752 -388.511538) (xy 253.710694 -388.507732) (xy 253.753293 -388.4895)
			(xy 253.841462 -388.460986) (xy 253.932119 -388.441796) (xy 254.024279 -388.432139) (xy 254.070612 -388.431532)
			(xy 254.07112 -388.431532) (xy 254.11347 -388.431957) (xy 254.197786 -388.44001) (xy 254.280954 -388.456041)
			(xy 254.362223 -388.479905) (xy 254.440854 -388.511386) (xy 254.516138 -388.550199) (xy 254.587391 -388.595992)
			(xy 254.653969 -388.64835) (xy 254.715268 -388.7068) (xy 254.770734 -388.770813) (xy 254.819864 -388.839807)
			(xy 254.862213 -388.91316) (xy 254.897398 -388.990205) (xy 254.9251 -389.070247) (xy 254.945069 -389.152559)
			(xy 254.957122 -389.236396) (xy 254.961153 -389.321) (xy 254.959095 -389.3642) (xy 258.047807 -389.3642)
			(xy 258.051837 -389.279603) (xy 258.06389 -389.195773) (xy 258.083856 -389.113467) (xy 258.111556 -389.033432)
			(xy 258.146738 -388.956393) (xy 258.189083 -388.883046) (xy 258.238208 -388.814056) (xy 258.293669 -388.750049)
			(xy 258.354962 -388.691603) (xy 258.421534 -388.639248) (xy 258.492781 -388.593457) (xy 258.568057 -388.554646)
			(xy 258.646682 -388.523167) (xy 258.727943 -388.499303) (xy 258.811105 -388.483272) (xy 258.895414 -388.475217)
			(xy 258.93776 -388.474712) (xy 258.938268 -388.474712) (xy 258.984599 -388.47533) (xy 259.076757 -388.484998)
			(xy 259.167411 -388.50419) (xy 259.25558 -388.532698) (xy 259.298186 -388.550912) (xy 259.308128 -388.554718)
			(xy 259.329392 -388.554718) (xy 259.339334 -388.550912) (xy 259.381972 -388.532693) (xy 259.4702 -388.504158)
			(xy 259.560919 -388.484961) (xy 259.653142 -388.475311) (xy 259.699506 -388.474712) (xy 259.700014 -388.474712)
			(xy 259.746377 -388.475319) (xy 259.8386 -388.484973) (xy 259.929319 -388.504165) (xy 260.017551 -388.532687)
			(xy 260.060186 -388.550912) (xy 260.070128 -388.554718) (xy 260.091392 -388.554718) (xy 260.101334 -388.550912)
			(xy 260.143972 -388.532693) (xy 260.2322 -388.504158) (xy 260.322919 -388.484961) (xy 260.415142 -388.475311)
			(xy 260.461506 -388.474712) (xy 260.462014 -388.474712) (xy 260.508377 -388.475319) (xy 260.6006 -388.484973)
			(xy 260.691319 -388.504165) (xy 260.779551 -388.532687) (xy 260.822186 -388.550912) (xy 260.832128 -388.554718)
			(xy 260.853392 -388.554718) (xy 260.863334 -388.550912) (xy 260.905972 -388.532693) (xy 260.9942 -388.504158)
			(xy 261.084919 -388.484961) (xy 261.177142 -388.475311) (xy 261.223506 -388.474712) (xy 261.224014 -388.474712)
			(xy 261.270377 -388.475319) (xy 261.3626 -388.484973) (xy 261.453319 -388.504165) (xy 261.541551 -388.532687)
			(xy 261.584186 -388.550912) (xy 261.594128 -388.554718) (xy 261.615392 -388.554718) (xy 261.625334 -388.550912)
			(xy 261.673582 -388.530355) (xy 261.773794 -388.499416) (xy 261.825232 -388.48919) (xy 261.834695 -388.487076)
			(xy 261.851111 -388.476778) (xy 261.862543 -388.461131) (xy 261.865364 -388.451852) (xy 261.892288 -388.348474)
			(xy 261.883144 -388.32028) (xy 261.87146 -388.310882) (xy 261.838207 -388.282721) (xy 261.77672 -388.220971)
			(xy 261.721566 -388.153504) (xy 261.673272 -388.080968) (xy 261.632303 -388.004058) (xy 261.599049 -387.92351)
			(xy 261.57383 -387.840097) (xy 261.556889 -387.754617) (xy 261.548386 -387.667891) (xy 261.547864 -387.62432)
			(xy 261.548456 -387.577925) (xy 261.558099 -387.485637) (xy 261.577292 -387.394853) (xy 261.605828 -387.306559)
			(xy 261.624064 -387.263894) (xy 261.627859 -387.253948) (xy 261.627867 -387.232688) (xy 261.624064 -387.222746)
			(xy 261.605824 -387.180082) (xy 261.577279 -387.09179) (xy 261.558085 -387.001006) (xy 261.54845 -386.908716)
			(xy 261.547864 -386.86232) (xy 261.548456 -386.815925) (xy 261.558099 -386.723637) (xy 261.577292 -386.632853)
			(xy 261.605828 -386.544559) (xy 261.624064 -386.501894) (xy 261.627859 -386.491948) (xy 261.627867 -386.470688)
			(xy 261.624064 -386.460746) (xy 261.605847 -386.418141) (xy 261.577328 -386.329974) (xy 261.558134 -386.23932)
			(xy 261.548473 -386.14716) (xy 261.547864 -386.100828) (xy 261.547864 -386.10032) (xy 261.548368 -386.057972)
			(xy 261.556419 -385.973658) (xy 261.572448 -385.890492) (xy 261.596309 -385.809225) (xy 261.627788 -385.730595)
			(xy 261.666599 -385.655314) (xy 261.712389 -385.584062) (xy 261.764745 -385.517486) (xy 261.823193 -385.456188)
			(xy 261.887203 -385.400723) (xy 261.956195 -385.351594) (xy 262.029545 -385.309245) (xy 262.106588 -385.274061)
			(xy 262.186627 -385.246359) (xy 262.268936 -385.226391) (xy 262.352771 -385.214338) (xy 262.437372 -385.210308)
			(xy 262.521973 -385.214338) (xy 262.605808 -385.226391) (xy 262.688117 -385.246359) (xy 262.768156 -385.274061)
			(xy 262.845199 -385.309245) (xy 262.918549 -385.351594) (xy 262.987541 -385.400723) (xy 263.051551 -385.456188)
			(xy 263.109999 -385.517486) (xy 263.162355 -385.584062) (xy 263.208145 -385.655314) (xy 263.246956 -385.730595)
			(xy 263.278435 -385.809225) (xy 263.302296 -385.890492) (xy 263.318325 -385.973658) (xy 263.326376 -386.057972)
			(xy 263.32688 -386.10032) (xy 263.32688 -386.100828) (xy 263.326283 -386.14716) (xy 263.31661 -386.239318)
			(xy 263.297411 -386.329973) (xy 263.268897 -386.418141) (xy 263.25068 -386.460746) (xy 263.246864 -386.470685)
			(xy 263.246872 -386.491951) (xy 263.25068 -386.501894) (xy 263.26893 -386.544554) (xy 263.297473 -386.632847)
			(xy 263.316665 -386.723633) (xy 263.326296 -386.815924) (xy 263.32688 -386.86232) (xy 263.326271 -386.908715)
			(xy 263.316634 -387.001003) (xy 263.297446 -387.091786) (xy 263.268915 -387.180081) (xy 263.25068 -387.222746)
			(xy 263.246864 -387.232685) (xy 263.246872 -387.253951) (xy 263.25068 -387.263894) (xy 263.268907 -387.306495)
			(xy 263.297424 -387.394663) (xy 263.316615 -387.485319) (xy 263.326273 -387.57748) (xy 263.32688 -387.623812)
			(xy 263.32688 -387.62432) (xy 263.326348 -387.665522) (xy 263.318718 -387.747571) (xy 263.303535 -387.828564)
			(xy 263.280929 -387.907805) (xy 263.251093 -387.984618) (xy 263.214282 -388.058343) (xy 263.170814 -388.128348)
			(xy 263.121058 -388.194035) (xy 263.065443 -388.25484) (xy 263.004444 -388.310243) (xy 262.938584 -388.359768)
			(xy 262.868427 -388.402993) (xy 262.794575 -388.439545) (xy 262.717659 -388.469113) (xy 262.638339 -388.491443)
			(xy 262.5979 -388.49935) (xy 262.588454 -388.501522) (xy 262.57204 -388.511796) (xy 262.560598 -388.527419)
			(xy 262.557768 -388.536688) (xy 262.530844 -388.640066) (xy 262.539988 -388.66826) (xy 262.551672 -388.677658)
			(xy 262.58493 -388.705769) (xy 262.646379 -388.767481) (xy 262.701504 -388.834901) (xy 262.749777 -388.907385)
			(xy 262.790737 -388.984239) (xy 262.823992 -389.064728) (xy 262.849222 -389.148081) (xy 262.866187 -389.2335)
			(xy 262.874725 -389.320168) (xy 262.875021 -389.3439) (xy 266.091872 -389.3439) (xy 266.095902 -389.259295)
			(xy 266.107957 -389.175456) (xy 266.127926 -389.093143) (xy 266.15563 -389.013101) (xy 266.190817 -388.936055)
			(xy 266.233169 -388.862702) (xy 266.282301 -388.793708) (xy 266.33777 -388.729696) (xy 266.399072 -388.671247)
			(xy 266.465653 -388.618891) (xy 266.536909 -388.5731) (xy 266.612195 -388.53429) (xy 266.69083 -388.502812)
			(xy 266.772101 -388.478952) (xy 266.855272 -388.462926) (xy 266.93959 -388.454878) (xy 266.98194 -388.454392)
			(xy 266.982448 -388.454392) (xy 267.028779 -388.455019) (xy 267.120937 -388.464684) (xy 267.211591 -388.483874)
			(xy 267.29976 -388.51238) (xy 267.342366 -388.530592) (xy 267.352308 -388.534398) (xy 267.373572 -388.534398)
			(xy 267.383514 -388.530592) (xy 267.421715 -388.514199) (xy 267.500531 -388.487758) (xy 267.58147 -388.468784)
			(xy 267.663826 -388.457441) (xy 267.705332 -388.455154) (xy 267.705586 -388.455154) (xy 267.715547 -388.454267)
			(xy 267.733653 -388.445817) (xy 267.747164 -388.431096) (xy 267.751052 -388.42188) (xy 267.78839 -388.31901)
			(xy 267.781278 -388.289292) (xy 267.769848 -388.278878) (xy 267.740077 -388.250874) (xy 267.685266 -388.190234)
			(xy 267.636254 -388.124818) (xy 267.593452 -388.05518) (xy 267.557224 -387.981907) (xy 267.527875 -387.905618)
			(xy 267.505652 -387.826957) (xy 267.490743 -387.746588) (xy 267.483275 -387.66519) (xy 267.482828 -387.62432)
			(xy 267.483415 -387.577925) (xy 267.493058 -387.485636) (xy 267.512253 -387.394852) (xy 267.54079 -387.306559)
			(xy 267.559028 -387.263894) (xy 267.56282 -387.253948) (xy 267.562827 -387.232688) (xy 267.559028 -387.222746)
			(xy 267.540792 -387.18008) (xy 267.512245 -387.091789) (xy 267.49305 -387.001005) (xy 267.483414 -386.908716)
			(xy 267.482828 -386.86232) (xy 267.483415 -386.815925) (xy 267.493058 -386.723636) (xy 267.512253 -386.632852)
			(xy 267.54079 -386.544559) (xy 267.559028 -386.501894) (xy 267.56282 -386.491948) (xy 267.562827 -386.470688)
			(xy 267.559028 -386.460746) (xy 267.540809 -386.418142) (xy 267.512291 -386.329975) (xy 267.493098 -386.23932)
			(xy 267.483437 -386.14716) (xy 267.482828 -386.100828) (xy 267.482828 -386.10032) (xy 267.483332 -386.057972)
			(xy 267.491383 -385.973658) (xy 267.507412 -385.890492) (xy 267.531273 -385.809225) (xy 267.562752 -385.730595)
			(xy 267.601563 -385.655314) (xy 267.647353 -385.584062) (xy 267.699709 -385.517486) (xy 267.758157 -385.456188)
			(xy 267.822167 -385.400723) (xy 267.891159 -385.351594) (xy 267.964509 -385.309245) (xy 268.041552 -385.274061)
			(xy 268.121591 -385.246359) (xy 268.2039 -385.226391) (xy 268.287735 -385.214338) (xy 268.372336 -385.210308)
			(xy 268.456937 -385.214338) (xy 268.540772 -385.226391) (xy 268.623081 -385.246359) (xy 268.70312 -385.274061)
			(xy 268.780163 -385.309245) (xy 268.853513 -385.351594) (xy 268.922505 -385.400723) (xy 268.986515 -385.456188)
			(xy 269.044963 -385.517486) (xy 269.097319 -385.584062) (xy 269.143109 -385.655314) (xy 269.18192 -385.730595)
			(xy 269.213399 -385.809225) (xy 269.23726 -385.890492) (xy 269.253289 -385.973658) (xy 269.26134 -386.057972)
			(xy 269.261844 -386.10032) (xy 269.261844 -386.100828) (xy 269.261242 -386.14716) (xy 269.251569 -386.239318)
			(xy 269.232372 -386.329972) (xy 269.203859 -386.418141) (xy 269.185644 -386.460746) (xy 269.181825 -386.470684)
			(xy 269.181833 -386.491952) (xy 269.185644 -386.501894) (xy 269.203898 -386.544553) (xy 269.232439 -386.632846)
			(xy 269.251629 -386.723633) (xy 269.26126 -386.815924) (xy 269.261844 -386.86232) (xy 269.261238 -386.908715)
			(xy 269.251601 -387.001003) (xy 269.232412 -387.091787) (xy 269.203879 -387.180081) (xy 269.185644 -387.222746)
			(xy 269.181825 -387.232684) (xy 269.181833 -387.253952) (xy 269.185644 -387.263894) (xy 269.203875 -387.306493)
			(xy 269.23239 -387.394662) (xy 269.25158 -387.485319) (xy 269.261237 -387.577479) (xy 269.261844 -387.623812)
			(xy 269.261844 -387.62432) (xy 269.261348 -387.66668) (xy 269.253296 -387.751015) (xy 269.237266 -387.834205)
			(xy 269.213405 -387.915494) (xy 269.181926 -387.994148) (xy 269.143116 -388.069455) (xy 269.097326 -388.140734)
			(xy 269.04497 -388.207339) (xy 268.986522 -388.268667) (xy 268.922511 -388.324164) (xy 268.853515 -388.373328)
			(xy 268.81709 -388.394956) (xy 268.809042 -388.400057) (xy 268.797209 -388.414978) (xy 268.791622 -388.433184)
			(xy 268.791944 -388.442708) (xy 268.793976 -388.470648) (xy 268.795065 -388.48018) (xy 268.803481 -388.497409)
			(xy 268.817662 -388.510315) (xy 268.826488 -388.514082) (xy 268.866366 -388.530592) (xy 268.876308 -388.534398)
			(xy 268.897572 -388.534398) (xy 268.907514 -388.530592) (xy 268.950141 -388.512345) (xy 269.038373 -388.483818)
			(xy 269.129095 -388.464629) (xy 269.221321 -388.454986) (xy 269.267686 -388.454392) (xy 269.268194 -388.454392)
			(xy 269.314557 -388.455008) (xy 269.40678 -388.46466) (xy 269.497499 -388.483849) (xy 269.58573 -388.512368)
			(xy 269.628366 -388.530592) (xy 269.638308 -388.534398) (xy 269.659572 -388.534398) (xy 269.669514 -388.530592)
			(xy 269.712111 -388.512357) (xy 269.800281 -388.483843) (xy 269.890938 -388.464654) (xy 269.983099 -388.454998)
			(xy 270.029432 -388.454392) (xy 270.02994 -388.454392) (xy 270.072287 -388.454897) (xy 270.156598 -388.462952)
			(xy 270.239761 -388.478984) (xy 270.321024 -388.502848) (xy 270.399651 -388.534328) (xy 270.474929 -388.57314)
			(xy 270.546178 -388.618931) (xy 270.612751 -388.671288) (xy 270.674046 -388.729735) (xy 270.729508 -388.793744)
			(xy 270.778634 -388.862735) (xy 270.82098 -388.936083) (xy 270.856163 -389.013125) (xy 270.883863 -389.093161)
			(xy 270.90383 -389.175469) (xy 270.915883 -389.259301) (xy 270.917612 -389.2956) (xy 275.284228 -389.2956)
			(xy 275.288257 -389.211003) (xy 275.30031 -389.127172) (xy 275.320278 -389.044866) (xy 275.347978 -388.964831)
			(xy 275.383161 -388.887791) (xy 275.425507 -388.814445) (xy 275.474634 -388.745456) (xy 275.530097 -388.681449)
			(xy 275.591392 -388.623004) (xy 275.657965 -388.57065) (xy 275.729214 -388.524861) (xy 275.804492 -388.486053)
			(xy 275.883119 -388.454575) (xy 275.964381 -388.430714) (xy 276.047544 -388.414686) (xy 276.131853 -388.406636)
			(xy 276.1742 -388.406132) (xy 276.174708 -388.406132) (xy 276.22104 -388.406735) (xy 276.313198 -388.416407)
			(xy 276.403852 -388.435603) (xy 276.492021 -388.464116) (xy 276.534626 -388.482332) (xy 276.544568 -388.486138)
			(xy 276.565832 -388.486138) (xy 276.575774 -388.482332) (xy 276.618408 -388.464101) (xy 276.706637 -388.435569)
			(xy 276.797357 -388.416375) (xy 276.889582 -388.406729) (xy 276.935946 -388.406132) (xy 276.936454 -388.406132)
			(xy 276.982818 -388.406723) (xy 277.075041 -388.416382) (xy 277.16576 -388.435578) (xy 277.253991 -388.464105)
			(xy 277.296626 -388.482332) (xy 277.306568 -388.486138) (xy 277.327832 -388.486138) (xy 277.337774 -388.482332)
			(xy 277.380408 -388.464101) (xy 277.468637 -388.435569) (xy 277.559357 -388.416375) (xy 277.651582 -388.406729)
			(xy 277.697946 -388.406132) (xy 277.698454 -388.406132) (xy 277.744818 -388.406723) (xy 277.837041 -388.416382)
			(xy 277.92776 -388.435578) (xy 278.015991 -388.464105) (xy 278.058626 -388.482332) (xy 278.068568 -388.486138)
			(xy 278.089832 -388.486138) (xy 278.099774 -388.482332) (xy 278.142375 -388.464106) (xy 278.230544 -388.43559)
			(xy 278.321199 -388.416399) (xy 278.41336 -388.40674) (xy 278.459692 -388.406132) (xy 278.4602 -388.406132)
			(xy 278.50255 -388.406556) (xy 278.586868 -388.414607) (xy 278.670038 -388.430637) (xy 278.751308 -388.4545)
			(xy 278.829941 -388.48598) (xy 278.905226 -388.524792) (xy 278.976481 -388.570585) (xy 279.04306 -388.622943)
			(xy 279.104361 -388.681393) (xy 279.159829 -388.745406) (xy 279.20896 -388.814401) (xy 279.25131 -388.887754)
			(xy 279.286496 -388.964801) (xy 279.314199 -389.044843) (xy 279.334168 -389.127156) (xy 279.346222 -389.210995)
			(xy 279.350253 -389.2956) (xy 279.346222 -389.380205) (xy 279.334168 -389.464044) (xy 279.314199 -389.546357)
			(xy 279.286496 -389.626399) (xy 279.25131 -389.703446) (xy 279.20896 -389.776799) (xy 279.159829 -389.845794)
			(xy 279.104361 -389.909807) (xy 279.04306 -389.968257) (xy 278.976481 -390.020615) (xy 278.905226 -390.066408)
			(xy 278.829941 -390.10522) (xy 278.751308 -390.1367) (xy 278.670038 -390.160563) (xy 278.586868 -390.176593)
			(xy 278.50255 -390.184644) (xy 278.4602 -390.185148) (xy 278.459692 -390.185148) (xy 278.41336 -390.184539)
			(xy 278.321203 -390.174868) (xy 278.230548 -390.155673) (xy 278.14238 -390.127162) (xy 278.099774 -390.108948)
			(xy 278.089832 -390.105142) (xy 278.068568 -390.105142) (xy 278.058626 -390.108948) (xy 278.015992 -390.127178)
			(xy 277.927763 -390.15571) (xy 277.837043 -390.174904) (xy 277.744818 -390.184551) (xy 277.698454 -390.185148)
			(xy 277.697946 -390.185148) (xy 277.651582 -390.184559) (xy 277.559359 -390.1749) (xy 277.46864 -390.155703)
			(xy 277.380409 -390.127176) (xy 277.337774 -390.108948) (xy 277.327832 -390.105142) (xy 277.306568 -390.105142)
			(xy 277.296626 -390.108948) (xy 277.253992 -390.127178) (xy 277.165763 -390.15571) (xy 277.075043 -390.174904)
			(xy 276.982818 -390.184551) (xy 276.936454 -390.185148) (xy 276.935946 -390.185148) (xy 276.889582 -390.184559)
			(xy 276.797359 -390.1749) (xy 276.70664 -390.155703) (xy 276.618409 -390.127176) (xy 276.575774 -390.108948)
			(xy 276.565832 -390.105142) (xy 276.544568 -390.105142) (xy 276.534626 -390.108948) (xy 276.492024 -390.127173)
			(xy 276.403856 -390.155689) (xy 276.3132 -390.174881) (xy 276.22104 -390.18454) (xy 276.174708 -390.185148)
			(xy 276.1742 -390.185148) (xy 276.131853 -390.184564) (xy 276.047544 -390.176514) (xy 275.964381 -390.160486)
			(xy 275.883119 -390.136625) (xy 275.804492 -390.105147) (xy 275.729214 -390.066339) (xy 275.657965 -390.02055)
			(xy 275.591392 -389.968196) (xy 275.530097 -389.909751) (xy 275.474634 -389.845744) (xy 275.425507 -389.776755)
			(xy 275.383161 -389.703409) (xy 275.347978 -389.626369) (xy 275.320278 -389.546334) (xy 275.30031 -389.464028)
			(xy 275.288257 -389.380197) (xy 275.284228 -389.2956) (xy 270.917612 -389.2956) (xy 270.919913 -389.3439)
			(xy 270.915883 -389.428499) (xy 270.90383 -389.512331) (xy 270.883863 -389.594639) (xy 270.856163 -389.674675)
			(xy 270.82098 -389.751717) (xy 270.778634 -389.825065) (xy 270.729508 -389.894056) (xy 270.674046 -389.958065)
			(xy 270.612751 -390.016512) (xy 270.546178 -390.068869) (xy 270.474929 -390.11466) (xy 270.399651 -390.153472)
			(xy 270.321024 -390.184952) (xy 270.239761 -390.208816) (xy 270.156598 -390.224848) (xy 270.072287 -390.232903)
			(xy 270.02994 -390.233408) (xy 270.029432 -390.233408) (xy 269.983101 -390.232788) (xy 269.890943 -390.223121)
			(xy 269.800289 -390.203929) (xy 269.71212 -390.175421) (xy 269.669514 -390.157208) (xy 269.659572 -390.153402)
			(xy 269.638308 -390.153402) (xy 269.628366 -390.157208) (xy 269.585728 -390.175428) (xy 269.4975 -390.203962)
			(xy 269.406782 -390.223159) (xy 269.314558 -390.232809) (xy 269.268194 -390.233408) (xy 269.267686 -390.233408)
			(xy 269.221323 -390.232799) (xy 269.1291 -390.223145) (xy 269.038381 -390.203954) (xy 268.950149 -390.175433)
			(xy 268.907514 -390.157208) (xy 268.897572 -390.153402) (xy 268.876308 -390.153402) (xy 268.866366 -390.157208)
			(xy 268.823728 -390.175428) (xy 268.7355 -390.203962) (xy 268.644782 -390.223159) (xy 268.552558 -390.232809)
			(xy 268.506194 -390.233408) (xy 268.505686 -390.233408) (xy 268.459323 -390.232799) (xy 268.3671 -390.223145)
			(xy 268.276381 -390.203954) (xy 268.188149 -390.175433) (xy 268.145514 -390.157208) (xy 268.135572 -390.153402)
			(xy 268.114308 -390.153402) (xy 268.104366 -390.157208) (xy 268.061728 -390.175428) (xy 267.9735 -390.203962)
			(xy 267.882782 -390.223159) (xy 267.790558 -390.232809) (xy 267.744194 -390.233408) (xy 267.743686 -390.233408)
			(xy 267.697323 -390.232799) (xy 267.6051 -390.223145) (xy 267.514381 -390.203954) (xy 267.426149 -390.175433)
			(xy 267.383514 -390.157208) (xy 267.373572 -390.153402) (xy 267.352308 -390.153402) (xy 267.342366 -390.157208)
			(xy 267.299758 -390.175417) (xy 267.211592 -390.203938) (xy 267.120938 -390.223134) (xy 267.02878 -390.232798)
			(xy 266.982448 -390.233408) (xy 266.98194 -390.233408) (xy 266.93959 -390.232922) (xy 266.855272 -390.224874)
			(xy 266.772101 -390.208848) (xy 266.69083 -390.184988) (xy 266.612195 -390.15351) (xy 266.536909 -390.1147)
			(xy 266.465653 -390.068909) (xy 266.399072 -390.016553) (xy 266.33777 -389.958104) (xy 266.282301 -389.894092)
			(xy 266.233169 -389.825098) (xy 266.190817 -389.751745) (xy 266.15563 -389.674699) (xy 266.127926 -389.594657)
			(xy 266.107957 -389.512344) (xy 266.095902 -389.428505) (xy 266.091872 -389.3439) (xy 262.875021 -389.3439)
			(xy 262.875268 -389.363712) (xy 262.875268 -389.36422) (xy 262.874867 -389.405325) (xy 262.86728 -389.487183)
			(xy 262.852172 -389.567992) (xy 262.829672 -389.647063) (xy 262.799972 -389.72372) (xy 262.763326 -389.79731)
			(xy 262.720047 -389.867204) (xy 262.670502 -389.932807) (xy 262.615116 -389.993559) (xy 262.554361 -390.048941)
			(xy 262.488755 -390.09848) (xy 262.418857 -390.141756) (xy 262.345265 -390.178397) (xy 262.268606 -390.208091)
			(xy 262.189534 -390.230585) (xy 262.108724 -390.245688) (xy 262.026865 -390.25327) (xy 261.98576 -390.253728)
			(xy 261.985252 -390.253728) (xy 261.938921 -390.253099) (xy 261.846764 -390.243434) (xy 261.756109 -390.224245)
			(xy 261.66794 -390.19574) (xy 261.625334 -390.177528) (xy 261.615392 -390.173722) (xy 261.594128 -390.173722)
			(xy 261.584186 -390.177528) (xy 261.541559 -390.195776) (xy 261.453327 -390.224303) (xy 261.362605 -390.243491)
			(xy 261.270379 -390.253134) (xy 261.224014 -390.253728) (xy 261.223506 -390.253728) (xy 261.177143 -390.253111)
			(xy 261.08492 -390.243459) (xy 260.994202 -390.22427) (xy 260.90597 -390.195751) (xy 260.863334 -390.177528)
			(xy 260.853392 -390.173722) (xy 260.832128 -390.173722) (xy 260.822186 -390.177528) (xy 260.779559 -390.195776)
			(xy 260.691327 -390.224303) (xy 260.600605 -390.243491) (xy 260.508379 -390.253134) (xy 260.462014 -390.253728)
			(xy 260.461506 -390.253728) (xy 260.415143 -390.253111) (xy 260.32292 -390.243459) (xy 260.232202 -390.22427)
			(xy 260.14397 -390.195751) (xy 260.101334 -390.177528) (xy 260.091392 -390.173722) (xy 260.070128 -390.173722)
			(xy 260.060186 -390.177528) (xy 260.017559 -390.195776) (xy 259.929327 -390.224303) (xy 259.838605 -390.243491)
			(xy 259.746379 -390.253134) (xy 259.700014 -390.253728) (xy 259.699506 -390.253728) (xy 259.653143 -390.253111)
			(xy 259.56092 -390.243459) (xy 259.470202 -390.22427) (xy 259.38197 -390.195751) (xy 259.339334 -390.177528)
			(xy 259.329392 -390.173722) (xy 259.308128 -390.173722) (xy 259.298186 -390.177528) (xy 259.255589 -390.195764)
			(xy 259.167419 -390.224278) (xy 259.076762 -390.243467) (xy 258.984601 -390.253122) (xy 258.938268 -390.253728)
			(xy 258.93776 -390.253728) (xy 258.895414 -390.253183) (xy 258.811105 -390.245128) (xy 258.727943 -390.229097)
			(xy 258.646682 -390.205233) (xy 258.568057 -390.173754) (xy 258.492781 -390.134943) (xy 258.421534 -390.089152)
			(xy 258.354962 -390.036797) (xy 258.293669 -389.978351) (xy 258.238208 -389.914344) (xy 258.189083 -389.845354)
			(xy 258.146738 -389.772007) (xy 258.111556 -389.694968) (xy 258.083856 -389.614933) (xy 258.06389 -389.532627)
			(xy 258.051837 -389.448797) (xy 258.047807 -389.3642) (xy 254.959095 -389.3642) (xy 254.957122 -389.405604)
			(xy 254.945069 -389.489441) (xy 254.9251 -389.571753) (xy 254.897398 -389.651795) (xy 254.862213 -389.72884)
			(xy 254.819864 -389.802193) (xy 254.770734 -389.871187) (xy 254.715268 -389.9352) (xy 254.653969 -389.99365)
			(xy 254.587391 -390.046008) (xy 254.516138 -390.091801) (xy 254.440854 -390.130614) (xy 254.362223 -390.162095)
			(xy 254.280954 -390.185959) (xy 254.197786 -390.20199) (xy 254.11347 -390.210043) (xy 254.07112 -390.210548)
			(xy 254.070612 -390.210548) (xy 254.024281 -390.209931) (xy 253.932123 -390.200263) (xy 253.841469 -390.18107)
			(xy 253.7533 -390.152561) (xy 253.710694 -390.134348) (xy 253.700752 -390.130542) (xy 253.679488 -390.130542)
			(xy 253.669546 -390.134348) (xy 253.626909 -390.152571) (xy 253.538681 -390.181105) (xy 253.447962 -390.200301)
			(xy 253.355738 -390.20995) (xy 253.309374 -390.210548) (xy 253.308866 -390.210548) (xy 253.262502 -390.209952)
			(xy 253.170279 -390.200295) (xy 253.07956 -390.1811) (xy 252.991329 -390.152575) (xy 252.948694 -390.134348)
			(xy 252.938752 -390.130542) (xy 252.917488 -390.130542) (xy 252.907546 -390.134348) (xy 252.864909 -390.152571)
			(xy 252.776681 -390.181105) (xy 252.685962 -390.200301) (xy 252.593738 -390.20995) (xy 252.547374 -390.210548)
			(xy 252.546866 -390.210548) (xy 252.500502 -390.209952) (xy 252.408279 -390.200295) (xy 252.31756 -390.1811)
			(xy 252.229329 -390.152575) (xy 252.186694 -390.134348) (xy 252.176752 -390.130542) (xy 252.155488 -390.130542)
			(xy 252.145546 -390.134348) (xy 252.102909 -390.152571) (xy 252.014681 -390.181105) (xy 251.923962 -390.200301)
			(xy 251.831738 -390.20995) (xy 251.785374 -390.210548) (xy 251.784866 -390.210548) (xy 251.738502 -390.209952)
			(xy 251.646279 -390.200295) (xy 251.55556 -390.1811) (xy 251.467329 -390.152575) (xy 251.424694 -390.134348)
			(xy 251.414752 -390.130542) (xy 251.393488 -390.130542) (xy 251.383546 -390.134348) (xy 251.340941 -390.152566)
			(xy 251.252774 -390.181084) (xy 251.16212 -390.200278) (xy 251.06996 -390.209939) (xy 251.023628 -390.210548)
			(xy 251.02312 -390.210548) (xy 250.982019 -390.210014) (xy 250.900168 -390.202432) (xy 250.819365 -390.187329)
			(xy 250.7403 -390.164836) (xy 250.663648 -390.135143) (xy 250.590063 -390.098504) (xy 250.520172 -390.055233)
			(xy 250.454572 -390.005697) (xy 250.393822 -389.95032) (xy 250.338441 -389.889574) (xy 250.288901 -389.823977)
			(xy 250.245625 -389.754089) (xy 250.208981 -389.680507) (xy 250.179284 -389.603857) (xy 250.156785 -389.524794)
			(xy 250.141677 -389.443992) (xy 250.134088 -389.362141) (xy 250.133612 -389.32104) (xy 250.133612 -389.320786)
			(xy 250.134084 -389.279933) (xy 250.141595 -389.198572) (xy 250.156533 -389.118242) (xy 250.178773 -389.03962)
			(xy 250.208128 -388.963369) (xy 250.24435 -388.89013) (xy 250.287134 -388.82052) (xy 250.336119 -388.755125)
			(xy 250.390894 -388.694498) (xy 250.420632 -388.666482) (xy 250.431046 -388.65683) (xy 250.43892 -388.629652)
			(xy 250.408186 -388.515352) (xy 250.387866 -388.495794) (xy 250.373896 -388.492746) (xy 250.332086 -388.482917)
			(xy 250.250448 -388.456208) (xy 250.171765 -388.421758) (xy 250.096766 -388.379887) (xy 250.026152 -388.330983)
			(xy 249.960578 -388.275503) (xy 249.900655 -388.213962) (xy 249.846941 -388.146934) (xy 249.799936 -388.075042)
			(xy 249.760077 -387.998955) (xy 249.727734 -387.919382) (xy 249.70321 -387.837062) (xy 249.686732 -387.752763)
			(xy 249.678453 -387.667268) (xy 249.677936 -387.62432) (xy 245.521988 -387.62432) (xy 245.521472 -387.667499)
			(xy 245.513112 -387.753451) (xy 245.496463 -387.838189) (xy 245.471682 -387.920915) (xy 245.439002 -388.000851)
			(xy 245.398731 -388.077244) (xy 245.351247 -388.149375) (xy 245.296998 -388.216566) (xy 245.236493 -388.278185)
			(xy 245.203726 -388.30631) (xy 245.197019 -388.312325) (xy 245.188001 -388.32791) (xy 245.184926 -388.345651)
			(xy 245.1862 -388.35457) (xy 245.204996 -388.455154) (xy 245.222776 -388.475728) (xy 245.23573 -388.4803)
			(xy 245.253374 -388.48652) (xy 245.288184 -388.50024) (xy 245.305326 -388.507732) (xy 245.315268 -388.511538)
			(xy 245.336532 -388.511538) (xy 245.346474 -388.507732) (xy 245.389075 -388.489506) (xy 245.477244 -388.46099)
			(xy 245.567899 -388.441799) (xy 245.66006 -388.43214) (xy 245.706392 -388.431532) (xy 245.7069 -388.431532)
			(xy 245.74925 -388.431956) (xy 245.833568 -388.440007) (xy 245.916738 -388.456037) (xy 245.998008 -388.4799)
			(xy 246.076641 -388.51138) (xy 246.151926 -388.550192) (xy 246.223181 -388.595985) (xy 246.28976 -388.648343)
			(xy 246.351061 -388.706793) (xy 246.406529 -388.770806) (xy 246.45566 -388.839801) (xy 246.49801 -388.913154)
			(xy 246.533196 -388.990201) (xy 246.560899 -389.070243) (xy 246.580868 -389.152556) (xy 246.592922 -389.236395)
			(xy 246.596953 -389.321) (xy 246.592922 -389.405605) (xy 246.580868 -389.489444) (xy 246.560899 -389.571757)
			(xy 246.533196 -389.651799) (xy 246.49801 -389.728846) (xy 246.45566 -389.802199) (xy 246.406529 -389.871194)
			(xy 246.351061 -389.935207) (xy 246.28976 -389.993657) (xy 246.223181 -390.046015) (xy 246.151926 -390.091808)
			(xy 246.076641 -390.13062) (xy 245.998008 -390.1621) (xy 245.916738 -390.185963) (xy 245.833568 -390.201993)
			(xy 245.74925 -390.210044) (xy 245.7069 -390.210548) (xy 245.706392 -390.210548) (xy 245.66006 -390.209939)
			(xy 245.567903 -390.200268) (xy 245.477248 -390.181073) (xy 245.38908 -390.152562) (xy 245.346474 -390.134348)
			(xy 245.336532 -390.130542) (xy 245.315268 -390.130542) (xy 245.305326 -390.134348) (xy 245.262692 -390.152578)
			(xy 245.174463 -390.18111) (xy 245.083743 -390.200304) (xy 244.991518 -390.209951) (xy 244.945154 -390.210548)
			(xy 244.944646 -390.210548) (xy 244.898282 -390.209959) (xy 244.806059 -390.2003) (xy 244.71534 -390.181103)
			(xy 244.627109 -390.152576) (xy 244.584474 -390.134348) (xy 244.574532 -390.130542) (xy 244.553268 -390.130542)
			(xy 244.543326 -390.134348) (xy 244.500692 -390.152578) (xy 244.412463 -390.18111) (xy 244.321743 -390.200304)
			(xy 244.229518 -390.209951) (xy 244.183154 -390.210548) (xy 244.182646 -390.210548) (xy 244.136282 -390.209959)
			(xy 244.044059 -390.2003) (xy 243.95334 -390.181103) (xy 243.865109 -390.152576) (xy 243.822474 -390.134348)
			(xy 243.812532 -390.130542) (xy 243.791268 -390.130542) (xy 243.781326 -390.134348) (xy 243.738692 -390.152578)
			(xy 243.650463 -390.18111) (xy 243.559743 -390.200304) (xy 243.467518 -390.209951) (xy 243.421154 -390.210548)
			(xy 243.420646 -390.210548) (xy 243.374282 -390.209959) (xy 243.282059 -390.2003) (xy 243.19134 -390.181103)
			(xy 243.103109 -390.152576) (xy 243.060474 -390.134348) (xy 243.050532 -390.130542) (xy 243.029268 -390.130542)
			(xy 243.019326 -390.134348) (xy 242.976724 -390.152573) (xy 242.888556 -390.181089) (xy 242.7979 -390.200281)
			(xy 242.70574 -390.20994) (xy 242.659408 -390.210548) (xy 242.6589 -390.210548) (xy 242.616553 -390.209964)
			(xy 242.532244 -390.201914) (xy 242.449081 -390.185886) (xy 242.367819 -390.162025) (xy 242.289192 -390.130547)
			(xy 242.213914 -390.091739) (xy 242.142665 -390.04595) (xy 242.076092 -389.993596) (xy 242.014797 -389.935151)
			(xy 241.959334 -389.871144) (xy 241.910207 -389.802155) (xy 241.867861 -389.728809) (xy 241.832678 -389.651769)
			(xy 241.804978 -389.571734) (xy 241.78501 -389.489428) (xy 241.772957 -389.405597) (xy 241.768928 -389.321)
			(xy 240.768792 -389.321) (xy 240.768886 -389.328914) (xy 240.768382 -389.371275) (xy 240.760329 -389.455612)
			(xy 240.744295 -389.538802) (xy 240.720427 -389.620092) (xy 240.688939 -389.698744) (xy 240.650117 -389.774047)
			(xy 240.604314 -389.845319) (xy 240.551943 -389.911915) (xy 240.493478 -389.97323) (xy 240.42945 -390.028711)
			(xy 240.360438 -390.077854) (xy 240.287068 -390.120214) (xy 240.210003 -390.155409) (xy 240.129941 -390.183118)
			(xy 240.047608 -390.203092) (xy 239.963749 -390.215149) (xy 239.879124 -390.219181) (xy 239.794499 -390.215149)
			(xy 239.71064 -390.203092) (xy 239.628307 -390.183118) (xy 239.548245 -390.155409) (xy 239.47118 -390.120214)
			(xy 239.39781 -390.077854) (xy 239.328798 -390.028711) (xy 239.26477 -389.97323) (xy 239.206305 -389.911915)
			(xy 239.153934 -389.845319) (xy 239.108131 -389.774047) (xy 239.069309 -389.698744) (xy 239.037821 -389.620092)
			(xy 239.013953 -389.538802) (xy 238.997919 -389.455612) (xy 238.989866 -389.371275) (xy 195.355765 -389.371275)
			(xy 195.340132 -389.384821) (xy 195.27112 -389.433964) (xy 195.19775 -389.476324) (xy 195.120685 -389.511519)
			(xy 195.040623 -389.539228) (xy 194.95829 -389.559202) (xy 194.874431 -389.571259) (xy 194.789806 -389.575291)
			(xy 194.705181 -389.571259) (xy 194.621322 -389.559202) (xy 194.538989 -389.539228) (xy 194.458927 -389.511519)
			(xy 194.381862 -389.476324) (xy 194.308492 -389.433964) (xy 194.23948 -389.384821) (xy 194.175452 -389.32934)
			(xy 194.116987 -389.268025) (xy 194.064616 -389.201429) (xy 194.018813 -389.130157) (xy 193.979991 -389.054854)
			(xy 193.948503 -388.976202) (xy 193.924635 -388.894912) (xy 193.908601 -388.811722) (xy 193.900548 -388.727385)
			(xy 165.744132 -388.727385) (xy 166.083742 -389.314944) (xy 166.096549 -389.338286) (xy 166.114776 -389.388304)
			(xy 166.124043 -389.440727) (xy 166.124636 -389.467344) (xy 166.124202 -389.49135) (xy 166.116681 -389.538768)
			(xy 166.101833 -389.584426) (xy 166.080022 -389.627197) (xy 166.051787 -389.666029) (xy 166.017823 -389.699963)
			(xy 165.978967 -389.728164) (xy 165.936176 -389.749936) (xy 165.890505 -389.764744) (xy 165.84308 -389.772223)
			(xy 165.819074 -389.772652) (xy 165.795501 -389.772252) (xy 165.748914 -389.765008) (xy 165.703997 -389.750681)
			(xy 165.66182 -389.729613) (xy 165.623387 -389.702305) (xy 165.589614 -389.669408) (xy 165.561306 -389.631706)
			(xy 165.549834 -389.611108) (xy 165.549326 -389.610346) (xy 165.151562 -388.922006) (xy 165.139686 -388.899329)
			(xy 165.122835 -388.850996) (xy 165.114262 -388.800533) (xy 165.113716 -388.77494) (xy 164.571468 -388.77494)
			(xy 164.883592 -389.314944) (xy 164.896324 -389.33831) (xy 164.91444 -389.388338) (xy 164.92365 -389.440741)
			(xy 164.924232 -389.467344) (xy 164.923778 -389.491335) (xy 164.916266 -389.538726) (xy 164.901434 -389.584359)
			(xy 164.879647 -389.62711) (xy 164.851442 -389.665927) (xy 164.817512 -389.699855) (xy 164.778693 -389.728058)
			(xy 164.73594 -389.749842) (xy 164.690307 -389.764671) (xy 164.642915 -389.77218) (xy 164.618924 -389.772652)
			(xy 164.595352 -389.772211) (xy 164.548767 -389.764975) (xy 164.503851 -389.750656) (xy 164.461674 -389.729594)
			(xy 164.423241 -389.702292) (xy 164.389467 -389.669401) (xy 164.361157 -389.631704) (xy 164.349684 -389.611108)
			(xy 164.349176 -389.610346) (xy 163.951412 -388.922006) (xy 163.939498 -388.899337) (xy 163.92256 -388.851012)
			(xy 163.9139 -388.800542) (xy 163.913312 -388.77494) (xy 163.371572 -388.77494) (xy 163.683696 -389.314944)
			(xy 163.696428 -389.33831) (xy 163.714544 -389.388338) (xy 163.723754 -389.440741) (xy 163.724336 -389.467344)
			(xy 163.723878 -389.491335) (xy 163.716366 -389.538726) (xy 163.701535 -389.584358) (xy 163.679748 -389.627109)
			(xy 163.651543 -389.665926) (xy 163.617613 -389.699853) (xy 163.578795 -389.728056) (xy 163.536043 -389.749841)
			(xy 163.49041 -389.76467) (xy 163.443019 -389.772179) (xy 163.419028 -389.772652) (xy 163.395456 -389.772208)
			(xy 163.348872 -389.764972) (xy 163.303956 -389.750653) (xy 163.261778 -389.729592) (xy 163.223345 -389.702291)
			(xy 163.189571 -389.6694) (xy 163.161261 -389.631704) (xy 163.149788 -389.611108) (xy 163.14928 -389.610346)
			(xy 162.751516 -388.922006) (xy 162.739602 -388.899337) (xy 162.722664 -388.851012) (xy 162.714004 -388.800542)
			(xy 162.713416 -388.77494) (xy 162.171422 -388.77494) (xy 162.483546 -389.314944) (xy 162.496353 -389.338286)
			(xy 162.51458 -389.388304) (xy 162.523847 -389.440727) (xy 162.52444 -389.467344) (xy 162.524002 -389.491349)
			(xy 162.516481 -389.538768) (xy 162.501633 -389.584425) (xy 162.479823 -389.627196) (xy 162.451588 -389.666027)
			(xy 162.417625 -389.699961) (xy 162.378769 -389.728162) (xy 162.335979 -389.749935) (xy 162.290309 -389.764744)
			(xy 162.242884 -389.772222) (xy 162.218878 -389.772652) (xy 162.195305 -389.772249) (xy 162.148718 -389.765005)
			(xy 162.103801 -389.750679) (xy 162.061624 -389.729611) (xy 162.023191 -389.702304) (xy 161.989418 -389.669408)
			(xy 161.96111 -389.631706) (xy 161.949638 -389.611108) (xy 161.94913 -389.610346) (xy 161.551366 -388.922006)
			(xy 161.539491 -388.899329) (xy 161.522639 -388.850996) (xy 161.514066 -388.800533) (xy 161.51352 -388.77494)
			(xy 160.971526 -388.77494) (xy 161.28365 -389.314944) (xy 161.296457 -389.338285) (xy 161.314684 -389.388304)
			(xy 161.323951 -389.440726) (xy 161.324544 -389.467344) (xy 161.324102 -389.491349) (xy 161.316582 -389.538767)
			(xy 161.301734 -389.584424) (xy 161.279924 -389.627195) (xy 161.25169 -389.666026) (xy 161.217726 -389.69996)
			(xy 161.178871 -389.728161) (xy 161.136082 -389.749934) (xy 161.090412 -389.764743) (xy 161.042988 -389.772222)
			(xy 161.018982 -389.772652) (xy 160.995409 -389.772245) (xy 160.948822 -389.765003) (xy 160.903906 -389.750677)
			(xy 160.861728 -389.72961) (xy 160.823295 -389.702303) (xy 160.789523 -389.669407) (xy 160.761214 -389.631706)
			(xy 160.749742 -389.611108) (xy 160.749234 -389.610346) (xy 160.35147 -388.922006) (xy 160.339595 -388.899329)
			(xy 160.322743 -388.850996) (xy 160.31417 -388.800533) (xy 160.313624 -388.77494) (xy 159.77163 -388.77494)
			(xy 160.083754 -389.314944) (xy 160.096562 -389.338285) (xy 160.114788 -389.388304) (xy 160.124055 -389.440726)
			(xy 160.124648 -389.467344) (xy 160.124202 -389.491349) (xy 160.116682 -389.538767) (xy 160.101834 -389.584423)
			(xy 160.080025 -389.627194) (xy 160.051791 -389.666025) (xy 160.017828 -389.699959) (xy 159.978973 -389.72816)
			(xy 159.936184 -389.749933) (xy 159.890515 -389.764742) (xy 159.843091 -389.772222) (xy 159.819086 -389.772652)
			(xy 159.795513 -389.772242) (xy 159.748927 -389.765) (xy 159.70401 -389.750675) (xy 159.661833 -389.729608)
			(xy 159.6234 -389.702302) (xy 159.589627 -389.669406) (xy 159.561319 -389.631705) (xy 159.549846 -389.611108)
			(xy 159.549338 -389.610346) (xy 159.151574 -388.922006) (xy 159.139699 -388.899329) (xy 159.122848 -388.850996)
			(xy 159.114274 -388.800533) (xy 159.113728 -388.77494) (xy 158.57148 -388.77494) (xy 158.883604 -389.314944)
			(xy 158.896337 -389.33831) (xy 158.914452 -389.388337) (xy 158.923662 -389.440741) (xy 158.924244 -389.467344)
			(xy 158.923778 -389.491335) (xy 158.916267 -389.538724) (xy 158.901435 -389.584356) (xy 158.879649 -389.627106)
			(xy 158.851445 -389.665923) (xy 158.817517 -389.69985) (xy 158.778699 -389.728054) (xy 158.735949 -389.749838)
			(xy 158.690317 -389.764668) (xy 158.642927 -389.772179) (xy 158.618936 -389.772652) (xy 158.595364 -389.772202)
			(xy 158.54878 -389.764967) (xy 158.503864 -389.750649) (xy 158.461687 -389.729589) (xy 158.423253 -389.702289)
			(xy 158.389479 -389.669399) (xy 158.361169 -389.631703) (xy 158.349696 -389.611108) (xy 158.349188 -389.610346)
			(xy 157.951424 -388.922006) (xy 157.939511 -388.899337) (xy 157.922572 -388.851012) (xy 157.913912 -388.800542)
			(xy 157.913324 -388.77494) (xy 157.371584 -388.77494) (xy 157.683708 -389.314944) (xy 157.696441 -389.33831)
			(xy 157.714556 -389.388337) (xy 157.723766 -389.440741) (xy 157.724348 -389.467344) (xy 157.723878 -389.491334)
			(xy 157.716367 -389.538724) (xy 157.701536 -389.584355) (xy 157.67975 -389.627105) (xy 157.651546 -389.665922)
			(xy 157.617618 -389.699849) (xy 157.578802 -389.728052) (xy 157.536051 -389.749837) (xy 157.49042 -389.764668)
			(xy 157.44303 -389.772178) (xy 157.41904 -389.772652) (xy 157.395469 -389.772199) (xy 157.348884 -389.764965)
			(xy 157.303969 -389.750647) (xy 157.261791 -389.729588) (xy 157.223358 -389.702288) (xy 157.189583 -389.669399)
			(xy 157.161273 -389.631703) (xy 157.1498 -389.611108) (xy 157.149292 -389.610346) (xy 156.751528 -388.922006)
			(xy 156.739615 -388.899337) (xy 156.722676 -388.851012) (xy 156.714016 -388.800542) (xy 156.713428 -388.77494)
			(xy 156.171434 -388.77494) (xy 156.483558 -389.314944) (xy 156.496366 -389.338285) (xy 156.514592 -389.388304)
			(xy 156.523859 -389.440726) (xy 156.524452 -389.467344) (xy 156.524002 -389.491349) (xy 156.516482 -389.538766)
			(xy 156.501634 -389.584422) (xy 156.479825 -389.627193) (xy 156.451592 -389.666023) (xy 156.41763 -389.699957)
			(xy 156.378776 -389.728158) (xy 156.335987 -389.749932) (xy 156.290319 -389.764741) (xy 156.242895 -389.772222)
			(xy 156.21889 -389.772652) (xy 156.195317 -389.772239) (xy 156.148731 -389.764997) (xy 156.103814 -389.750673)
			(xy 156.061637 -389.729607) (xy 156.023204 -389.702301) (xy 155.989431 -389.669406) (xy 155.961123 -389.631705)
			(xy 155.94965 -389.611108) (xy 155.949142 -389.610346) (xy 155.551378 -388.922006) (xy 155.539503 -388.899328)
			(xy 155.522652 -388.850996) (xy 155.514078 -388.800533) (xy 155.513532 -388.77494) (xy 154.971538 -388.77494)
			(xy 155.283662 -389.314944) (xy 155.29647 -389.338285) (xy 155.314696 -389.388304) (xy 155.323963 -389.440726)
			(xy 155.324556 -389.467344) (xy 155.324102 -389.491349) (xy 155.316582 -389.538765) (xy 155.301735 -389.584421)
			(xy 155.279926 -389.627191) (xy 155.251693 -389.666022) (xy 155.217731 -389.699956) (xy 155.178878 -389.728157)
			(xy 155.13609 -389.749931) (xy 155.090422 -389.76474) (xy 155.042999 -389.772221) (xy 155.018994 -389.772652)
			(xy 154.995421 -389.772236) (xy 154.948835 -389.764995) (xy 154.903919 -389.750671) (xy 154.861741 -389.729605)
			(xy 154.823308 -389.7023) (xy 154.789535 -389.669405) (xy 154.761227 -389.631705) (xy 154.749754 -389.611108)
			(xy 154.749246 -389.610346) (xy 154.351482 -388.922006) (xy 154.339608 -388.899328) (xy 154.322756 -388.850996)
			(xy 154.314182 -388.800533) (xy 154.313636 -388.77494) (xy 153.771642 -388.77494) (xy 154.083766 -389.314944)
			(xy 154.096575 -389.338285) (xy 154.1148 -389.388303) (xy 154.124067 -389.440726) (xy 154.12466 -389.467344)
			(xy 154.124301 -389.491353) (xy 154.116779 -389.53878) (xy 154.101926 -389.584444) (xy 154.080109 -389.62722)
			(xy 154.051865 -389.666055) (xy 154.017891 -389.69999) (xy 153.979025 -389.72819) (xy 153.936223 -389.749958)
			(xy 153.890542 -389.764759) (xy 153.843108 -389.772228) (xy 153.819098 -389.772652) (xy 153.795525 -389.772232)
			(xy 153.74894 -389.764992) (xy 153.704023 -389.750669) (xy 153.661846 -389.729604) (xy 153.623413 -389.702299)
			(xy 153.589639 -389.669405) (xy 153.561331 -389.631705) (xy 153.549858 -389.611108) (xy 153.54935 -389.610346)
			(xy 153.151586 -388.922006) (xy 153.139712 -388.899328) (xy 153.12286 -388.850996) (xy 153.114286 -388.800533)
			(xy 153.11374 -388.77494) (xy 152.571492 -388.77494) (xy 152.883616 -389.314944) (xy 152.89635 -389.338309)
			(xy 152.914465 -389.388337) (xy 152.923674 -389.440741) (xy 152.924256 -389.467344) (xy 152.923778 -389.491334)
			(xy 152.916267 -389.538723) (xy 152.901436 -389.584353) (xy 152.879652 -389.627103) (xy 152.851449 -389.665919)
			(xy 152.817522 -389.699846) (xy 152.778706 -389.72805) (xy 152.735957 -389.749835) (xy 152.690327 -389.764666)
			(xy 152.642938 -389.772178) (xy 152.618948 -389.772652) (xy 152.595377 -389.772192) (xy 152.548793 -389.764959)
			(xy 152.503877 -389.750643) (xy 152.4617 -389.729585) (xy 152.423266 -389.702286) (xy 152.389492 -389.669398)
			(xy 152.361182 -389.631703) (xy 152.349708 -389.611108) (xy 152.3492 -389.610346) (xy 151.951436 -388.922006)
			(xy 151.939523 -388.899336) (xy 151.922584 -388.851012) (xy 151.913924 -388.800542) (xy 151.913336 -388.77494)
			(xy 151.371596 -388.77494) (xy 151.68372 -389.314944) (xy 151.696454 -389.338309) (xy 151.714569 -389.388337)
			(xy 151.723778 -389.440741) (xy 151.72436 -389.467344) (xy 151.724002 -389.491341) (xy 151.716487 -389.538742)
			(xy 151.70165 -389.584385) (xy 151.679855 -389.627144) (xy 151.651639 -389.665968) (xy 151.617698 -389.699899)
			(xy 151.578866 -389.728103) (xy 151.5361 -389.749885) (xy 151.490453 -389.764709) (xy 151.443049 -389.772209)
			(xy 151.419052 -389.772652) (xy 151.395481 -389.772189) (xy 151.348897 -389.764957) (xy 151.303982 -389.750641)
			(xy 151.261804 -389.729583) (xy 151.223371 -389.702285) (xy 151.189596 -389.669397) (xy 151.161286 -389.631703)
			(xy 151.149812 -389.611108) (xy 151.149304 -389.610346) (xy 150.75154 -388.922006) (xy 150.739628 -388.899336)
			(xy 150.722688 -388.851012) (xy 150.714028 -388.800542) (xy 150.71344 -388.77494) (xy 150.171446 -388.77494)
			(xy 150.48357 -389.314944) (xy 150.496379 -389.338285) (xy 150.514604 -389.388303) (xy 150.523871 -389.440726)
			(xy 150.524464 -389.467344) (xy 150.524101 -389.491353) (xy 150.516579 -389.538779) (xy 150.501726 -389.584443)
			(xy 150.479909 -389.627219) (xy 150.451666 -389.666053) (xy 150.417693 -389.699989) (xy 150.378827 -389.728188)
			(xy 150.336026 -389.749957) (xy 150.290346 -389.764759) (xy 150.242912 -389.772228) (xy 150.218902 -389.772652)
			(xy 150.195329 -389.772229) (xy 150.148744 -389.76499) (xy 150.103827 -389.750667) (xy 150.06165 -389.729602)
			(xy 150.023217 -389.702298) (xy 149.989444 -389.669404) (xy 149.961135 -389.631705) (xy 149.949662 -389.611108)
			(xy 149.949154 -389.610346) (xy 149.55139 -388.922006) (xy 149.539516 -388.899328) (xy 149.522664 -388.850995)
			(xy 149.51409 -388.800533) (xy 149.513544 -388.77494) (xy 148.97155 -388.77494) (xy 149.283674 -389.314944)
			(xy 149.296483 -389.338284) (xy 149.314708 -389.388303) (xy 149.323975 -389.440726) (xy 149.324568 -389.467344)
			(xy 149.324201 -389.491353) (xy 149.316679 -389.538778) (xy 149.301826 -389.584442) (xy 149.28001 -389.627218)
			(xy 149.251767 -389.666052) (xy 149.217795 -389.699987) (xy 149.178929 -389.728187) (xy 149.136129 -389.749956)
			(xy 149.090449 -389.764758) (xy 149.043016 -389.772228) (xy 149.019006 -389.772652) (xy 148.995434 -389.772226)
			(xy 148.948848 -389.764987) (xy 148.903932 -389.750665) (xy 148.861754 -389.729601) (xy 148.823321 -389.702297)
			(xy 148.789548 -389.669404) (xy 148.761239 -389.631705) (xy 148.749766 -389.611108) (xy 148.749258 -389.610346)
			(xy 148.351494 -388.922006) (xy 148.339621 -388.899328) (xy 148.322768 -388.850995) (xy 148.314194 -388.800532)
			(xy 148.313648 -388.77494) (xy 147.771654 -388.77494) (xy 148.083778 -389.314944) (xy 148.096588 -389.338284)
			(xy 148.114813 -389.388303) (xy 148.124079 -389.440726) (xy 148.124672 -389.467344) (xy 148.124301 -389.491353)
			(xy 148.116779 -389.538778) (xy 148.101927 -389.584441) (xy 148.080111 -389.627217) (xy 148.051868 -389.666051)
			(xy 148.017896 -389.699986) (xy 147.979031 -389.728185) (xy 147.936232 -389.749955) (xy 147.890552 -389.764757)
			(xy 147.843119 -389.772228) (xy 147.81911 -389.772652) (xy 147.795538 -389.772223) (xy 147.748952 -389.764984)
			(xy 147.704036 -389.750663) (xy 147.661859 -389.729599) (xy 147.623425 -389.702296) (xy 147.589652 -389.669403)
			(xy 147.561343 -389.631704) (xy 147.54987 -389.611108) (xy 147.549362 -389.610346) (xy 147.151598 -388.922006)
			(xy 147.139725 -388.899328) (xy 147.122872 -388.850995) (xy 147.114298 -388.800532) (xy 147.113752 -388.77494)
			(xy 133.243924 -388.77494) (xy 133.555994 -389.314944) (xy 133.556248 -389.315452) (xy 133.556502 -389.315452)
			(xy 133.557772 -389.317992) (xy 133.570041 -389.340909) (xy 133.587449 -389.389886) (xy 133.596324 -389.441102)
			(xy 133.596888 -389.46709) (xy 133.596888 -389.467344) (xy 133.596501 -389.491352) (xy 133.58898 -389.538775)
			(xy 133.574128 -389.584437) (xy 133.552314 -389.627212) (xy 133.524073 -389.666045) (xy 133.490103 -389.69998)
			(xy 133.45124 -389.72818) (xy 133.408443 -389.74995) (xy 133.362766 -389.764754) (xy 133.315334 -389.772226)
			(xy 133.291326 -389.772652) (xy 133.267662 -389.772192) (xy 133.220902 -389.764885) (xy 133.175827 -389.750458)
			(xy 133.133515 -389.729255) (xy 133.094977 -389.701783) (xy 133.061134 -389.6687) (xy 133.032795 -389.630795)
			(xy 133.021324 -389.610092) (xy 133.02107 -389.60933) (xy 132.623814 -388.922006) (xy 132.611633 -388.89879)
			(xy 132.59452 -388.849239) (xy 132.589778 -388.823454) (xy 132.589778 -388.8232) (xy 132.586219 -388.797977)
			(xy 132.057087 -388.797977) (xy 132.355844 -389.314944) (xy 132.356098 -389.315452) (xy 132.356352 -389.315452)
			(xy 132.357622 -389.317992) (xy 132.369855 -389.340916) (xy 132.387175 -389.389902) (xy 132.395962 -389.441111)
			(xy 132.396484 -389.46709) (xy 132.396484 -389.467344) (xy 132.396078 -389.491338) (xy 132.388564 -389.538733)
			(xy 132.37373 -389.58437) (xy 132.351938 -389.627124) (xy 132.323728 -389.665943) (xy 132.289792 -389.699872)
			(xy 132.250966 -389.728074) (xy 132.208207 -389.749856) (xy 132.162567 -389.76468) (xy 132.11517 -389.772183)
			(xy 132.091176 -389.772652) (xy 132.067511 -389.772232) (xy 132.020749 -389.764918) (xy 131.975673 -389.750483)
			(xy 131.933361 -389.729274) (xy 131.894823 -389.701796) (xy 131.860981 -389.668707) (xy 131.832644 -389.630797)
			(xy 131.821174 -389.610092) (xy 131.82092 -389.60933) (xy 131.423664 -388.922006) (xy 131.411486 -388.898789)
			(xy 131.39437 -388.849239) (xy 131.389628 -388.823454) (xy 131.389628 -388.8232) (xy 131.386145 -388.799395)
			(xy 131.385933 -388.751285) (xy 130.830208 -388.751285) (xy 131.155948 -389.314944) (xy 131.156202 -389.315452)
			(xy 131.156456 -389.315452) (xy 131.157726 -389.317992) (xy 131.16996 -389.340916) (xy 131.187279 -389.389902)
			(xy 131.196066 -389.441111) (xy 131.196588 -389.46709) (xy 131.196588 -389.467344) (xy 131.196178 -389.491337)
			(xy 131.188665 -389.538733) (xy 131.17383 -389.584369) (xy 131.152039 -389.627123) (xy 131.123829 -389.665942)
			(xy 131.089893 -389.69987) (xy 131.051068 -389.728073) (xy 131.00831 -389.749854) (xy 130.96267 -389.76468)
			(xy 130.915274 -389.772183) (xy 130.89128 -389.772652) (xy 130.867615 -389.772229) (xy 130.820853 -389.764915)
			(xy 130.775777 -389.750481) (xy 130.733465 -389.729272) (xy 130.694927 -389.701795) (xy 130.661085 -389.668706)
			(xy 130.632748 -389.630797) (xy 130.621278 -389.610092) (xy 130.621024 -389.60933) (xy 130.223768 -388.922006)
			(xy 130.21159 -388.898789) (xy 130.194475 -388.849239) (xy 130.189732 -388.823454) (xy 130.189732 -388.8232)
			(xy 130.186241 -388.799396) (xy 130.18603 -388.751285) (xy 129.630058 -388.751285) (xy 129.955798 -389.314944)
			(xy 129.956052 -389.315452) (xy 129.956306 -389.315452) (xy 129.957576 -389.317992) (xy 129.969845 -389.340909)
			(xy 129.987253 -389.389886) (xy 129.996128 -389.441102) (xy 129.996692 -389.46709) (xy 129.996692 -389.467344)
			(xy 129.996301 -389.491352) (xy 129.98878 -389.538775) (xy 129.973929 -389.584436) (xy 129.952114 -389.627211)
			(xy 129.923874 -389.666044) (xy 129.889905 -389.699979) (xy 129.851042 -389.728179) (xy 129.808246 -389.749949)
			(xy 129.762569 -389.764753) (xy 129.715138 -389.772226) (xy 129.69113 -389.772652) (xy 129.667466 -389.772188)
			(xy 129.620707 -389.764882) (xy 129.575632 -389.750456) (xy 129.533319 -389.729254) (xy 129.494781 -389.701782)
			(xy 129.460938 -389.668699) (xy 129.432599 -389.630794) (xy 129.421128 -389.610092) (xy 129.420874 -389.60933)
			(xy 129.023618 -388.922006) (xy 129.011437 -388.89879) (xy 128.994324 -388.849239) (xy 128.989582 -388.823454)
			(xy 128.989582 -388.8232) (xy 128.986016 -388.797978) (xy 128.457146 -388.797978) (xy 128.755902 -389.314944)
			(xy 128.756156 -389.315452) (xy 128.75641 -389.315452) (xy 128.75768 -389.317992) (xy 128.769949 -389.340909)
			(xy 128.787357 -389.389886) (xy 128.796232 -389.441102) (xy 128.796796 -389.46709) (xy 128.796796 -389.467344)
			(xy 128.796401 -389.491352) (xy 128.78888 -389.538774) (xy 128.774029 -389.584435) (xy 128.752215 -389.627209)
			(xy 128.723975 -389.666042) (xy 128.690006 -389.699977) (xy 128.651145 -389.728177) (xy 128.608348 -389.749948)
			(xy 128.562672 -389.764752) (xy 128.515242 -389.772226) (xy 128.491234 -389.772652) (xy 128.467571 -389.772185)
			(xy 128.420811 -389.76488) (xy 128.375736 -389.750454) (xy 128.333424 -389.729252) (xy 128.294885 -389.701781)
			(xy 128.261042 -389.668699) (xy 128.232703 -389.630794) (xy 128.221232 -389.610092) (xy 128.220978 -389.60933)
			(xy 127.823722 -388.922006) (xy 127.811541 -388.89879) (xy 127.794428 -388.849239) (xy 127.789686 -388.823454)
			(xy 127.789686 -388.8232) (xy 127.786112 -388.797979) (xy 127.257251 -388.797979) (xy 127.556006 -389.314944)
			(xy 127.55626 -389.315452) (xy 127.556514 -389.315452) (xy 127.557784 -389.317992) (xy 127.570054 -389.340909)
			(xy 127.587461 -389.389886) (xy 127.596336 -389.441101) (xy 127.5969 -389.46709) (xy 127.5969 -389.467344)
			(xy 127.596501 -389.491351) (xy 127.58898 -389.538774) (xy 127.57413 -389.584434) (xy 127.552316 -389.627208)
			(xy 127.524077 -389.666041) (xy 127.490108 -389.699976) (xy 127.451247 -389.728176) (xy 127.408451 -389.749947)
			(xy 127.362776 -389.764752) (xy 127.315346 -389.772225) (xy 127.291338 -389.772652) (xy 127.267675 -389.772182)
			(xy 127.220915 -389.764877) (xy 127.17584 -389.750452) (xy 127.133528 -389.729251) (xy 127.094989 -389.70178)
			(xy 127.061146 -389.668698) (xy 127.032807 -389.630794) (xy 127.021336 -389.610092) (xy 127.021082 -389.60933)
			(xy 126.623826 -388.922006) (xy 126.611646 -388.89879) (xy 126.594532 -388.849239) (xy 126.58979 -388.823454)
			(xy 126.58979 -388.8232) (xy 126.586378 -388.799387) (xy 126.586167 -388.751284) (xy 126.030115 -388.751284)
			(xy 126.355856 -389.314944) (xy 126.35611 -389.315452) (xy 126.356364 -389.315452) (xy 126.357634 -389.317992)
			(xy 126.369868 -389.340915) (xy 126.387188 -389.389902) (xy 126.395975 -389.441111) (xy 126.396496 -389.46709)
			(xy 126.396496 -389.467344) (xy 126.396078 -389.491337) (xy 126.388565 -389.538731) (xy 126.373731 -389.584367)
			(xy 126.351941 -389.627121) (xy 126.323731 -389.665939) (xy 126.289797 -389.699868) (xy 126.250973 -389.72807)
			(xy 126.208215 -389.749852) (xy 126.162577 -389.764678) (xy 126.115181 -389.772182) (xy 126.091188 -389.772652)
			(xy 126.067523 -389.772222) (xy 126.020762 -389.76491) (xy 125.975686 -389.750477) (xy 125.933374 -389.729269)
			(xy 125.894836 -389.701793) (xy 125.860994 -389.668705) (xy 125.832656 -389.630796) (xy 125.821186 -389.610092)
			(xy 125.820932 -389.60933) (xy 125.423676 -388.922006) (xy 125.411499 -388.898788) (xy 125.394383 -388.849238)
			(xy 125.38964 -388.823454) (xy 125.38964 -388.8232) (xy 125.386134 -388.799398) (xy 125.385922 -388.751286)
			(xy 124.830221 -388.751286) (xy 125.15596 -389.314944) (xy 125.156214 -389.315452) (xy 125.156468 -389.315452)
			(xy 125.157738 -389.317992) (xy 125.169973 -389.340915) (xy 125.187292 -389.389902) (xy 125.196079 -389.441111)
			(xy 125.1966 -389.46709) (xy 125.1966 -389.467344) (xy 125.196178 -389.491337) (xy 125.188665 -389.538731)
			(xy 125.173831 -389.584366) (xy 125.152041 -389.627119) (xy 125.123832 -389.665938) (xy 125.089898 -389.699866)
			(xy 125.051075 -389.728069) (xy 125.008318 -389.749851) (xy 124.96268 -389.764677) (xy 124.915285 -389.772182)
			(xy 124.891292 -389.772652) (xy 124.867627 -389.772219) (xy 124.820866 -389.764907) (xy 124.77579 -389.750475)
			(xy 124.733478 -389.729268) (xy 124.69494 -389.701792) (xy 124.661098 -389.668705) (xy 124.63276 -389.630796)
			(xy 124.62129 -389.610092) (xy 124.621036 -389.60933) (xy 124.22378 -388.922006) (xy 124.211603 -388.898788)
			(xy 124.194487 -388.849238) (xy 124.189744 -388.823454) (xy 124.189744 -388.8232) (xy 124.186231 -388.799399)
			(xy 124.186019 -388.751286) (xy 123.630071 -388.751286) (xy 123.95581 -389.314944) (xy 123.956064 -389.315452)
			(xy 123.956318 -389.315452) (xy 123.957588 -389.317992) (xy 123.969858 -389.340908) (xy 123.987265 -389.389886)
			(xy 123.99614 -389.441101) (xy 123.996704 -389.46709) (xy 123.996704 -389.467344) (xy 123.996301 -389.491351)
			(xy 123.98878 -389.538773) (xy 123.97393 -389.584433) (xy 123.952117 -389.627207) (xy 123.923878 -389.66604)
			(xy 123.88991 -389.699974) (xy 123.851049 -389.728175) (xy 123.808254 -389.749946) (xy 123.762579 -389.764751)
			(xy 123.71515 -389.772225) (xy 123.691142 -389.772652) (xy 123.667479 -389.772179) (xy 123.620719 -389.764875)
			(xy 123.575645 -389.75045) (xy 123.533332 -389.729249) (xy 123.494794 -389.701779) (xy 123.46095 -389.668697)
			(xy 123.432611 -389.630794) (xy 123.42114 -389.610092) (xy 123.420886 -389.60933) (xy 123.02363 -388.922006)
			(xy 123.01145 -388.89879) (xy 122.994336 -388.849239) (xy 122.989594 -388.823454) (xy 122.989594 -388.8232)
			(xy 122.986174 -388.799388) (xy 122.985964 -388.751284) (xy 122.430173 -388.751284) (xy 122.755914 -389.314944)
			(xy 122.756168 -389.315452) (xy 122.756422 -389.315452) (xy 122.757692 -389.317992) (xy 122.769962 -389.340908)
			(xy 122.787369 -389.389886) (xy 122.796244 -389.441101) (xy 122.796808 -389.46709) (xy 122.796808 -389.467344)
			(xy 122.796401 -389.491351) (xy 122.78888 -389.538772) (xy 122.77403 -389.584432) (xy 122.752217 -389.627206)
			(xy 122.723979 -389.666038) (xy 122.690011 -389.699973) (xy 122.651151 -389.728173) (xy 122.608357 -389.749944)
			(xy 122.562682 -389.76475) (xy 122.515253 -389.772225) (xy 122.491246 -389.772652) (xy 122.467583 -389.772176)
			(xy 122.420824 -389.764872) (xy 122.375749 -389.750448) (xy 122.333437 -389.729248) (xy 122.294898 -389.701778)
			(xy 122.261054 -389.668697) (xy 122.232715 -389.630794) (xy 122.221244 -389.610092) (xy 122.22099 -389.60933)
			(xy 121.823734 -388.922006) (xy 121.811554 -388.89879) (xy 121.79444 -388.849239) (xy 121.789698 -388.823454)
			(xy 121.789698 -388.8232) (xy 121.786271 -388.799389) (xy 121.78606 -388.751284) (xy 121.230277 -388.751284)
			(xy 121.556018 -389.314944) (xy 121.556272 -389.315452) (xy 121.556526 -389.315452) (xy 121.557796 -389.317992)
			(xy 121.570067 -389.340908) (xy 121.587474 -389.389886) (xy 121.596348 -389.441101) (xy 121.596912 -389.46709)
			(xy 121.596912 -389.467344) (xy 121.596502 -389.491351) (xy 121.58898 -389.538772) (xy 121.574131 -389.584432)
			(xy 121.552318 -389.627205) (xy 121.52408 -389.666037) (xy 121.490113 -389.699971) (xy 121.451253 -389.728172)
			(xy 121.408459 -389.749943) (xy 121.362786 -389.764749) (xy 121.315357 -389.772225) (xy 121.29135 -389.772652)
			(xy 121.267687 -389.772172) (xy 121.220928 -389.764869) (xy 121.175853 -389.750446) (xy 121.133541 -389.729246)
			(xy 121.095002 -389.701777) (xy 121.061159 -389.668696) (xy 121.032819 -389.630793) (xy 121.021348 -389.610092)
			(xy 121.021094 -389.60933) (xy 120.623838 -388.922006) (xy 120.611658 -388.89879) (xy 120.594544 -388.849239)
			(xy 120.589802 -388.823454) (xy 120.589802 -388.8232) (xy 120.586367 -388.799389) (xy 120.586156 -388.751284)
			(xy 120.030127 -388.751284) (xy 120.355868 -389.314944) (xy 120.356122 -389.315452) (xy 120.356376 -389.315452)
			(xy 120.357646 -389.317992) (xy 120.369881 -389.340915) (xy 120.3872 -389.389902) (xy 120.395987 -389.441111)
			(xy 120.396508 -389.46709) (xy 120.396508 -389.467344) (xy 120.396078 -389.491336) (xy 120.388565 -389.53873)
			(xy 120.373732 -389.584364) (xy 120.351943 -389.627117) (xy 120.323735 -389.665935) (xy 120.289802 -389.699863)
			(xy 120.250979 -389.728066) (xy 120.208224 -389.749849) (xy 120.162587 -389.764676) (xy 120.115192 -389.772181)
			(xy 120.0912 -389.772652) (xy 120.067536 -389.772213) (xy 120.020775 -389.764902) (xy 119.975699 -389.750471)
			(xy 119.933387 -389.729265) (xy 119.894849 -389.70179) (xy 119.861006 -389.668703) (xy 119.832668 -389.630796)
			(xy 119.821198 -389.610092) (xy 119.820944 -389.60933) (xy 119.423688 -388.922006) (xy 119.411512 -388.898788)
			(xy 119.394395 -388.849238) (xy 119.389652 -388.823454) (xy 119.389652 -388.8232) (xy 119.386123 -388.7994)
			(xy 119.385912 -388.751286) (xy 118.830233 -388.751286) (xy 119.155972 -389.314944) (xy 119.156226 -389.315452)
			(xy 119.15648 -389.315452) (xy 119.15775 -389.317992) (xy 119.169986 -389.340915) (xy 119.187304 -389.389901)
			(xy 119.196091 -389.441111) (xy 119.196612 -389.46709) (xy 119.196612 -389.467344) (xy 119.196178 -389.491336)
			(xy 119.188665 -389.538729) (xy 119.173832 -389.584363) (xy 119.152044 -389.627116) (xy 119.123836 -389.665934)
			(xy 119.089903 -389.699862) (xy 119.051082 -389.728065) (xy 119.008326 -389.749848) (xy 118.96269 -389.764675)
			(xy 118.915296 -389.772181) (xy 118.891304 -389.772652) (xy 118.86764 -389.772209) (xy 118.820879 -389.764899)
			(xy 118.775803 -389.750469) (xy 118.733491 -389.729263) (xy 118.694953 -389.701789) (xy 118.66111 -389.668703)
			(xy 118.632772 -389.630796) (xy 118.621302 -389.610092) (xy 118.621048 -389.60933) (xy 118.223792 -388.922006)
			(xy 118.211609 -388.898791) (xy 118.194497 -388.849239) (xy 118.189756 -388.823454) (xy 118.189756 -388.8232)
			(xy 118.18622 -388.799401) (xy 118.186008 -388.751286) (xy 117.630083 -388.751286) (xy 117.955822 -389.314944)
			(xy 117.956076 -389.315452) (xy 117.95633 -389.315452) (xy 117.9576 -389.317992) (xy 117.969871 -389.340908)
			(xy 117.987278 -389.389886) (xy 117.996152 -389.441101) (xy 117.996716 -389.46709) (xy 117.996716 -389.467344)
			(xy 117.996302 -389.491351) (xy 117.988781 -389.538771) (xy 117.973931 -389.584431) (xy 117.952119 -389.627203)
			(xy 117.923881 -389.666036) (xy 117.889915 -389.69997) (xy 117.851056 -389.728171) (xy 117.808262 -389.749942)
			(xy 117.762589 -389.764748) (xy 117.715161 -389.772224) (xy 117.691154 -389.772652) (xy 117.667491 -389.772169)
			(xy 117.620732 -389.764867) (xy 117.575658 -389.750444) (xy 117.533345 -389.729245) (xy 117.494807 -389.701776)
			(xy 117.460963 -389.668696) (xy 117.432623 -389.630793) (xy 117.421152 -389.610092) (xy 117.420898 -389.60933)
			(xy 117.023642 -388.922006) (xy 117.011463 -388.898789) (xy 116.994348 -388.849239) (xy 116.989606 -388.823454)
			(xy 116.989606 -388.8232) (xy 116.986164 -388.79939) (xy 116.985953 -388.751284) (xy 116.430185 -388.751284)
			(xy 116.755926 -389.314944) (xy 116.75618 -389.315452) (xy 116.756434 -389.315452) (xy 116.757704 -389.317992)
			(xy 116.769975 -389.340908) (xy 116.787382 -389.389886) (xy 116.796256 -389.441101) (xy 116.79682 -389.46709)
			(xy 116.79682 -389.467344) (xy 116.796402 -389.49135) (xy 116.788881 -389.538771) (xy 116.774031 -389.58443)
			(xy 116.752219 -389.627202) (xy 116.723982 -389.666034) (xy 116.690016 -389.699969) (xy 116.651158 -389.728169)
			(xy 116.608365 -389.749941) (xy 116.562692 -389.764748) (xy 116.515265 -389.772224) (xy 116.491258 -389.772652)
			(xy 116.467595 -389.772166) (xy 116.420836 -389.764864) (xy 116.375762 -389.750442) (xy 116.33345 -389.729243)
			(xy 116.294911 -389.701775) (xy 116.261067 -389.668695) (xy 116.232727 -389.630793) (xy 116.221256 -389.610092)
			(xy 116.221002 -389.60933) (xy 115.823746 -388.922006) (xy 115.811567 -388.898789) (xy 115.794452 -388.849239)
			(xy 115.78971 -388.823454) (xy 115.78971 -388.8232) (xy 115.78626 -388.799391) (xy 115.786049 -388.751284)
			(xy 115.230289 -388.751284) (xy 115.55603 -389.314944) (xy 115.556284 -389.315452) (xy 115.556538 -389.315452)
			(xy 115.557808 -389.317992) (xy 115.57008 -389.340908) (xy 115.587486 -389.389886) (xy 115.59636 -389.441101)
			(xy 115.596924 -389.46709) (xy 115.596924 -389.467344) (xy 115.596502 -389.49135) (xy 115.588981 -389.53877)
			(xy 115.574132 -389.584429) (xy 115.55232 -389.627201) (xy 115.524084 -389.666033) (xy 115.490118 -389.699967)
			(xy 115.45126 -389.728168) (xy 115.408468 -389.74994) (xy 115.362795 -389.764747) (xy 115.315369 -389.772224)
			(xy 115.291362 -389.772652) (xy 115.267699 -389.772163) (xy 115.220941 -389.764861) (xy 115.175866 -389.750439)
			(xy 115.133554 -389.729241) (xy 115.095015 -389.701774) (xy 115.061171 -389.668695) (xy 115.032831 -389.630793)
			(xy 115.02136 -389.610092) (xy 115.021106 -389.60933) (xy 114.62385 -388.922006) (xy 114.611671 -388.898789)
			(xy 114.594556 -388.849239) (xy 114.589814 -388.823454) (xy 114.589814 -388.8232) (xy 114.586357 -388.799392)
			(xy 114.586146 -388.751285) (xy 98.65806 -388.751285) (xy 98.9838 -389.314944) (xy 98.984054 -389.315452)
			(xy 98.984308 -389.315452) (xy 98.985578 -389.317992) (xy 98.997808 -389.340918) (xy 99.01513 -389.389903)
			(xy 99.023918 -389.441111) (xy 99.02444 -389.46709) (xy 99.02444 -389.467344) (xy 99.023978 -389.491335)
			(xy 99.016466 -389.538725) (xy 99.001635 -389.584357) (xy 98.979849 -389.627107) (xy 98.951644 -389.665924)
			(xy 98.917715 -389.699852) (xy 98.878897 -389.728055) (xy 98.836146 -389.74984) (xy 98.790513 -389.764669)
			(xy 98.743123 -389.772179) (xy 98.719132 -389.772652) (xy 98.695469 -389.772187) (xy 98.648709 -389.764881)
			(xy 98.603634 -389.750455) (xy 98.561321 -389.729253) (xy 98.522783 -389.701782) (xy 98.48894 -389.668699)
			(xy 98.460601 -389.630794) (xy 98.44913 -389.610092) (xy 98.448876 -389.60933) (xy 98.05162 -388.922006)
			(xy 98.039439 -388.89879) (xy 98.022326 -388.849239) (xy 98.017584 -388.823454) (xy 98.017584 -388.8232)
			(xy 98.014014 -388.797978) (xy 97.484894 -388.797978) (xy 97.78365 -389.314944) (xy 97.783904 -389.315452)
			(xy 97.784158 -389.315452) (xy 97.785428 -389.317992) (xy 97.797701 -389.340907) (xy 97.815106 -389.389885)
			(xy 97.82398 -389.441101) (xy 97.824544 -389.46709) (xy 97.824544 -389.467344) (xy 97.824102 -389.491349)
			(xy 97.816582 -389.538767) (xy 97.801734 -389.584424) (xy 97.779924 -389.627195) (xy 97.75169 -389.666026)
			(xy 97.717726 -389.69996) (xy 97.678871 -389.728161) (xy 97.636082 -389.749934) (xy 97.590412 -389.764743)
			(xy 97.542988 -389.772222) (xy 97.518982 -389.772652) (xy 97.495317 -389.772227) (xy 97.448555 -389.764914)
			(xy 97.40348 -389.75048) (xy 97.361167 -389.729272) (xy 97.322629 -389.701795) (xy 97.288787 -389.668706)
			(xy 97.26045 -389.630797) (xy 97.24898 -389.610092) (xy 97.248726 -389.60933) (xy 96.85147 -388.922006)
			(xy 96.839293 -388.898789) (xy 96.822177 -388.849238) (xy 96.817434 -388.823454) (xy 96.817434 -388.8232)
			(xy 96.813939 -388.799396) (xy 96.813728 -388.751285) (xy 96.258014 -388.751285) (xy 96.583754 -389.314944)
			(xy 96.584008 -389.315452) (xy 96.584262 -389.315452) (xy 96.585532 -389.317992) (xy 96.597806 -389.340907)
			(xy 96.615211 -389.389885) (xy 96.624084 -389.441101) (xy 96.624648 -389.46709) (xy 96.624648 -389.467344)
			(xy 96.624202 -389.491349) (xy 96.616682 -389.538767) (xy 96.601834 -389.584423) (xy 96.580025 -389.627194)
			(xy 96.551791 -389.666025) (xy 96.517828 -389.699959) (xy 96.478973 -389.72816) (xy 96.436184 -389.749933)
			(xy 96.390515 -389.764742) (xy 96.343091 -389.772222) (xy 96.319086 -389.772652) (xy 96.295421 -389.772224)
			(xy 96.24866 -389.764911) (xy 96.203584 -389.750478) (xy 96.161272 -389.72927) (xy 96.122734 -389.701794)
			(xy 96.088892 -389.668705) (xy 96.060554 -389.630796) (xy 96.049084 -389.610092) (xy 96.04883 -389.60933)
			(xy 95.651574 -388.922006) (xy 95.639397 -388.898788) (xy 95.622281 -388.849238) (xy 95.617538 -388.823454)
			(xy 95.617538 -388.8232) (xy 95.614036 -388.799397) (xy 95.613824 -388.751286) (xy 95.057865 -388.751286)
			(xy 95.383604 -389.314944) (xy 95.383858 -389.315452) (xy 95.384112 -389.315452) (xy 95.385382 -389.317992)
			(xy 95.397612 -389.340918) (xy 95.414934 -389.389903) (xy 95.423722 -389.441111) (xy 95.424244 -389.46709)
			(xy 95.424244 -389.467344) (xy 95.423778 -389.491335) (xy 95.416267 -389.538724) (xy 95.401435 -389.584356)
			(xy 95.379649 -389.627106) (xy 95.351445 -389.665923) (xy 95.317517 -389.69985) (xy 95.278699 -389.728054)
			(xy 95.235949 -389.749838) (xy 95.190317 -389.764668) (xy 95.142927 -389.772179) (xy 95.118936 -389.772652)
			(xy 95.095273 -389.772184) (xy 95.048513 -389.764878) (xy 95.003438 -389.750453) (xy 94.961126 -389.729251)
			(xy 94.922587 -389.701781) (xy 94.888744 -389.668698) (xy 94.860405 -389.630794) (xy 94.848934 -389.610092)
			(xy 94.84868 -389.60933) (xy 94.451424 -388.922006) (xy 94.439244 -388.89879) (xy 94.42213 -388.849239)
			(xy 94.417388 -388.823454) (xy 94.417388 -388.8232) (xy 94.413811 -388.797979) (xy 93.884953 -388.797979)
			(xy 94.183708 -389.314944) (xy 94.183962 -389.315452) (xy 94.184216 -389.315452) (xy 94.185486 -389.317992)
			(xy 94.197717 -389.340917) (xy 94.215038 -389.389902) (xy 94.223826 -389.441111) (xy 94.224348 -389.46709)
			(xy 94.224348 -389.467344) (xy 94.223878 -389.491334) (xy 94.216367 -389.538724) (xy 94.201536 -389.584355)
			(xy 94.17975 -389.627105) (xy 94.151546 -389.665922) (xy 94.117618 -389.699849) (xy 94.078802 -389.728052)
			(xy 94.036051 -389.749837) (xy 93.99042 -389.764668) (xy 93.94303 -389.772178) (xy 93.91904 -389.772652)
			(xy 93.895377 -389.77218) (xy 93.848617 -389.764876) (xy 93.803542 -389.750451) (xy 93.76123 -389.72925)
			(xy 93.722692 -389.70178) (xy 93.688848 -389.668698) (xy 93.660509 -389.630794) (xy 93.649038 -389.610092)
			(xy 93.648784 -389.60933) (xy 93.251528 -388.922006) (xy 93.239348 -388.89879) (xy 93.222234 -388.849239)
			(xy 93.217492 -388.823454) (xy 93.217492 -388.8232) (xy 93.214076 -388.799387) (xy 93.213865 -388.751284)
			(xy 92.658071 -388.751284) (xy 92.983812 -389.314944) (xy 92.984066 -389.315452) (xy 92.98432 -389.315452)
			(xy 92.98559 -389.317992) (xy 92.997821 -389.340917) (xy 93.015142 -389.389902) (xy 93.02393 -389.441111)
			(xy 93.024452 -389.46709) (xy 93.024452 -389.467344) (xy 93.023978 -389.491334) (xy 93.016467 -389.538723)
			(xy 93.001636 -389.584354) (xy 92.979851 -389.627104) (xy 92.951648 -389.66592) (xy 92.91772 -389.699848)
			(xy 92.878904 -389.728051) (xy 92.836154 -389.749836) (xy 92.790523 -389.764667) (xy 92.743134 -389.772178)
			(xy 92.719144 -389.772652) (xy 92.695481 -389.772177) (xy 92.648721 -389.764873) (xy 92.603647 -389.750449)
			(xy 92.561334 -389.729248) (xy 92.522796 -389.701779) (xy 92.488952 -389.668697) (xy 92.460613 -389.630794)
			(xy 92.449142 -389.610092) (xy 92.448888 -389.60933) (xy 92.051632 -388.922006) (xy 92.039452 -388.89879)
			(xy 92.022338 -388.849239) (xy 92.017596 -388.823454) (xy 92.017596 -388.8232) (xy 92.014173 -388.799388)
			(xy 92.013962 -388.751284) (xy 91.457921 -388.751284) (xy 91.783662 -389.314944) (xy 91.783916 -389.315452)
			(xy 91.78417 -389.315452) (xy 91.78544 -389.317992) (xy 91.797714 -389.340906) (xy 91.815119 -389.389885)
			(xy 91.823992 -389.441101) (xy 91.824556 -389.46709) (xy 91.824556 -389.467344) (xy 91.824102 -389.491349)
			(xy 91.816582 -389.538765) (xy 91.801735 -389.584421) (xy 91.779926 -389.627191) (xy 91.751693 -389.666022)
			(xy 91.717731 -389.699956) (xy 91.678878 -389.728157) (xy 91.63609 -389.749931) (xy 91.590422 -389.76474)
			(xy 91.542999 -389.772221) (xy 91.518994 -389.772652) (xy 91.495329 -389.772217) (xy 91.448568 -389.764906)
			(xy 91.403493 -389.750474) (xy 91.36118 -389.729267) (xy 91.322642 -389.701792) (xy 91.2888 -389.668704)
			(xy 91.260462 -389.630796) (xy 91.248992 -389.610092) (xy 91.248738 -389.60933) (xy 90.851482 -388.922006)
			(xy 90.839305 -388.898788) (xy 90.822189 -388.849238) (xy 90.817446 -388.823454) (xy 90.817446 -388.8232)
			(xy 90.813929 -388.799399) (xy 90.813717 -388.751286) (xy 90.258027 -388.751286) (xy 90.583766 -389.314944)
			(xy 90.58402 -389.315452) (xy 90.584274 -389.315452) (xy 90.585544 -389.317992) (xy 90.597819 -389.340906)
			(xy 90.615223 -389.389885) (xy 90.624096 -389.441101) (xy 90.62466 -389.46709) (xy 90.62466 -389.467344)
			(xy 90.624301 -389.491353) (xy 90.616779 -389.53878) (xy 90.601926 -389.584444) (xy 90.580109 -389.62722)
			(xy 90.551865 -389.666055) (xy 90.517891 -389.69999) (xy 90.479025 -389.72819) (xy 90.436223 -389.749958)
			(xy 90.390542 -389.764759) (xy 90.343108 -389.772228) (xy 90.319098 -389.772652) (xy 90.295434 -389.772214)
			(xy 90.248672 -389.764903) (xy 90.203597 -389.750472) (xy 90.161285 -389.729266) (xy 90.122747 -389.701791)
			(xy 90.088904 -389.668704) (xy 90.060566 -389.630796) (xy 90.049096 -389.610092) (xy 90.048842 -389.60933)
			(xy 89.651586 -388.922006) (xy 89.63941 -388.898788) (xy 89.622293 -388.849238) (xy 89.61755 -388.823454)
			(xy 89.61755 -388.8232) (xy 89.614025 -388.7994) (xy 89.613813 -388.751286) (xy 89.057877 -388.751286)
			(xy 89.383616 -389.314944) (xy 89.38387 -389.315452) (xy 89.384124 -389.315452) (xy 89.385394 -389.317992)
			(xy 89.397625 -389.340917) (xy 89.414946 -389.389902) (xy 89.423734 -389.441111) (xy 89.424256 -389.46709)
			(xy 89.424256 -389.467344) (xy 89.423778 -389.491334) (xy 89.416267 -389.538723) (xy 89.401436 -389.584353)
			(xy 89.379652 -389.627103) (xy 89.351449 -389.665919) (xy 89.317522 -389.699846) (xy 89.278706 -389.72805)
			(xy 89.235957 -389.749835) (xy 89.190327 -389.764666) (xy 89.142938 -389.772178) (xy 89.118948 -389.772652)
			(xy 89.095285 -389.772174) (xy 89.048526 -389.764871) (xy 89.003451 -389.750447) (xy 88.961139 -389.729247)
			(xy 88.9226 -389.701778) (xy 88.888757 -389.668697) (xy 88.860417 -389.630794) (xy 88.848946 -389.610092)
			(xy 88.848692 -389.60933) (xy 88.451436 -388.922006) (xy 88.439256 -388.89879) (xy 88.422142 -388.849239)
			(xy 88.4174 -388.823454) (xy 88.4174 -388.8232) (xy 88.413969 -388.799389) (xy 88.413758 -388.751284)
			(xy 87.857979 -388.751284) (xy 88.18372 -389.314944) (xy 88.183974 -389.315452) (xy 88.184228 -389.315452)
			(xy 88.185498 -389.317992) (xy 88.197729 -389.340917) (xy 88.21505 -389.389902) (xy 88.223838 -389.441111)
			(xy 88.22436 -389.46709) (xy 88.22436 -389.467344) (xy 88.224002 -389.491341) (xy 88.216487 -389.538742)
			(xy 88.20165 -389.584385) (xy 88.179855 -389.627144) (xy 88.151639 -389.665968) (xy 88.117698 -389.699899)
			(xy 88.078866 -389.728103) (xy 88.0361 -389.749885) (xy 87.990453 -389.764709) (xy 87.943049 -389.772209)
			(xy 87.919052 -389.772652) (xy 87.895389 -389.772171) (xy 87.84863 -389.764868) (xy 87.803556 -389.750445)
			(xy 87.761243 -389.729245) (xy 87.722705 -389.701777) (xy 87.688861 -389.668696) (xy 87.660521 -389.630793)
			(xy 87.64905 -389.610092) (xy 87.648796 -389.60933) (xy 87.25154 -388.922006) (xy 87.239361 -388.89879)
			(xy 87.222246 -388.849239) (xy 87.217504 -388.823454) (xy 87.217504 -388.8232) (xy 87.214066 -388.79939)
			(xy 87.213855 -388.751284) (xy 86.658083 -388.751284) (xy 86.983824 -389.314944) (xy 86.984078 -389.315452)
			(xy 86.984332 -389.315452) (xy 86.985602 -389.317992) (xy 86.997834 -389.340917) (xy 87.015155 -389.389902)
			(xy 87.023942 -389.441111) (xy 87.024464 -389.46709) (xy 87.024464 -389.467344) (xy 87.024078 -389.491339)
			(xy 87.016564 -389.538736) (xy 87.001728 -389.584375) (xy 86.979935 -389.62713) (xy 86.951722 -389.66595)
			(xy 86.917783 -389.699879) (xy 86.878955 -389.728081) (xy 86.836193 -389.749861) (xy 86.79055 -389.764684)
			(xy 86.743151 -389.772185) (xy 86.719156 -389.772652) (xy 86.695493 -389.772167) (xy 86.648734 -389.764865)
			(xy 86.60366 -389.750443) (xy 86.561348 -389.729244) (xy 86.522809 -389.701776) (xy 86.488965 -389.668695)
			(xy 86.460625 -389.630793) (xy 86.449154 -389.610092) (xy 86.4489 -389.60933) (xy 86.051644 -388.922006)
			(xy 86.039465 -388.898789) (xy 86.02235 -388.849239) (xy 86.017608 -388.823454) (xy 86.017608 -388.8232)
			(xy 86.014162 -388.799391) (xy 86.013951 -388.751284) (xy 85.457933 -388.751284) (xy 85.783674 -389.314944)
			(xy 85.783928 -389.315452) (xy 85.784182 -389.315452) (xy 85.785452 -389.317992) (xy 85.797727 -389.340906)
			(xy 85.815131 -389.389885) (xy 85.824004 -389.441101) (xy 85.824568 -389.46709) (xy 85.824568 -389.467344)
			(xy 85.824201 -389.491353) (xy 85.816679 -389.538778) (xy 85.801826 -389.584442) (xy 85.78001 -389.627218)
			(xy 85.751767 -389.666052) (xy 85.717795 -389.699987) (xy 85.678929 -389.728187) (xy 85.636129 -389.749956)
			(xy 85.590449 -389.764758) (xy 85.543016 -389.772228) (xy 85.519006 -389.772652) (xy 85.495342 -389.772208)
			(xy 85.448581 -389.764898) (xy 85.403506 -389.750468) (xy 85.361193 -389.729263) (xy 85.322655 -389.701789)
			(xy 85.288813 -389.668703) (xy 85.260474 -389.630795) (xy 85.249004 -389.610092) (xy 85.24875 -389.60933)
			(xy 84.851494 -388.922006) (xy 84.839312 -388.898791) (xy 84.822199 -388.849239) (xy 84.817458 -388.823454)
			(xy 84.817458 -388.8232) (xy 84.813918 -388.799402) (xy 84.813706 -388.751287) (xy 84.258039 -388.751287)
			(xy 84.583778 -389.314944) (xy 84.584032 -389.315452) (xy 84.584286 -389.315452) (xy 84.585556 -389.317992)
			(xy 84.597831 -389.340906) (xy 84.615235 -389.389885) (xy 84.624108 -389.441101) (xy 84.624672 -389.46709)
			(xy 84.624672 -389.467344) (xy 84.624301 -389.491353) (xy 84.616779 -389.538778) (xy 84.601927 -389.584441)
			(xy 84.580111 -389.627217) (xy 84.551868 -389.666051) (xy 84.517896 -389.699986) (xy 84.479031 -389.728185)
			(xy 84.436232 -389.749955) (xy 84.390552 -389.764757) (xy 84.343119 -389.772228) (xy 84.31911 -389.772652)
			(xy 84.295446 -389.772205) (xy 84.248685 -389.764896) (xy 84.20361 -389.750466) (xy 84.161298 -389.729261)
			(xy 84.122759 -389.701788) (xy 84.088917 -389.668702) (xy 84.060578 -389.630795) (xy 84.049108 -389.610092)
			(xy 84.048854 -389.60933) (xy 83.651598 -388.922006) (xy 83.639416 -388.898791) (xy 83.622303 -388.849239)
			(xy 83.617562 -388.823454) (xy 83.617562 -388.8232) (xy 83.614015 -388.799402) (xy 83.613803 -388.751287)
			(xy 83.057889 -388.751287) (xy 83.383628 -389.314944) (xy 83.383882 -389.315452) (xy 83.384136 -389.315452)
			(xy 83.385406 -389.317992) (xy 83.397638 -389.340917) (xy 83.414959 -389.389902) (xy 83.423746 -389.441111)
			(xy 83.424268 -389.46709) (xy 83.424268 -389.467344) (xy 83.423878 -389.491338) (xy 83.416364 -389.538735)
			(xy 83.401528 -389.584374) (xy 83.379736 -389.627129) (xy 83.351523 -389.665949) (xy 83.317585 -389.699878)
			(xy 83.278757 -389.728079) (xy 83.235996 -389.74986) (xy 83.190354 -389.764684) (xy 83.142955 -389.772184)
			(xy 83.11896 -389.772652) (xy 83.095297 -389.772164) (xy 83.048539 -389.764863) (xy 83.003464 -389.75044)
			(xy 82.961152 -389.729242) (xy 82.922613 -389.701775) (xy 82.888769 -389.668695) (xy 82.860429 -389.630793)
			(xy 82.848958 -389.610092) (xy 82.848704 -389.60933) (xy 82.451448 -388.922006) (xy 82.439269 -388.898789)
			(xy 82.422154 -388.849239) (xy 82.417412 -388.823454) (xy 82.417412 -388.8232) (xy 82.413959 -388.799392)
			(xy 82.413748 -388.751285) (xy 81.857992 -388.751285) (xy 82.183732 -389.314944) (xy 82.183986 -389.315452)
			(xy 82.18424 -389.315452) (xy 82.18551 -389.317992) (xy 82.197742 -389.340916) (xy 82.215063 -389.389902)
			(xy 82.22385 -389.441111) (xy 82.224372 -389.46709) (xy 82.224372 -389.467344) (xy 82.223978 -389.491338)
			(xy 82.216464 -389.538735) (xy 82.201628 -389.584373) (xy 82.179836 -389.627128) (xy 82.151624 -389.665948)
			(xy 82.117687 -389.699876) (xy 82.078859 -389.728078) (xy 82.036099 -389.749859) (xy 81.990457 -389.764683)
			(xy 81.943058 -389.772184) (xy 81.919064 -389.772652) (xy 81.895401 -389.772161) (xy 81.848643 -389.76486)
			(xy 81.803569 -389.750438) (xy 81.761256 -389.729241) (xy 81.722717 -389.701774) (xy 81.688873 -389.668694)
			(xy 81.660533 -389.630793) (xy 81.649062 -389.610092) (xy 81.648808 -389.60933) (xy 81.251552 -388.922006)
			(xy 81.239373 -388.898789) (xy 81.222258 -388.849239) (xy 81.217516 -388.823454) (xy 81.217516 -388.8232)
			(xy 81.214055 -388.799392) (xy 81.213844 -388.751285) (xy 80.658096 -388.751285) (xy 80.983836 -389.314944)
			(xy 80.98409 -389.315452) (xy 80.984344 -389.315452) (xy 80.985614 -389.317992) (xy 80.997847 -389.340916)
			(xy 81.015167 -389.389902) (xy 81.023954 -389.441111) (xy 81.024476 -389.46709) (xy 81.024476 -389.467344)
			(xy 81.024078 -389.491338) (xy 81.016564 -389.538734) (xy 81.001729 -389.584372) (xy 80.979937 -389.627127)
			(xy 80.951725 -389.665946) (xy 80.917788 -389.699875) (xy 80.878962 -389.728077) (xy 80.836201 -389.749858)
			(xy 80.79056 -389.764682) (xy 80.743162 -389.772184) (xy 80.719168 -389.772652) (xy 80.695506 -389.772158)
			(xy 80.648747 -389.764857) (xy 80.603673 -389.750436) (xy 80.561361 -389.729239) (xy 80.522822 -389.701773)
			(xy 80.488978 -389.668694) (xy 80.460637 -389.630793) (xy 80.449166 -389.610092) (xy 80.448912 -389.60933)
			(xy 80.051656 -388.922006) (xy 80.039478 -388.898789) (xy 80.022362 -388.849239) (xy 80.01762 -388.823454)
			(xy 80.01762 -388.8232) (xy 80.014152 -388.799393) (xy 80.01394 -388.751285) (xy 66.130312 -388.751285)
			(xy 66.456052 -389.314944) (xy 66.456306 -389.315452) (xy 66.45656 -389.315452) (xy 66.45783 -389.317992)
			(xy 66.470064 -389.340916) (xy 66.487383 -389.389902) (xy 66.496171 -389.441111) (xy 66.496692 -389.46709)
			(xy 66.496692 -389.467344) (xy 66.496278 -389.491337) (xy 66.488765 -389.538732) (xy 66.47393 -389.584368)
			(xy 66.45214 -389.627122) (xy 66.42393 -389.665941) (xy 66.389995 -389.699869) (xy 66.351171 -389.728071)
			(xy 66.308412 -389.749853) (xy 66.262774 -389.764679) (xy 66.215377 -389.772183) (xy 66.191384 -389.772652)
			(xy 66.167719 -389.772226) (xy 66.120957 -389.764913) (xy 66.075882 -389.750479) (xy 66.033569 -389.729271)
			(xy 65.995032 -389.701794) (xy 65.961189 -389.668706) (xy 65.932852 -389.630796) (xy 65.921382 -389.610092)
			(xy 65.921128 -389.60933) (xy 65.523872 -388.922006) (xy 65.511695 -388.898788) (xy 65.494579 -388.849238)
			(xy 65.489836 -388.823454) (xy 65.489836 -388.8232) (xy 65.486338 -388.799397) (xy 65.486126 -388.751286)
			(xy 64.930163 -388.751286) (xy 65.255902 -389.314944) (xy 65.256156 -389.315452) (xy 65.25641 -389.315452)
			(xy 65.25768 -389.317992) (xy 65.269949 -389.340909) (xy 65.287357 -389.389886) (xy 65.296232 -389.441102)
			(xy 65.296796 -389.46709) (xy 65.296796 -389.467344) (xy 65.296401 -389.491352) (xy 65.28888 -389.538774)
			(xy 65.274029 -389.584435) (xy 65.252215 -389.627209) (xy 65.223975 -389.666042) (xy 65.190006 -389.699977)
			(xy 65.151145 -389.728177) (xy 65.108348 -389.749948) (xy 65.062672 -389.764752) (xy 65.015242 -389.772226)
			(xy 64.991234 -389.772652) (xy 64.967571 -389.772185) (xy 64.920811 -389.76488) (xy 64.875736 -389.750454)
			(xy 64.833424 -389.729252) (xy 64.794885 -389.701781) (xy 64.761042 -389.668699) (xy 64.732703 -389.630794)
			(xy 64.721232 -389.610092) (xy 64.720978 -389.60933) (xy 64.323722 -388.922006) (xy 64.311541 -388.89879)
			(xy 64.294428 -388.849239) (xy 64.289686 -388.823454) (xy 64.289686 -388.8232) (xy 64.286112 -388.797979)
			(xy 63.757251 -388.797979) (xy 64.056006 -389.314944) (xy 64.05626 -389.315452) (xy 64.056514 -389.315452)
			(xy 64.057784 -389.317992) (xy 64.070054 -389.340909) (xy 64.087461 -389.389886) (xy 64.096336 -389.441101)
			(xy 64.0969 -389.46709) (xy 64.0969 -389.467344) (xy 64.096501 -389.491351) (xy 64.08898 -389.538774)
			(xy 64.07413 -389.584434) (xy 64.052316 -389.627208) (xy 64.024077 -389.666041) (xy 63.990108 -389.699976)
			(xy 63.951247 -389.728176) (xy 63.908451 -389.749947) (xy 63.862776 -389.764752) (xy 63.815346 -389.772225)
			(xy 63.791338 -389.772652) (xy 63.767675 -389.772182) (xy 63.720915 -389.764877) (xy 63.67584 -389.750452)
			(xy 63.633528 -389.729251) (xy 63.594989 -389.70178) (xy 63.561146 -389.668698) (xy 63.532807 -389.630794)
			(xy 63.521336 -389.610092) (xy 63.521082 -389.60933) (xy 63.123826 -388.922006) (xy 63.111646 -388.89879)
			(xy 63.094532 -388.849239) (xy 63.08979 -388.823454) (xy 63.08979 -388.8232) (xy 63.086378 -388.799387)
			(xy 63.086167 -388.751284) (xy 62.530115 -388.751284) (xy 62.855856 -389.314944) (xy 62.85611 -389.315452)
			(xy 62.856364 -389.315452) (xy 62.857634 -389.317992) (xy 62.869868 -389.340915) (xy 62.887188 -389.389902)
			(xy 62.895975 -389.441111) (xy 62.896496 -389.46709) (xy 62.896496 -389.467344) (xy 62.896078 -389.491337)
			(xy 62.888565 -389.538731) (xy 62.873731 -389.584367) (xy 62.851941 -389.627121) (xy 62.823731 -389.665939)
			(xy 62.789797 -389.699868) (xy 62.750973 -389.72807) (xy 62.708215 -389.749852) (xy 62.662577 -389.764678)
			(xy 62.615181 -389.772182) (xy 62.591188 -389.772652) (xy 62.567523 -389.772222) (xy 62.520762 -389.76491)
			(xy 62.475686 -389.750477) (xy 62.433374 -389.729269) (xy 62.394836 -389.701793) (xy 62.360994 -389.668705)
			(xy 62.332656 -389.630796) (xy 62.321186 -389.610092) (xy 62.320932 -389.60933) (xy 61.923676 -388.922006)
			(xy 61.911499 -388.898788) (xy 61.894383 -388.849238) (xy 61.88964 -388.823454) (xy 61.88964 -388.8232)
			(xy 61.886134 -388.799398) (xy 61.885922 -388.751286) (xy 61.330221 -388.751286) (xy 61.65596 -389.314944)
			(xy 61.656214 -389.315452) (xy 61.656468 -389.315452) (xy 61.657738 -389.317992) (xy 61.669973 -389.340915)
			(xy 61.687292 -389.389902) (xy 61.696079 -389.441111) (xy 61.6966 -389.46709) (xy 61.6966 -389.467344)
			(xy 61.696178 -389.491337) (xy 61.688665 -389.538731) (xy 61.673831 -389.584366) (xy 61.652041 -389.627119)
			(xy 61.623832 -389.665938) (xy 61.589898 -389.699866) (xy 61.551075 -389.728069) (xy 61.508318 -389.749851)
			(xy 61.46268 -389.764677) (xy 61.415285 -389.772182) (xy 61.391292 -389.772652) (xy 61.367627 -389.772219)
			(xy 61.320866 -389.764907) (xy 61.27579 -389.750475) (xy 61.233478 -389.729268) (xy 61.19494 -389.701792)
			(xy 61.161098 -389.668705) (xy 61.13276 -389.630796) (xy 61.12129 -389.610092) (xy 61.121036 -389.60933)
			(xy 60.72378 -388.922006) (xy 60.711603 -388.898788) (xy 60.694487 -388.849238) (xy 60.689744 -388.823454)
			(xy 60.689744 -388.8232) (xy 60.686231 -388.799399) (xy 60.686019 -388.751286) (xy 60.130325 -388.751286)
			(xy 60.456064 -389.314944) (xy 60.456318 -389.315452) (xy 60.456572 -389.315452) (xy 60.457842 -389.317992)
			(xy 60.470077 -389.340915) (xy 60.487396 -389.389902) (xy 60.496183 -389.441111) (xy 60.496704 -389.46709)
			(xy 60.496704 -389.467344) (xy 60.496278 -389.491337) (xy 60.488765 -389.53873) (xy 60.473931 -389.584365)
			(xy 60.452142 -389.627118) (xy 60.423933 -389.665937) (xy 60.39 -389.699865) (xy 60.351177 -389.728067)
			(xy 60.308421 -389.74985) (xy 60.262783 -389.764676) (xy 60.215389 -389.772182) (xy 60.191396 -389.772652)
			(xy 60.167731 -389.772216) (xy 60.12097 -389.764905) (xy 60.075895 -389.750473) (xy 60.033582 -389.729266)
			(xy 59.995044 -389.701791) (xy 59.961202 -389.668704) (xy 59.932864 -389.630796) (xy 59.921394 -389.610092)
			(xy 59.92114 -389.60933) (xy 59.523884 -388.922006) (xy 59.511708 -388.898788) (xy 59.494591 -388.849238)
			(xy 59.489848 -388.823454) (xy 59.489848 -388.8232) (xy 59.486327 -388.799399) (xy 59.486115 -388.751286)
			(xy 58.930175 -388.751286) (xy 59.255914 -389.314944) (xy 59.256168 -389.315452) (xy 59.256422 -389.315452)
			(xy 59.257692 -389.317992) (xy 59.269962 -389.340908) (xy 59.287369 -389.389886) (xy 59.296244 -389.441101)
			(xy 59.296808 -389.46709) (xy 59.296808 -389.467344) (xy 59.296401 -389.491351) (xy 59.28888 -389.538772)
			(xy 59.27403 -389.584432) (xy 59.252217 -389.627206) (xy 59.223979 -389.666038) (xy 59.190011 -389.699973)
			(xy 59.151151 -389.728173) (xy 59.108357 -389.749944) (xy 59.062682 -389.76475) (xy 59.015253 -389.772225)
			(xy 58.991246 -389.772652) (xy 58.967583 -389.772176) (xy 58.920824 -389.764872) (xy 58.875749 -389.750448)
			(xy 58.833437 -389.729248) (xy 58.794898 -389.701778) (xy 58.761054 -389.668697) (xy 58.732715 -389.630794)
			(xy 58.721244 -389.610092) (xy 58.72099 -389.60933) (xy 58.323734 -388.922006) (xy 58.311554 -388.89879)
			(xy 58.29444 -388.849239) (xy 58.289698 -388.823454) (xy 58.289698 -388.8232) (xy 58.286271 -388.799389)
			(xy 58.28606 -388.751284) (xy 57.730277 -388.751284) (xy 58.056018 -389.314944) (xy 58.056272 -389.315452)
			(xy 58.056526 -389.315452) (xy 58.057796 -389.317992) (xy 58.070067 -389.340908) (xy 58.087474 -389.389886)
			(xy 58.096348 -389.441101) (xy 58.096912 -389.46709) (xy 58.096912 -389.467344) (xy 58.096502 -389.491351)
			(xy 58.08898 -389.538772) (xy 58.074131 -389.584432) (xy 58.052318 -389.627205) (xy 58.02408 -389.666037)
			(xy 57.990113 -389.699971) (xy 57.951253 -389.728172) (xy 57.908459 -389.749943) (xy 57.862786 -389.764749)
			(xy 57.815357 -389.772225) (xy 57.79135 -389.772652) (xy 57.767687 -389.772172) (xy 57.720928 -389.764869)
			(xy 57.675853 -389.750446) (xy 57.633541 -389.729246) (xy 57.595002 -389.701777) (xy 57.561159 -389.668696)
			(xy 57.532819 -389.630793) (xy 57.521348 -389.610092) (xy 57.521094 -389.60933) (xy 57.123838 -388.922006)
			(xy 57.111658 -388.89879) (xy 57.094544 -388.849239) (xy 57.089802 -388.823454) (xy 57.089802 -388.8232)
			(xy 57.086367 -388.799389) (xy 57.086156 -388.751284) (xy 56.530127 -388.751284) (xy 56.855868 -389.314944)
			(xy 56.856122 -389.315452) (xy 56.856376 -389.315452) (xy 56.857646 -389.317992) (xy 56.869881 -389.340915)
			(xy 56.8872 -389.389902) (xy 56.895987 -389.441111) (xy 56.896508 -389.46709) (xy 56.896508 -389.467344)
			(xy 56.896078 -389.491336) (xy 56.888565 -389.53873) (xy 56.873732 -389.584364) (xy 56.851943 -389.627117)
			(xy 56.823735 -389.665935) (xy 56.789802 -389.699863) (xy 56.750979 -389.728066) (xy 56.708224 -389.749849)
			(xy 56.662587 -389.764676) (xy 56.615192 -389.772181) (xy 56.5912 -389.772652) (xy 56.567536 -389.772213)
			(xy 56.520775 -389.764902) (xy 56.475699 -389.750471) (xy 56.433387 -389.729265) (xy 56.394849 -389.70179)
			(xy 56.361006 -389.668703) (xy 56.332668 -389.630796) (xy 56.321198 -389.610092) (xy 56.320944 -389.60933)
			(xy 55.923688 -388.922006) (xy 55.911512 -388.898788) (xy 55.894395 -388.849238) (xy 55.889652 -388.823454)
			(xy 55.889652 -388.8232) (xy 55.886123 -388.7994) (xy 55.885912 -388.751286) (xy 55.330233 -388.751286)
			(xy 55.655972 -389.314944) (xy 55.656226 -389.315452) (xy 55.65648 -389.315452) (xy 55.65775 -389.317992)
			(xy 55.669986 -389.340915) (xy 55.687304 -389.389901) (xy 55.696091 -389.441111) (xy 55.696612 -389.46709)
			(xy 55.696612 -389.467344) (xy 55.696178 -389.491336) (xy 55.688665 -389.538729) (xy 55.673832 -389.584363)
			(xy 55.652044 -389.627116) (xy 55.623836 -389.665934) (xy 55.589903 -389.699862) (xy 55.551082 -389.728065)
			(xy 55.508326 -389.749848) (xy 55.46269 -389.764675) (xy 55.415296 -389.772181) (xy 55.391304 -389.772652)
			(xy 55.36764 -389.772209) (xy 55.320879 -389.764899) (xy 55.275803 -389.750469) (xy 55.233491 -389.729263)
			(xy 55.194953 -389.701789) (xy 55.16111 -389.668703) (xy 55.132772 -389.630796) (xy 55.121302 -389.610092)
			(xy 55.121048 -389.60933) (xy 54.723792 -388.922006) (xy 54.711609 -388.898791) (xy 54.694497 -388.849239)
			(xy 54.689756 -388.823454) (xy 54.689756 -388.8232) (xy 54.68622 -388.799401) (xy 54.686008 -388.751286)
			(xy 54.130337 -388.751286) (xy 54.456076 -389.314944) (xy 54.45633 -389.315452) (xy 54.456584 -389.315452)
			(xy 54.457854 -389.317992) (xy 54.47009 -389.340915) (xy 54.487408 -389.389901) (xy 54.496195 -389.441111)
			(xy 54.496716 -389.46709) (xy 54.496716 -389.467344) (xy 54.496278 -389.491336) (xy 54.488766 -389.538728)
			(xy 54.473933 -389.584362) (xy 54.452144 -389.627115) (xy 54.423937 -389.665932) (xy 54.390005 -389.69986)
			(xy 54.351184 -389.728063) (xy 54.308429 -389.749846) (xy 54.262793 -389.764674) (xy 54.2154 -389.772181)
			(xy 54.191408 -389.772652) (xy 54.167744 -389.772206) (xy 54.120983 -389.764897) (xy 54.075908 -389.750467)
			(xy 54.033595 -389.729262) (xy 53.995057 -389.701788) (xy 53.961215 -389.668702) (xy 53.932876 -389.630795)
			(xy 53.921406 -389.610092) (xy 53.921152 -389.60933) (xy 53.523896 -388.922006) (xy 53.511714 -388.898791)
			(xy 53.494601 -388.849239) (xy 53.48986 -388.823454) (xy 53.48986 -388.8232) (xy 53.486316 -388.799402)
			(xy 53.486104 -388.751287) (xy 52.930187 -388.751287) (xy 53.255926 -389.314944) (xy 53.25618 -389.315452)
			(xy 53.256434 -389.315452) (xy 53.257704 -389.317992) (xy 53.269975 -389.340908) (xy 53.287382 -389.389886)
			(xy 53.296256 -389.441101) (xy 53.29682 -389.46709) (xy 53.29682 -389.467344) (xy 53.296402 -389.49135)
			(xy 53.288881 -389.538771) (xy 53.274031 -389.58443) (xy 53.252219 -389.627202) (xy 53.223982 -389.666034)
			(xy 53.190016 -389.699969) (xy 53.151158 -389.728169) (xy 53.108365 -389.749941) (xy 53.062692 -389.764748)
			(xy 53.015265 -389.772224) (xy 52.991258 -389.772652) (xy 52.967595 -389.772166) (xy 52.920836 -389.764864)
			(xy 52.875762 -389.750442) (xy 52.83345 -389.729243) (xy 52.794911 -389.701775) (xy 52.761067 -389.668695)
			(xy 52.732727 -389.630793) (xy 52.721256 -389.610092) (xy 52.721002 -389.60933) (xy 52.323746 -388.922006)
			(xy 52.311567 -388.898789) (xy 52.294452 -388.849239) (xy 52.28971 -388.823454) (xy 52.28971 -388.8232)
			(xy 52.28626 -388.799391) (xy 52.286049 -388.751284) (xy 51.730289 -388.751284) (xy 52.05603 -389.314944)
			(xy 52.056284 -389.315452) (xy 52.056538 -389.315452) (xy 52.057808 -389.317992) (xy 52.07008 -389.340908)
			(xy 52.087486 -389.389886) (xy 52.09636 -389.441101) (xy 52.096924 -389.46709) (xy 52.096924 -389.467344)
			(xy 52.096502 -389.49135) (xy 52.088981 -389.53877) (xy 52.074132 -389.584429) (xy 52.05232 -389.627201)
			(xy 52.024084 -389.666033) (xy 51.990118 -389.699967) (xy 51.95126 -389.728168) (xy 51.908468 -389.74994)
			(xy 51.862795 -389.764747) (xy 51.815369 -389.772224) (xy 51.791362 -389.772652) (xy 51.767699 -389.772163)
			(xy 51.720941 -389.764861) (xy 51.675866 -389.750439) (xy 51.633554 -389.729241) (xy 51.595015 -389.701774)
			(xy 51.561171 -389.668695) (xy 51.532831 -389.630793) (xy 51.52136 -389.610092) (xy 51.521106 -389.60933)
			(xy 51.12385 -388.922006) (xy 51.111671 -388.898789) (xy 51.094556 -388.849239) (xy 51.089814 -388.823454)
			(xy 51.089814 -388.8232) (xy 51.086357 -388.799392) (xy 51.086146 -388.751285) (xy 50.53014 -388.751285)
			(xy 50.85588 -389.314944) (xy 50.856134 -389.315452) (xy 50.856388 -389.315452) (xy 50.857658 -389.317992)
			(xy 50.869894 -389.340914) (xy 50.887212 -389.389901) (xy 50.895999 -389.441111) (xy 50.89652 -389.46709)
			(xy 50.89652 -389.467344) (xy 50.896078 -389.491336) (xy 50.888566 -389.538728) (xy 50.873733 -389.584362)
			(xy 50.851945 -389.627113) (xy 50.823738 -389.665931) (xy 50.789807 -389.699859) (xy 50.750986 -389.728062)
			(xy 50.708232 -389.749845) (xy 50.662597 -389.764673) (xy 50.615204 -389.772181) (xy 50.591212 -389.772652)
			(xy 50.567548 -389.772203) (xy 50.520787 -389.764894) (xy 50.475712 -389.750465) (xy 50.4334 -389.72926)
			(xy 50.394862 -389.701787) (xy 50.361019 -389.668702) (xy 50.33268 -389.630795) (xy 50.32121 -389.610092)
			(xy 50.320956 -389.60933) (xy 49.9237 -388.922006) (xy 49.911518 -388.898791) (xy 49.894405 -388.849239)
			(xy 49.889664 -388.823454) (xy 49.889664 -388.8232) (xy 49.886113 -388.799403) (xy 49.885901 -388.751287)
			(xy 49.330245 -388.751287) (xy 49.655984 -389.314944) (xy 49.656238 -389.315452) (xy 49.656492 -389.315452)
			(xy 49.657762 -389.317992) (xy 49.669999 -389.340914) (xy 49.687316 -389.389901) (xy 49.696103 -389.441111)
			(xy 49.696624 -389.46709) (xy 49.696624 -389.467344) (xy 49.696178 -389.491336) (xy 49.688666 -389.538727)
			(xy 49.673833 -389.584361) (xy 49.652046 -389.627112) (xy 49.623839 -389.66593) (xy 49.589908 -389.699858)
			(xy 49.551088 -389.72806) (xy 49.508335 -389.749844) (xy 49.4627 -389.764672) (xy 49.415308 -389.77218)
			(xy 49.391316 -389.772652) (xy 49.367652 -389.7722) (xy 49.320892 -389.764892) (xy 49.275816 -389.750463)
			(xy 49.233504 -389.729259) (xy 49.194966 -389.701786) (xy 49.161123 -389.668701) (xy 49.132784 -389.630795)
			(xy 49.121314 -389.610092) (xy 49.12106 -389.60933) (xy 48.723804 -388.922006) (xy 48.711622 -388.898791)
			(xy 48.694509 -388.849239) (xy 48.689768 -388.823454) (xy 48.689768 -388.8232) (xy 48.686228 -388.797975)
			(xy 48.15733 -388.797975) (xy 48.456088 -389.314944) (xy 48.456342 -389.315452) (xy 48.456596 -389.315452)
			(xy 48.457866 -389.317992) (xy 48.470103 -389.340914) (xy 48.48742 -389.389901) (xy 48.496207 -389.441111)
			(xy 48.496728 -389.46709) (xy 48.496728 -389.467344) (xy 48.496278 -389.491335) (xy 48.488766 -389.538727)
			(xy 48.473934 -389.58436) (xy 48.452147 -389.627111) (xy 48.423941 -389.665928) (xy 48.39001 -389.699856)
			(xy 48.351191 -389.728059) (xy 48.308437 -389.749843) (xy 48.262803 -389.764672) (xy 48.215411 -389.77218)
			(xy 48.19142 -389.772652) (xy 48.167756 -389.772196) (xy 48.120996 -389.764889) (xy 48.075921 -389.750461)
			(xy 48.033608 -389.729257) (xy 47.99507 -389.701785) (xy 47.961227 -389.668701) (xy 47.932888 -389.630795)
			(xy 47.921418 -389.610092) (xy 47.921164 -389.60933) (xy 47.523908 -388.922006) (xy 47.511727 -388.898791)
			(xy 47.494614 -388.849239) (xy 47.489872 -388.823454) (xy 47.489872 -388.8232) (xy 47.486325 -388.797976)
			(xy 2.509012 -388.797976) (xy 2.509012 -390.75106) (xy 297.048936 -390.75106) (xy 297.048936 -389.88746)
			(xy 297.049422 -389.860209) (xy 297.057178 -389.806261) (xy 297.072533 -389.753966) (xy 297.095175 -389.704389)
			(xy 297.124641 -389.658539) (xy 297.160332 -389.617348) (xy 297.201523 -389.581657) (xy 297.247373 -389.552191)
			(xy 297.29695 -389.529549) (xy 297.349245 -389.514194) (xy 297.403193 -389.506438) (xy 297.457695 -389.506438)
			(xy 297.511643 -389.514194) (xy 297.563938 -389.529549) (xy 297.613515 -389.552191) (xy 297.659365 -389.581657)
			(xy 297.700556 -389.617348) (xy 297.736247 -389.658539) (xy 297.765713 -389.704389) (xy 297.788355 -389.753966)
			(xy 297.80371 -389.806261) (xy 297.811466 -389.860209) (xy 297.811952 -389.88746) (xy 297.811952 -390.75106)
			(xy 329.576684 -390.75106) (xy 329.576684 -389.88746) (xy 329.57717 -389.860209) (xy 329.584926 -389.806261)
			(xy 329.600281 -389.753966) (xy 329.622923 -389.704389) (xy 329.652389 -389.658539) (xy 329.68808 -389.617348)
			(xy 329.729271 -389.581657) (xy 329.775121 -389.552191) (xy 329.824698 -389.529549) (xy 329.876993 -389.514194)
			(xy 329.930941 -389.506438) (xy 329.985443 -389.506438) (xy 330.039391 -389.514194) (xy 330.091686 -389.529549)
			(xy 330.141263 -389.552191) (xy 330.187113 -389.581657) (xy 330.228304 -389.617348) (xy 330.263995 -389.658539)
			(xy 330.293461 -389.704389) (xy 330.316103 -389.753966) (xy 330.331458 -389.806261) (xy 330.339214 -389.860209)
			(xy 330.3397 -389.88746) (xy 330.3397 -390.75106) (xy 364.149132 -390.75106) (xy 364.149132 -389.88746)
			(xy 364.149618 -389.860209) (xy 364.157374 -389.806261) (xy 364.172729 -389.753966) (xy 364.195371 -389.704389)
			(xy 364.224837 -389.658539) (xy 364.260528 -389.617348) (xy 364.301719 -389.581657) (xy 364.347569 -389.552191)
			(xy 364.397146 -389.529549) (xy 364.449441 -389.514194) (xy 364.503389 -389.506438) (xy 364.557891 -389.506438)
			(xy 364.611839 -389.514194) (xy 364.664134 -389.529549) (xy 364.713711 -389.552191) (xy 364.759561 -389.581657)
			(xy 364.800752 -389.617348) (xy 364.836443 -389.658539) (xy 364.865909 -389.704389) (xy 364.888551 -389.753966)
			(xy 364.903906 -389.806261) (xy 364.911662 -389.860209) (xy 364.912148 -389.88746) (xy 364.912148 -390.75106)
			(xy 396.67688 -390.75106) (xy 396.67688 -389.88746) (xy 396.677366 -389.860209) (xy 396.685122 -389.806261)
			(xy 396.700477 -389.753966) (xy 396.723119 -389.704389) (xy 396.752585 -389.658539) (xy 396.788276 -389.617348)
			(xy 396.829467 -389.581657) (xy 396.875317 -389.552191) (xy 396.924894 -389.529549) (xy 396.977189 -389.514194)
			(xy 397.031137 -389.506438) (xy 397.085639 -389.506438) (xy 397.139587 -389.514194) (xy 397.191882 -389.529549)
			(xy 397.241459 -389.552191) (xy 397.287309 -389.581657) (xy 397.3285 -389.617348) (xy 397.364191 -389.658539)
			(xy 397.393657 -389.704389) (xy 397.416299 -389.753966) (xy 397.431654 -389.806261) (xy 397.43941 -389.860209)
			(xy 397.439896 -389.88746) (xy 397.439896 -390.75106) (xy 397.43941 -390.778311) (xy 397.431654 -390.832259)
			(xy 397.416299 -390.884554) (xy 397.393657 -390.934131) (xy 397.364191 -390.979981) (xy 397.3285 -391.021172)
			(xy 397.287309 -391.056863) (xy 397.241459 -391.086329) (xy 397.191882 -391.108971) (xy 397.139587 -391.124326)
			(xy 397.085639 -391.132082) (xy 397.031137 -391.132082) (xy 396.977189 -391.124326) (xy 396.924894 -391.108971)
			(xy 396.875317 -391.086329) (xy 396.829467 -391.056863) (xy 396.788276 -391.021172) (xy 396.752585 -390.979981)
			(xy 396.723119 -390.934131) (xy 396.700477 -390.884554) (xy 396.685122 -390.832259) (xy 396.677366 -390.778311)
			(xy 396.67688 -390.75106) (xy 364.912148 -390.75106) (xy 364.911662 -390.778311) (xy 364.903906 -390.832259)
			(xy 364.888551 -390.884554) (xy 364.865909 -390.934131) (xy 364.836443 -390.979981) (xy 364.800752 -391.021172)
			(xy 364.759561 -391.056863) (xy 364.713711 -391.086329) (xy 364.664134 -391.108971) (xy 364.611839 -391.124326)
			(xy 364.557891 -391.132082) (xy 364.503389 -391.132082) (xy 364.449441 -391.124326) (xy 364.397146 -391.108971)
			(xy 364.347569 -391.086329) (xy 364.301719 -391.056863) (xy 364.260528 -391.021172) (xy 364.224837 -390.979981)
			(xy 364.195371 -390.934131) (xy 364.172729 -390.884554) (xy 364.157374 -390.832259) (xy 364.149618 -390.778311)
			(xy 364.149132 -390.75106) (xy 330.3397 -390.75106) (xy 330.339214 -390.778311) (xy 330.331458 -390.832259)
			(xy 330.316103 -390.884554) (xy 330.293461 -390.934131) (xy 330.263995 -390.979981) (xy 330.228304 -391.021172)
			(xy 330.187113 -391.056863) (xy 330.141263 -391.086329) (xy 330.091686 -391.108971) (xy 330.039391 -391.124326)
			(xy 329.985443 -391.132082) (xy 329.930941 -391.132082) (xy 329.876993 -391.124326) (xy 329.824698 -391.108971)
			(xy 329.775121 -391.086329) (xy 329.729271 -391.056863) (xy 329.68808 -391.021172) (xy 329.652389 -390.979981)
			(xy 329.622923 -390.934131) (xy 329.600281 -390.884554) (xy 329.584926 -390.832259) (xy 329.57717 -390.778311)
			(xy 329.576684 -390.75106) (xy 297.811952 -390.75106) (xy 297.811466 -390.778311) (xy 297.80371 -390.832259)
			(xy 297.788355 -390.884554) (xy 297.765713 -390.934131) (xy 297.736247 -390.979981) (xy 297.700556 -391.021172)
			(xy 297.659365 -391.056863) (xy 297.613515 -391.086329) (xy 297.563938 -391.108971) (xy 297.511643 -391.124326)
			(xy 297.457695 -391.132082) (xy 297.403193 -391.132082) (xy 297.349245 -391.124326) (xy 297.29695 -391.108971)
			(xy 297.247373 -391.086329) (xy 297.201523 -391.056863) (xy 297.160332 -391.021172) (xy 297.124641 -390.979981)
			(xy 297.095175 -390.934131) (xy 297.072533 -390.884554) (xy 297.057178 -390.832259) (xy 297.049422 -390.778311)
			(xy 297.048936 -390.75106) (xy 2.509012 -390.75106) (xy 2.509012 -393.292838) (xy 47.435008 -393.292838)
			(xy 47.435008 -392.429238) (xy 47.435494 -392.401987) (xy 47.44325 -392.348039) (xy 47.458605 -392.295744)
			(xy 47.481247 -392.246167) (xy 47.510713 -392.200317) (xy 47.546404 -392.159126) (xy 47.587595 -392.123435)
			(xy 47.633445 -392.093969) (xy 47.683022 -392.071327) (xy 47.735317 -392.055972) (xy 47.789265 -392.048216)
			(xy 47.843767 -392.048216) (xy 47.897715 -392.055972) (xy 47.95001 -392.071327) (xy 47.999587 -392.093969)
			(xy 48.045437 -392.123435) (xy 48.086628 -392.159126) (xy 48.122319 -392.200317) (xy 48.151785 -392.246167)
			(xy 48.174427 -392.295744) (xy 48.189782 -392.348039) (xy 48.197538 -392.401987) (xy 48.198024 -392.429238)
			(xy 48.198024 -393.292838) (xy 48.634904 -393.292838) (xy 48.634904 -392.429238) (xy 48.63539 -392.401987)
			(xy 48.643146 -392.348039) (xy 48.658501 -392.295744) (xy 48.681143 -392.246167) (xy 48.710609 -392.200317)
			(xy 48.7463 -392.159126) (xy 48.787491 -392.123435) (xy 48.833341 -392.093969) (xy 48.882918 -392.071327)
			(xy 48.935213 -392.055972) (xy 48.989161 -392.048216) (xy 49.043663 -392.048216) (xy 49.097611 -392.055972)
			(xy 49.149906 -392.071327) (xy 49.199483 -392.093969) (xy 49.245333 -392.123435) (xy 49.286524 -392.159126)
			(xy 49.322215 -392.200317) (xy 49.351681 -392.246167) (xy 49.374323 -392.295744) (xy 49.389678 -392.348039)
			(xy 49.397434 -392.401987) (xy 49.39792 -392.429238) (xy 49.39792 -393.292838) (xy 49.8348 -393.292838)
			(xy 49.8348 -392.429238) (xy 49.835286 -392.401969) (xy 49.843048 -392.347985) (xy 49.858413 -392.295655)
			(xy 49.88107 -392.246045) (xy 49.910556 -392.200164) (xy 49.946271 -392.158947) (xy 49.987488 -392.123232)
			(xy 50.033369 -392.093746) (xy 50.082979 -392.071089) (xy 50.135309 -392.055724) (xy 50.189293 -392.047962)
			(xy 50.243831 -392.047962) (xy 50.297815 -392.055724) (xy 50.350145 -392.071089) (xy 50.399755 -392.093746)
			(xy 50.445636 -392.123232) (xy 50.486853 -392.158947) (xy 50.522568 -392.200164) (xy 50.552054 -392.246045)
			(xy 50.574711 -392.295655) (xy 50.590076 -392.347985) (xy 50.597838 -392.401969) (xy 50.598324 -392.429238)
			(xy 50.598324 -393.292838) (xy 51.034696 -393.292838) (xy 51.034696 -392.429238) (xy 51.035182 -392.401969)
			(xy 51.042944 -392.347985) (xy 51.058309 -392.295655) (xy 51.080966 -392.246045) (xy 51.110452 -392.200164)
			(xy 51.146167 -392.158947) (xy 51.187384 -392.123232) (xy 51.233265 -392.093746) (xy 51.282875 -392.071089)
			(xy 51.335205 -392.055724) (xy 51.389189 -392.047962) (xy 51.443727 -392.047962) (xy 51.497711 -392.055724)
			(xy 51.550041 -392.071089) (xy 51.599651 -392.093746) (xy 51.645532 -392.123232) (xy 51.686749 -392.158947)
			(xy 51.722464 -392.200164) (xy 51.75195 -392.246045) (xy 51.774607 -392.295655) (xy 51.789972 -392.347985)
			(xy 51.797734 -392.401969) (xy 51.79822 -392.429238) (xy 51.79822 -393.292838) (xy 52.2351 -393.292838)
			(xy 52.2351 -392.429238) (xy 52.235586 -392.401987) (xy 52.243342 -392.348039) (xy 52.258697 -392.295744)
			(xy 52.281339 -392.246167) (xy 52.310805 -392.200317) (xy 52.346496 -392.159126) (xy 52.387687 -392.123435)
			(xy 52.433537 -392.093969) (xy 52.483114 -392.071327) (xy 52.535409 -392.055972) (xy 52.589357 -392.048216)
			(xy 52.643859 -392.048216) (xy 52.697807 -392.055972) (xy 52.750102 -392.071327) (xy 52.799679 -392.093969)
			(xy 52.845529 -392.123435) (xy 52.88672 -392.159126) (xy 52.922411 -392.200317) (xy 52.951877 -392.246167)
			(xy 52.974519 -392.295744) (xy 52.989874 -392.348039) (xy 52.99763 -392.401987) (xy 52.998116 -392.429238)
			(xy 52.998116 -393.292838) (xy 53.434996 -393.292838) (xy 53.434996 -392.429238) (xy 53.435482 -392.401987)
			(xy 53.443238 -392.348039) (xy 53.458593 -392.295744) (xy 53.481235 -392.246167) (xy 53.510701 -392.200317)
			(xy 53.546392 -392.159126) (xy 53.587583 -392.123435) (xy 53.633433 -392.093969) (xy 53.68301 -392.071327)
			(xy 53.735305 -392.055972) (xy 53.789253 -392.048216) (xy 53.843755 -392.048216) (xy 53.897703 -392.055972)
			(xy 53.949998 -392.071327) (xy 53.999575 -392.093969) (xy 54.045425 -392.123435) (xy 54.086616 -392.159126)
			(xy 54.122307 -392.200317) (xy 54.151773 -392.246167) (xy 54.174415 -392.295744) (xy 54.18977 -392.348039)
			(xy 54.197526 -392.401987) (xy 54.198012 -392.429238) (xy 54.198012 -393.292838) (xy 54.634892 -393.292838)
			(xy 54.634892 -392.429238) (xy 54.635378 -392.401969) (xy 54.64314 -392.347985) (xy 54.658505 -392.295655)
			(xy 54.681162 -392.246045) (xy 54.710648 -392.200164) (xy 54.746363 -392.158947) (xy 54.78758 -392.123232)
			(xy 54.833461 -392.093746) (xy 54.883071 -392.071089) (xy 54.935401 -392.055724) (xy 54.989385 -392.047962)
			(xy 55.043923 -392.047962) (xy 55.097907 -392.055724) (xy 55.150237 -392.071089) (xy 55.199847 -392.093746)
			(xy 55.245728 -392.123232) (xy 55.286945 -392.158947) (xy 55.32266 -392.200164) (xy 55.352146 -392.246045)
			(xy 55.374803 -392.295655) (xy 55.390168 -392.347985) (xy 55.39793 -392.401969) (xy 55.398416 -392.429238)
			(xy 55.398416 -393.292838) (xy 55.834788 -393.292838) (xy 55.834788 -392.429238) (xy 55.835274 -392.401969)
			(xy 55.843036 -392.347985) (xy 55.858401 -392.295655) (xy 55.881058 -392.246045) (xy 55.910544 -392.200164)
			(xy 55.946259 -392.158947) (xy 55.987476 -392.123232) (xy 56.033357 -392.093746) (xy 56.082967 -392.071089)
			(xy 56.135297 -392.055724) (xy 56.189281 -392.047962) (xy 56.243819 -392.047962) (xy 56.297803 -392.055724)
			(xy 56.350133 -392.071089) (xy 56.399743 -392.093746) (xy 56.445624 -392.123232) (xy 56.486841 -392.158947)
			(xy 56.522556 -392.200164) (xy 56.552042 -392.246045) (xy 56.574699 -392.295655) (xy 56.590064 -392.347985)
			(xy 56.597826 -392.401969) (xy 56.598312 -392.429238) (xy 56.598312 -393.292838) (xy 57.035192 -393.292838)
			(xy 57.035192 -392.429238) (xy 57.035678 -392.401987) (xy 57.043434 -392.348039) (xy 57.058789 -392.295744)
			(xy 57.081431 -392.246167) (xy 57.110897 -392.200317) (xy 57.146588 -392.159126) (xy 57.187779 -392.123435)
			(xy 57.233629 -392.093969) (xy 57.283206 -392.071327) (xy 57.335501 -392.055972) (xy 57.389449 -392.048216)
			(xy 57.443951 -392.048216) (xy 57.497899 -392.055972) (xy 57.550194 -392.071327) (xy 57.599771 -392.093969)
			(xy 57.645621 -392.123435) (xy 57.686812 -392.159126) (xy 57.722503 -392.200317) (xy 57.751969 -392.246167)
			(xy 57.774611 -392.295744) (xy 57.789966 -392.348039) (xy 57.797722 -392.401987) (xy 57.798208 -392.429238)
			(xy 57.798208 -393.292838) (xy 58.235088 -393.292838) (xy 58.235088 -392.429238) (xy 58.235574 -392.401987)
			(xy 58.24333 -392.348039) (xy 58.258685 -392.295744) (xy 58.281327 -392.246167) (xy 58.310793 -392.200317)
			(xy 58.346484 -392.159126) (xy 58.387675 -392.123435) (xy 58.433525 -392.093969) (xy 58.483102 -392.071327)
			(xy 58.535397 -392.055972) (xy 58.589345 -392.048216) (xy 58.643847 -392.048216) (xy 58.697795 -392.055972)
			(xy 58.75009 -392.071327) (xy 58.799667 -392.093969) (xy 58.845517 -392.123435) (xy 58.886708 -392.159126)
			(xy 58.922399 -392.200317) (xy 58.951865 -392.246167) (xy 58.974507 -392.295744) (xy 58.989862 -392.348039)
			(xy 58.997618 -392.401987) (xy 58.998104 -392.429238) (xy 58.998104 -393.292838) (xy 59.434984 -393.292838)
			(xy 59.434984 -392.429238) (xy 59.43547 -392.401969) (xy 59.443232 -392.347985) (xy 59.458597 -392.295655)
			(xy 59.481254 -392.246045) (xy 59.51074 -392.200164) (xy 59.546455 -392.158947) (xy 59.587672 -392.123232)
			(xy 59.633553 -392.093746) (xy 59.683163 -392.071089) (xy 59.735493 -392.055724) (xy 59.789477 -392.047962)
			(xy 59.844015 -392.047962) (xy 59.897999 -392.055724) (xy 59.950329 -392.071089) (xy 59.999939 -392.093746)
			(xy 60.04582 -392.123232) (xy 60.087037 -392.158947) (xy 60.122752 -392.200164) (xy 60.152238 -392.246045)
			(xy 60.174895 -392.295655) (xy 60.19026 -392.347985) (xy 60.198022 -392.401969) (xy 60.198508 -392.429238)
			(xy 60.198508 -393.292838) (xy 60.63488 -393.292838) (xy 60.63488 -392.429238) (xy 60.635366 -392.401969)
			(xy 60.643128 -392.347985) (xy 60.658493 -392.295655) (xy 60.68115 -392.246045) (xy 60.710636 -392.200164)
			(xy 60.746351 -392.158947) (xy 60.787568 -392.123232) (xy 60.833449 -392.093746) (xy 60.883059 -392.071089)
			(xy 60.935389 -392.055724) (xy 60.989373 -392.047962) (xy 61.043911 -392.047962) (xy 61.097895 -392.055724)
			(xy 61.150225 -392.071089) (xy 61.199835 -392.093746) (xy 61.245716 -392.123232) (xy 61.286933 -392.158947)
			(xy 61.322648 -392.200164) (xy 61.352134 -392.246045) (xy 61.374791 -392.295655) (xy 61.390156 -392.347985)
			(xy 61.397918 -392.401969) (xy 61.398404 -392.429238) (xy 61.398404 -393.292838) (xy 61.834776 -393.292838)
			(xy 61.834776 -392.429238) (xy 61.835262 -392.401969) (xy 61.843024 -392.347985) (xy 61.858389 -392.295655)
			(xy 61.881046 -392.246045) (xy 61.910532 -392.200164) (xy 61.946247 -392.158947) (xy 61.987464 -392.123232)
			(xy 62.033345 -392.093746) (xy 62.082955 -392.071089) (xy 62.135285 -392.055724) (xy 62.189269 -392.047962)
			(xy 62.243807 -392.047962) (xy 62.297791 -392.055724) (xy 62.350121 -392.071089) (xy 62.399731 -392.093746)
			(xy 62.445612 -392.123232) (xy 62.486829 -392.158947) (xy 62.522544 -392.200164) (xy 62.55203 -392.246045)
			(xy 62.574687 -392.295655) (xy 62.590052 -392.347985) (xy 62.597814 -392.401969) (xy 62.5983 -392.429238)
			(xy 62.5983 -393.292838) (xy 63.034672 -393.292838) (xy 63.034672 -392.429238) (xy 63.035158 -392.401969)
			(xy 63.04292 -392.347985) (xy 63.058285 -392.295655) (xy 63.080942 -392.246045) (xy 63.110428 -392.200164)
			(xy 63.146143 -392.158947) (xy 63.18736 -392.123232) (xy 63.233241 -392.093746) (xy 63.282851 -392.071089)
			(xy 63.335181 -392.055724) (xy 63.389165 -392.047962) (xy 63.443703 -392.047962) (xy 63.497687 -392.055724)
			(xy 63.550017 -392.071089) (xy 63.599627 -392.093746) (xy 63.645508 -392.123232) (xy 63.686725 -392.158947)
			(xy 63.72244 -392.200164) (xy 63.751926 -392.246045) (xy 63.774583 -392.295655) (xy 63.789948 -392.347985)
			(xy 63.79771 -392.401969) (xy 63.798196 -392.429238) (xy 63.798196 -393.292838) (xy 64.235076 -393.292838)
			(xy 64.235076 -392.429238) (xy 64.235562 -392.401987) (xy 64.243318 -392.348039) (xy 64.258673 -392.295744)
			(xy 64.281315 -392.246167) (xy 64.310781 -392.200317) (xy 64.346472 -392.159126) (xy 64.387663 -392.123435)
			(xy 64.433513 -392.093969) (xy 64.48309 -392.071327) (xy 64.535385 -392.055972) (xy 64.589333 -392.048216)
			(xy 64.643835 -392.048216) (xy 64.697783 -392.055972) (xy 64.750078 -392.071327) (xy 64.799655 -392.093969)
			(xy 64.845505 -392.123435) (xy 64.886696 -392.159126) (xy 64.922387 -392.200317) (xy 64.951853 -392.246167)
			(xy 64.974495 -392.295744) (xy 64.98985 -392.348039) (xy 64.997606 -392.401987) (xy 64.998092 -392.429238)
			(xy 64.998092 -393.292838) (xy 65.434972 -393.292838) (xy 65.434972 -392.429238) (xy 65.435458 -392.401987)
			(xy 65.443214 -392.348039) (xy 65.458569 -392.295744) (xy 65.481211 -392.246167) (xy 65.510677 -392.200317)
			(xy 65.546368 -392.159126) (xy 65.587559 -392.123435) (xy 65.633409 -392.093969) (xy 65.682986 -392.071327)
			(xy 65.735281 -392.055972) (xy 65.789229 -392.048216) (xy 65.843731 -392.048216) (xy 65.897679 -392.055972)
			(xy 65.949974 -392.071327) (xy 65.999551 -392.093969) (xy 66.045401 -392.123435) (xy 66.086592 -392.159126)
			(xy 66.122283 -392.200317) (xy 66.151749 -392.246167) (xy 66.174391 -392.295744) (xy 66.189746 -392.348039)
			(xy 66.197502 -392.401987) (xy 66.197988 -392.429238) (xy 66.197988 -393.292838) (xy 79.962756 -393.292838)
			(xy 79.962756 -392.429238) (xy 79.963242 -392.401987) (xy 79.970998 -392.348039) (xy 79.986353 -392.295744)
			(xy 80.008995 -392.246167) (xy 80.038461 -392.200317) (xy 80.074152 -392.159126) (xy 80.115343 -392.123435)
			(xy 80.161193 -392.093969) (xy 80.21077 -392.071327) (xy 80.263065 -392.055972) (xy 80.317013 -392.048216)
			(xy 80.371515 -392.048216) (xy 80.425463 -392.055972) (xy 80.477758 -392.071327) (xy 80.527335 -392.093969)
			(xy 80.573185 -392.123435) (xy 80.614376 -392.159126) (xy 80.650067 -392.200317) (xy 80.679533 -392.246167)
			(xy 80.702175 -392.295744) (xy 80.71753 -392.348039) (xy 80.725286 -392.401987) (xy 80.725772 -392.429238)
			(xy 80.725772 -393.292838) (xy 81.162652 -393.292838) (xy 81.162652 -392.429238) (xy 81.163138 -392.401987)
			(xy 81.170894 -392.348039) (xy 81.186249 -392.295744) (xy 81.208891 -392.246167) (xy 81.238357 -392.200317)
			(xy 81.274048 -392.159126) (xy 81.315239 -392.123435) (xy 81.361089 -392.093969) (xy 81.410666 -392.071327)
			(xy 81.462961 -392.055972) (xy 81.516909 -392.048216) (xy 81.571411 -392.048216) (xy 81.625359 -392.055972)
			(xy 81.677654 -392.071327) (xy 81.727231 -392.093969) (xy 81.773081 -392.123435) (xy 81.814272 -392.159126)
			(xy 81.849963 -392.200317) (xy 81.879429 -392.246167) (xy 81.902071 -392.295744) (xy 81.917426 -392.348039)
			(xy 81.925182 -392.401987) (xy 81.925668 -392.429238) (xy 81.925668 -393.292838) (xy 82.362548 -393.292838)
			(xy 82.362548 -392.429238) (xy 82.363034 -392.401969) (xy 82.370796 -392.347985) (xy 82.386161 -392.295655)
			(xy 82.408818 -392.246045) (xy 82.438304 -392.200164) (xy 82.474019 -392.158947) (xy 82.515236 -392.123232)
			(xy 82.561117 -392.093746) (xy 82.610727 -392.071089) (xy 82.663057 -392.055724) (xy 82.717041 -392.047962)
			(xy 82.771579 -392.047962) (xy 82.825563 -392.055724) (xy 82.877893 -392.071089) (xy 82.927503 -392.093746)
			(xy 82.973384 -392.123232) (xy 83.014601 -392.158947) (xy 83.050316 -392.200164) (xy 83.079802 -392.246045)
			(xy 83.102459 -392.295655) (xy 83.117824 -392.347985) (xy 83.125586 -392.401969) (xy 83.126072 -392.429238)
			(xy 83.126072 -393.292838) (xy 83.562444 -393.292838) (xy 83.562444 -392.429238) (xy 83.56293 -392.401969)
			(xy 83.570692 -392.347985) (xy 83.586057 -392.295655) (xy 83.608714 -392.246045) (xy 83.6382 -392.200164)
			(xy 83.673915 -392.158947) (xy 83.715132 -392.123232) (xy 83.761013 -392.093746) (xy 83.810623 -392.071089)
			(xy 83.862953 -392.055724) (xy 83.916937 -392.047962) (xy 83.971475 -392.047962) (xy 84.025459 -392.055724)
			(xy 84.077789 -392.071089) (xy 84.127399 -392.093746) (xy 84.17328 -392.123232) (xy 84.214497 -392.158947)
			(xy 84.250212 -392.200164) (xy 84.279698 -392.246045) (xy 84.302355 -392.295655) (xy 84.31772 -392.347985)
			(xy 84.325482 -392.401969) (xy 84.325968 -392.429238) (xy 84.325968 -393.292838) (xy 84.762848 -393.292838)
			(xy 84.762848 -392.429238) (xy 84.763334 -392.401987) (xy 84.77109 -392.348039) (xy 84.786445 -392.295744)
			(xy 84.809087 -392.246167) (xy 84.838553 -392.200317) (xy 84.874244 -392.159126) (xy 84.915435 -392.123435)
			(xy 84.961285 -392.093969) (xy 85.010862 -392.071327) (xy 85.063157 -392.055972) (xy 85.117105 -392.048216)
			(xy 85.171607 -392.048216) (xy 85.225555 -392.055972) (xy 85.27785 -392.071327) (xy 85.327427 -392.093969)
			(xy 85.373277 -392.123435) (xy 85.414468 -392.159126) (xy 85.450159 -392.200317) (xy 85.479625 -392.246167)
			(xy 85.502267 -392.295744) (xy 85.517622 -392.348039) (xy 85.525378 -392.401987) (xy 85.525864 -392.429238)
			(xy 85.525864 -393.292838) (xy 85.962744 -393.292838) (xy 85.962744 -392.429238) (xy 85.96323 -392.401987)
			(xy 85.970986 -392.348039) (xy 85.986341 -392.295744) (xy 86.008983 -392.246167) (xy 86.038449 -392.200317)
			(xy 86.07414 -392.159126) (xy 86.115331 -392.123435) (xy 86.161181 -392.093969) (xy 86.210758 -392.071327)
			(xy 86.263053 -392.055972) (xy 86.317001 -392.048216) (xy 86.371503 -392.048216) (xy 86.425451 -392.055972)
			(xy 86.477746 -392.071327) (xy 86.527323 -392.093969) (xy 86.573173 -392.123435) (xy 86.614364 -392.159126)
			(xy 86.650055 -392.200317) (xy 86.679521 -392.246167) (xy 86.702163 -392.295744) (xy 86.717518 -392.348039)
			(xy 86.725274 -392.401987) (xy 86.72576 -392.429238) (xy 86.72576 -393.292838) (xy 87.16264 -393.292838)
			(xy 87.16264 -392.429238) (xy 87.163126 -392.401969) (xy 87.170888 -392.347985) (xy 87.186253 -392.295655)
			(xy 87.20891 -392.246045) (xy 87.238396 -392.200164) (xy 87.274111 -392.158947) (xy 87.315328 -392.123232)
			(xy 87.361209 -392.093746) (xy 87.410819 -392.071089) (xy 87.463149 -392.055724) (xy 87.517133 -392.047962)
			(xy 87.571671 -392.047962) (xy 87.625655 -392.055724) (xy 87.677985 -392.071089) (xy 87.727595 -392.093746)
			(xy 87.773476 -392.123232) (xy 87.814693 -392.158947) (xy 87.850408 -392.200164) (xy 87.879894 -392.246045)
			(xy 87.902551 -392.295655) (xy 87.917916 -392.347985) (xy 87.925678 -392.401969) (xy 87.926164 -392.429238)
			(xy 87.926164 -393.292838) (xy 88.362536 -393.292838) (xy 88.362536 -392.429238) (xy 88.363022 -392.401969)
			(xy 88.370784 -392.347985) (xy 88.386149 -392.295655) (xy 88.408806 -392.246045) (xy 88.438292 -392.200164)
			(xy 88.474007 -392.158947) (xy 88.515224 -392.123232) (xy 88.561105 -392.093746) (xy 88.610715 -392.071089)
			(xy 88.663045 -392.055724) (xy 88.717029 -392.047962) (xy 88.771567 -392.047962) (xy 88.825551 -392.055724)
			(xy 88.877881 -392.071089) (xy 88.927491 -392.093746) (xy 88.973372 -392.123232) (xy 89.014589 -392.158947)
			(xy 89.050304 -392.200164) (xy 89.07979 -392.246045) (xy 89.102447 -392.295655) (xy 89.117812 -392.347985)
			(xy 89.125574 -392.401969) (xy 89.12606 -392.429238) (xy 89.12606 -393.292838) (xy 89.56294 -393.292838)
			(xy 89.56294 -392.429238) (xy 89.563426 -392.401987) (xy 89.571182 -392.348039) (xy 89.586537 -392.295744)
			(xy 89.609179 -392.246167) (xy 89.638645 -392.200317) (xy 89.674336 -392.159126) (xy 89.715527 -392.123435)
			(xy 89.761377 -392.093969) (xy 89.810954 -392.071327) (xy 89.863249 -392.055972) (xy 89.917197 -392.048216)
			(xy 89.971699 -392.048216) (xy 90.025647 -392.055972) (xy 90.077942 -392.071327) (xy 90.127519 -392.093969)
			(xy 90.173369 -392.123435) (xy 90.21456 -392.159126) (xy 90.250251 -392.200317) (xy 90.279717 -392.246167)
			(xy 90.302359 -392.295744) (xy 90.317714 -392.348039) (xy 90.32547 -392.401987) (xy 90.325956 -392.429238)
			(xy 90.325956 -393.292838) (xy 90.762836 -393.292838) (xy 90.762836 -392.429238) (xy 90.763322 -392.401987)
			(xy 90.771078 -392.348039) (xy 90.786433 -392.295744) (xy 90.809075 -392.246167) (xy 90.838541 -392.200317)
			(xy 90.874232 -392.159126) (xy 90.915423 -392.123435) (xy 90.961273 -392.093969) (xy 91.01085 -392.071327)
			(xy 91.063145 -392.055972) (xy 91.117093 -392.048216) (xy 91.171595 -392.048216) (xy 91.225543 -392.055972)
			(xy 91.277838 -392.071327) (xy 91.327415 -392.093969) (xy 91.373265 -392.123435) (xy 91.414456 -392.159126)
			(xy 91.450147 -392.200317) (xy 91.479613 -392.246167) (xy 91.502255 -392.295744) (xy 91.51761 -392.348039)
			(xy 91.525366 -392.401987) (xy 91.525852 -392.429238) (xy 91.525852 -393.292838) (xy 91.962732 -393.292838)
			(xy 91.962732 -392.429238) (xy 91.963218 -392.401969) (xy 91.97098 -392.347985) (xy 91.986345 -392.295655)
			(xy 92.009002 -392.246045) (xy 92.038488 -392.200164) (xy 92.074203 -392.158947) (xy 92.11542 -392.123232)
			(xy 92.161301 -392.093746) (xy 92.210911 -392.071089) (xy 92.263241 -392.055724) (xy 92.317225 -392.047962)
			(xy 92.371763 -392.047962) (xy 92.425747 -392.055724) (xy 92.478077 -392.071089) (xy 92.527687 -392.093746)
			(xy 92.573568 -392.123232) (xy 92.614785 -392.158947) (xy 92.6505 -392.200164) (xy 92.679986 -392.246045)
			(xy 92.702643 -392.295655) (xy 92.718008 -392.347985) (xy 92.72577 -392.401969) (xy 92.726256 -392.429238)
			(xy 92.726256 -393.292838) (xy 93.162628 -393.292838) (xy 93.162628 -392.429238) (xy 93.163114 -392.401969)
			(xy 93.170876 -392.347985) (xy 93.186241 -392.295655) (xy 93.208898 -392.246045) (xy 93.238384 -392.200164)
			(xy 93.274099 -392.158947) (xy 93.315316 -392.123232) (xy 93.361197 -392.093746) (xy 93.410807 -392.071089)
			(xy 93.463137 -392.055724) (xy 93.517121 -392.047962) (xy 93.571659 -392.047962) (xy 93.625643 -392.055724)
			(xy 93.677973 -392.071089) (xy 93.727583 -392.093746) (xy 93.773464 -392.123232) (xy 93.814681 -392.158947)
			(xy 93.850396 -392.200164) (xy 93.879882 -392.246045) (xy 93.902539 -392.295655) (xy 93.917904 -392.347985)
			(xy 93.925666 -392.401969) (xy 93.926152 -392.429238) (xy 93.926152 -393.292838) (xy 94.362524 -393.292838)
			(xy 94.362524 -392.429238) (xy 94.36301 -392.401969) (xy 94.370772 -392.347985) (xy 94.386137 -392.295655)
			(xy 94.408794 -392.246045) (xy 94.43828 -392.200164) (xy 94.473995 -392.158947) (xy 94.515212 -392.123232)
			(xy 94.561093 -392.093746) (xy 94.610703 -392.071089) (xy 94.663033 -392.055724) (xy 94.717017 -392.047962)
			(xy 94.771555 -392.047962) (xy 94.825539 -392.055724) (xy 94.877869 -392.071089) (xy 94.927479 -392.093746)
			(xy 94.97336 -392.123232) (xy 95.014577 -392.158947) (xy 95.050292 -392.200164) (xy 95.079778 -392.246045)
			(xy 95.102435 -392.295655) (xy 95.1178 -392.347985) (xy 95.125562 -392.401969) (xy 95.126048 -392.429238)
			(xy 95.126048 -393.292838) (xy 95.56242 -393.292838) (xy 95.56242 -392.429238) (xy 95.562906 -392.401969)
			(xy 95.570668 -392.347985) (xy 95.586033 -392.295655) (xy 95.60869 -392.246045) (xy 95.638176 -392.200164)
			(xy 95.673891 -392.158947) (xy 95.715108 -392.123232) (xy 95.760989 -392.093746) (xy 95.810599 -392.071089)
			(xy 95.862929 -392.055724) (xy 95.916913 -392.047962) (xy 95.971451 -392.047962) (xy 96.025435 -392.055724)
			(xy 96.077765 -392.071089) (xy 96.127375 -392.093746) (xy 96.173256 -392.123232) (xy 96.214473 -392.158947)
			(xy 96.250188 -392.200164) (xy 96.279674 -392.246045) (xy 96.302331 -392.295655) (xy 96.317696 -392.347985)
			(xy 96.325458 -392.401969) (xy 96.325944 -392.429238) (xy 96.325944 -393.292838) (xy 96.762824 -393.292838)
			(xy 96.762824 -392.429238) (xy 96.76331 -392.401987) (xy 96.771066 -392.348039) (xy 96.786421 -392.295744)
			(xy 96.809063 -392.246167) (xy 96.838529 -392.200317) (xy 96.87422 -392.159126) (xy 96.915411 -392.123435)
			(xy 96.961261 -392.093969) (xy 97.010838 -392.071327) (xy 97.063133 -392.055972) (xy 97.117081 -392.048216)
			(xy 97.171583 -392.048216) (xy 97.225531 -392.055972) (xy 97.277826 -392.071327) (xy 97.327403 -392.093969)
			(xy 97.373253 -392.123435) (xy 97.414444 -392.159126) (xy 97.450135 -392.200317) (xy 97.479601 -392.246167)
			(xy 97.502243 -392.295744) (xy 97.517598 -392.348039) (xy 97.525354 -392.401987) (xy 97.52584 -392.429238)
			(xy 97.52584 -393.292838) (xy 97.96272 -393.292838) (xy 97.96272 -392.429238) (xy 97.963206 -392.401987)
			(xy 97.970962 -392.348039) (xy 97.986317 -392.295744) (xy 98.008959 -392.246167) (xy 98.038425 -392.200317)
			(xy 98.074116 -392.159126) (xy 98.115307 -392.123435) (xy 98.161157 -392.093969) (xy 98.210734 -392.071327)
			(xy 98.263029 -392.055972) (xy 98.316977 -392.048216) (xy 98.371479 -392.048216) (xy 98.425427 -392.055972)
			(xy 98.477722 -392.071327) (xy 98.527299 -392.093969) (xy 98.573149 -392.123435) (xy 98.61434 -392.159126)
			(xy 98.650031 -392.200317) (xy 98.679497 -392.246167) (xy 98.702139 -392.295744) (xy 98.717494 -392.348039)
			(xy 98.72525 -392.401987) (xy 98.725736 -392.429238) (xy 98.725736 -393.292838) (xy 114.534696 -393.292838)
			(xy 114.534696 -392.429238) (xy 114.535182 -392.401969) (xy 114.542944 -392.347985) (xy 114.558309 -392.295655)
			(xy 114.580966 -392.246045) (xy 114.610452 -392.200164) (xy 114.646167 -392.158947) (xy 114.687384 -392.123232)
			(xy 114.733265 -392.093746) (xy 114.782875 -392.071089) (xy 114.835205 -392.055724) (xy 114.889189 -392.047962)
			(xy 114.943727 -392.047962) (xy 114.997711 -392.055724) (xy 115.050041 -392.071089) (xy 115.099651 -392.093746)
			(xy 115.145532 -392.123232) (xy 115.186749 -392.158947) (xy 115.222464 -392.200164) (xy 115.25195 -392.246045)
			(xy 115.274607 -392.295655) (xy 115.289972 -392.347985) (xy 115.297734 -392.401969) (xy 115.29822 -392.429238)
			(xy 115.29822 -393.292838) (xy 115.734592 -393.292838) (xy 115.734592 -392.429238) (xy 115.735078 -392.401969)
			(xy 115.74284 -392.347985) (xy 115.758205 -392.295655) (xy 115.780862 -392.246045) (xy 115.810348 -392.200164)
			(xy 115.846063 -392.158947) (xy 115.88728 -392.123232) (xy 115.933161 -392.093746) (xy 115.982771 -392.071089)
			(xy 116.035101 -392.055724) (xy 116.089085 -392.047962) (xy 116.143623 -392.047962) (xy 116.197607 -392.055724)
			(xy 116.249937 -392.071089) (xy 116.299547 -392.093746) (xy 116.345428 -392.123232) (xy 116.386645 -392.158947)
			(xy 116.42236 -392.200164) (xy 116.451846 -392.246045) (xy 116.474503 -392.295655) (xy 116.489868 -392.347985)
			(xy 116.49763 -392.401969) (xy 116.498116 -392.429238) (xy 116.498116 -393.292838) (xy 116.934996 -393.292838)
			(xy 116.934996 -392.429238) (xy 116.935482 -392.401987) (xy 116.943238 -392.348039) (xy 116.958593 -392.295744)
			(xy 116.981235 -392.246167) (xy 117.010701 -392.200317) (xy 117.046392 -392.159126) (xy 117.087583 -392.123435)
			(xy 117.133433 -392.093969) (xy 117.18301 -392.071327) (xy 117.235305 -392.055972) (xy 117.289253 -392.048216)
			(xy 117.343755 -392.048216) (xy 117.397703 -392.055972) (xy 117.449998 -392.071327) (xy 117.499575 -392.093969)
			(xy 117.545425 -392.123435) (xy 117.586616 -392.159126) (xy 117.622307 -392.200317) (xy 117.651773 -392.246167)
			(xy 117.674415 -392.295744) (xy 117.68977 -392.348039) (xy 117.697526 -392.401987) (xy 117.698012 -392.429238)
			(xy 117.698012 -393.292838) (xy 118.134892 -393.292838) (xy 118.134892 -392.429238) (xy 118.135378 -392.401987)
			(xy 118.143134 -392.348039) (xy 118.158489 -392.295744) (xy 118.181131 -392.246167) (xy 118.210597 -392.200317)
			(xy 118.246288 -392.159126) (xy 118.287479 -392.123435) (xy 118.333329 -392.093969) (xy 118.382906 -392.071327)
			(xy 118.435201 -392.055972) (xy 118.489149 -392.048216) (xy 118.543651 -392.048216) (xy 118.597599 -392.055972)
			(xy 118.649894 -392.071327) (xy 118.699471 -392.093969) (xy 118.745321 -392.123435) (xy 118.786512 -392.159126)
			(xy 118.822203 -392.200317) (xy 118.851669 -392.246167) (xy 118.874311 -392.295744) (xy 118.889666 -392.348039)
			(xy 118.897422 -392.401987) (xy 118.897908 -392.429238) (xy 118.897908 -393.292838) (xy 119.334788 -393.292838)
			(xy 119.334788 -392.429238) (xy 119.335274 -392.401969) (xy 119.343036 -392.347985) (xy 119.358401 -392.295655)
			(xy 119.381058 -392.246045) (xy 119.410544 -392.200164) (xy 119.446259 -392.158947) (xy 119.487476 -392.123232)
			(xy 119.533357 -392.093746) (xy 119.582967 -392.071089) (xy 119.635297 -392.055724) (xy 119.689281 -392.047962)
			(xy 119.743819 -392.047962) (xy 119.797803 -392.055724) (xy 119.850133 -392.071089) (xy 119.899743 -392.093746)
			(xy 119.945624 -392.123232) (xy 119.986841 -392.158947) (xy 120.022556 -392.200164) (xy 120.052042 -392.246045)
			(xy 120.074699 -392.295655) (xy 120.090064 -392.347985) (xy 120.097826 -392.401969) (xy 120.098312 -392.429238)
			(xy 120.098312 -393.292838) (xy 120.534684 -393.292838) (xy 120.534684 -392.429238) (xy 120.53517 -392.401969)
			(xy 120.542932 -392.347985) (xy 120.558297 -392.295655) (xy 120.580954 -392.246045) (xy 120.61044 -392.200164)
			(xy 120.646155 -392.158947) (xy 120.687372 -392.123232) (xy 120.733253 -392.093746) (xy 120.782863 -392.071089)
			(xy 120.835193 -392.055724) (xy 120.889177 -392.047962) (xy 120.943715 -392.047962) (xy 120.997699 -392.055724)
			(xy 121.050029 -392.071089) (xy 121.099639 -392.093746) (xy 121.14552 -392.123232) (xy 121.186737 -392.158947)
			(xy 121.222452 -392.200164) (xy 121.251938 -392.246045) (xy 121.274595 -392.295655) (xy 121.28996 -392.347985)
			(xy 121.297722 -392.401969) (xy 121.298208 -392.429238) (xy 121.298208 -393.292838) (xy 121.735088 -393.292838)
			(xy 121.735088 -392.429238) (xy 121.735574 -392.401987) (xy 121.74333 -392.348039) (xy 121.758685 -392.295744)
			(xy 121.781327 -392.246167) (xy 121.810793 -392.200317) (xy 121.846484 -392.159126) (xy 121.887675 -392.123435)
			(xy 121.933525 -392.093969) (xy 121.983102 -392.071327) (xy 122.035397 -392.055972) (xy 122.089345 -392.048216)
			(xy 122.143847 -392.048216) (xy 122.197795 -392.055972) (xy 122.25009 -392.071327) (xy 122.299667 -392.093969)
			(xy 122.345517 -392.123435) (xy 122.386708 -392.159126) (xy 122.422399 -392.200317) (xy 122.451865 -392.246167)
			(xy 122.474507 -392.295744) (xy 122.489862 -392.348039) (xy 122.497618 -392.401987) (xy 122.498104 -392.429238)
			(xy 122.498104 -393.292838) (xy 122.934984 -393.292838) (xy 122.934984 -392.429238) (xy 122.93547 -392.401987)
			(xy 122.943226 -392.348039) (xy 122.958581 -392.295744) (xy 122.981223 -392.246167) (xy 123.010689 -392.200317)
			(xy 123.04638 -392.159126) (xy 123.087571 -392.123435) (xy 123.133421 -392.093969) (xy 123.182998 -392.071327)
			(xy 123.235293 -392.055972) (xy 123.289241 -392.048216) (xy 123.343743 -392.048216) (xy 123.397691 -392.055972)
			(xy 123.449986 -392.071327) (xy 123.499563 -392.093969) (xy 123.545413 -392.123435) (xy 123.586604 -392.159126)
			(xy 123.622295 -392.200317) (xy 123.651761 -392.246167) (xy 123.674403 -392.295744) (xy 123.689758 -392.348039)
			(xy 123.697514 -392.401987) (xy 123.698 -392.429238) (xy 123.698 -393.292838) (xy 124.13488 -393.292838)
			(xy 124.13488 -392.429238) (xy 124.135366 -392.401969) (xy 124.143128 -392.347985) (xy 124.158493 -392.295655)
			(xy 124.18115 -392.246045) (xy 124.210636 -392.200164) (xy 124.246351 -392.158947) (xy 124.287568 -392.123232)
			(xy 124.333449 -392.093746) (xy 124.383059 -392.071089) (xy 124.435389 -392.055724) (xy 124.489373 -392.047962)
			(xy 124.543911 -392.047962) (xy 124.597895 -392.055724) (xy 124.650225 -392.071089) (xy 124.699835 -392.093746)
			(xy 124.745716 -392.123232) (xy 124.786933 -392.158947) (xy 124.822648 -392.200164) (xy 124.852134 -392.246045)
			(xy 124.874791 -392.295655) (xy 124.890156 -392.347985) (xy 124.897918 -392.401969) (xy 124.898404 -392.429238)
			(xy 124.898404 -393.292838) (xy 125.334776 -393.292838) (xy 125.334776 -392.429238) (xy 125.335262 -392.401969)
			(xy 125.343024 -392.347985) (xy 125.358389 -392.295655) (xy 125.381046 -392.246045) (xy 125.410532 -392.200164)
			(xy 125.446247 -392.158947) (xy 125.487464 -392.123232) (xy 125.533345 -392.093746) (xy 125.582955 -392.071089)
			(xy 125.635285 -392.055724) (xy 125.689269 -392.047962) (xy 125.743807 -392.047962) (xy 125.797791 -392.055724)
			(xy 125.850121 -392.071089) (xy 125.899731 -392.093746) (xy 125.945612 -392.123232) (xy 125.986829 -392.158947)
			(xy 126.022544 -392.200164) (xy 126.05203 -392.246045) (xy 126.074687 -392.295655) (xy 126.090052 -392.347985)
			(xy 126.097814 -392.401969) (xy 126.0983 -392.429238) (xy 126.0983 -393.292838) (xy 126.53518 -393.292838)
			(xy 126.53518 -392.429238) (xy 126.535666 -392.401987) (xy 126.543422 -392.348039) (xy 126.558777 -392.295744)
			(xy 126.581419 -392.246167) (xy 126.610885 -392.200317) (xy 126.646576 -392.159126) (xy 126.687767 -392.123435)
			(xy 126.733617 -392.093969) (xy 126.783194 -392.071327) (xy 126.835489 -392.055972) (xy 126.889437 -392.048216)
			(xy 126.943939 -392.048216) (xy 126.997887 -392.055972) (xy 127.050182 -392.071327) (xy 127.099759 -392.093969)
			(xy 127.145609 -392.123435) (xy 127.1868 -392.159126) (xy 127.222491 -392.200317) (xy 127.251957 -392.246167)
			(xy 127.274599 -392.295744) (xy 127.289954 -392.348039) (xy 127.29771 -392.401987) (xy 127.298196 -392.429238)
			(xy 127.298196 -393.292838) (xy 127.735076 -393.292838) (xy 127.735076 -392.429238) (xy 127.735562 -392.401987)
			(xy 127.743318 -392.348039) (xy 127.758673 -392.295744) (xy 127.781315 -392.246167) (xy 127.810781 -392.200317)
			(xy 127.846472 -392.159126) (xy 127.887663 -392.123435) (xy 127.933513 -392.093969) (xy 127.98309 -392.071327)
			(xy 128.035385 -392.055972) (xy 128.089333 -392.048216) (xy 128.143835 -392.048216) (xy 128.197783 -392.055972)
			(xy 128.250078 -392.071327) (xy 128.299655 -392.093969) (xy 128.345505 -392.123435) (xy 128.386696 -392.159126)
			(xy 128.422387 -392.200317) (xy 128.451853 -392.246167) (xy 128.474495 -392.295744) (xy 128.48985 -392.348039)
			(xy 128.497606 -392.401987) (xy 128.498092 -392.429238) (xy 128.498092 -393.292838) (xy 128.934972 -393.292838)
			(xy 128.934972 -392.429238) (xy 128.935458 -392.401987) (xy 128.943214 -392.348039) (xy 128.958569 -392.295744)
			(xy 128.981211 -392.246167) (xy 129.010677 -392.200317) (xy 129.046368 -392.159126) (xy 129.087559 -392.123435)
			(xy 129.133409 -392.093969) (xy 129.182986 -392.071327) (xy 129.235281 -392.055972) (xy 129.289229 -392.048216)
			(xy 129.343731 -392.048216) (xy 129.397679 -392.055972) (xy 129.449974 -392.071327) (xy 129.499551 -392.093969)
			(xy 129.545401 -392.123435) (xy 129.586592 -392.159126) (xy 129.622283 -392.200317) (xy 129.651749 -392.246167)
			(xy 129.674391 -392.295744) (xy 129.689746 -392.348039) (xy 129.697502 -392.401987) (xy 129.697988 -392.429238)
			(xy 129.697988 -393.292838) (xy 130.134868 -393.292838) (xy 130.134868 -392.429238) (xy 130.135354 -392.401987)
			(xy 130.14311 -392.348039) (xy 130.158465 -392.295744) (xy 130.181107 -392.246167) (xy 130.210573 -392.200317)
			(xy 130.246264 -392.159126) (xy 130.287455 -392.123435) (xy 130.333305 -392.093969) (xy 130.382882 -392.071327)
			(xy 130.435177 -392.055972) (xy 130.489125 -392.048216) (xy 130.543627 -392.048216) (xy 130.597575 -392.055972)
			(xy 130.64987 -392.071327) (xy 130.699447 -392.093969) (xy 130.745297 -392.123435) (xy 130.786488 -392.159126)
			(xy 130.822179 -392.200317) (xy 130.851645 -392.246167) (xy 130.874287 -392.295744) (xy 130.889642 -392.348039)
			(xy 130.897398 -392.401987) (xy 130.897884 -392.429238) (xy 130.897884 -393.292838) (xy 131.334764 -393.292838)
			(xy 131.334764 -392.429238) (xy 131.33525 -392.401969) (xy 131.343012 -392.347985) (xy 131.358377 -392.295655)
			(xy 131.381034 -392.246045) (xy 131.41052 -392.200164) (xy 131.446235 -392.158947) (xy 131.487452 -392.123232)
			(xy 131.533333 -392.093746) (xy 131.582943 -392.071089) (xy 131.635273 -392.055724) (xy 131.689257 -392.047962)
			(xy 131.743795 -392.047962) (xy 131.797779 -392.055724) (xy 131.850109 -392.071089) (xy 131.899719 -392.093746)
			(xy 131.9456 -392.123232) (xy 131.986817 -392.158947) (xy 132.022532 -392.200164) (xy 132.052018 -392.246045)
			(xy 132.074675 -392.295655) (xy 132.09004 -392.347985) (xy 132.097802 -392.401969) (xy 132.098288 -392.429238)
			(xy 132.098288 -393.292838) (xy 132.53466 -393.292838) (xy 132.53466 -392.429238) (xy 132.535146 -392.401969)
			(xy 132.542908 -392.347985) (xy 132.558273 -392.295655) (xy 132.58093 -392.246045) (xy 132.610416 -392.200164)
			(xy 132.646131 -392.158947) (xy 132.687348 -392.123232) (xy 132.733229 -392.093746) (xy 132.782839 -392.071089)
			(xy 132.835169 -392.055724) (xy 132.889153 -392.047962) (xy 132.943691 -392.047962) (xy 132.997675 -392.055724)
			(xy 133.050005 -392.071089) (xy 133.099615 -392.093746) (xy 133.145496 -392.123232) (xy 133.186713 -392.158947)
			(xy 133.222428 -392.200164) (xy 133.251914 -392.246045) (xy 133.274571 -392.295655) (xy 133.289936 -392.347985)
			(xy 133.297698 -392.401969) (xy 133.298184 -392.429238) (xy 133.298184 -393.292838) (xy 147.062444 -393.292838)
			(xy 147.062444 -392.429238) (xy 147.06293 -392.401969) (xy 147.070692 -392.347985) (xy 147.086057 -392.295655)
			(xy 147.108714 -392.246045) (xy 147.1382 -392.200164) (xy 147.173915 -392.158947) (xy 147.215132 -392.123232)
			(xy 147.261013 -392.093746) (xy 147.310623 -392.071089) (xy 147.362953 -392.055724) (xy 147.416937 -392.047962)
			(xy 147.471475 -392.047962) (xy 147.525459 -392.055724) (xy 147.577789 -392.071089) (xy 147.627399 -392.093746)
			(xy 147.67328 -392.123232) (xy 147.714497 -392.158947) (xy 147.750212 -392.200164) (xy 147.779698 -392.246045)
			(xy 147.802355 -392.295655) (xy 147.81772 -392.347985) (xy 147.825482 -392.401969) (xy 147.825968 -392.429238)
			(xy 147.825968 -393.292838) (xy 148.26234 -393.292838) (xy 148.26234 -392.429238) (xy 148.262826 -392.401969)
			(xy 148.270588 -392.347985) (xy 148.285953 -392.295655) (xy 148.30861 -392.246045) (xy 148.338096 -392.200164)
			(xy 148.373811 -392.158947) (xy 148.415028 -392.123232) (xy 148.460909 -392.093746) (xy 148.510519 -392.071089)
			(xy 148.562849 -392.055724) (xy 148.616833 -392.047962) (xy 148.671371 -392.047962) (xy 148.725355 -392.055724)
			(xy 148.777685 -392.071089) (xy 148.827295 -392.093746) (xy 148.873176 -392.123232) (xy 148.914393 -392.158947)
			(xy 148.950108 -392.200164) (xy 148.979594 -392.246045) (xy 149.002251 -392.295655) (xy 149.017616 -392.347985)
			(xy 149.025378 -392.401969) (xy 149.025864 -392.429238) (xy 149.025864 -393.292838) (xy 149.462744 -393.292838)
			(xy 149.462744 -392.429238) (xy 149.46323 -392.401987) (xy 149.470986 -392.348039) (xy 149.486341 -392.295744)
			(xy 149.508983 -392.246167) (xy 149.538449 -392.200317) (xy 149.57414 -392.159126) (xy 149.615331 -392.123435)
			(xy 149.661181 -392.093969) (xy 149.710758 -392.071327) (xy 149.763053 -392.055972) (xy 149.817001 -392.048216)
			(xy 149.871503 -392.048216) (xy 149.925451 -392.055972) (xy 149.977746 -392.071327) (xy 150.027323 -392.093969)
			(xy 150.073173 -392.123435) (xy 150.114364 -392.159126) (xy 150.150055 -392.200317) (xy 150.179521 -392.246167)
			(xy 150.202163 -392.295744) (xy 150.217518 -392.348039) (xy 150.225274 -392.401987) (xy 150.22576 -392.429238)
			(xy 150.22576 -393.292838) (xy 150.66264 -393.292838) (xy 150.66264 -392.429238) (xy 150.663126 -392.401987)
			(xy 150.670882 -392.348039) (xy 150.686237 -392.295744) (xy 150.708879 -392.246167) (xy 150.738345 -392.200317)
			(xy 150.774036 -392.159126) (xy 150.815227 -392.123435) (xy 150.861077 -392.093969) (xy 150.910654 -392.071327)
			(xy 150.962949 -392.055972) (xy 151.016897 -392.048216) (xy 151.071399 -392.048216) (xy 151.125347 -392.055972)
			(xy 151.177642 -392.071327) (xy 151.227219 -392.093969) (xy 151.273069 -392.123435) (xy 151.31426 -392.159126)
			(xy 151.349951 -392.200317) (xy 151.379417 -392.246167) (xy 151.402059 -392.295744) (xy 151.417414 -392.348039)
			(xy 151.42517 -392.401987) (xy 151.425656 -392.429238) (xy 151.425656 -393.292838) (xy 151.862536 -393.292838)
			(xy 151.862536 -392.429238) (xy 151.863022 -392.401969) (xy 151.870784 -392.347985) (xy 151.886149 -392.295655)
			(xy 151.908806 -392.246045) (xy 151.938292 -392.200164) (xy 151.974007 -392.158947) (xy 152.015224 -392.123232)
			(xy 152.061105 -392.093746) (xy 152.110715 -392.071089) (xy 152.163045 -392.055724) (xy 152.217029 -392.047962)
			(xy 152.271567 -392.047962) (xy 152.325551 -392.055724) (xy 152.377881 -392.071089) (xy 152.427491 -392.093746)
			(xy 152.473372 -392.123232) (xy 152.514589 -392.158947) (xy 152.550304 -392.200164) (xy 152.57979 -392.246045)
			(xy 152.602447 -392.295655) (xy 152.617812 -392.347985) (xy 152.625574 -392.401969) (xy 152.62606 -392.429238)
			(xy 152.62606 -393.292838) (xy 153.062432 -393.292838) (xy 153.062432 -392.429238) (xy 153.062918 -392.401969)
			(xy 153.07068 -392.347985) (xy 153.086045 -392.295655) (xy 153.108702 -392.246045) (xy 153.138188 -392.200164)
			(xy 153.173903 -392.158947) (xy 153.21512 -392.123232) (xy 153.261001 -392.093746) (xy 153.310611 -392.071089)
			(xy 153.362941 -392.055724) (xy 153.416925 -392.047962) (xy 153.471463 -392.047962) (xy 153.525447 -392.055724)
			(xy 153.577777 -392.071089) (xy 153.627387 -392.093746) (xy 153.673268 -392.123232) (xy 153.714485 -392.158947)
			(xy 153.7502 -392.200164) (xy 153.779686 -392.246045) (xy 153.802343 -392.295655) (xy 153.817708 -392.347985)
			(xy 153.82547 -392.401969) (xy 153.825956 -392.429238) (xy 153.825956 -393.292838) (xy 154.262836 -393.292838)
			(xy 154.262836 -392.429238) (xy 154.263322 -392.401987) (xy 154.271078 -392.348039) (xy 154.286433 -392.295744)
			(xy 154.309075 -392.246167) (xy 154.338541 -392.200317) (xy 154.374232 -392.159126) (xy 154.415423 -392.123435)
			(xy 154.461273 -392.093969) (xy 154.51085 -392.071327) (xy 154.563145 -392.055972) (xy 154.617093 -392.048216)
			(xy 154.671595 -392.048216) (xy 154.725543 -392.055972) (xy 154.777838 -392.071327) (xy 154.827415 -392.093969)
			(xy 154.873265 -392.123435) (xy 154.914456 -392.159126) (xy 154.950147 -392.200317) (xy 154.979613 -392.246167)
			(xy 155.002255 -392.295744) (xy 155.01761 -392.348039) (xy 155.025366 -392.401987) (xy 155.025852 -392.429238)
			(xy 155.025852 -393.292838) (xy 155.462732 -393.292838) (xy 155.462732 -392.429238) (xy 155.463218 -392.401987)
			(xy 155.470974 -392.348039) (xy 155.486329 -392.295744) (xy 155.508971 -392.246167) (xy 155.538437 -392.200317)
			(xy 155.574128 -392.159126) (xy 155.615319 -392.123435) (xy 155.661169 -392.093969) (xy 155.710746 -392.071327)
			(xy 155.763041 -392.055972) (xy 155.816989 -392.048216) (xy 155.871491 -392.048216) (xy 155.925439 -392.055972)
			(xy 155.977734 -392.071327) (xy 156.027311 -392.093969) (xy 156.073161 -392.123435) (xy 156.114352 -392.159126)
			(xy 156.150043 -392.200317) (xy 156.179509 -392.246167) (xy 156.202151 -392.295744) (xy 156.217506 -392.348039)
			(xy 156.225262 -392.401987) (xy 156.225748 -392.429238) (xy 156.225748 -393.292838) (xy 156.662628 -393.292838)
			(xy 156.662628 -392.429238) (xy 156.663114 -392.401969) (xy 156.670876 -392.347985) (xy 156.686241 -392.295655)
			(xy 156.708898 -392.246045) (xy 156.738384 -392.200164) (xy 156.774099 -392.158947) (xy 156.815316 -392.123232)
			(xy 156.861197 -392.093746) (xy 156.910807 -392.071089) (xy 156.963137 -392.055724) (xy 157.017121 -392.047962)
			(xy 157.071659 -392.047962) (xy 157.125643 -392.055724) (xy 157.177973 -392.071089) (xy 157.227583 -392.093746)
			(xy 157.273464 -392.123232) (xy 157.314681 -392.158947) (xy 157.350396 -392.200164) (xy 157.379882 -392.246045)
			(xy 157.402539 -392.295655) (xy 157.417904 -392.347985) (xy 157.425666 -392.401969) (xy 157.426152 -392.429238)
			(xy 157.426152 -393.292838) (xy 157.862524 -393.292838) (xy 157.862524 -392.429238) (xy 157.86301 -392.401969)
			(xy 157.870772 -392.347985) (xy 157.886137 -392.295655) (xy 157.908794 -392.246045) (xy 157.93828 -392.200164)
			(xy 157.973995 -392.158947) (xy 158.015212 -392.123232) (xy 158.061093 -392.093746) (xy 158.110703 -392.071089)
			(xy 158.163033 -392.055724) (xy 158.217017 -392.047962) (xy 158.271555 -392.047962) (xy 158.325539 -392.055724)
			(xy 158.377869 -392.071089) (xy 158.427479 -392.093746) (xy 158.47336 -392.123232) (xy 158.514577 -392.158947)
			(xy 158.550292 -392.200164) (xy 158.579778 -392.246045) (xy 158.602435 -392.295655) (xy 158.6178 -392.347985)
			(xy 158.625562 -392.401969) (xy 158.626048 -392.429238) (xy 158.626048 -393.292838) (xy 159.062928 -393.292838)
			(xy 159.062928 -392.429238) (xy 159.063414 -392.401987) (xy 159.07117 -392.348039) (xy 159.086525 -392.295744)
			(xy 159.109167 -392.246167) (xy 159.138633 -392.200317) (xy 159.174324 -392.159126) (xy 159.215515 -392.123435)
			(xy 159.261365 -392.093969) (xy 159.310942 -392.071327) (xy 159.363237 -392.055972) (xy 159.417185 -392.048216)
			(xy 159.471687 -392.048216) (xy 159.525635 -392.055972) (xy 159.57793 -392.071327) (xy 159.627507 -392.093969)
			(xy 159.673357 -392.123435) (xy 159.714548 -392.159126) (xy 159.750239 -392.200317) (xy 159.779705 -392.246167)
			(xy 159.802347 -392.295744) (xy 159.817702 -392.348039) (xy 159.825458 -392.401987) (xy 159.825944 -392.429238)
			(xy 159.825944 -393.292838) (xy 160.262824 -393.292838) (xy 160.262824 -392.429238) (xy 160.26331 -392.401987)
			(xy 160.271066 -392.348039) (xy 160.286421 -392.295744) (xy 160.309063 -392.246167) (xy 160.338529 -392.200317)
			(xy 160.37422 -392.159126) (xy 160.415411 -392.123435) (xy 160.461261 -392.093969) (xy 160.510838 -392.071327)
			(xy 160.563133 -392.055972) (xy 160.617081 -392.048216) (xy 160.671583 -392.048216) (xy 160.725531 -392.055972)
			(xy 160.777826 -392.071327) (xy 160.827403 -392.093969) (xy 160.873253 -392.123435) (xy 160.914444 -392.159126)
			(xy 160.950135 -392.200317) (xy 160.979601 -392.246167) (xy 161.002243 -392.295744) (xy 161.017598 -392.348039)
			(xy 161.025354 -392.401987) (xy 161.02584 -392.429238) (xy 161.02584 -393.292838) (xy 161.46272 -393.292838)
			(xy 161.46272 -392.429238) (xy 161.463206 -392.401987) (xy 161.470962 -392.348039) (xy 161.486317 -392.295744)
			(xy 161.508959 -392.246167) (xy 161.538425 -392.200317) (xy 161.574116 -392.159126) (xy 161.615307 -392.123435)
			(xy 161.661157 -392.093969) (xy 161.710734 -392.071327) (xy 161.763029 -392.055972) (xy 161.816977 -392.048216)
			(xy 161.871479 -392.048216) (xy 161.925427 -392.055972) (xy 161.977722 -392.071327) (xy 162.027299 -392.093969)
			(xy 162.073149 -392.123435) (xy 162.11434 -392.159126) (xy 162.150031 -392.200317) (xy 162.179497 -392.246167)
			(xy 162.202139 -392.295744) (xy 162.217494 -392.348039) (xy 162.22525 -392.401987) (xy 162.225736 -392.429238)
			(xy 162.225736 -393.292838) (xy 162.662616 -393.292838) (xy 162.662616 -392.429238) (xy 162.663102 -392.401987)
			(xy 162.670858 -392.348039) (xy 162.686213 -392.295744) (xy 162.708855 -392.246167) (xy 162.738321 -392.200317)
			(xy 162.774012 -392.159126) (xy 162.815203 -392.123435) (xy 162.861053 -392.093969) (xy 162.91063 -392.071327)
			(xy 162.962925 -392.055972) (xy 163.016873 -392.048216) (xy 163.071375 -392.048216) (xy 163.125323 -392.055972)
			(xy 163.177618 -392.071327) (xy 163.227195 -392.093969) (xy 163.273045 -392.123435) (xy 163.314236 -392.159126)
			(xy 163.349927 -392.200317) (xy 163.379393 -392.246167) (xy 163.402035 -392.295744) (xy 163.41739 -392.348039)
			(xy 163.425146 -392.401987) (xy 163.425632 -392.429238) (xy 163.425632 -393.292838) (xy 163.862512 -393.292838)
			(xy 163.862512 -392.429238) (xy 163.862998 -392.401969) (xy 163.87076 -392.347985) (xy 163.886125 -392.295655)
			(xy 163.908782 -392.246045) (xy 163.938268 -392.200164) (xy 163.973983 -392.158947) (xy 164.0152 -392.123232)
			(xy 164.061081 -392.093746) (xy 164.110691 -392.071089) (xy 164.163021 -392.055724) (xy 164.217005 -392.047962)
			(xy 164.271543 -392.047962) (xy 164.325527 -392.055724) (xy 164.377857 -392.071089) (xy 164.427467 -392.093746)
			(xy 164.473348 -392.123232) (xy 164.514565 -392.158947) (xy 164.55028 -392.200164) (xy 164.579766 -392.246045)
			(xy 164.602423 -392.295655) (xy 164.617788 -392.347985) (xy 164.62555 -392.401969) (xy 164.626036 -392.429238)
			(xy 164.626036 -393.292838) (xy 165.062408 -393.292838) (xy 165.062408 -392.429238) (xy 165.062894 -392.401969)
			(xy 165.070656 -392.347985) (xy 165.086021 -392.295655) (xy 165.108678 -392.246045) (xy 165.138164 -392.200164)
			(xy 165.173879 -392.158947) (xy 165.215096 -392.123232) (xy 165.260977 -392.093746) (xy 165.310587 -392.071089)
			(xy 165.362917 -392.055724) (xy 165.416901 -392.047962) (xy 165.471439 -392.047962) (xy 165.525423 -392.055724)
			(xy 165.577753 -392.071089) (xy 165.627363 -392.093746) (xy 165.673244 -392.123232) (xy 165.714461 -392.158947)
			(xy 165.750176 -392.200164) (xy 165.779662 -392.246045) (xy 165.802319 -392.295655) (xy 165.817684 -392.347985)
			(xy 165.825446 -392.401969) (xy 165.825932 -392.429238) (xy 165.825932 -393.292838) (xy 165.825446 -393.320107)
			(xy 165.817684 -393.374091) (xy 165.802319 -393.426421) (xy 165.779662 -393.476031) (xy 165.750176 -393.521912)
			(xy 165.714461 -393.563129) (xy 165.673244 -393.598844) (xy 165.627363 -393.62833) (xy 165.577753 -393.650987)
			(xy 165.525423 -393.666352) (xy 165.471439 -393.674114) (xy 165.416901 -393.674114) (xy 165.362917 -393.666352)
			(xy 165.310587 -393.650987) (xy 165.260977 -393.62833) (xy 165.215096 -393.598844) (xy 165.173879 -393.563129)
			(xy 165.138164 -393.521912) (xy 165.108678 -393.476031) (xy 165.086021 -393.426421) (xy 165.070656 -393.374091)
			(xy 165.062894 -393.320107) (xy 165.062408 -393.292838) (xy 164.626036 -393.292838) (xy 164.62555 -393.320107)
			(xy 164.617788 -393.374091) (xy 164.602423 -393.426421) (xy 164.579766 -393.476031) (xy 164.55028 -393.521912)
			(xy 164.514565 -393.563129) (xy 164.473348 -393.598844) (xy 164.427467 -393.62833) (xy 164.377857 -393.650987)
			(xy 164.325527 -393.666352) (xy 164.271543 -393.674114) (xy 164.217005 -393.674114) (xy 164.163021 -393.666352)
			(xy 164.110691 -393.650987) (xy 164.061081 -393.62833) (xy 164.0152 -393.598844) (xy 163.973983 -393.563129)
			(xy 163.938268 -393.521912) (xy 163.908782 -393.476031) (xy 163.886125 -393.426421) (xy 163.87076 -393.374091)
			(xy 163.862998 -393.320107) (xy 163.862512 -393.292838) (xy 163.425632 -393.292838) (xy 163.425146 -393.320089)
			(xy 163.41739 -393.374037) (xy 163.402035 -393.426332) (xy 163.379393 -393.475909) (xy 163.349927 -393.521759)
			(xy 163.314236 -393.56295) (xy 163.273045 -393.598641) (xy 163.227195 -393.628107) (xy 163.177618 -393.650749)
			(xy 163.125323 -393.666104) (xy 163.071375 -393.67386) (xy 163.016873 -393.67386) (xy 162.962925 -393.666104)
			(xy 162.91063 -393.650749) (xy 162.861053 -393.628107) (xy 162.815203 -393.598641) (xy 162.774012 -393.56295)
			(xy 162.738321 -393.521759) (xy 162.708855 -393.475909) (xy 162.686213 -393.426332) (xy 162.670858 -393.374037)
			(xy 162.663102 -393.320089) (xy 162.662616 -393.292838) (xy 162.225736 -393.292838) (xy 162.22525 -393.320089)
			(xy 162.217494 -393.374037) (xy 162.202139 -393.426332) (xy 162.179497 -393.475909) (xy 162.150031 -393.521759)
			(xy 162.11434 -393.56295) (xy 162.073149 -393.598641) (xy 162.027299 -393.628107) (xy 161.977722 -393.650749)
			(xy 161.925427 -393.666104) (xy 161.871479 -393.67386) (xy 161.816977 -393.67386) (xy 161.763029 -393.666104)
			(xy 161.710734 -393.650749) (xy 161.661157 -393.628107) (xy 161.615307 -393.598641) (xy 161.574116 -393.56295)
			(xy 161.538425 -393.521759) (xy 161.508959 -393.475909) (xy 161.486317 -393.426332) (xy 161.470962 -393.374037)
			(xy 161.463206 -393.320089) (xy 161.46272 -393.292838) (xy 161.02584 -393.292838) (xy 161.025354 -393.320089)
			(xy 161.017598 -393.374037) (xy 161.002243 -393.426332) (xy 160.979601 -393.475909) (xy 160.950135 -393.521759)
			(xy 160.914444 -393.56295) (xy 160.873253 -393.598641) (xy 160.827403 -393.628107) (xy 160.777826 -393.650749)
			(xy 160.725531 -393.666104) (xy 160.671583 -393.67386) (xy 160.617081 -393.67386) (xy 160.563133 -393.666104)
			(xy 160.510838 -393.650749) (xy 160.461261 -393.628107) (xy 160.415411 -393.598641) (xy 160.37422 -393.56295)
			(xy 160.338529 -393.521759) (xy 160.309063 -393.475909) (xy 160.286421 -393.426332) (xy 160.271066 -393.374037)
			(xy 160.26331 -393.320089) (xy 160.262824 -393.292838) (xy 159.825944 -393.292838) (xy 159.825458 -393.320089)
			(xy 159.817702 -393.374037) (xy 159.802347 -393.426332) (xy 159.779705 -393.475909) (xy 159.750239 -393.521759)
			(xy 159.714548 -393.56295) (xy 159.673357 -393.598641) (xy 159.627507 -393.628107) (xy 159.57793 -393.650749)
			(xy 159.525635 -393.666104) (xy 159.471687 -393.67386) (xy 159.417185 -393.67386) (xy 159.363237 -393.666104)
			(xy 159.310942 -393.650749) (xy 159.261365 -393.628107) (xy 159.215515 -393.598641) (xy 159.174324 -393.56295)
			(xy 159.138633 -393.521759) (xy 159.109167 -393.475909) (xy 159.086525 -393.426332) (xy 159.07117 -393.374037)
			(xy 159.063414 -393.320089) (xy 159.062928 -393.292838) (xy 158.626048 -393.292838) (xy 158.625562 -393.320107)
			(xy 158.6178 -393.374091) (xy 158.602435 -393.426421) (xy 158.579778 -393.476031) (xy 158.550292 -393.521912)
			(xy 158.514577 -393.563129) (xy 158.47336 -393.598844) (xy 158.427479 -393.62833) (xy 158.377869 -393.650987)
			(xy 158.325539 -393.666352) (xy 158.271555 -393.674114) (xy 158.217017 -393.674114) (xy 158.163033 -393.666352)
			(xy 158.110703 -393.650987) (xy 158.061093 -393.62833) (xy 158.015212 -393.598844) (xy 157.973995 -393.563129)
			(xy 157.93828 -393.521912) (xy 157.908794 -393.476031) (xy 157.886137 -393.426421) (xy 157.870772 -393.374091)
			(xy 157.86301 -393.320107) (xy 157.862524 -393.292838) (xy 157.426152 -393.292838) (xy 157.425666 -393.320107)
			(xy 157.417904 -393.374091) (xy 157.402539 -393.426421) (xy 157.379882 -393.476031) (xy 157.350396 -393.521912)
			(xy 157.314681 -393.563129) (xy 157.273464 -393.598844) (xy 157.227583 -393.62833) (xy 157.177973 -393.650987)
			(xy 157.125643 -393.666352) (xy 157.071659 -393.674114) (xy 157.017121 -393.674114) (xy 156.963137 -393.666352)
			(xy 156.910807 -393.650987) (xy 156.861197 -393.62833) (xy 156.815316 -393.598844) (xy 156.774099 -393.563129)
			(xy 156.738384 -393.521912) (xy 156.708898 -393.476031) (xy 156.686241 -393.426421) (xy 156.670876 -393.374091)
			(xy 156.663114 -393.320107) (xy 156.662628 -393.292838) (xy 156.225748 -393.292838) (xy 156.225262 -393.320089)
			(xy 156.217506 -393.374037) (xy 156.202151 -393.426332) (xy 156.179509 -393.475909) (xy 156.150043 -393.521759)
			(xy 156.114352 -393.56295) (xy 156.073161 -393.598641) (xy 156.027311 -393.628107) (xy 155.977734 -393.650749)
			(xy 155.925439 -393.666104) (xy 155.871491 -393.67386) (xy 155.816989 -393.67386) (xy 155.763041 -393.666104)
			(xy 155.710746 -393.650749) (xy 155.661169 -393.628107) (xy 155.615319 -393.598641) (xy 155.574128 -393.56295)
			(xy 155.538437 -393.521759) (xy 155.508971 -393.475909) (xy 155.486329 -393.426332) (xy 155.470974 -393.374037)
			(xy 155.463218 -393.320089) (xy 155.462732 -393.292838) (xy 155.025852 -393.292838) (xy 155.025366 -393.320089)
			(xy 155.01761 -393.374037) (xy 155.002255 -393.426332) (xy 154.979613 -393.475909) (xy 154.950147 -393.521759)
			(xy 154.914456 -393.56295) (xy 154.873265 -393.598641) (xy 154.827415 -393.628107) (xy 154.777838 -393.650749)
			(xy 154.725543 -393.666104) (xy 154.671595 -393.67386) (xy 154.617093 -393.67386) (xy 154.563145 -393.666104)
			(xy 154.51085 -393.650749) (xy 154.461273 -393.628107) (xy 154.415423 -393.598641) (xy 154.374232 -393.56295)
			(xy 154.338541 -393.521759) (xy 154.309075 -393.475909) (xy 154.286433 -393.426332) (xy 154.271078 -393.374037)
			(xy 154.263322 -393.320089) (xy 154.262836 -393.292838) (xy 153.825956 -393.292838) (xy 153.82547 -393.320107)
			(xy 153.817708 -393.374091) (xy 153.802343 -393.426421) (xy 153.779686 -393.476031) (xy 153.7502 -393.521912)
			(xy 153.714485 -393.563129) (xy 153.673268 -393.598844) (xy 153.627387 -393.62833) (xy 153.577777 -393.650987)
			(xy 153.525447 -393.666352) (xy 153.471463 -393.674114) (xy 153.416925 -393.674114) (xy 153.362941 -393.666352)
			(xy 153.310611 -393.650987) (xy 153.261001 -393.62833) (xy 153.21512 -393.598844) (xy 153.173903 -393.563129)
			(xy 153.138188 -393.521912) (xy 153.108702 -393.476031) (xy 153.086045 -393.426421) (xy 153.07068 -393.374091)
			(xy 153.062918 -393.320107) (xy 153.062432 -393.292838) (xy 152.62606 -393.292838) (xy 152.625574 -393.320107)
			(xy 152.617812 -393.374091) (xy 152.602447 -393.426421) (xy 152.57979 -393.476031) (xy 152.550304 -393.521912)
			(xy 152.514589 -393.563129) (xy 152.473372 -393.598844) (xy 152.427491 -393.62833) (xy 152.377881 -393.650987)
			(xy 152.325551 -393.666352) (xy 152.271567 -393.674114) (xy 152.217029 -393.674114) (xy 152.163045 -393.666352)
			(xy 152.110715 -393.650987) (xy 152.061105 -393.62833) (xy 152.015224 -393.598844) (xy 151.974007 -393.563129)
			(xy 151.938292 -393.521912) (xy 151.908806 -393.476031) (xy 151.886149 -393.426421) (xy 151.870784 -393.374091)
			(xy 151.863022 -393.320107) (xy 151.862536 -393.292838) (xy 151.425656 -393.292838) (xy 151.42517 -393.320089)
			(xy 151.417414 -393.374037) (xy 151.402059 -393.426332) (xy 151.379417 -393.475909) (xy 151.349951 -393.521759)
			(xy 151.31426 -393.56295) (xy 151.273069 -393.598641) (xy 151.227219 -393.628107) (xy 151.177642 -393.650749)
			(xy 151.125347 -393.666104) (xy 151.071399 -393.67386) (xy 151.016897 -393.67386) (xy 150.962949 -393.666104)
			(xy 150.910654 -393.650749) (xy 150.861077 -393.628107) (xy 150.815227 -393.598641) (xy 150.774036 -393.56295)
			(xy 150.738345 -393.521759) (xy 150.708879 -393.475909) (xy 150.686237 -393.426332) (xy 150.670882 -393.374037)
			(xy 150.663126 -393.320089) (xy 150.66264 -393.292838) (xy 150.22576 -393.292838) (xy 150.225274 -393.320089)
			(xy 150.217518 -393.374037) (xy 150.202163 -393.426332) (xy 150.179521 -393.475909) (xy 150.150055 -393.521759)
			(xy 150.114364 -393.56295) (xy 150.073173 -393.598641) (xy 150.027323 -393.628107) (xy 149.977746 -393.650749)
			(xy 149.925451 -393.666104) (xy 149.871503 -393.67386) (xy 149.817001 -393.67386) (xy 149.763053 -393.666104)
			(xy 149.710758 -393.650749) (xy 149.661181 -393.628107) (xy 149.615331 -393.598641) (xy 149.57414 -393.56295)
			(xy 149.538449 -393.521759) (xy 149.508983 -393.475909) (xy 149.486341 -393.426332) (xy 149.470986 -393.374037)
			(xy 149.46323 -393.320089) (xy 149.462744 -393.292838) (xy 149.025864 -393.292838) (xy 149.025378 -393.320107)
			(xy 149.017616 -393.374091) (xy 149.002251 -393.426421) (xy 148.979594 -393.476031) (xy 148.950108 -393.521912)
			(xy 148.914393 -393.563129) (xy 148.873176 -393.598844) (xy 148.827295 -393.62833) (xy 148.777685 -393.650987)
			(xy 148.725355 -393.666352) (xy 148.671371 -393.674114) (xy 148.616833 -393.674114) (xy 148.562849 -393.666352)
			(xy 148.510519 -393.650987) (xy 148.460909 -393.62833) (xy 148.415028 -393.598844) (xy 148.373811 -393.563129)
			(xy 148.338096 -393.521912) (xy 148.30861 -393.476031) (xy 148.285953 -393.426421) (xy 148.270588 -393.374091)
			(xy 148.262826 -393.320107) (xy 148.26234 -393.292838) (xy 147.825968 -393.292838) (xy 147.825482 -393.320107)
			(xy 147.81772 -393.374091) (xy 147.802355 -393.426421) (xy 147.779698 -393.476031) (xy 147.750212 -393.521912)
			(xy 147.714497 -393.563129) (xy 147.67328 -393.598844) (xy 147.627399 -393.62833) (xy 147.577789 -393.650987)
			(xy 147.525459 -393.666352) (xy 147.471475 -393.674114) (xy 147.416937 -393.674114) (xy 147.362953 -393.666352)
			(xy 147.310623 -393.650987) (xy 147.261013 -393.62833) (xy 147.215132 -393.598844) (xy 147.173915 -393.563129)
			(xy 147.1382 -393.521912) (xy 147.108714 -393.476031) (xy 147.086057 -393.426421) (xy 147.070692 -393.374091)
			(xy 147.06293 -393.320107) (xy 147.062444 -393.292838) (xy 133.298184 -393.292838) (xy 133.297698 -393.320107)
			(xy 133.289936 -393.374091) (xy 133.274571 -393.426421) (xy 133.251914 -393.476031) (xy 133.222428 -393.521912)
			(xy 133.186713 -393.563129) (xy 133.145496 -393.598844) (xy 133.099615 -393.62833) (xy 133.050005 -393.650987)
			(xy 132.997675 -393.666352) (xy 132.943691 -393.674114) (xy 132.889153 -393.674114) (xy 132.835169 -393.666352)
			(xy 132.782839 -393.650987) (xy 132.733229 -393.62833) (xy 132.687348 -393.598844) (xy 132.646131 -393.563129)
			(xy 132.610416 -393.521912) (xy 132.58093 -393.476031) (xy 132.558273 -393.426421) (xy 132.542908 -393.374091)
			(xy 132.535146 -393.320107) (xy 132.53466 -393.292838) (xy 132.098288 -393.292838) (xy 132.097802 -393.320107)
			(xy 132.09004 -393.374091) (xy 132.074675 -393.426421) (xy 132.052018 -393.476031) (xy 132.022532 -393.521912)
			(xy 131.986817 -393.563129) (xy 131.9456 -393.598844) (xy 131.899719 -393.62833) (xy 131.850109 -393.650987)
			(xy 131.797779 -393.666352) (xy 131.743795 -393.674114) (xy 131.689257 -393.674114) (xy 131.635273 -393.666352)
			(xy 131.582943 -393.650987) (xy 131.533333 -393.62833) (xy 131.487452 -393.598844) (xy 131.446235 -393.563129)
			(xy 131.41052 -393.521912) (xy 131.381034 -393.476031) (xy 131.358377 -393.426421) (xy 131.343012 -393.374091)
			(xy 131.33525 -393.320107) (xy 131.334764 -393.292838) (xy 130.897884 -393.292838) (xy 130.897398 -393.320089)
			(xy 130.889642 -393.374037) (xy 130.874287 -393.426332) (xy 130.851645 -393.475909) (xy 130.822179 -393.521759)
			(xy 130.786488 -393.56295) (xy 130.745297 -393.598641) (xy 130.699447 -393.628107) (xy 130.64987 -393.650749)
			(xy 130.597575 -393.666104) (xy 130.543627 -393.67386) (xy 130.489125 -393.67386) (xy 130.435177 -393.666104)
			(xy 130.382882 -393.650749) (xy 130.333305 -393.628107) (xy 130.287455 -393.598641) (xy 130.246264 -393.56295)
			(xy 130.210573 -393.521759) (xy 130.181107 -393.475909) (xy 130.158465 -393.426332) (xy 130.14311 -393.374037)
			(xy 130.135354 -393.320089) (xy 130.134868 -393.292838) (xy 129.697988 -393.292838) (xy 129.697502 -393.320089)
			(xy 129.689746 -393.374037) (xy 129.674391 -393.426332) (xy 129.651749 -393.475909) (xy 129.622283 -393.521759)
			(xy 129.586592 -393.56295) (xy 129.545401 -393.598641) (xy 129.499551 -393.628107) (xy 129.449974 -393.650749)
			(xy 129.397679 -393.666104) (xy 129.343731 -393.67386) (xy 129.289229 -393.67386) (xy 129.235281 -393.666104)
			(xy 129.182986 -393.650749) (xy 129.133409 -393.628107) (xy 129.087559 -393.598641) (xy 129.046368 -393.56295)
			(xy 129.010677 -393.521759) (xy 128.981211 -393.475909) (xy 128.958569 -393.426332) (xy 128.943214 -393.374037)
			(xy 128.935458 -393.320089) (xy 128.934972 -393.292838) (xy 128.498092 -393.292838) (xy 128.497606 -393.320089)
			(xy 128.48985 -393.374037) (xy 128.474495 -393.426332) (xy 128.451853 -393.475909) (xy 128.422387 -393.521759)
			(xy 128.386696 -393.56295) (xy 128.345505 -393.598641) (xy 128.299655 -393.628107) (xy 128.250078 -393.650749)
			(xy 128.197783 -393.666104) (xy 128.143835 -393.67386) (xy 128.089333 -393.67386) (xy 128.035385 -393.666104)
			(xy 127.98309 -393.650749) (xy 127.933513 -393.628107) (xy 127.887663 -393.598641) (xy 127.846472 -393.56295)
			(xy 127.810781 -393.521759) (xy 127.781315 -393.475909) (xy 127.758673 -393.426332) (xy 127.743318 -393.374037)
			(xy 127.735562 -393.320089) (xy 127.735076 -393.292838) (xy 127.298196 -393.292838) (xy 127.29771 -393.320089)
			(xy 127.289954 -393.374037) (xy 127.274599 -393.426332) (xy 127.251957 -393.475909) (xy 127.222491 -393.521759)
			(xy 127.1868 -393.56295) (xy 127.145609 -393.598641) (xy 127.099759 -393.628107) (xy 127.050182 -393.650749)
			(xy 126.997887 -393.666104) (xy 126.943939 -393.67386) (xy 126.889437 -393.67386) (xy 126.835489 -393.666104)
			(xy 126.783194 -393.650749) (xy 126.733617 -393.628107) (xy 126.687767 -393.598641) (xy 126.646576 -393.56295)
			(xy 126.610885 -393.521759) (xy 126.581419 -393.475909) (xy 126.558777 -393.426332) (xy 126.543422 -393.374037)
			(xy 126.535666 -393.320089) (xy 126.53518 -393.292838) (xy 126.0983 -393.292838) (xy 126.097814 -393.320107)
			(xy 126.090052 -393.374091) (xy 126.074687 -393.426421) (xy 126.05203 -393.476031) (xy 126.022544 -393.521912)
			(xy 125.986829 -393.563129) (xy 125.945612 -393.598844) (xy 125.899731 -393.62833) (xy 125.850121 -393.650987)
			(xy 125.797791 -393.666352) (xy 125.743807 -393.674114) (xy 125.689269 -393.674114) (xy 125.635285 -393.666352)
			(xy 125.582955 -393.650987) (xy 125.533345 -393.62833) (xy 125.487464 -393.598844) (xy 125.446247 -393.563129)
			(xy 125.410532 -393.521912) (xy 125.381046 -393.476031) (xy 125.358389 -393.426421) (xy 125.343024 -393.374091)
			(xy 125.335262 -393.320107) (xy 125.334776 -393.292838) (xy 124.898404 -393.292838) (xy 124.897918 -393.320107)
			(xy 124.890156 -393.374091) (xy 124.874791 -393.426421) (xy 124.852134 -393.476031) (xy 124.822648 -393.521912)
			(xy 124.786933 -393.563129) (xy 124.745716 -393.598844) (xy 124.699835 -393.62833) (xy 124.650225 -393.650987)
			(xy 124.597895 -393.666352) (xy 124.543911 -393.674114) (xy 124.489373 -393.674114) (xy 124.435389 -393.666352)
			(xy 124.383059 -393.650987) (xy 124.333449 -393.62833) (xy 124.287568 -393.598844) (xy 124.246351 -393.563129)
			(xy 124.210636 -393.521912) (xy 124.18115 -393.476031) (xy 124.158493 -393.426421) (xy 124.143128 -393.374091)
			(xy 124.135366 -393.320107) (xy 124.13488 -393.292838) (xy 123.698 -393.292838) (xy 123.697514 -393.320089)
			(xy 123.689758 -393.374037) (xy 123.674403 -393.426332) (xy 123.651761 -393.475909) (xy 123.622295 -393.521759)
			(xy 123.586604 -393.56295) (xy 123.545413 -393.598641) (xy 123.499563 -393.628107) (xy 123.449986 -393.650749)
			(xy 123.397691 -393.666104) (xy 123.343743 -393.67386) (xy 123.289241 -393.67386) (xy 123.235293 -393.666104)
			(xy 123.182998 -393.650749) (xy 123.133421 -393.628107) (xy 123.087571 -393.598641) (xy 123.04638 -393.56295)
			(xy 123.010689 -393.521759) (xy 122.981223 -393.475909) (xy 122.958581 -393.426332) (xy 122.943226 -393.374037)
			(xy 122.93547 -393.320089) (xy 122.934984 -393.292838) (xy 122.498104 -393.292838) (xy 122.497618 -393.320089)
			(xy 122.489862 -393.374037) (xy 122.474507 -393.426332) (xy 122.451865 -393.475909) (xy 122.422399 -393.521759)
			(xy 122.386708 -393.56295) (xy 122.345517 -393.598641) (xy 122.299667 -393.628107) (xy 122.25009 -393.650749)
			(xy 122.197795 -393.666104) (xy 122.143847 -393.67386) (xy 122.089345 -393.67386) (xy 122.035397 -393.666104)
			(xy 121.983102 -393.650749) (xy 121.933525 -393.628107) (xy 121.887675 -393.598641) (xy 121.846484 -393.56295)
			(xy 121.810793 -393.521759) (xy 121.781327 -393.475909) (xy 121.758685 -393.426332) (xy 121.74333 -393.374037)
			(xy 121.735574 -393.320089) (xy 121.735088 -393.292838) (xy 121.298208 -393.292838) (xy 121.297722 -393.320107)
			(xy 121.28996 -393.374091) (xy 121.274595 -393.426421) (xy 121.251938 -393.476031) (xy 121.222452 -393.521912)
			(xy 121.186737 -393.563129) (xy 121.14552 -393.598844) (xy 121.099639 -393.62833) (xy 121.050029 -393.650987)
			(xy 120.997699 -393.666352) (xy 120.943715 -393.674114) (xy 120.889177 -393.674114) (xy 120.835193 -393.666352)
			(xy 120.782863 -393.650987) (xy 120.733253 -393.62833) (xy 120.687372 -393.598844) (xy 120.646155 -393.563129)
			(xy 120.61044 -393.521912) (xy 120.580954 -393.476031) (xy 120.558297 -393.426421) (xy 120.542932 -393.374091)
			(xy 120.53517 -393.320107) (xy 120.534684 -393.292838) (xy 120.098312 -393.292838) (xy 120.097826 -393.320107)
			(xy 120.090064 -393.374091) (xy 120.074699 -393.426421) (xy 120.052042 -393.476031) (xy 120.022556 -393.521912)
			(xy 119.986841 -393.563129) (xy 119.945624 -393.598844) (xy 119.899743 -393.62833) (xy 119.850133 -393.650987)
			(xy 119.797803 -393.666352) (xy 119.743819 -393.674114) (xy 119.689281 -393.674114) (xy 119.635297 -393.666352)
			(xy 119.582967 -393.650987) (xy 119.533357 -393.62833) (xy 119.487476 -393.598844) (xy 119.446259 -393.563129)
			(xy 119.410544 -393.521912) (xy 119.381058 -393.476031) (xy 119.358401 -393.426421) (xy 119.343036 -393.374091)
			(xy 119.335274 -393.320107) (xy 119.334788 -393.292838) (xy 118.897908 -393.292838) (xy 118.897422 -393.320089)
			(xy 118.889666 -393.374037) (xy 118.874311 -393.426332) (xy 118.851669 -393.475909) (xy 118.822203 -393.521759)
			(xy 118.786512 -393.56295) (xy 118.745321 -393.598641) (xy 118.699471 -393.628107) (xy 118.649894 -393.650749)
			(xy 118.597599 -393.666104) (xy 118.543651 -393.67386) (xy 118.489149 -393.67386) (xy 118.435201 -393.666104)
			(xy 118.382906 -393.650749) (xy 118.333329 -393.628107) (xy 118.287479 -393.598641) (xy 118.246288 -393.56295)
			(xy 118.210597 -393.521759) (xy 118.181131 -393.475909) (xy 118.158489 -393.426332) (xy 118.143134 -393.374037)
			(xy 118.135378 -393.320089) (xy 118.134892 -393.292838) (xy 117.698012 -393.292838) (xy 117.697526 -393.320089)
			(xy 117.68977 -393.374037) (xy 117.674415 -393.426332) (xy 117.651773 -393.475909) (xy 117.622307 -393.521759)
			(xy 117.586616 -393.56295) (xy 117.545425 -393.598641) (xy 117.499575 -393.628107) (xy 117.449998 -393.650749)
			(xy 117.397703 -393.666104) (xy 117.343755 -393.67386) (xy 117.289253 -393.67386) (xy 117.235305 -393.666104)
			(xy 117.18301 -393.650749) (xy 117.133433 -393.628107) (xy 117.087583 -393.598641) (xy 117.046392 -393.56295)
			(xy 117.010701 -393.521759) (xy 116.981235 -393.475909) (xy 116.958593 -393.426332) (xy 116.943238 -393.374037)
			(xy 116.935482 -393.320089) (xy 116.934996 -393.292838) (xy 116.498116 -393.292838) (xy 116.49763 -393.320107)
			(xy 116.489868 -393.374091) (xy 116.474503 -393.426421) (xy 116.451846 -393.476031) (xy 116.42236 -393.521912)
			(xy 116.386645 -393.563129) (xy 116.345428 -393.598844) (xy 116.299547 -393.62833) (xy 116.249937 -393.650987)
			(xy 116.197607 -393.666352) (xy 116.143623 -393.674114) (xy 116.089085 -393.674114) (xy 116.035101 -393.666352)
			(xy 115.982771 -393.650987) (xy 115.933161 -393.62833) (xy 115.88728 -393.598844) (xy 115.846063 -393.563129)
			(xy 115.810348 -393.521912) (xy 115.780862 -393.476031) (xy 115.758205 -393.426421) (xy 115.74284 -393.374091)
			(xy 115.735078 -393.320107) (xy 115.734592 -393.292838) (xy 115.29822 -393.292838) (xy 115.297734 -393.320107)
			(xy 115.289972 -393.374091) (xy 115.274607 -393.426421) (xy 115.25195 -393.476031) (xy 115.222464 -393.521912)
			(xy 115.186749 -393.563129) (xy 115.145532 -393.598844) (xy 115.099651 -393.62833) (xy 115.050041 -393.650987)
			(xy 114.997711 -393.666352) (xy 114.943727 -393.674114) (xy 114.889189 -393.674114) (xy 114.835205 -393.666352)
			(xy 114.782875 -393.650987) (xy 114.733265 -393.62833) (xy 114.687384 -393.598844) (xy 114.646167 -393.563129)
			(xy 114.610452 -393.521912) (xy 114.580966 -393.476031) (xy 114.558309 -393.426421) (xy 114.542944 -393.374091)
			(xy 114.535182 -393.320107) (xy 114.534696 -393.292838) (xy 98.725736 -393.292838) (xy 98.72525 -393.320089)
			(xy 98.717494 -393.374037) (xy 98.702139 -393.426332) (xy 98.679497 -393.475909) (xy 98.650031 -393.521759)
			(xy 98.61434 -393.56295) (xy 98.573149 -393.598641) (xy 98.527299 -393.628107) (xy 98.477722 -393.650749)
			(xy 98.425427 -393.666104) (xy 98.371479 -393.67386) (xy 98.316977 -393.67386) (xy 98.263029 -393.666104)
			(xy 98.210734 -393.650749) (xy 98.161157 -393.628107) (xy 98.115307 -393.598641) (xy 98.074116 -393.56295)
			(xy 98.038425 -393.521759) (xy 98.008959 -393.475909) (xy 97.986317 -393.426332) (xy 97.970962 -393.374037)
			(xy 97.963206 -393.320089) (xy 97.96272 -393.292838) (xy 97.52584 -393.292838) (xy 97.525354 -393.320089)
			(xy 97.517598 -393.374037) (xy 97.502243 -393.426332) (xy 97.479601 -393.475909) (xy 97.450135 -393.521759)
			(xy 97.414444 -393.56295) (xy 97.373253 -393.598641) (xy 97.327403 -393.628107) (xy 97.277826 -393.650749)
			(xy 97.225531 -393.666104) (xy 97.171583 -393.67386) (xy 97.117081 -393.67386) (xy 97.063133 -393.666104)
			(xy 97.010838 -393.650749) (xy 96.961261 -393.628107) (xy 96.915411 -393.598641) (xy 96.87422 -393.56295)
			(xy 96.838529 -393.521759) (xy 96.809063 -393.475909) (xy 96.786421 -393.426332) (xy 96.771066 -393.374037)
			(xy 96.76331 -393.320089) (xy 96.762824 -393.292838) (xy 96.325944 -393.292838) (xy 96.325458 -393.320107)
			(xy 96.317696 -393.374091) (xy 96.302331 -393.426421) (xy 96.279674 -393.476031) (xy 96.250188 -393.521912)
			(xy 96.214473 -393.563129) (xy 96.173256 -393.598844) (xy 96.127375 -393.62833) (xy 96.077765 -393.650987)
			(xy 96.025435 -393.666352) (xy 95.971451 -393.674114) (xy 95.916913 -393.674114) (xy 95.862929 -393.666352)
			(xy 95.810599 -393.650987) (xy 95.760989 -393.62833) (xy 95.715108 -393.598844) (xy 95.673891 -393.563129)
			(xy 95.638176 -393.521912) (xy 95.60869 -393.476031) (xy 95.586033 -393.426421) (xy 95.570668 -393.374091)
			(xy 95.562906 -393.320107) (xy 95.56242 -393.292838) (xy 95.126048 -393.292838) (xy 95.125562 -393.320107)
			(xy 95.1178 -393.374091) (xy 95.102435 -393.426421) (xy 95.079778 -393.476031) (xy 95.050292 -393.521912)
			(xy 95.014577 -393.563129) (xy 94.97336 -393.598844) (xy 94.927479 -393.62833) (xy 94.877869 -393.650987)
			(xy 94.825539 -393.666352) (xy 94.771555 -393.674114) (xy 94.717017 -393.674114) (xy 94.663033 -393.666352)
			(xy 94.610703 -393.650987) (xy 94.561093 -393.62833) (xy 94.515212 -393.598844) (xy 94.473995 -393.563129)
			(xy 94.43828 -393.521912) (xy 94.408794 -393.476031) (xy 94.386137 -393.426421) (xy 94.370772 -393.374091)
			(xy 94.36301 -393.320107) (xy 94.362524 -393.292838) (xy 93.926152 -393.292838) (xy 93.925666 -393.320107)
			(xy 93.917904 -393.374091) (xy 93.902539 -393.426421) (xy 93.879882 -393.476031) (xy 93.850396 -393.521912)
			(xy 93.814681 -393.563129) (xy 93.773464 -393.598844) (xy 93.727583 -393.62833) (xy 93.677973 -393.650987)
			(xy 93.625643 -393.666352) (xy 93.571659 -393.674114) (xy 93.517121 -393.674114) (xy 93.463137 -393.666352)
			(xy 93.410807 -393.650987) (xy 93.361197 -393.62833) (xy 93.315316 -393.598844) (xy 93.274099 -393.563129)
			(xy 93.238384 -393.521912) (xy 93.208898 -393.476031) (xy 93.186241 -393.426421) (xy 93.170876 -393.374091)
			(xy 93.163114 -393.320107) (xy 93.162628 -393.292838) (xy 92.726256 -393.292838) (xy 92.72577 -393.320107)
			(xy 92.718008 -393.374091) (xy 92.702643 -393.426421) (xy 92.679986 -393.476031) (xy 92.6505 -393.521912)
			(xy 92.614785 -393.563129) (xy 92.573568 -393.598844) (xy 92.527687 -393.62833) (xy 92.478077 -393.650987)
			(xy 92.425747 -393.666352) (xy 92.371763 -393.674114) (xy 92.317225 -393.674114) (xy 92.263241 -393.666352)
			(xy 92.210911 -393.650987) (xy 92.161301 -393.62833) (xy 92.11542 -393.598844) (xy 92.074203 -393.563129)
			(xy 92.038488 -393.521912) (xy 92.009002 -393.476031) (xy 91.986345 -393.426421) (xy 91.97098 -393.374091)
			(xy 91.963218 -393.320107) (xy 91.962732 -393.292838) (xy 91.525852 -393.292838) (xy 91.525366 -393.320089)
			(xy 91.51761 -393.374037) (xy 91.502255 -393.426332) (xy 91.479613 -393.475909) (xy 91.450147 -393.521759)
			(xy 91.414456 -393.56295) (xy 91.373265 -393.598641) (xy 91.327415 -393.628107) (xy 91.277838 -393.650749)
			(xy 91.225543 -393.666104) (xy 91.171595 -393.67386) (xy 91.117093 -393.67386) (xy 91.063145 -393.666104)
			(xy 91.01085 -393.650749) (xy 90.961273 -393.628107) (xy 90.915423 -393.598641) (xy 90.874232 -393.56295)
			(xy 90.838541 -393.521759) (xy 90.809075 -393.475909) (xy 90.786433 -393.426332) (xy 90.771078 -393.374037)
			(xy 90.763322 -393.320089) (xy 90.762836 -393.292838) (xy 90.325956 -393.292838) (xy 90.32547 -393.320089)
			(xy 90.317714 -393.374037) (xy 90.302359 -393.426332) (xy 90.279717 -393.475909) (xy 90.250251 -393.521759)
			(xy 90.21456 -393.56295) (xy 90.173369 -393.598641) (xy 90.127519 -393.628107) (xy 90.077942 -393.650749)
			(xy 90.025647 -393.666104) (xy 89.971699 -393.67386) (xy 89.917197 -393.67386) (xy 89.863249 -393.666104)
			(xy 89.810954 -393.650749) (xy 89.761377 -393.628107) (xy 89.715527 -393.598641) (xy 89.674336 -393.56295)
			(xy 89.638645 -393.521759) (xy 89.609179 -393.475909) (xy 89.586537 -393.426332) (xy 89.571182 -393.374037)
			(xy 89.563426 -393.320089) (xy 89.56294 -393.292838) (xy 89.12606 -393.292838) (xy 89.125574 -393.320107)
			(xy 89.117812 -393.374091) (xy 89.102447 -393.426421) (xy 89.07979 -393.476031) (xy 89.050304 -393.521912)
			(xy 89.014589 -393.563129) (xy 88.973372 -393.598844) (xy 88.927491 -393.62833) (xy 88.877881 -393.650987)
			(xy 88.825551 -393.666352) (xy 88.771567 -393.674114) (xy 88.717029 -393.674114) (xy 88.663045 -393.666352)
			(xy 88.610715 -393.650987) (xy 88.561105 -393.62833) (xy 88.515224 -393.598844) (xy 88.474007 -393.563129)
			(xy 88.438292 -393.521912) (xy 88.408806 -393.476031) (xy 88.386149 -393.426421) (xy 88.370784 -393.374091)
			(xy 88.363022 -393.320107) (xy 88.362536 -393.292838) (xy 87.926164 -393.292838) (xy 87.925678 -393.320107)
			(xy 87.917916 -393.374091) (xy 87.902551 -393.426421) (xy 87.879894 -393.476031) (xy 87.850408 -393.521912)
			(xy 87.814693 -393.563129) (xy 87.773476 -393.598844) (xy 87.727595 -393.62833) (xy 87.677985 -393.650987)
			(xy 87.625655 -393.666352) (xy 87.571671 -393.674114) (xy 87.517133 -393.674114) (xy 87.463149 -393.666352)
			(xy 87.410819 -393.650987) (xy 87.361209 -393.62833) (xy 87.315328 -393.598844) (xy 87.274111 -393.563129)
			(xy 87.238396 -393.521912) (xy 87.20891 -393.476031) (xy 87.186253 -393.426421) (xy 87.170888 -393.374091)
			(xy 87.163126 -393.320107) (xy 87.16264 -393.292838) (xy 86.72576 -393.292838) (xy 86.725274 -393.320089)
			(xy 86.717518 -393.374037) (xy 86.702163 -393.426332) (xy 86.679521 -393.475909) (xy 86.650055 -393.521759)
			(xy 86.614364 -393.56295) (xy 86.573173 -393.598641) (xy 86.527323 -393.628107) (xy 86.477746 -393.650749)
			(xy 86.425451 -393.666104) (xy 86.371503 -393.67386) (xy 86.317001 -393.67386) (xy 86.263053 -393.666104)
			(xy 86.210758 -393.650749) (xy 86.161181 -393.628107) (xy 86.115331 -393.598641) (xy 86.07414 -393.56295)
			(xy 86.038449 -393.521759) (xy 86.008983 -393.475909) (xy 85.986341 -393.426332) (xy 85.970986 -393.374037)
			(xy 85.96323 -393.320089) (xy 85.962744 -393.292838) (xy 85.525864 -393.292838) (xy 85.525378 -393.320089)
			(xy 85.517622 -393.374037) (xy 85.502267 -393.426332) (xy 85.479625 -393.475909) (xy 85.450159 -393.521759)
			(xy 85.414468 -393.56295) (xy 85.373277 -393.598641) (xy 85.327427 -393.628107) (xy 85.27785 -393.650749)
			(xy 85.225555 -393.666104) (xy 85.171607 -393.67386) (xy 85.117105 -393.67386) (xy 85.063157 -393.666104)
			(xy 85.010862 -393.650749) (xy 84.961285 -393.628107) (xy 84.915435 -393.598641) (xy 84.874244 -393.56295)
			(xy 84.838553 -393.521759) (xy 84.809087 -393.475909) (xy 84.786445 -393.426332) (xy 84.77109 -393.374037)
			(xy 84.763334 -393.320089) (xy 84.762848 -393.292838) (xy 84.325968 -393.292838) (xy 84.325482 -393.320107)
			(xy 84.31772 -393.374091) (xy 84.302355 -393.426421) (xy 84.279698 -393.476031) (xy 84.250212 -393.521912)
			(xy 84.214497 -393.563129) (xy 84.17328 -393.598844) (xy 84.127399 -393.62833) (xy 84.077789 -393.650987)
			(xy 84.025459 -393.666352) (xy 83.971475 -393.674114) (xy 83.916937 -393.674114) (xy 83.862953 -393.666352)
			(xy 83.810623 -393.650987) (xy 83.761013 -393.62833) (xy 83.715132 -393.598844) (xy 83.673915 -393.563129)
			(xy 83.6382 -393.521912) (xy 83.608714 -393.476031) (xy 83.586057 -393.426421) (xy 83.570692 -393.374091)
			(xy 83.56293 -393.320107) (xy 83.562444 -393.292838) (xy 83.126072 -393.292838) (xy 83.125586 -393.320107)
			(xy 83.117824 -393.374091) (xy 83.102459 -393.426421) (xy 83.079802 -393.476031) (xy 83.050316 -393.521912)
			(xy 83.014601 -393.563129) (xy 82.973384 -393.598844) (xy 82.927503 -393.62833) (xy 82.877893 -393.650987)
			(xy 82.825563 -393.666352) (xy 82.771579 -393.674114) (xy 82.717041 -393.674114) (xy 82.663057 -393.666352)
			(xy 82.610727 -393.650987) (xy 82.561117 -393.62833) (xy 82.515236 -393.598844) (xy 82.474019 -393.563129)
			(xy 82.438304 -393.521912) (xy 82.408818 -393.476031) (xy 82.386161 -393.426421) (xy 82.370796 -393.374091)
			(xy 82.363034 -393.320107) (xy 82.362548 -393.292838) (xy 81.925668 -393.292838) (xy 81.925182 -393.320089)
			(xy 81.917426 -393.374037) (xy 81.902071 -393.426332) (xy 81.879429 -393.475909) (xy 81.849963 -393.521759)
			(xy 81.814272 -393.56295) (xy 81.773081 -393.598641) (xy 81.727231 -393.628107) (xy 81.677654 -393.650749)
			(xy 81.625359 -393.666104) (xy 81.571411 -393.67386) (xy 81.516909 -393.67386) (xy 81.462961 -393.666104)
			(xy 81.410666 -393.650749) (xy 81.361089 -393.628107) (xy 81.315239 -393.598641) (xy 81.274048 -393.56295)
			(xy 81.238357 -393.521759) (xy 81.208891 -393.475909) (xy 81.186249 -393.426332) (xy 81.170894 -393.374037)
			(xy 81.163138 -393.320089) (xy 81.162652 -393.292838) (xy 80.725772 -393.292838) (xy 80.725286 -393.320089)
			(xy 80.71753 -393.374037) (xy 80.702175 -393.426332) (xy 80.679533 -393.475909) (xy 80.650067 -393.521759)
			(xy 80.614376 -393.56295) (xy 80.573185 -393.598641) (xy 80.527335 -393.628107) (xy 80.477758 -393.650749)
			(xy 80.425463 -393.666104) (xy 80.371515 -393.67386) (xy 80.317013 -393.67386) (xy 80.263065 -393.666104)
			(xy 80.21077 -393.650749) (xy 80.161193 -393.628107) (xy 80.115343 -393.598641) (xy 80.074152 -393.56295)
			(xy 80.038461 -393.521759) (xy 80.008995 -393.475909) (xy 79.986353 -393.426332) (xy 79.970998 -393.374037)
			(xy 79.963242 -393.320089) (xy 79.962756 -393.292838) (xy 66.197988 -393.292838) (xy 66.197502 -393.320089)
			(xy 66.189746 -393.374037) (xy 66.174391 -393.426332) (xy 66.151749 -393.475909) (xy 66.122283 -393.521759)
			(xy 66.086592 -393.56295) (xy 66.045401 -393.598641) (xy 65.999551 -393.628107) (xy 65.949974 -393.650749)
			(xy 65.897679 -393.666104) (xy 65.843731 -393.67386) (xy 65.789229 -393.67386) (xy 65.735281 -393.666104)
			(xy 65.682986 -393.650749) (xy 65.633409 -393.628107) (xy 65.587559 -393.598641) (xy 65.546368 -393.56295)
			(xy 65.510677 -393.521759) (xy 65.481211 -393.475909) (xy 65.458569 -393.426332) (xy 65.443214 -393.374037)
			(xy 65.435458 -393.320089) (xy 65.434972 -393.292838) (xy 64.998092 -393.292838) (xy 64.997606 -393.320089)
			(xy 64.98985 -393.374037) (xy 64.974495 -393.426332) (xy 64.951853 -393.475909) (xy 64.922387 -393.521759)
			(xy 64.886696 -393.56295) (xy 64.845505 -393.598641) (xy 64.799655 -393.628107) (xy 64.750078 -393.650749)
			(xy 64.697783 -393.666104) (xy 64.643835 -393.67386) (xy 64.589333 -393.67386) (xy 64.535385 -393.666104)
			(xy 64.48309 -393.650749) (xy 64.433513 -393.628107) (xy 64.387663 -393.598641) (xy 64.346472 -393.56295)
			(xy 64.310781 -393.521759) (xy 64.281315 -393.475909) (xy 64.258673 -393.426332) (xy 64.243318 -393.374037)
			(xy 64.235562 -393.320089) (xy 64.235076 -393.292838) (xy 63.798196 -393.292838) (xy 63.79771 -393.320107)
			(xy 63.789948 -393.374091) (xy 63.774583 -393.426421) (xy 63.751926 -393.476031) (xy 63.72244 -393.521912)
			(xy 63.686725 -393.563129) (xy 63.645508 -393.598844) (xy 63.599627 -393.62833) (xy 63.550017 -393.650987)
			(xy 63.497687 -393.666352) (xy 63.443703 -393.674114) (xy 63.389165 -393.674114) (xy 63.335181 -393.666352)
			(xy 63.282851 -393.650987) (xy 63.233241 -393.62833) (xy 63.18736 -393.598844) (xy 63.146143 -393.563129)
			(xy 63.110428 -393.521912) (xy 63.080942 -393.476031) (xy 63.058285 -393.426421) (xy 63.04292 -393.374091)
			(xy 63.035158 -393.320107) (xy 63.034672 -393.292838) (xy 62.5983 -393.292838) (xy 62.597814 -393.320107)
			(xy 62.590052 -393.374091) (xy 62.574687 -393.426421) (xy 62.55203 -393.476031) (xy 62.522544 -393.521912)
			(xy 62.486829 -393.563129) (xy 62.445612 -393.598844) (xy 62.399731 -393.62833) (xy 62.350121 -393.650987)
			(xy 62.297791 -393.666352) (xy 62.243807 -393.674114) (xy 62.189269 -393.674114) (xy 62.135285 -393.666352)
			(xy 62.082955 -393.650987) (xy 62.033345 -393.62833) (xy 61.987464 -393.598844) (xy 61.946247 -393.563129)
			(xy 61.910532 -393.521912) (xy 61.881046 -393.476031) (xy 61.858389 -393.426421) (xy 61.843024 -393.374091)
			(xy 61.835262 -393.320107) (xy 61.834776 -393.292838) (xy 61.398404 -393.292838) (xy 61.397918 -393.320107)
			(xy 61.390156 -393.374091) (xy 61.374791 -393.426421) (xy 61.352134 -393.476031) (xy 61.322648 -393.521912)
			(xy 61.286933 -393.563129) (xy 61.245716 -393.598844) (xy 61.199835 -393.62833) (xy 61.150225 -393.650987)
			(xy 61.097895 -393.666352) (xy 61.043911 -393.674114) (xy 60.989373 -393.674114) (xy 60.935389 -393.666352)
			(xy 60.883059 -393.650987) (xy 60.833449 -393.62833) (xy 60.787568 -393.598844) (xy 60.746351 -393.563129)
			(xy 60.710636 -393.521912) (xy 60.68115 -393.476031) (xy 60.658493 -393.426421) (xy 60.643128 -393.374091)
			(xy 60.635366 -393.320107) (xy 60.63488 -393.292838) (xy 60.198508 -393.292838) (xy 60.198022 -393.320107)
			(xy 60.19026 -393.374091) (xy 60.174895 -393.426421) (xy 60.152238 -393.476031) (xy 60.122752 -393.521912)
			(xy 60.087037 -393.563129) (xy 60.04582 -393.598844) (xy 59.999939 -393.62833) (xy 59.950329 -393.650987)
			(xy 59.897999 -393.666352) (xy 59.844015 -393.674114) (xy 59.789477 -393.674114) (xy 59.735493 -393.666352)
			(xy 59.683163 -393.650987) (xy 59.633553 -393.62833) (xy 59.587672 -393.598844) (xy 59.546455 -393.563129)
			(xy 59.51074 -393.521912) (xy 59.481254 -393.476031) (xy 59.458597 -393.426421) (xy 59.443232 -393.374091)
			(xy 59.43547 -393.320107) (xy 59.434984 -393.292838) (xy 58.998104 -393.292838) (xy 58.997618 -393.320089)
			(xy 58.989862 -393.374037) (xy 58.974507 -393.426332) (xy 58.951865 -393.475909) (xy 58.922399 -393.521759)
			(xy 58.886708 -393.56295) (xy 58.845517 -393.598641) (xy 58.799667 -393.628107) (xy 58.75009 -393.650749)
			(xy 58.697795 -393.666104) (xy 58.643847 -393.67386) (xy 58.589345 -393.67386) (xy 58.535397 -393.666104)
			(xy 58.483102 -393.650749) (xy 58.433525 -393.628107) (xy 58.387675 -393.598641) (xy 58.346484 -393.56295)
			(xy 58.310793 -393.521759) (xy 58.281327 -393.475909) (xy 58.258685 -393.426332) (xy 58.24333 -393.374037)
			(xy 58.235574 -393.320089) (xy 58.235088 -393.292838) (xy 57.798208 -393.292838) (xy 57.797722 -393.320089)
			(xy 57.789966 -393.374037) (xy 57.774611 -393.426332) (xy 57.751969 -393.475909) (xy 57.722503 -393.521759)
			(xy 57.686812 -393.56295) (xy 57.645621 -393.598641) (xy 57.599771 -393.628107) (xy 57.550194 -393.650749)
			(xy 57.497899 -393.666104) (xy 57.443951 -393.67386) (xy 57.389449 -393.67386) (xy 57.335501 -393.666104)
			(xy 57.283206 -393.650749) (xy 57.233629 -393.628107) (xy 57.187779 -393.598641) (xy 57.146588 -393.56295)
			(xy 57.110897 -393.521759) (xy 57.081431 -393.475909) (xy 57.058789 -393.426332) (xy 57.043434 -393.374037)
			(xy 57.035678 -393.320089) (xy 57.035192 -393.292838) (xy 56.598312 -393.292838) (xy 56.597826 -393.320107)
			(xy 56.590064 -393.374091) (xy 56.574699 -393.426421) (xy 56.552042 -393.476031) (xy 56.522556 -393.521912)
			(xy 56.486841 -393.563129) (xy 56.445624 -393.598844) (xy 56.399743 -393.62833) (xy 56.350133 -393.650987)
			(xy 56.297803 -393.666352) (xy 56.243819 -393.674114) (xy 56.189281 -393.674114) (xy 56.135297 -393.666352)
			(xy 56.082967 -393.650987) (xy 56.033357 -393.62833) (xy 55.987476 -393.598844) (xy 55.946259 -393.563129)
			(xy 55.910544 -393.521912) (xy 55.881058 -393.476031) (xy 55.858401 -393.426421) (xy 55.843036 -393.374091)
			(xy 55.835274 -393.320107) (xy 55.834788 -393.292838) (xy 55.398416 -393.292838) (xy 55.39793 -393.320107)
			(xy 55.390168 -393.374091) (xy 55.374803 -393.426421) (xy 55.352146 -393.476031) (xy 55.32266 -393.521912)
			(xy 55.286945 -393.563129) (xy 55.245728 -393.598844) (xy 55.199847 -393.62833) (xy 55.150237 -393.650987)
			(xy 55.097907 -393.666352) (xy 55.043923 -393.674114) (xy 54.989385 -393.674114) (xy 54.935401 -393.666352)
			(xy 54.883071 -393.650987) (xy 54.833461 -393.62833) (xy 54.78758 -393.598844) (xy 54.746363 -393.563129)
			(xy 54.710648 -393.521912) (xy 54.681162 -393.476031) (xy 54.658505 -393.426421) (xy 54.64314 -393.374091)
			(xy 54.635378 -393.320107) (xy 54.634892 -393.292838) (xy 54.198012 -393.292838) (xy 54.197526 -393.320089)
			(xy 54.18977 -393.374037) (xy 54.174415 -393.426332) (xy 54.151773 -393.475909) (xy 54.122307 -393.521759)
			(xy 54.086616 -393.56295) (xy 54.045425 -393.598641) (xy 53.999575 -393.628107) (xy 53.949998 -393.650749)
			(xy 53.897703 -393.666104) (xy 53.843755 -393.67386) (xy 53.789253 -393.67386) (xy 53.735305 -393.666104)
			(xy 53.68301 -393.650749) (xy 53.633433 -393.628107) (xy 53.587583 -393.598641) (xy 53.546392 -393.56295)
			(xy 53.510701 -393.521759) (xy 53.481235 -393.475909) (xy 53.458593 -393.426332) (xy 53.443238 -393.374037)
			(xy 53.435482 -393.320089) (xy 53.434996 -393.292838) (xy 52.998116 -393.292838) (xy 52.99763 -393.320089)
			(xy 52.989874 -393.374037) (xy 52.974519 -393.426332) (xy 52.951877 -393.475909) (xy 52.922411 -393.521759)
			(xy 52.88672 -393.56295) (xy 52.845529 -393.598641) (xy 52.799679 -393.628107) (xy 52.750102 -393.650749)
			(xy 52.697807 -393.666104) (xy 52.643859 -393.67386) (xy 52.589357 -393.67386) (xy 52.535409 -393.666104)
			(xy 52.483114 -393.650749) (xy 52.433537 -393.628107) (xy 52.387687 -393.598641) (xy 52.346496 -393.56295)
			(xy 52.310805 -393.521759) (xy 52.281339 -393.475909) (xy 52.258697 -393.426332) (xy 52.243342 -393.374037)
			(xy 52.235586 -393.320089) (xy 52.2351 -393.292838) (xy 51.79822 -393.292838) (xy 51.797734 -393.320107)
			(xy 51.789972 -393.374091) (xy 51.774607 -393.426421) (xy 51.75195 -393.476031) (xy 51.722464 -393.521912)
			(xy 51.686749 -393.563129) (xy 51.645532 -393.598844) (xy 51.599651 -393.62833) (xy 51.550041 -393.650987)
			(xy 51.497711 -393.666352) (xy 51.443727 -393.674114) (xy 51.389189 -393.674114) (xy 51.335205 -393.666352)
			(xy 51.282875 -393.650987) (xy 51.233265 -393.62833) (xy 51.187384 -393.598844) (xy 51.146167 -393.563129)
			(xy 51.110452 -393.521912) (xy 51.080966 -393.476031) (xy 51.058309 -393.426421) (xy 51.042944 -393.374091)
			(xy 51.035182 -393.320107) (xy 51.034696 -393.292838) (xy 50.598324 -393.292838) (xy 50.597838 -393.320107)
			(xy 50.590076 -393.374091) (xy 50.574711 -393.426421) (xy 50.552054 -393.476031) (xy 50.522568 -393.521912)
			(xy 50.486853 -393.563129) (xy 50.445636 -393.598844) (xy 50.399755 -393.62833) (xy 50.350145 -393.650987)
			(xy 50.297815 -393.666352) (xy 50.243831 -393.674114) (xy 50.189293 -393.674114) (xy 50.135309 -393.666352)
			(xy 50.082979 -393.650987) (xy 50.033369 -393.62833) (xy 49.987488 -393.598844) (xy 49.946271 -393.563129)
			(xy 49.910556 -393.521912) (xy 49.88107 -393.476031) (xy 49.858413 -393.426421) (xy 49.843048 -393.374091)
			(xy 49.835286 -393.320107) (xy 49.8348 -393.292838) (xy 49.39792 -393.292838) (xy 49.397434 -393.320089)
			(xy 49.389678 -393.374037) (xy 49.374323 -393.426332) (xy 49.351681 -393.475909) (xy 49.322215 -393.521759)
			(xy 49.286524 -393.56295) (xy 49.245333 -393.598641) (xy 49.199483 -393.628107) (xy 49.149906 -393.650749)
			(xy 49.097611 -393.666104) (xy 49.043663 -393.67386) (xy 48.989161 -393.67386) (xy 48.935213 -393.666104)
			(xy 48.882918 -393.650749) (xy 48.833341 -393.628107) (xy 48.787491 -393.598641) (xy 48.7463 -393.56295)
			(xy 48.710609 -393.521759) (xy 48.681143 -393.475909) (xy 48.658501 -393.426332) (xy 48.643146 -393.374037)
			(xy 48.63539 -393.320089) (xy 48.634904 -393.292838) (xy 48.198024 -393.292838) (xy 48.197538 -393.320089)
			(xy 48.189782 -393.374037) (xy 48.174427 -393.426332) (xy 48.151785 -393.475909) (xy 48.122319 -393.521759)
			(xy 48.086628 -393.56295) (xy 48.045437 -393.598641) (xy 47.999587 -393.628107) (xy 47.95001 -393.650749)
			(xy 47.897715 -393.666104) (xy 47.843767 -393.67386) (xy 47.789265 -393.67386) (xy 47.735317 -393.666104)
			(xy 47.683022 -393.650749) (xy 47.633445 -393.628107) (xy 47.587595 -393.598641) (xy 47.546404 -393.56295)
			(xy 47.510713 -393.521759) (xy 47.481247 -393.475909) (xy 47.458605 -393.426332) (xy 47.44325 -393.374037)
			(xy 47.435494 -393.320089) (xy 47.435008 -393.292838) (xy 2.509012 -393.292838) (xy 2.509012 -393.692888)
			(xy 303.485804 -393.692888) (xy 303.485804 -393.69238) (xy 303.486244 -393.668388) (xy 303.493754 -393.620994)
			(xy 303.508585 -393.575359) (xy 303.530372 -393.532605) (xy 303.558579 -393.493786) (xy 303.592511 -393.459858)
			(xy 303.631333 -393.431655) (xy 303.674088 -393.409872) (xy 303.719725 -393.395046) (xy 303.76712 -393.387542)
			(xy 303.791112 -393.387072) (xy 303.815046 -393.38757) (xy 303.862329 -393.395022) (xy 303.907871 -393.409757)
			(xy 303.950558 -393.431416) (xy 303.989344 -393.459467) (xy 304.02328 -393.493224) (xy 304.051536 -393.531861)
			(xy 304.062892 -393.552934) (xy 304.0634 -393.55395) (xy 304.143706 -393.692888) (xy 304.6857 -393.692888)
			(xy 304.6857 -393.69238) (xy 304.686144 -393.668388) (xy 304.693654 -393.620995) (xy 304.708484 -393.57536)
			(xy 304.730271 -393.532606) (xy 304.758477 -393.493788) (xy 304.792409 -393.459859) (xy 304.83123 -393.431656)
			(xy 304.873986 -393.409873) (xy 304.919622 -393.395047) (xy 304.967016 -393.387542) (xy 304.991008 -393.387072)
			(xy 305.014941 -393.387573) (xy 305.062224 -393.395024) (xy 305.107767 -393.409759) (xy 305.150453 -393.431417)
			(xy 305.189239 -393.459468) (xy 305.223176 -393.493224) (xy 305.251432 -393.531861) (xy 305.262788 -393.552934)
			(xy 305.263296 -393.55395) (xy 305.343602 -393.692888) (xy 305.885596 -393.692888) (xy 305.885596 -393.69238)
			(xy 305.886044 -393.668388) (xy 305.893553 -393.620995) (xy 305.908384 -393.575361) (xy 305.93017 -393.532608)
			(xy 305.958376 -393.493789) (xy 305.992307 -393.459861) (xy 306.031128 -393.431658) (xy 306.073883 -393.409875)
			(xy 306.119519 -393.395048) (xy 306.166912 -393.387542) (xy 306.190904 -393.387072) (xy 306.191158 -393.387072)
			(xy 306.215093 -393.387532) (xy 306.262378 -393.394992) (xy 306.307921 -393.409734) (xy 306.350607 -393.431398)
			(xy 306.389393 -393.459455) (xy 306.423328 -393.493217) (xy 306.451583 -393.531859) (xy 306.462938 -393.552934)
			(xy 306.463446 -393.55395) (xy 306.543752 -393.692888) (xy 307.085492 -393.692888) (xy 307.085492 -393.69238)
			(xy 307.085921 -393.668374) (xy 307.093438 -393.620953) (xy 307.108285 -393.575293) (xy 307.130095 -393.53252)
			(xy 307.158331 -393.493687) (xy 307.192296 -393.459752) (xy 307.231154 -393.431552) (xy 307.273947 -393.40978)
			(xy 307.31962 -393.394974) (xy 307.367047 -393.387499) (xy 307.391054 -393.387072) (xy 307.414989 -393.387536)
			(xy 307.462274 -393.394994) (xy 307.507817 -393.409736) (xy 307.550503 -393.4314) (xy 307.589289 -393.459456)
			(xy 307.623224 -393.493218) (xy 307.651479 -393.531859) (xy 307.662834 -393.552934) (xy 307.663342 -393.55395)
			(xy 307.743648 -393.692888) (xy 308.285388 -393.692888) (xy 308.285388 -393.69238) (xy 308.285821 -393.668374)
			(xy 308.293338 -393.620954) (xy 308.308185 -393.575294) (xy 308.329994 -393.532521) (xy 308.35823 -393.493689)
			(xy 308.392194 -393.459754) (xy 308.431052 -393.431553) (xy 308.473844 -393.409781) (xy 308.519517 -393.394975)
			(xy 308.566943 -393.3875) (xy 308.59095 -393.387072) (xy 308.614885 -393.387539) (xy 308.662169 -393.394997)
			(xy 308.707712 -393.409738) (xy 308.750399 -393.431401) (xy 308.789184 -393.459457) (xy 308.82312 -393.493218)
			(xy 308.851375 -393.531859) (xy 308.86273 -393.552934) (xy 308.863238 -393.55395) (xy 308.943544 -393.692888)
			(xy 309.485792 -393.692888) (xy 309.485792 -393.69238) (xy 309.486244 -393.668388) (xy 309.493753 -393.620996)
			(xy 309.508583 -393.575362) (xy 309.530369 -393.532609) (xy 309.558575 -393.49379) (xy 309.592506 -393.459862)
			(xy 309.631326 -393.431659) (xy 309.67408 -393.409876) (xy 309.719715 -393.395049) (xy 309.767108 -393.387543)
			(xy 309.7911 -393.387072) (xy 309.815033 -393.38758) (xy 309.862316 -393.39503) (xy 309.907858 -393.409764)
			(xy 309.950544 -393.43142) (xy 309.989331 -393.45947) (xy 310.023268 -393.493226) (xy 310.051524 -393.531862)
			(xy 310.06288 -393.552934) (xy 310.063388 -393.55395) (xy 310.143694 -393.692888) (xy 310.685688 -393.692888)
			(xy 310.685688 -393.69238) (xy 310.686144 -393.668388) (xy 310.693653 -393.620996) (xy 310.708483 -393.575362)
			(xy 310.730269 -393.53261) (xy 310.758474 -393.493792) (xy 310.792404 -393.459863) (xy 310.831224 -393.43166)
			(xy 310.873977 -393.409877) (xy 310.919612 -393.395049) (xy 310.967004 -393.387543) (xy 310.990996 -393.387072)
			(xy 311.014932 -393.387502) (xy 311.062218 -393.394966) (xy 311.107762 -393.409714) (xy 311.150449 -393.431384)
			(xy 311.189234 -393.459445) (xy 311.223168 -393.493212) (xy 311.251422 -393.531857) (xy 311.262776 -393.552934)
			(xy 311.263284 -393.55395) (xy 311.34359 -393.692888) (xy 311.885584 -393.692888) (xy 311.885584 -393.69238)
			(xy 311.886044 -393.668389) (xy 311.893553 -393.620997) (xy 311.908383 -393.575363) (xy 311.930168 -393.532611)
			(xy 311.958373 -393.493793) (xy 311.992302 -393.459865) (xy 312.031121 -393.431662) (xy 312.073874 -393.409878)
			(xy 312.119509 -393.39505) (xy 312.166901 -393.387543) (xy 312.190892 -393.387072) (xy 312.191146 -393.387072)
			(xy 312.215081 -393.387542) (xy 312.262365 -393.394999) (xy 312.307908 -393.40974) (xy 312.350594 -393.431403)
			(xy 312.38938 -393.459458) (xy 312.423316 -393.493219) (xy 312.451571 -393.531859) (xy 312.462926 -393.552934)
			(xy 312.463434 -393.55395) (xy 312.54374 -393.692888) (xy 313.08548 -393.692888) (xy 313.08548 -393.69238)
			(xy 313.085921 -393.668374) (xy 313.093438 -393.620955) (xy 313.108284 -393.575296) (xy 313.130093 -393.532524)
			(xy 313.158327 -393.493692) (xy 313.192291 -393.459757) (xy 313.231147 -393.431556) (xy 313.273939 -393.409783)
			(xy 313.31961 -393.394977) (xy 313.367036 -393.3875) (xy 313.391042 -393.387072) (xy 313.391296 -393.387072)
			(xy 313.415232 -393.387502) (xy 313.462518 -393.394966) (xy 313.508062 -393.409714) (xy 313.550749 -393.431384)
			(xy 313.589534 -393.459445) (xy 313.623468 -393.493212) (xy 313.651722 -393.531857) (xy 313.663076 -393.552934)
			(xy 313.663584 -393.55395) (xy 313.74389 -393.692888) (xy 314.285376 -393.692888) (xy 314.285376 -393.69238)
			(xy 314.285821 -393.668374) (xy 314.293338 -393.620955) (xy 314.308183 -393.575297) (xy 314.329992 -393.532525)
			(xy 314.358226 -393.493693) (xy 314.392189 -393.459758) (xy 314.431045 -393.431557) (xy 314.473836 -393.409785)
			(xy 314.519507 -393.394977) (xy 314.566932 -393.3875) (xy 314.590938 -393.387072) (xy 314.591192 -393.387072)
			(xy 314.615128 -393.387505) (xy 314.662414 -393.394969) (xy 314.707958 -393.409716) (xy 314.750644 -393.431385)
			(xy 314.78943 -393.459446) (xy 314.823364 -393.493212) (xy 314.851618 -393.531857) (xy 314.862972 -393.552934)
			(xy 314.86348 -393.55395) (xy 314.943786 -393.692888) (xy 315.48578 -393.692888) (xy 315.48578 -393.69238)
			(xy 315.486244 -393.668389) (xy 315.493753 -393.620998) (xy 315.508582 -393.575364) (xy 315.530367 -393.532612)
			(xy 315.558571 -393.493795) (xy 315.592501 -393.459866) (xy 315.631319 -393.431663) (xy 315.674072 -393.409879)
			(xy 315.719705 -393.395051) (xy 315.767097 -393.387543) (xy 315.791088 -393.387072) (xy 315.815024 -393.387508)
			(xy 315.86231 -393.394972) (xy 315.907853 -393.409718) (xy 315.95054 -393.431387) (xy 315.989325 -393.459447)
			(xy 316.02326 -393.493213) (xy 316.051514 -393.531858) (xy 316.062868 -393.552934) (xy 316.063376 -393.55395)
			(xy 316.143682 -393.692888) (xy 316.685676 -393.692888) (xy 316.685676 -393.69238) (xy 316.686144 -393.668389)
			(xy 316.693653 -393.620998) (xy 316.708482 -393.575365) (xy 316.730267 -393.532614) (xy 316.75847 -393.493796)
			(xy 316.792399 -393.459868) (xy 316.831217 -393.431664) (xy 316.873969 -393.40988) (xy 316.919602 -393.395052)
			(xy 316.966993 -393.387544) (xy 316.990984 -393.387072) (xy 316.991238 -393.387072) (xy 317.015172 -393.387549)
			(xy 317.062456 -393.395005) (xy 317.107999 -393.409744) (xy 317.150686 -393.431406) (xy 317.189472 -393.45946)
			(xy 317.223407 -393.49322) (xy 317.251663 -393.53186) (xy 317.263018 -393.552934) (xy 317.263526 -393.55395)
			(xy 317.343832 -393.692888) (xy 317.885572 -393.692888) (xy 317.885572 -393.69238) (xy 317.886021 -393.668375)
			(xy 317.893538 -393.620956) (xy 317.908383 -393.575298) (xy 317.930191 -393.532526) (xy 317.958425 -393.493694)
			(xy 317.992388 -393.45976) (xy 318.031243 -393.431558) (xy 318.074033 -393.409786) (xy 318.119703 -393.394978)
			(xy 318.167128 -393.387501) (xy 318.191134 -393.387072) (xy 318.215068 -393.387552) (xy 318.262352 -393.395007)
			(xy 318.307895 -393.409746) (xy 318.350581 -393.431407) (xy 318.389367 -393.459461) (xy 318.423303 -393.493221)
			(xy 318.451559 -393.53186) (xy 318.462914 -393.552934) (xy 318.463422 -393.55395) (xy 318.543728 -393.692888)
			(xy 319.085468 -393.692888) (xy 319.085468 -393.69238) (xy 319.085921 -393.668375) (xy 319.093437 -393.620957)
			(xy 319.108283 -393.575299) (xy 319.130091 -393.532527) (xy 319.158324 -393.493696) (xy 319.192286 -393.459761)
			(xy 319.231141 -393.43156) (xy 319.27393 -393.409787) (xy 319.3196 -393.394979) (xy 319.367024 -393.387501)
			(xy 319.39103 -393.387072) (xy 319.391284 -393.387072) (xy 319.41522 -393.387511) (xy 319.462506 -393.394974)
			(xy 319.508049 -393.40972) (xy 319.550736 -393.431388) (xy 319.589521 -393.459448) (xy 319.623456 -393.493214)
			(xy 319.65171 -393.531858) (xy 319.663064 -393.552934) (xy 319.663572 -393.55395) (xy 319.743878 -393.692888)
			(xy 320.285872 -393.692888) (xy 320.285872 -393.69238) (xy 320.286344 -393.668389) (xy 320.293853 -393.620999)
			(xy 320.308681 -393.575366) (xy 320.330466 -393.532615) (xy 320.358669 -393.493797) (xy 320.392597 -393.459869)
			(xy 320.431415 -393.431666) (xy 320.474166 -393.409881) (xy 320.519799 -393.395053) (xy 320.567189 -393.387544)
			(xy 320.59118 -393.387072) (xy 320.615116 -393.387515) (xy 320.662401 -393.394977) (xy 320.707945 -393.409722)
			(xy 320.750631 -393.43139) (xy 320.789417 -393.459449) (xy 320.823352 -393.493214) (xy 320.851606 -393.531858)
			(xy 320.86296 -393.552934) (xy 320.863468 -393.55395) (xy 320.943774 -393.692888) (xy 321.485768 -393.692888)
			(xy 321.485768 -393.69238) (xy 321.486244 -393.668389) (xy 321.493752 -393.620999) (xy 321.508581 -393.575367)
			(xy 321.530365 -393.532616) (xy 321.558568 -393.493799) (xy 321.592496 -393.459871) (xy 321.631313 -393.431667)
			(xy 321.674063 -393.409883) (xy 321.719695 -393.395053) (xy 321.767085 -393.387544) (xy 321.791076 -393.387072)
			(xy 321.815011 -393.387518) (xy 321.862297 -393.39498) (xy 321.90784 -393.409724) (xy 321.950527 -393.431391)
			(xy 321.989312 -393.45945) (xy 322.023247 -393.493215) (xy 322.051501 -393.531858) (xy 322.062856 -393.552934)
			(xy 322.063364 -393.55395) (xy 322.14367 -393.692888) (xy 336.013552 -393.692888) (xy 336.013552 -393.69238)
			(xy 336.014044 -393.66839) (xy 336.021552 -393.621002) (xy 336.03638 -393.575371) (xy 336.058162 -393.532621)
			(xy 336.086363 -393.493804) (xy 336.120289 -393.459876) (xy 336.159104 -393.431673) (xy 336.201852 -393.409887)
			(xy 336.247482 -393.395057) (xy 336.29487 -393.387546) (xy 336.31886 -393.387072) (xy 336.342795 -393.387531)
			(xy 336.39008 -393.39499) (xy 336.435623 -393.409733) (xy 336.47831 -393.431398) (xy 336.517095 -393.459455)
			(xy 336.551031 -393.493217) (xy 336.579285 -393.531859) (xy 336.59064 -393.552934) (xy 336.591148 -393.55395)
			(xy 336.671454 -393.692888) (xy 337.213448 -393.692888) (xy 337.213448 -393.69238) (xy 337.213944 -393.66839)
			(xy 337.221452 -393.621002) (xy 337.236279 -393.575372) (xy 337.258061 -393.532622) (xy 337.286262 -393.493805)
			(xy 337.320187 -393.459878) (xy 337.359001 -393.431674) (xy 337.401749 -393.409888) (xy 337.447379 -393.395057)
			(xy 337.494766 -393.387546) (xy 337.518756 -393.387072) (xy 337.542691 -393.387534) (xy 337.589976 -393.394993)
			(xy 337.635519 -393.409735) (xy 337.678205 -393.431399) (xy 337.716991 -393.459456) (xy 337.750926 -393.493218)
			(xy 337.779181 -393.531859) (xy 337.790536 -393.552934) (xy 337.791044 -393.55395) (xy 337.87135 -393.692888)
			(xy 338.413344 -393.692888) (xy 338.413344 -393.69238) (xy 338.413844 -393.668391) (xy 338.421352 -393.621003)
			(xy 338.436179 -393.575373) (xy 338.457961 -393.532623) (xy 338.486161 -393.493807) (xy 338.520086 -393.459879)
			(xy 338.558899 -393.431675) (xy 338.601647 -393.40989) (xy 338.647276 -393.395058) (xy 338.694663 -393.387546)
			(xy 338.718652 -393.387072) (xy 338.718906 -393.387072) (xy 338.742839 -393.387575) (xy 338.790122 -393.395026)
			(xy 338.835664 -393.40976) (xy 338.878351 -393.431418) (xy 338.917137 -393.459468) (xy 338.951074 -393.493225)
			(xy 338.97933 -393.531861) (xy 338.990686 -393.552934) (xy 338.991194 -393.55395) (xy 339.0715 -393.692888)
			(xy 339.61324 -393.692888) (xy 339.61324 -393.69238) (xy 339.613621 -393.668371) (xy 339.62114 -393.620946)
			(xy 339.63599 -393.575282) (xy 339.657804 -393.532506) (xy 339.686045 -393.493671) (xy 339.720016 -393.459735)
			(xy 339.758881 -393.431535) (xy 339.80168 -393.409766) (xy 339.84736 -393.394965) (xy 339.894793 -393.387496)
			(xy 339.918802 -393.387072) (xy 339.942735 -393.387578) (xy 339.990018 -393.395028) (xy 340.03556 -393.409763)
			(xy 340.078247 -393.43142) (xy 340.117033 -393.459469) (xy 340.15097 -393.493225) (xy 340.179226 -393.531861)
			(xy 340.190582 -393.552934) (xy 340.19109 -393.55395) (xy 340.271396 -393.692888) (xy 340.813136 -393.692888)
			(xy 340.813136 -393.69238) (xy 340.813521 -393.668371) (xy 340.82104 -393.620947) (xy 340.835889 -393.575283)
			(xy 340.857703 -393.532507) (xy 340.885944 -393.493672) (xy 340.919915 -393.459737) (xy 340.958779 -393.431537)
			(xy 341.001577 -393.409767) (xy 341.047256 -393.394965) (xy 341.094689 -393.387496) (xy 341.118698 -393.387072)
			(xy 341.142634 -393.3875) (xy 341.189921 -393.394965) (xy 341.235464 -393.409713) (xy 341.278151 -393.431383)
			(xy 341.316936 -393.459445) (xy 341.35087 -393.493212) (xy 341.379124 -393.531857) (xy 341.390478 -393.552934)
			(xy 341.390986 -393.55395) (xy 341.471292 -393.692888) (xy 342.01354 -393.692888) (xy 342.01354 -393.69238)
			(xy 342.01392 -393.668384) (xy 342.021431 -393.620983) (xy 342.036265 -393.575341) (xy 342.058057 -393.532582)
			(xy 342.08627 -393.493758) (xy 342.12021 -393.459826) (xy 342.15904 -393.431622) (xy 342.201804 -393.409839)
			(xy 342.247449 -393.395015) (xy 342.294852 -393.387515) (xy 342.318848 -393.387072) (xy 342.342783 -393.387541)
			(xy 342.390067 -393.394998) (xy 342.43561 -393.409739) (xy 342.478297 -393.431402) (xy 342.517082 -393.459458)
			(xy 342.551018 -393.493219) (xy 342.579273 -393.531859) (xy 342.590628 -393.552934) (xy 342.591136 -393.55395)
			(xy 342.671442 -393.692888) (xy 343.213436 -393.692888) (xy 343.213436 -393.69238) (xy 343.21382 -393.668384)
			(xy 343.221331 -393.620984) (xy 343.236165 -393.575342) (xy 343.257957 -393.532583) (xy 343.286169 -393.493759)
			(xy 343.320108 -393.459828) (xy 343.358938 -393.431623) (xy 343.401701 -393.40984) (xy 343.447346 -393.395016)
			(xy 343.494748 -393.387515) (xy 343.518744 -393.387072) (xy 343.542678 -393.387544) (xy 343.589963 -393.395001)
			(xy 343.635506 -393.409741) (xy 343.678192 -393.431404) (xy 343.716978 -393.459459) (xy 343.750914 -393.493219)
			(xy 343.779169 -393.53186) (xy 343.790524 -393.552934) (xy 343.791032 -393.55395) (xy 343.871338 -393.692888)
			(xy 344.413332 -393.692888) (xy 344.413332 -393.69238) (xy 344.41372 -393.668384) (xy 344.421231 -393.620984)
			(xy 344.436065 -393.575343) (xy 344.457856 -393.532584) (xy 344.486068 -393.493761) (xy 344.520006 -393.459829)
			(xy 344.558835 -393.431624) (xy 344.601598 -393.409842) (xy 344.647243 -393.395017) (xy 344.694644 -393.387515)
			(xy 344.71864 -393.387072) (xy 344.718894 -393.387072) (xy 344.74283 -393.387503) (xy 344.790116 -393.394968)
			(xy 344.83566 -393.409715) (xy 344.878347 -393.431385) (xy 344.917132 -393.459446) (xy 344.951066 -393.493212)
			(xy 344.97932 -393.531857) (xy 344.990674 -393.552934) (xy 344.991182 -393.55395) (xy 345.071488 -393.692888)
			(xy 345.613228 -393.692888) (xy 345.613228 -393.69238) (xy 345.613621 -393.668372) (xy 345.621139 -393.620948)
			(xy 345.635988 -393.575285) (xy 345.657802 -393.532509) (xy 345.686041 -393.493675) (xy 345.720011 -393.45974)
			(xy 345.758874 -393.431539) (xy 345.801672 -393.40977) (xy 345.84735 -393.394967) (xy 345.894781 -393.387497)
			(xy 345.91879 -393.387072) (xy 345.942726 -393.387506) (xy 345.990012 -393.39497) (xy 346.035556 -393.409717)
			(xy 346.078242 -393.431386) (xy 346.117027 -393.459447) (xy 346.150962 -393.493213) (xy 346.179216 -393.531857)
			(xy 346.19057 -393.552934) (xy 346.191078 -393.55395) (xy 346.271384 -393.692888) (xy 346.813124 -393.692888)
			(xy 346.813124 -393.69238) (xy 346.813521 -393.668372) (xy 346.821039 -393.620948) (xy 346.835888 -393.575286)
			(xy 346.857701 -393.53251) (xy 346.88594 -393.493676) (xy 346.919909 -393.459741) (xy 346.958772 -393.431541)
			(xy 347.001569 -393.409771) (xy 347.047246 -393.394968) (xy 347.094678 -393.387497) (xy 347.118686 -393.387072)
			(xy 347.142622 -393.38751) (xy 347.189908 -393.394973) (xy 347.235451 -393.409719) (xy 347.278138 -393.431388)
			(xy 347.316923 -393.459448) (xy 347.350858 -393.493213) (xy 347.379112 -393.531858) (xy 347.390466 -393.552934)
			(xy 347.390974 -393.55395) (xy 347.47128 -393.692888) (xy 348.013528 -393.692888) (xy 348.013528 -393.69238)
			(xy 348.01392 -393.668385) (xy 348.021431 -393.620985) (xy 348.036264 -393.575344) (xy 348.058055 -393.532585)
			(xy 348.086267 -393.493762) (xy 348.120205 -393.45983) (xy 348.159033 -393.431626) (xy 348.201796 -393.409843)
			(xy 348.247439 -393.395018) (xy 348.29484 -393.387515) (xy 348.318836 -393.387072) (xy 348.34277 -393.38755)
			(xy 348.390054 -393.395006) (xy 348.435597 -393.409745) (xy 348.478284 -393.431407) (xy 348.517069 -393.459461)
			(xy 348.551005 -393.49322) (xy 348.579261 -393.53186) (xy 348.590616 -393.552934) (xy 348.591124 -393.55395)
			(xy 348.67143 -393.692888) (xy 349.213424 -393.692888) (xy 349.213424 -393.69238) (xy 349.21382 -393.668385)
			(xy 349.221331 -393.620985) (xy 349.236164 -393.575345) (xy 349.257954 -393.532586) (xy 349.286166 -393.493764)
			(xy 349.320103 -393.459832) (xy 349.358931 -393.431627) (xy 349.401693 -393.409844) (xy 349.447336 -393.395018)
			(xy 349.494737 -393.387516) (xy 349.518732 -393.387072) (xy 349.542666 -393.387554) (xy 349.58995 -393.395009)
			(xy 349.635493 -393.409747) (xy 349.678179 -393.431408) (xy 349.716965 -393.459462) (xy 349.750901 -393.493221)
			(xy 349.779157 -393.53186) (xy 349.790512 -393.552934) (xy 349.79102 -393.55395) (xy 349.871326 -393.692888)
			(xy 350.41332 -393.692888) (xy 350.41332 -393.69238) (xy 350.41372 -393.668385) (xy 350.42123 -393.620986)
			(xy 350.436063 -393.575346) (xy 350.457854 -393.532588) (xy 350.486065 -393.493765) (xy 350.520001 -393.459833)
			(xy 350.558829 -393.431629) (xy 350.60159 -393.409845) (xy 350.647233 -393.395019) (xy 350.694633 -393.387516)
			(xy 350.718628 -393.387072) (xy 350.718882 -393.387072) (xy 350.742818 -393.387513) (xy 350.790103 -393.394976)
			(xy 350.835647 -393.409721) (xy 350.878334 -393.431389) (xy 350.917119 -393.459449) (xy 350.951054 -393.493214)
			(xy 350.979308 -393.531858) (xy 350.990662 -393.552934) (xy 350.99117 -393.55395) (xy 351.071476 -393.692888)
			(xy 351.613216 -393.692888) (xy 351.613216 -393.69238) (xy 351.613621 -393.668372) (xy 351.621139 -393.620949)
			(xy 351.635987 -393.575288) (xy 351.657799 -393.532513) (xy 351.686038 -393.493679) (xy 351.720006 -393.459744)
			(xy 351.758867 -393.431543) (xy 351.801664 -393.409773) (xy 351.84734 -393.394969) (xy 351.89477 -393.387497)
			(xy 351.918778 -393.387072) (xy 351.942713 -393.387516) (xy 351.989999 -393.394978) (xy 352.035543 -393.409723)
			(xy 352.078229 -393.431391) (xy 352.117015 -393.45945) (xy 352.150949 -393.493214) (xy 352.179204 -393.531858)
			(xy 352.190558 -393.552934) (xy 352.191066 -393.55395) (xy 352.271372 -393.692888) (xy 352.813112 -393.692888)
			(xy 352.813112 -393.69238) (xy 352.813521 -393.668373) (xy 352.821039 -393.62095) (xy 352.835887 -393.575289)
			(xy 352.857699 -393.532514) (xy 352.885937 -393.493681) (xy 352.919904 -393.459745) (xy 352.958765 -393.431545)
			(xy 353.001561 -393.409774) (xy 353.047236 -393.39497) (xy 353.094666 -393.387498) (xy 353.118674 -393.387072)
			(xy 353.118928 -393.387072) (xy 353.142862 -393.387557) (xy 353.190146 -393.395011) (xy 353.235688 -393.409749)
			(xy 353.278375 -393.43141) (xy 353.317161 -393.459463) (xy 353.351097 -393.493222) (xy 353.379353 -393.53186)
			(xy 353.390708 -393.552934) (xy 353.391216 -393.55395) (xy 353.471522 -393.692888) (xy 354.013516 -393.692888)
			(xy 354.013516 -393.69238) (xy 354.01392 -393.668385) (xy 354.02143 -393.620987) (xy 354.036263 -393.575347)
			(xy 354.058053 -393.532589) (xy 354.086263 -393.493766) (xy 354.1202 -393.459835) (xy 354.159026 -393.43163)
			(xy 354.201787 -393.409846) (xy 354.247429 -393.39502) (xy 354.294829 -393.387516) (xy 354.318824 -393.387072)
			(xy 354.342758 -393.38756) (xy 354.390042 -393.395014) (xy 354.435584 -393.409751) (xy 354.478271 -393.431411)
			(xy 354.517057 -393.459464) (xy 354.550993 -393.493222) (xy 354.579249 -393.53186) (xy 354.590604 -393.552934)
			(xy 354.591112 -393.55395) (xy 354.671418 -393.692888) (xy 370.586 -393.692888) (xy 370.586 -393.69238)
			(xy 370.586444 -393.668388) (xy 370.593954 -393.620995) (xy 370.608784 -393.57536) (xy 370.630571 -393.532606)
			(xy 370.658777 -393.493788) (xy 370.692709 -393.459859) (xy 370.73153 -393.431656) (xy 370.774286 -393.409873)
			(xy 370.819922 -393.395047) (xy 370.867316 -393.387542) (xy 370.891308 -393.387072) (xy 370.915241 -393.387573)
			(xy 370.962524 -393.395024) (xy 371.008067 -393.409759) (xy 371.050753 -393.431417) (xy 371.089539 -393.459468)
			(xy 371.123476 -393.493224) (xy 371.151732 -393.531861) (xy 371.163088 -393.552934) (xy 371.163596 -393.55395)
			(xy 371.243902 -393.692888) (xy 371.785896 -393.692888) (xy 371.785896 -393.69238) (xy 371.786344 -393.668388)
			(xy 371.793853 -393.620995) (xy 371.808684 -393.575361) (xy 371.83047 -393.532608) (xy 371.858676 -393.493789)
			(xy 371.892607 -393.459861) (xy 371.931428 -393.431658) (xy 371.974183 -393.409875) (xy 372.019819 -393.395048)
			(xy 372.067212 -393.387542) (xy 372.091204 -393.387072) (xy 372.115137 -393.387576) (xy 372.16242 -393.395027)
			(xy 372.207962 -393.409762) (xy 372.250649 -393.431419) (xy 372.289435 -393.459469) (xy 372.323372 -393.493225)
			(xy 372.351628 -393.531861) (xy 372.362984 -393.552934) (xy 372.363492 -393.55395) (xy 372.443798 -393.692888)
			(xy 372.985792 -393.692888) (xy 372.985792 -393.69238) (xy 372.986244 -393.668388) (xy 372.993753 -393.620996)
			(xy 373.008583 -393.575362) (xy 373.030369 -393.532609) (xy 373.058575 -393.49379) (xy 373.092506 -393.459862)
			(xy 373.131326 -393.431659) (xy 373.17408 -393.409876) (xy 373.219715 -393.395049) (xy 373.267108 -393.387543)
			(xy 373.2911 -393.387072) (xy 373.315033 -393.38758) (xy 373.362316 -393.39503) (xy 373.407858 -393.409764)
			(xy 373.450544 -393.43142) (xy 373.489331 -393.45947) (xy 373.523268 -393.493226) (xy 373.551524 -393.531862)
			(xy 373.56288 -393.552934) (xy 373.563388 -393.55395) (xy 373.643694 -393.692888) (xy 374.185688 -393.692888)
			(xy 374.185688 -393.69238) (xy 374.186121 -393.668374) (xy 374.193638 -393.620954) (xy 374.208485 -393.575294)
			(xy 374.230294 -393.532521) (xy 374.25853 -393.493689) (xy 374.292494 -393.459754) (xy 374.331352 -393.431553)
			(xy 374.374144 -393.409781) (xy 374.419817 -393.394975) (xy 374.467243 -393.3875) (xy 374.49125 -393.387072)
			(xy 374.515185 -393.387539) (xy 374.562469 -393.394997) (xy 374.608012 -393.409738) (xy 374.650699 -393.431401)
			(xy 374.689484 -393.459457) (xy 374.72342 -393.493218) (xy 374.751675 -393.531859) (xy 374.76303 -393.552934)
			(xy 374.763538 -393.55395) (xy 374.843844 -393.692888) (xy 375.385584 -393.692888) (xy 375.385584 -393.69238)
			(xy 375.386021 -393.668374) (xy 375.393538 -393.620954) (xy 375.408384 -393.575295) (xy 375.430194 -393.532522)
			(xy 375.458428 -393.49369) (xy 375.492393 -393.459755) (xy 375.53125 -393.431554) (xy 375.574041 -393.409782)
			(xy 375.619713 -393.394976) (xy 375.66714 -393.3875) (xy 375.691146 -393.387072) (xy 375.715081 -393.387542)
			(xy 375.762365 -393.394999) (xy 375.807908 -393.40974) (xy 375.850594 -393.431403) (xy 375.88938 -393.459458)
			(xy 375.923316 -393.493219) (xy 375.951571 -393.531859) (xy 375.962926 -393.552934) (xy 375.963434 -393.55395)
			(xy 376.04374 -393.692888) (xy 376.585988 -393.692888) (xy 376.585988 -393.69238) (xy 376.586444 -393.668388)
			(xy 376.593953 -393.620996) (xy 376.608783 -393.575362) (xy 376.630569 -393.53261) (xy 376.658774 -393.493792)
			(xy 376.692704 -393.459863) (xy 376.731524 -393.43166) (xy 376.774277 -393.409877) (xy 376.819912 -393.395049)
			(xy 376.867304 -393.387543) (xy 376.891296 -393.387072) (xy 376.915232 -393.387502) (xy 376.962518 -393.394966)
			(xy 377.008062 -393.409714) (xy 377.050749 -393.431384) (xy 377.089534 -393.459445) (xy 377.123468 -393.493212)
			(xy 377.151722 -393.531857) (xy 377.163076 -393.552934) (xy 377.163584 -393.55395) (xy 377.24389 -393.692888)
			(xy 377.785884 -393.692888) (xy 377.785884 -393.69238) (xy 377.786344 -393.668389) (xy 377.793853 -393.620997)
			(xy 377.808683 -393.575363) (xy 377.830468 -393.532611) (xy 377.858673 -393.493793) (xy 377.892602 -393.459865)
			(xy 377.931421 -393.431662) (xy 377.974174 -393.409878) (xy 378.019809 -393.39505) (xy 378.067201 -393.387543)
			(xy 378.091192 -393.387072) (xy 378.115128 -393.387505) (xy 378.162414 -393.394969) (xy 378.207958 -393.409716)
			(xy 378.250644 -393.431385) (xy 378.28943 -393.459446) (xy 378.323364 -393.493212) (xy 378.351618 -393.531857)
			(xy 378.362972 -393.552934) (xy 378.36348 -393.55395) (xy 378.443786 -393.692888) (xy 378.98578 -393.692888)
			(xy 378.98578 -393.69238) (xy 378.986244 -393.668389) (xy 378.993753 -393.620998) (xy 379.008582 -393.575364)
			(xy 379.030367 -393.532612) (xy 379.058571 -393.493795) (xy 379.092501 -393.459866) (xy 379.131319 -393.431663)
			(xy 379.174072 -393.409879) (xy 379.219705 -393.395051) (xy 379.267097 -393.387543) (xy 379.291088 -393.387072)
			(xy 379.315024 -393.387508) (xy 379.36231 -393.394972) (xy 379.407853 -393.409718) (xy 379.45054 -393.431387)
			(xy 379.489325 -393.459447) (xy 379.52326 -393.493213) (xy 379.551514 -393.531858) (xy 379.562868 -393.552934)
			(xy 379.563376 -393.55395) (xy 379.643682 -393.692888) (xy 380.185676 -393.692888) (xy 380.185676 -393.69238)
			(xy 380.186121 -393.668374) (xy 380.193638 -393.620955) (xy 380.208483 -393.575297) (xy 380.230292 -393.532525)
			(xy 380.258526 -393.493693) (xy 380.292489 -393.459758) (xy 380.331345 -393.431557) (xy 380.374136 -393.409785)
			(xy 380.419807 -393.394977) (xy 380.467232 -393.3875) (xy 380.491238 -393.387072) (xy 380.515172 -393.387549)
			(xy 380.562456 -393.395005) (xy 380.607999 -393.409744) (xy 380.650686 -393.431406) (xy 380.689472 -393.45946)
			(xy 380.723407 -393.49322) (xy 380.751663 -393.53186) (xy 380.763018 -393.552934) (xy 380.763526 -393.55395)
			(xy 380.843832 -393.692888) (xy 381.385572 -393.692888) (xy 381.385572 -393.69238) (xy 381.386021 -393.668375)
			(xy 381.393538 -393.620956) (xy 381.408383 -393.575298) (xy 381.430191 -393.532526) (xy 381.458425 -393.493694)
			(xy 381.492388 -393.45976) (xy 381.531243 -393.431558) (xy 381.574033 -393.409786) (xy 381.619703 -393.394978)
			(xy 381.667128 -393.387501) (xy 381.691134 -393.387072) (xy 381.715068 -393.387552) (xy 381.762352 -393.395007)
			(xy 381.807895 -393.409746) (xy 381.850581 -393.431407) (xy 381.889367 -393.459461) (xy 381.923303 -393.493221)
			(xy 381.951559 -393.53186) (xy 381.962914 -393.552934) (xy 381.963422 -393.55395) (xy 382.043728 -393.692888)
			(xy 382.585976 -393.692888) (xy 382.585976 -393.69238) (xy 382.586444 -393.668389) (xy 382.593953 -393.620998)
			(xy 382.608782 -393.575365) (xy 382.630567 -393.532614) (xy 382.65877 -393.493796) (xy 382.692699 -393.459868)
			(xy 382.731517 -393.431664) (xy 382.774269 -393.40988) (xy 382.819902 -393.395052) (xy 382.867293 -393.387544)
			(xy 382.891284 -393.387072) (xy 382.91522 -393.387511) (xy 382.962506 -393.394974) (xy 383.008049 -393.40972)
			(xy 383.050736 -393.431388) (xy 383.089521 -393.459448) (xy 383.123456 -393.493214) (xy 383.15171 -393.531858)
			(xy 383.163064 -393.552934) (xy 383.163572 -393.55395) (xy 383.243878 -393.692888) (xy 383.785872 -393.692888)
			(xy 383.785872 -393.69238) (xy 383.786344 -393.668389) (xy 383.793853 -393.620999) (xy 383.808681 -393.575366)
			(xy 383.830466 -393.532615) (xy 383.858669 -393.493797) (xy 383.892597 -393.459869) (xy 383.931415 -393.431666)
			(xy 383.974166 -393.409881) (xy 384.019799 -393.395053) (xy 384.067189 -393.387544) (xy 384.09118 -393.387072)
			(xy 384.115116 -393.387515) (xy 384.162401 -393.394977) (xy 384.207945 -393.409722) (xy 384.250631 -393.43139)
			(xy 384.289417 -393.459449) (xy 384.323352 -393.493214) (xy 384.351606 -393.531858) (xy 384.36296 -393.552934)
			(xy 384.363468 -393.55395) (xy 384.443774 -393.692888) (xy 384.985768 -393.692888) (xy 384.985768 -393.69238)
			(xy 384.986244 -393.668389) (xy 384.993752 -393.620999) (xy 385.008581 -393.575367) (xy 385.030365 -393.532616)
			(xy 385.058568 -393.493799) (xy 385.092496 -393.459871) (xy 385.131313 -393.431667) (xy 385.174063 -393.409883)
			(xy 385.219695 -393.395053) (xy 385.267085 -393.387544) (xy 385.291076 -393.387072) (xy 385.315011 -393.387518)
			(xy 385.362297 -393.39498) (xy 385.40784 -393.409724) (xy 385.450527 -393.431391) (xy 385.489312 -393.45945)
			(xy 385.523247 -393.493215) (xy 385.551501 -393.531858) (xy 385.562856 -393.552934) (xy 385.563364 -393.55395)
			(xy 385.64367 -393.692888) (xy 386.185664 -393.692888) (xy 386.185664 -393.69238) (xy 386.186121 -393.668375)
			(xy 386.193637 -393.620957) (xy 386.208482 -393.5753) (xy 386.23029 -393.532528) (xy 386.258522 -393.493697)
			(xy 386.292484 -393.459762) (xy 386.331339 -393.431561) (xy 386.374127 -393.409788) (xy 386.419797 -393.39498)
			(xy 386.467221 -393.387501) (xy 386.491226 -393.387072) (xy 386.51516 -393.387558) (xy 386.562444 -393.395013)
			(xy 386.607986 -393.40975) (xy 386.650673 -393.43141) (xy 386.689459 -393.459463) (xy 386.723395 -393.493222)
			(xy 386.751651 -393.53186) (xy 386.763006 -393.552934) (xy 386.763514 -393.55395) (xy 386.84382 -393.692888)
			(xy 387.38556 -393.692888) (xy 387.38556 -393.69238) (xy 387.386021 -393.668375) (xy 387.393537 -393.620958)
			(xy 387.408382 -393.575301) (xy 387.430189 -393.53253) (xy 387.458421 -393.493698) (xy 387.492383 -393.459764)
			(xy 387.531236 -393.431563) (xy 387.574025 -393.409789) (xy 387.619693 -393.394981) (xy 387.667117 -393.387502)
			(xy 387.691122 -393.387072) (xy 387.715056 -393.387562) (xy 387.762339 -393.395015) (xy 387.807882 -393.409752)
			(xy 387.850568 -393.431412) (xy 387.889354 -393.459464) (xy 387.923291 -393.493222) (xy 387.951547 -393.531861)
			(xy 387.962902 -393.552934) (xy 387.96341 -393.55395) (xy 388.043716 -393.692888) (xy 388.585964 -393.692888)
			(xy 388.585964 -393.69238) (xy 388.586444 -393.66839) (xy 388.593952 -393.621) (xy 388.608781 -393.575368)
			(xy 388.630564 -393.532617) (xy 388.658767 -393.4938) (xy 388.692694 -393.459872) (xy 388.73151 -393.431668)
			(xy 388.774261 -393.409884) (xy 388.819892 -393.395054) (xy 388.867282 -393.387545) (xy 388.891272 -393.387072)
			(xy 388.915207 -393.387521) (xy 388.962493 -393.394982) (xy 389.008036 -393.409727) (xy 389.050723 -393.431393)
			(xy 389.089508 -393.459451) (xy 389.123443 -393.493215) (xy 389.151697 -393.531858) (xy 389.163052 -393.552934)
			(xy 389.16356 -393.55395) (xy 389.243866 -393.692888) (xy 403.113748 -393.692888) (xy 403.113748 -393.69238)
			(xy 403.114244 -393.66839) (xy 403.121752 -393.621002) (xy 403.136579 -393.575372) (xy 403.158361 -393.532622)
			(xy 403.186562 -393.493805) (xy 403.220487 -393.459878) (xy 403.259301 -393.431674) (xy 403.302049 -393.409888)
			(xy 403.347679 -393.395057) (xy 403.395066 -393.387546) (xy 403.419056 -393.387072) (xy 403.442991 -393.387534)
			(xy 403.490276 -393.394993) (xy 403.535819 -393.409735) (xy 403.578505 -393.431399) (xy 403.617291 -393.459456)
			(xy 403.651226 -393.493218) (xy 403.679481 -393.531859) (xy 403.690836 -393.552934) (xy 403.691344 -393.55395)
			(xy 403.77165 -393.692888) (xy 404.313644 -393.692888) (xy 404.313644 -393.69238) (xy 404.314144 -393.668391)
			(xy 404.321652 -393.621003) (xy 404.336479 -393.575373) (xy 404.358261 -393.532623) (xy 404.386461 -393.493807)
			(xy 404.420386 -393.459879) (xy 404.459199 -393.431675) (xy 404.501947 -393.40989) (xy 404.547576 -393.395058)
			(xy 404.594963 -393.387546) (xy 404.618952 -393.387072) (xy 404.642887 -393.387537) (xy 404.690171 -393.394995)
			(xy 404.735714 -393.409737) (xy 404.778401 -393.431401) (xy 404.817187 -393.459457) (xy 404.851122 -393.493218)
			(xy 404.879377 -393.531859) (xy 404.890732 -393.552934) (xy 404.89124 -393.55395) (xy 404.971546 -393.692888)
			(xy 405.51354 -393.692888) (xy 405.51354 -393.69238) (xy 405.51392 -393.668384) (xy 405.521431 -393.620983)
			(xy 405.536265 -393.575341) (xy 405.558057 -393.532582) (xy 405.58627 -393.493758) (xy 405.62021 -393.459826)
			(xy 405.65904 -393.431622) (xy 405.701804 -393.409839) (xy 405.747449 -393.395015) (xy 405.794852 -393.387515)
			(xy 405.818848 -393.387072) (xy 405.842783 -393.387541) (xy 405.890067 -393.394998) (xy 405.93561 -393.409739)
			(xy 405.978297 -393.431402) (xy 406.017082 -393.459458) (xy 406.051018 -393.493219) (xy 406.079273 -393.531859)
			(xy 406.090628 -393.552934) (xy 406.091136 -393.55395) (xy 406.171442 -393.692888) (xy 406.713436 -393.692888)
			(xy 406.713436 -393.69238) (xy 406.713821 -393.668371) (xy 406.72134 -393.620947) (xy 406.736189 -393.575283)
			(xy 406.758003 -393.532507) (xy 406.786244 -393.493672) (xy 406.820215 -393.459737) (xy 406.859079 -393.431537)
			(xy 406.901877 -393.409767) (xy 406.947556 -393.394965) (xy 406.994989 -393.387496) (xy 407.018998 -393.387072)
			(xy 407.042934 -393.3875) (xy 407.090221 -393.394965) (xy 407.135764 -393.409713) (xy 407.178451 -393.431383)
			(xy 407.217236 -393.459445) (xy 407.25117 -393.493212) (xy 407.279424 -393.531857) (xy 407.290778 -393.552934)
			(xy 407.291286 -393.55395) (xy 407.371592 -393.692888) (xy 407.913332 -393.692888) (xy 407.913332 -393.69238)
			(xy 407.913721 -393.668372) (xy 407.92124 -393.620947) (xy 407.936089 -393.575284) (xy 407.957902 -393.532508)
			(xy 407.986142 -393.493674) (xy 408.020113 -393.459738) (xy 408.058976 -393.431538) (xy 408.101775 -393.409769)
			(xy 408.147453 -393.394966) (xy 408.194885 -393.387496) (xy 408.218894 -393.387072) (xy 408.24283 -393.387503)
			(xy 408.290116 -393.394968) (xy 408.33566 -393.409715) (xy 408.378347 -393.431385) (xy 408.417132 -393.459446)
			(xy 408.451066 -393.493212) (xy 408.47932 -393.531857) (xy 408.490674 -393.552934) (xy 408.491182 -393.55395)
			(xy 408.571488 -393.692888) (xy 409.113736 -393.692888) (xy 409.113736 -393.69238) (xy 409.11412 -393.668384)
			(xy 409.121631 -393.620984) (xy 409.136465 -393.575342) (xy 409.158257 -393.532583) (xy 409.186469 -393.493759)
			(xy 409.220408 -393.459828) (xy 409.259238 -393.431623) (xy 409.302001 -393.40984) (xy 409.347646 -393.395016)
			(xy 409.395048 -393.387515) (xy 409.419044 -393.387072) (xy 409.442978 -393.387544) (xy 409.490263 -393.395001)
			(xy 409.535806 -393.409741) (xy 409.578492 -393.431404) (xy 409.617278 -393.459459) (xy 409.651214 -393.493219)
			(xy 409.679469 -393.53186) (xy 409.690824 -393.552934) (xy 409.691332 -393.55395) (xy 409.771638 -393.692888)
			(xy 410.313632 -393.692888) (xy 410.313632 -393.69238) (xy 410.31402 -393.668384) (xy 410.321531 -393.620984)
			(xy 410.336365 -393.575343) (xy 410.358156 -393.532584) (xy 410.386368 -393.493761) (xy 410.420306 -393.459829)
			(xy 410.459135 -393.431624) (xy 410.501898 -393.409842) (xy 410.547543 -393.395017) (xy 410.594944 -393.387515)
			(xy 410.61894 -393.387072) (xy 410.642874 -393.387547) (xy 410.690159 -393.395003) (xy 410.735701 -393.409743)
			(xy 410.778388 -393.431405) (xy 410.817174 -393.45946) (xy 410.85111 -393.49322) (xy 410.879365 -393.53186)
			(xy 410.89072 -393.552934) (xy 410.891228 -393.55395) (xy 410.971534 -393.692888) (xy 411.513528 -393.692888)
			(xy 411.513528 -393.69238) (xy 411.51392 -393.668385) (xy 411.521431 -393.620985) (xy 411.536264 -393.575344)
			(xy 411.558055 -393.532585) (xy 411.586267 -393.493762) (xy 411.620205 -393.45983) (xy 411.659033 -393.431626)
			(xy 411.701796 -393.409843) (xy 411.747439 -393.395018) (xy 411.79484 -393.387515) (xy 411.818836 -393.387072)
			(xy 411.84277 -393.38755) (xy 411.890054 -393.395006) (xy 411.935597 -393.409745) (xy 411.978284 -393.431407)
			(xy 412.017069 -393.459461) (xy 412.051005 -393.49322) (xy 412.079261 -393.53186) (xy 412.090616 -393.552934)
			(xy 412.091124 -393.55395) (xy 412.17143 -393.692888) (xy 412.713424 -393.692888) (xy 412.713424 -393.69238)
			(xy 412.713821 -393.668372) (xy 412.721339 -393.620948) (xy 412.736188 -393.575286) (xy 412.758001 -393.53251)
			(xy 412.78624 -393.493676) (xy 412.820209 -393.459741) (xy 412.859072 -393.431541) (xy 412.901869 -393.409771)
			(xy 412.947546 -393.394968) (xy 412.994978 -393.387497) (xy 413.018986 -393.387072) (xy 413.042922 -393.38751)
			(xy 413.090208 -393.394973) (xy 413.135751 -393.409719) (xy 413.178438 -393.431388) (xy 413.217223 -393.459448)
			(xy 413.251158 -393.493213) (xy 413.279412 -393.531858) (xy 413.290766 -393.552934) (xy 413.291274 -393.55395)
			(xy 413.37158 -393.692888) (xy 413.91332 -393.692888) (xy 413.91332 -393.69238) (xy 413.913721 -393.668372)
			(xy 413.921239 -393.620949) (xy 413.936088 -393.575287) (xy 413.9579 -393.532512) (xy 413.986139 -393.493678)
			(xy 414.020108 -393.459742) (xy 414.05897 -393.431542) (xy 414.101766 -393.409772) (xy 414.147443 -393.394969)
			(xy 414.194874 -393.387497) (xy 414.218882 -393.387072) (xy 414.242818 -393.387513) (xy 414.290103 -393.394976)
			(xy 414.335647 -393.409721) (xy 414.378334 -393.431389) (xy 414.417119 -393.459449) (xy 414.451054 -393.493214)
			(xy 414.479308 -393.531858) (xy 414.490662 -393.552934) (xy 414.49117 -393.55395) (xy 414.571476 -393.692888)
			(xy 415.113724 -393.692888) (xy 415.113724 -393.69238) (xy 415.11412 -393.668385) (xy 415.121631 -393.620985)
			(xy 415.136464 -393.575345) (xy 415.158254 -393.532586) (xy 415.186466 -393.493764) (xy 415.220403 -393.459832)
			(xy 415.259231 -393.431627) (xy 415.301993 -393.409844) (xy 415.347636 -393.395018) (xy 415.395037 -393.387516)
			(xy 415.419032 -393.387072) (xy 415.442966 -393.387554) (xy 415.49025 -393.395009) (xy 415.535793 -393.409747)
			(xy 415.578479 -393.431408) (xy 415.617265 -393.459462) (xy 415.651201 -393.493221) (xy 415.679457 -393.53186)
			(xy 415.690812 -393.552934) (xy 415.69132 -393.55395) (xy 415.771626 -393.692888) (xy 416.31362 -393.692888)
			(xy 416.31362 -393.69238) (xy 416.31402 -393.668385) (xy 416.32153 -393.620986) (xy 416.336363 -393.575346)
			(xy 416.358154 -393.532588) (xy 416.386365 -393.493765) (xy 416.420301 -393.459833) (xy 416.459129 -393.431629)
			(xy 416.50189 -393.409845) (xy 416.547533 -393.395019) (xy 416.594933 -393.387516) (xy 416.618928 -393.387072)
			(xy 416.642862 -393.387557) (xy 416.690146 -393.395011) (xy 416.735688 -393.409749) (xy 416.778375 -393.43141)
			(xy 416.817161 -393.459463) (xy 416.851097 -393.493222) (xy 416.879353 -393.53186) (xy 416.890708 -393.552934)
			(xy 416.891216 -393.55395) (xy 416.971522 -393.692888) (xy 417.513516 -393.692888) (xy 417.513516 -393.69238)
			(xy 417.51392 -393.668385) (xy 417.52143 -393.620987) (xy 417.536263 -393.575347) (xy 417.558053 -393.532589)
			(xy 417.586263 -393.493766) (xy 417.6202 -393.459835) (xy 417.659026 -393.43163) (xy 417.701787 -393.409846)
			(xy 417.747429 -393.39502) (xy 417.794829 -393.387516) (xy 417.818824 -393.387072) (xy 417.842758 -393.38756)
			(xy 417.890042 -393.395014) (xy 417.935584 -393.409751) (xy 417.978271 -393.431411) (xy 418.017057 -393.459464)
			(xy 418.050993 -393.493222) (xy 418.079249 -393.53186) (xy 418.090604 -393.552934) (xy 418.091112 -393.55395)
			(xy 418.171418 -393.692888) (xy 418.713412 -393.692888) (xy 418.713412 -393.69238) (xy 418.713821 -393.668373)
			(xy 418.721339 -393.62095) (xy 418.736187 -393.575289) (xy 418.757999 -393.532514) (xy 418.786237 -393.493681)
			(xy 418.820204 -393.459745) (xy 418.859065 -393.431545) (xy 418.901861 -393.409774) (xy 418.947536 -393.39497)
			(xy 418.994966 -393.387498) (xy 419.018974 -393.387072) (xy 419.042909 -393.387519) (xy 419.090195 -393.394981)
			(xy 419.135738 -393.409726) (xy 419.178425 -393.431392) (xy 419.21721 -393.459451) (xy 419.251145 -393.493215)
			(xy 419.279399 -393.531858) (xy 419.290754 -393.552934) (xy 419.291262 -393.55395) (xy 419.371568 -393.692888)
			(xy 419.913308 -393.692888) (xy 419.913308 -393.69238) (xy 419.913721 -393.668373) (xy 419.921239 -393.620951)
			(xy 419.936087 -393.57529) (xy 419.957898 -393.532515) (xy 419.986135 -393.493682) (xy 420.020103 -393.459747)
			(xy 420.058963 -393.431546) (xy 420.101758 -393.409775) (xy 420.147433 -393.394971) (xy 420.194862 -393.387498)
			(xy 420.21887 -393.387072) (xy 420.242805 -393.387523) (xy 420.290091 -393.394984) (xy 420.335634 -393.409728)
			(xy 420.378321 -393.431394) (xy 420.417106 -393.459452) (xy 420.451041 -393.493216) (xy 420.479295 -393.531858)
			(xy 420.49065 -393.552934) (xy 420.491158 -393.55395) (xy 420.571464 -393.692888) (xy 421.113712 -393.692888)
			(xy 421.113712 -393.69238) (xy 421.114144 -393.668387) (xy 421.121654 -393.620993) (xy 421.136485 -393.575357)
			(xy 421.158273 -393.532603) (xy 421.186481 -393.493784) (xy 421.220414 -393.459855) (xy 421.259237 -393.431652)
			(xy 421.301994 -393.40987) (xy 421.347632 -393.395045) (xy 421.395027 -393.387541) (xy 421.41902 -393.387072)
			(xy 421.442954 -393.387563) (xy 421.490237 -393.395017) (xy 421.53578 -393.409753) (xy 421.578466 -393.431413)
			(xy 421.617252 -393.459465) (xy 421.651189 -393.493223) (xy 421.679444 -393.531861) (xy 421.6908 -393.552934)
			(xy 421.691308 -393.55395) (xy 422.083738 -394.232892) (xy 422.096563 -394.256225) (xy 422.114783 -394.306247)
			(xy 422.124043 -394.358673) (xy 422.124632 -394.385292) (xy 422.124154 -394.409296) (xy 422.116641 -394.456714)
			(xy 422.101799 -394.502371) (xy 422.079995 -394.545143) (xy 422.051765 -394.583974) (xy 422.017805 -394.617909)
			(xy 421.978953 -394.646111) (xy 421.936165 -394.667885) (xy 421.890498 -394.682693) (xy 421.843075 -394.690171)
			(xy 421.81907 -394.6906) (xy 421.795495 -394.69023) (xy 421.748906 -394.682984) (xy 421.703987 -394.668654)
			(xy 421.661808 -394.647582) (xy 421.623376 -394.620268) (xy 421.589605 -394.587365) (xy 421.5613 -394.549657)
			(xy 421.54983 -394.529056) (xy 421.549322 -394.528294) (xy 421.151558 -393.839954) (xy 421.139699 -393.817269)
			(xy 421.122842 -393.76894) (xy 421.114262 -393.71848) (xy 421.113712 -393.692888) (xy 420.571464 -393.692888)
			(xy 420.883588 -394.232892) (xy 420.896337 -394.256249) (xy 420.914447 -394.306281) (xy 420.92365 -394.358688)
			(xy 420.924228 -394.385292) (xy 420.92373 -394.409282) (xy 420.916226 -394.456672) (xy 420.901401 -394.502304)
			(xy 420.87962 -394.545055) (xy 420.85142 -394.583873) (xy 420.817494 -394.617801) (xy 420.778679 -394.646005)
			(xy 420.73593 -394.66779) (xy 420.690299 -394.682619) (xy 420.64291 -394.690128) (xy 420.61892 -394.6906)
			(xy 420.595347 -394.69019) (xy 420.548759 -394.682952) (xy 420.503841 -394.668629) (xy 420.461662 -394.647563)
			(xy 420.423229 -394.620256) (xy 420.389457 -394.587358) (xy 420.361151 -394.549655) (xy 420.34968 -394.529056)
			(xy 420.349172 -394.528294) (xy 419.951408 -393.839954) (xy 419.939474 -393.817295) (xy 419.922543 -393.768965)
			(xy 419.913891 -393.718491) (xy 419.913308 -393.692888) (xy 419.371568 -393.692888) (xy 419.683692 -394.232892)
			(xy 419.696442 -394.256249) (xy 419.714551 -394.306281) (xy 419.723754 -394.358688) (xy 419.724332 -394.385292)
			(xy 419.72383 -394.409282) (xy 419.716326 -394.456671) (xy 419.701501 -394.502303) (xy 419.679721 -394.545054)
			(xy 419.651521 -394.583871) (xy 419.617596 -394.6178) (xy 419.578781 -394.646004) (xy 419.536032 -394.667789)
			(xy 419.490402 -394.682618) (xy 419.443014 -394.690128) (xy 419.419024 -394.6906) (xy 419.395451 -394.690187)
			(xy 419.348863 -394.682949) (xy 419.303945 -394.668627) (xy 419.261767 -394.647561) (xy 419.223333 -394.620255)
			(xy 419.189561 -394.587358) (xy 419.161255 -394.549655) (xy 419.149784 -394.529056) (xy 419.149276 -394.528294)
			(xy 418.751512 -393.839954) (xy 418.739579 -393.817295) (xy 418.722647 -393.768965) (xy 418.713995 -393.718491)
			(xy 418.713412 -393.692888) (xy 418.171418 -393.692888) (xy 418.483542 -394.232892) (xy 418.496367 -394.256224)
			(xy 418.514587 -394.306247) (xy 418.523847 -394.358673) (xy 418.524436 -394.385292) (xy 418.523954 -394.409296)
			(xy 418.516441 -394.456713) (xy 418.5016 -394.50237) (xy 418.479796 -394.545141) (xy 418.451566 -394.583973)
			(xy 418.417607 -394.617908) (xy 418.378755 -394.64611) (xy 418.335968 -394.667883) (xy 418.290301 -394.682692)
			(xy 418.242879 -394.690171) (xy 418.218874 -394.6906) (xy 418.195299 -394.690227) (xy 418.14871 -394.682982)
			(xy 418.103791 -394.668652) (xy 418.061613 -394.64758) (xy 418.02318 -394.620267) (xy 417.989409 -394.587365)
			(xy 417.961104 -394.549657) (xy 417.949634 -394.529056) (xy 417.949126 -394.528294) (xy 417.551362 -393.839954)
			(xy 417.539504 -393.817268) (xy 417.522646 -393.76894) (xy 417.514066 -393.71848) (xy 417.513516 -393.692888)
			(xy 416.971522 -393.692888) (xy 417.283646 -394.232892) (xy 417.296471 -394.256224) (xy 417.314691 -394.306247)
			(xy 417.323951 -394.358673) (xy 417.32454 -394.385292) (xy 417.324054 -394.409296) (xy 417.316541 -394.456713)
			(xy 417.3017 -394.502369) (xy 417.279896 -394.54514) (xy 417.251667 -394.583972) (xy 417.217709 -394.617907)
			(xy 417.178857 -394.646108) (xy 417.136071 -394.667882) (xy 417.090404 -394.682691) (xy 417.042982 -394.69017)
			(xy 417.018978 -394.6906) (xy 416.995403 -394.690224) (xy 416.948814 -394.682979) (xy 416.903895 -394.66865)
			(xy 416.861717 -394.647579) (xy 416.823284 -394.620266) (xy 416.789513 -394.587364) (xy 416.761208 -394.549657)
			(xy 416.749738 -394.529056) (xy 416.74923 -394.528294) (xy 416.351466 -393.839954) (xy 416.339608 -393.817268)
			(xy 416.32275 -393.76894) (xy 416.31417 -393.71848) (xy 416.31362 -393.692888) (xy 415.771626 -393.692888)
			(xy 416.08375 -394.232892) (xy 416.096576 -394.256224) (xy 416.114795 -394.306247) (xy 416.124055 -394.358673)
			(xy 416.124644 -394.385292) (xy 416.124154 -394.409296) (xy 416.116641 -394.456712) (xy 416.101801 -394.502368)
			(xy 416.079997 -394.545139) (xy 416.051769 -394.58397) (xy 416.01781 -394.617905) (xy 415.97896 -394.646107)
			(xy 415.936174 -394.667881) (xy 415.890507 -394.68269) (xy 415.843086 -394.69017) (xy 415.819082 -394.6906)
			(xy 415.795507 -394.690221) (xy 415.748919 -394.682977) (xy 415.704 -394.668648) (xy 415.661821 -394.647577)
			(xy 415.623388 -394.620265) (xy 415.589617 -394.587364) (xy 415.561312 -394.549657) (xy 415.549842 -394.529056)
			(xy 415.549334 -394.528294) (xy 415.15157 -393.839954) (xy 415.139712 -393.817268) (xy 415.122855 -393.768939)
			(xy 415.114274 -393.71848) (xy 415.113724 -393.692888) (xy 414.571476 -393.692888) (xy 414.8836 -394.232892)
			(xy 414.89635 -394.256249) (xy 414.91446 -394.306281) (xy 414.923662 -394.358688) (xy 414.92424 -394.385292)
			(xy 414.92373 -394.409281) (xy 414.916226 -394.45667) (xy 414.901402 -394.502301) (xy 414.879622 -394.545051)
			(xy 414.851423 -394.583869) (xy 414.817499 -394.617797) (xy 414.778686 -394.646001) (xy 414.735938 -394.667787)
			(xy 414.690309 -394.682617) (xy 414.642921 -394.690127) (xy 414.618932 -394.6906) (xy 414.595359 -394.69018)
			(xy 414.548772 -394.682944) (xy 414.503854 -394.668623) (xy 414.461675 -394.647558) (xy 414.423242 -394.620253)
			(xy 414.38947 -394.587357) (xy 414.361163 -394.549654) (xy 414.349692 -394.529056) (xy 414.349184 -394.528294)
			(xy 413.95142 -393.839954) (xy 413.939487 -393.817294) (xy 413.922556 -393.768965) (xy 413.913903 -393.718491)
			(xy 413.91332 -393.692888) (xy 413.37158 -393.692888) (xy 413.683704 -394.232892) (xy 413.696455 -394.256249)
			(xy 413.714564 -394.306281) (xy 413.723766 -394.358688) (xy 413.724344 -394.385292) (xy 413.72383 -394.409281)
			(xy 413.716326 -394.456669) (xy 413.701502 -394.5023) (xy 413.679723 -394.54505) (xy 413.651524 -394.583867)
			(xy 413.617601 -394.617796) (xy 413.578788 -394.646) (xy 413.536041 -394.667785) (xy 413.490412 -394.682616)
			(xy 413.443025 -394.690127) (xy 413.419036 -394.6906) (xy 413.395463 -394.690177) (xy 413.348876 -394.682941)
			(xy 413.303958 -394.668621) (xy 413.26178 -394.647557) (xy 413.223346 -394.620252) (xy 413.189574 -394.587356)
			(xy 413.161267 -394.549654) (xy 413.149796 -394.529056) (xy 413.149288 -394.528294) (xy 412.751524 -393.839954)
			(xy 412.739592 -393.817294) (xy 412.72266 -393.768965) (xy 412.714007 -393.718491) (xy 412.713424 -393.692888)
			(xy 412.17143 -393.692888) (xy 412.483554 -394.232892) (xy 412.49638 -394.256224) (xy 412.514599 -394.306247)
			(xy 412.523859 -394.358673) (xy 412.524448 -394.385292) (xy 412.523954 -394.409296) (xy 412.516441 -394.456711)
			(xy 412.501601 -394.502367) (xy 412.479798 -394.545138) (xy 412.45157 -394.583969) (xy 412.417612 -394.617904)
			(xy 412.378762 -394.646106) (xy 412.335977 -394.66788) (xy 412.290311 -394.68269) (xy 412.24289 -394.69017)
			(xy 412.218886 -394.6906) (xy 412.195312 -394.690217) (xy 412.148723 -394.682974) (xy 412.103804 -394.668646)
			(xy 412.061626 -394.647576) (xy 412.023193 -394.620264) (xy 411.989421 -394.587363) (xy 411.961116 -394.549656)
			(xy 411.949646 -394.529056) (xy 411.949138 -394.528294) (xy 411.551374 -393.839954) (xy 411.539517 -393.817268)
			(xy 411.522659 -393.768939) (xy 411.514078 -393.718479) (xy 411.513528 -393.692888) (xy 410.971534 -393.692888)
			(xy 411.283658 -394.232892) (xy 411.296484 -394.256224) (xy 411.314704 -394.306247) (xy 411.323963 -394.358673)
			(xy 411.324552 -394.385292) (xy 411.324054 -394.409295) (xy 411.316542 -394.456711) (xy 411.301701 -394.502366)
			(xy 411.279899 -394.545137) (xy 411.251671 -394.583968) (xy 411.217714 -394.617902) (xy 411.178864 -394.646104)
			(xy 411.136079 -394.667879) (xy 411.090414 -394.682689) (xy 411.042994 -394.690169) (xy 411.01899 -394.6906)
			(xy 410.995416 -394.690214) (xy 410.948827 -394.682971) (xy 410.903908 -394.668644) (xy 410.86173 -394.647574)
			(xy 410.823297 -394.620263) (xy 410.789526 -394.587363) (xy 410.76122 -394.549656) (xy 410.74975 -394.529056)
			(xy 410.749242 -394.528294) (xy 410.351478 -393.839954) (xy 410.339621 -393.817268) (xy 410.322763 -393.768939)
			(xy 410.314182 -393.718479) (xy 410.313632 -393.692888) (xy 409.771638 -393.692888) (xy 410.083762 -394.232892)
			(xy 410.096589 -394.256224) (xy 410.114808 -394.306247) (xy 410.124067 -394.358673) (xy 410.124656 -394.385292)
			(xy 410.124154 -394.409295) (xy 410.116642 -394.45671) (xy 410.101802 -394.502365) (xy 410.079999 -394.545135)
			(xy 410.051772 -394.583966) (xy 410.017815 -394.617901) (xy 409.978966 -394.646103) (xy 409.936182 -394.667878)
			(xy 409.890517 -394.682688) (xy 409.843098 -394.690169) (xy 409.819094 -394.6906) (xy 409.79552 -394.690211)
			(xy 409.748931 -394.682969) (xy 409.704013 -394.668642) (xy 409.661834 -394.647573) (xy 409.623401 -394.620262)
			(xy 409.58963 -394.587362) (xy 409.561324 -394.549656) (xy 409.549854 -394.529056) (xy 409.549346 -394.528294)
			(xy 409.151582 -393.839954) (xy 409.139725 -393.817268) (xy 409.122867 -393.768939) (xy 409.114286 -393.718479)
			(xy 409.113736 -393.692888) (xy 408.571488 -393.692888) (xy 408.883612 -394.232892) (xy 408.896363 -394.256248)
			(xy 408.914472 -394.306281) (xy 408.923674 -394.358688) (xy 408.924252 -394.385292) (xy 408.92373 -394.409281)
			(xy 408.916227 -394.456668) (xy 408.901403 -394.502298) (xy 408.879624 -394.545048) (xy 408.851427 -394.583865)
			(xy 408.817504 -394.617793) (xy 408.778692 -394.645997) (xy 408.735946 -394.667783) (xy 408.690319 -394.682614)
			(xy 408.642933 -394.690126) (xy 408.618944 -394.6906) (xy 408.595371 -394.690171) (xy 408.548785 -394.682936)
			(xy 408.503867 -394.668616) (xy 408.461689 -394.647554) (xy 408.423255 -394.620249) (xy 408.389482 -394.587355)
			(xy 408.361175 -394.549654) (xy 408.349704 -394.529056) (xy 408.349196 -394.528294) (xy 407.951432 -393.839954)
			(xy 407.9395 -393.817294) (xy 407.922568 -393.768965) (xy 407.913915 -393.718491) (xy 407.913332 -393.692888)
			(xy 407.371592 -393.692888) (xy 407.683716 -394.232892) (xy 407.696468 -394.256248) (xy 407.714576 -394.306281)
			(xy 407.723778 -394.358688) (xy 407.724356 -394.385292) (xy 407.72383 -394.409281) (xy 407.716327 -394.456667)
			(xy 407.701503 -394.502297) (xy 407.679725 -394.545047) (xy 407.651528 -394.583863) (xy 407.617606 -394.617791)
			(xy 407.578794 -394.645996) (xy 407.536049 -394.667782) (xy 407.490422 -394.682614) (xy 407.443037 -394.690126)
			(xy 407.419048 -394.6906) (xy 407.395475 -394.690168) (xy 407.348889 -394.682933) (xy 407.303971 -394.668614)
			(xy 407.261793 -394.647552) (xy 407.223359 -394.620248) (xy 407.189586 -394.587354) (xy 407.161279 -394.549654)
			(xy 407.149808 -394.529056) (xy 407.1493 -394.528294) (xy 406.751536 -393.839954) (xy 406.739605 -393.817294)
			(xy 406.722672 -393.768964) (xy 406.714019 -393.718491) (xy 406.713436 -393.692888) (xy 406.171442 -393.692888)
			(xy 406.483566 -394.232892) (xy 406.496393 -394.256223) (xy 406.514612 -394.306247) (xy 406.523871 -394.358673)
			(xy 406.52446 -394.385292) (xy 406.524053 -394.4093) (xy 406.516538 -394.456724) (xy 406.501693 -394.502388)
			(xy 406.479882 -394.545164) (xy 406.451644 -394.583999) (xy 406.417675 -394.617935) (xy 406.378813 -394.646136)
			(xy 406.336016 -394.667905) (xy 406.290338 -394.682707) (xy 406.242906 -394.690176) (xy 406.218898 -394.6906)
			(xy 406.195324 -394.690208) (xy 406.148736 -394.682966) (xy 406.103817 -394.66864) (xy 406.061639 -394.647571)
			(xy 406.023206 -394.620261) (xy 405.989434 -394.587361) (xy 405.961128 -394.549656) (xy 405.949658 -394.529056)
			(xy 405.94915 -394.528294) (xy 405.551386 -393.839954) (xy 405.53953 -393.817267) (xy 405.522671 -393.768939)
			(xy 405.51409 -393.718479) (xy 405.51354 -393.692888) (xy 404.971546 -393.692888) (xy 405.28367 -394.232892)
			(xy 405.296497 -394.256223) (xy 405.314716 -394.306247) (xy 405.323975 -394.358673) (xy 405.324564 -394.385292)
			(xy 405.324153 -394.4093) (xy 405.316639 -394.456724) (xy 405.301793 -394.502387) (xy 405.279983 -394.545163)
			(xy 405.251745 -394.583998) (xy 405.217777 -394.617934) (xy 405.178915 -394.646134) (xy 405.136118 -394.667904)
			(xy 405.090441 -394.682706) (xy 405.04301 -394.690176) (xy 405.019002 -394.6906) (xy 404.995428 -394.690205)
			(xy 404.94884 -394.682963) (xy 404.903921 -394.668638) (xy 404.861743 -394.64757) (xy 404.82331 -394.62026)
			(xy 404.789538 -394.587361) (xy 404.761233 -394.549656) (xy 404.749762 -394.529056) (xy 404.749254 -394.528294)
			(xy 404.35149 -393.839954) (xy 404.339634 -393.817267) (xy 404.322775 -393.768939) (xy 404.314194 -393.718479)
			(xy 404.313644 -393.692888) (xy 403.77165 -393.692888) (xy 404.083774 -394.232892) (xy 404.096601 -394.256223)
			(xy 404.11482 -394.306247) (xy 404.124079 -394.358673) (xy 404.124668 -394.385292) (xy 404.124253 -394.4093)
			(xy 404.116739 -394.456723) (xy 404.101893 -394.502386) (xy 404.080083 -394.545162) (xy 404.051846 -394.583996)
			(xy 404.017879 -394.617932) (xy 403.979017 -394.646133) (xy 403.936221 -394.667903) (xy 403.890545 -394.682706)
			(xy 403.843114 -394.690176) (xy 403.819106 -394.6906) (xy 403.795532 -394.690201) (xy 403.748944 -394.682961)
			(xy 403.704026 -394.668636) (xy 403.661847 -394.647568) (xy 403.623414 -394.620259) (xy 403.589642 -394.58736)
			(xy 403.561337 -394.549655) (xy 403.549866 -394.529056) (xy 403.549358 -394.528294) (xy 403.151594 -393.839954)
			(xy 403.139738 -393.817267) (xy 403.122879 -393.768939) (xy 403.114298 -393.718479) (xy 403.113748 -393.692888)
			(xy 389.243866 -393.692888) (xy 389.55599 -394.232892) (xy 389.568819 -394.256222) (xy 389.587037 -394.306246)
			(xy 389.596295 -394.358673) (xy 389.596884 -394.385292) (xy 389.596453 -394.409299) (xy 389.588939 -394.456721)
			(xy 389.574095 -394.502382) (xy 389.552286 -394.545157) (xy 389.524051 -394.583991) (xy 389.490085 -394.617927)
			(xy 389.451226 -394.646128) (xy 389.408432 -394.667898) (xy 389.362758 -394.682702) (xy 389.315329 -394.690175)
			(xy 389.291322 -394.6906) (xy 389.267749 -394.690188) (xy 389.221161 -394.68295) (xy 389.176243 -394.668628)
			(xy 389.134065 -394.647562) (xy 389.095631 -394.620255) (xy 389.061859 -394.587358) (xy 389.033553 -394.549655)
			(xy 389.022082 -394.529056) (xy 389.021574 -394.528294) (xy 388.62381 -393.839954) (xy 388.611948 -393.81727)
			(xy 388.595093 -393.76894) (xy 388.586513 -393.71848) (xy 388.585964 -393.692888) (xy 388.043716 -393.692888)
			(xy 388.35584 -394.232892) (xy 388.368594 -394.256247) (xy 388.386701 -394.30628) (xy 388.395902 -394.358688)
			(xy 388.39648 -394.385292) (xy 388.396054 -394.409286) (xy 388.388548 -394.456684) (xy 388.373719 -394.502324)
			(xy 388.351932 -394.545082) (xy 388.323724 -394.583905) (xy 388.28979 -394.617837) (xy 388.250965 -394.646042)
			(xy 388.208206 -394.667826) (xy 388.162565 -394.682653) (xy 388.115166 -394.690156) (xy 388.091172 -394.6906)
			(xy 388.067597 -394.690229) (xy 388.021008 -394.682983) (xy 387.976089 -394.668653) (xy 387.93391 -394.647581)
			(xy 387.895478 -394.620268) (xy 387.861707 -394.587365) (xy 387.833402 -394.549657) (xy 387.821932 -394.529056)
			(xy 387.821424 -394.528294) (xy 387.42366 -393.839954) (xy 387.41173 -393.817293) (xy 387.394797 -393.768964)
			(xy 387.386143 -393.718491) (xy 387.38556 -393.692888) (xy 386.84382 -393.692888) (xy 387.155944 -394.232892)
			(xy 387.168698 -394.256247) (xy 387.186805 -394.30628) (xy 387.196006 -394.358688) (xy 387.196584 -394.385292)
			(xy 387.196154 -394.409286) (xy 387.188648 -394.456684) (xy 387.173819 -394.502323) (xy 387.152033 -394.545081)
			(xy 387.123825 -394.583904) (xy 387.089892 -394.617836) (xy 387.051067 -394.646041) (xy 387.008308 -394.667825)
			(xy 386.962668 -394.682652) (xy 386.91527 -394.690156) (xy 386.891276 -394.6906) (xy 386.867701 -394.690226)
			(xy 386.821112 -394.68298) (xy 386.776193 -394.668651) (xy 386.734015 -394.647579) (xy 386.695582 -394.620267)
			(xy 386.661811 -394.587365) (xy 386.633506 -394.549657) (xy 386.622036 -394.529056) (xy 386.621528 -394.528294)
			(xy 386.223764 -393.839954) (xy 386.211835 -393.817292) (xy 386.194901 -393.768964) (xy 386.186248 -393.718491)
			(xy 386.185664 -393.692888) (xy 385.64367 -393.692888) (xy 385.955794 -394.232892) (xy 385.968623 -394.256222)
			(xy 385.986841 -394.306246) (xy 385.996099 -394.358673) (xy 385.996688 -394.385292) (xy 385.996253 -394.409299)
			(xy 385.988739 -394.45672) (xy 385.973895 -394.502381) (xy 385.952087 -394.545156) (xy 385.923852 -394.58399)
			(xy 385.889887 -394.617925) (xy 385.851029 -394.646126) (xy 385.808235 -394.667897) (xy 385.762561 -394.682702)
			(xy 385.715133 -394.690174) (xy 385.691126 -394.6906) (xy 385.667553 -394.690185) (xy 385.620965 -394.682948)
			(xy 385.576047 -394.668626) (xy 385.533869 -394.64756) (xy 385.495436 -394.620254) (xy 385.461663 -394.587357)
			(xy 385.433357 -394.549655) (xy 385.421886 -394.529056) (xy 385.421378 -394.528294) (xy 385.023614 -393.839954)
			(xy 385.011752 -393.81727) (xy 384.994897 -393.76894) (xy 384.986317 -393.71848) (xy 384.985768 -393.692888)
			(xy 384.443774 -393.692888) (xy 384.755898 -394.232892) (xy 384.768719 -394.256226) (xy 384.786942 -394.306248)
			(xy 384.796203 -394.358674) (xy 384.796792 -394.385292) (xy 384.796353 -394.409298) (xy 384.78884 -394.45672)
			(xy 384.773996 -394.50238) (xy 384.752188 -394.545155) (xy 384.723953 -394.583988) (xy 384.689989 -394.617924)
			(xy 384.651131 -394.646125) (xy 384.608338 -394.667896) (xy 384.562664 -394.682701) (xy 384.515237 -394.690174)
			(xy 384.49123 -394.6906) (xy 384.467657 -394.690182) (xy 384.42107 -394.682945) (xy 384.376152 -394.668624)
			(xy 384.333973 -394.647559) (xy 384.29554 -394.620253) (xy 384.261768 -394.587357) (xy 384.233461 -394.549654)
			(xy 384.22199 -394.529056) (xy 384.221482 -394.528294) (xy 383.823718 -393.839954) (xy 383.811856 -393.81727)
			(xy 383.795001 -393.76894) (xy 383.786421 -393.71848) (xy 383.785872 -393.692888) (xy 383.243878 -393.692888)
			(xy 383.556002 -394.232892) (xy 383.568824 -394.256226) (xy 383.587046 -394.306248) (xy 383.596307 -394.358674)
			(xy 383.596896 -394.385292) (xy 383.596453 -394.409298) (xy 383.58894 -394.456719) (xy 383.574096 -394.502379)
			(xy 383.552288 -394.545153) (xy 383.524055 -394.583987) (xy 383.49009 -394.617922) (xy 383.451233 -394.646123)
			(xy 383.408441 -394.667895) (xy 383.362768 -394.6827) (xy 383.315341 -394.690174) (xy 383.291334 -394.6906)
			(xy 383.267761 -394.690179) (xy 383.221174 -394.682942) (xy 383.176256 -394.668622) (xy 383.134078 -394.647557)
			(xy 383.095644 -394.620252) (xy 383.061872 -394.587356) (xy 383.033565 -394.549654) (xy 383.022094 -394.529056)
			(xy 383.021586 -394.528294) (xy 382.623822 -393.839954) (xy 382.611961 -393.81727) (xy 382.595105 -393.76894)
			(xy 382.586526 -393.71848) (xy 382.585976 -393.692888) (xy 382.043728 -393.692888) (xy 382.355852 -394.232892)
			(xy 382.368607 -394.256246) (xy 382.386713 -394.30628) (xy 382.395914 -394.358688) (xy 382.396492 -394.385292)
			(xy 382.396054 -394.409286) (xy 382.388548 -394.456682) (xy 382.37372 -394.502321) (xy 382.351934 -394.545079)
			(xy 382.323728 -394.583901) (xy 382.289795 -394.617833) (xy 382.250972 -394.646038) (xy 382.208214 -394.667823)
			(xy 382.162575 -394.68265) (xy 382.115178 -394.690155) (xy 382.091184 -394.6906) (xy 382.06761 -394.690219)
			(xy 382.021021 -394.682975) (xy 381.976102 -394.668647) (xy 381.933923 -394.647576) (xy 381.895491 -394.620265)
			(xy 381.861719 -394.587363) (xy 381.833414 -394.549656) (xy 381.821944 -394.529056) (xy 381.821436 -394.528294)
			(xy 381.423672 -393.839954) (xy 381.411736 -393.817296) (xy 381.394806 -393.768965) (xy 381.386155 -393.718492)
			(xy 381.385572 -393.692888) (xy 380.843832 -393.692888) (xy 381.155956 -394.232892) (xy 381.168711 -394.256246)
			(xy 381.186817 -394.30628) (xy 381.196018 -394.358688) (xy 381.196596 -394.385292) (xy 381.196154 -394.409286)
			(xy 381.188648 -394.456682) (xy 381.17382 -394.50232) (xy 381.152035 -394.545077) (xy 381.123829 -394.5839)
			(xy 381.089897 -394.617831) (xy 381.051074 -394.646037) (xy 381.008317 -394.667822) (xy 380.962678 -394.682649)
			(xy 380.915282 -394.690155) (xy 380.891288 -394.6906) (xy 380.867714 -394.690216) (xy 380.821125 -394.682973)
			(xy 380.776206 -394.668645) (xy 380.734028 -394.647575) (xy 380.695595 -394.620264) (xy 380.661823 -394.587363)
			(xy 380.633518 -394.549656) (xy 380.622048 -394.529056) (xy 380.62154 -394.528294) (xy 380.223776 -393.839954)
			(xy 380.21184 -393.817296) (xy 380.19491 -393.768965) (xy 380.186259 -393.718492) (xy 380.185676 -393.692888)
			(xy 379.643682 -393.692888) (xy 379.955806 -394.232892) (xy 379.968628 -394.256226) (xy 379.98685 -394.306248)
			(xy 379.996111 -394.358674) (xy 379.9967 -394.385292) (xy 379.996254 -394.409298) (xy 379.98874 -394.456718)
			(xy 379.973896 -394.502378) (xy 379.952089 -394.545152) (xy 379.923856 -394.583985) (xy 379.889892 -394.617921)
			(xy 379.851035 -394.646122) (xy 379.808243 -394.667894) (xy 379.762571 -394.682699) (xy 379.715144 -394.690173)
			(xy 379.691138 -394.6906) (xy 379.667565 -394.690176) (xy 379.620978 -394.68294) (xy 379.57606 -394.66862)
			(xy 379.533882 -394.647556) (xy 379.495448 -394.620251) (xy 379.461676 -394.587356) (xy 379.433369 -394.549654)
			(xy 379.421898 -394.529056) (xy 379.42139 -394.528294) (xy 379.023626 -393.839954) (xy 379.011765 -393.81727)
			(xy 378.994909 -393.76894) (xy 378.98633 -393.71848) (xy 378.98578 -393.692888) (xy 378.443786 -393.692888)
			(xy 378.75591 -394.232892) (xy 378.768732 -394.256226) (xy 378.786954 -394.306248) (xy 378.796215 -394.358673)
			(xy 378.796804 -394.385292) (xy 378.796354 -394.409298) (xy 378.78884 -394.456718) (xy 378.773997 -394.502377)
			(xy 378.75219 -394.545151) (xy 378.723957 -394.583984) (xy 378.689994 -394.61792) (xy 378.651137 -394.646121)
			(xy 378.608346 -394.667893) (xy 378.562674 -394.682698) (xy 378.515248 -394.690173) (xy 378.491242 -394.6906)
			(xy 378.467669 -394.690172) (xy 378.421083 -394.682937) (xy 378.376165 -394.668617) (xy 378.333986 -394.647554)
			(xy 378.295553 -394.62025) (xy 378.26178 -394.587355) (xy 378.233473 -394.549654) (xy 378.222002 -394.529056)
			(xy 378.221494 -394.528294) (xy 377.82373 -393.839954) (xy 377.811869 -393.81727) (xy 377.795013 -393.76894)
			(xy 377.786434 -393.71848) (xy 377.785884 -393.692888) (xy 377.24389 -393.692888) (xy 377.556014 -394.232892)
			(xy 377.568837 -394.256226) (xy 377.587058 -394.306248) (xy 377.596319 -394.358673) (xy 377.596908 -394.385292)
			(xy 377.596454 -394.409298) (xy 377.58894 -394.456717) (xy 377.574097 -394.502377) (xy 377.552291 -394.54515)
			(xy 377.524058 -394.583983) (xy 377.490095 -394.617918) (xy 377.45124 -394.646119) (xy 377.408449 -394.667891)
			(xy 377.362778 -394.682698) (xy 377.315352 -394.690173) (xy 377.291346 -394.6906) (xy 377.267773 -394.690169)
			(xy 377.221187 -394.682935) (xy 377.176269 -394.668615) (xy 377.134091 -394.647553) (xy 377.095657 -394.620249)
			(xy 377.061884 -394.587355) (xy 377.033577 -394.549654) (xy 377.022106 -394.529056) (xy 377.021598 -394.528294)
			(xy 376.623834 -393.839954) (xy 376.611974 -393.81727) (xy 376.595118 -393.76894) (xy 376.586538 -393.71848)
			(xy 376.585988 -393.692888) (xy 376.04374 -393.692888) (xy 376.355864 -394.232892) (xy 376.36862 -394.256246)
			(xy 376.386726 -394.30628) (xy 376.395926 -394.358688) (xy 376.396504 -394.385292) (xy 376.396054 -394.409285)
			(xy 376.388549 -394.456681) (xy 376.373721 -394.502319) (xy 376.351936 -394.545075) (xy 376.323731 -394.583897)
			(xy 376.2898 -394.617829) (xy 376.250978 -394.646034) (xy 376.208222 -394.66782) (xy 376.162585 -394.682648)
			(xy 376.115189 -394.690154) (xy 376.091196 -394.6906) (xy 376.067622 -394.690209) (xy 376.021033 -394.682967)
			(xy 375.976115 -394.668641) (xy 375.933936 -394.647572) (xy 375.895503 -394.620262) (xy 375.861732 -394.587362)
			(xy 375.833426 -394.549656) (xy 375.821956 -394.529056) (xy 375.821448 -394.528294) (xy 375.423684 -393.839954)
			(xy 375.411748 -393.817296) (xy 375.394819 -393.768965) (xy 375.386167 -393.718492) (xy 375.385584 -393.692888)
			(xy 374.843844 -393.692888) (xy 375.155968 -394.232892) (xy 375.168724 -394.256246) (xy 375.18683 -394.30628)
			(xy 375.19603 -394.358688) (xy 375.196608 -394.385292) (xy 375.196154 -394.409285) (xy 375.188649 -394.45668)
			(xy 375.173821 -394.502318) (xy 375.152037 -394.545074) (xy 375.123832 -394.583896) (xy 375.089902 -394.617827)
			(xy 375.051081 -394.646033) (xy 375.008325 -394.667818) (xy 374.962688 -394.682647) (xy 374.915293 -394.690154)
			(xy 374.8913 -394.6906) (xy 374.867726 -394.690206) (xy 374.821138 -394.682965) (xy 374.776219 -394.668639)
			(xy 374.734041 -394.64757) (xy 374.695608 -394.620261) (xy 374.661836 -394.587361) (xy 374.63353 -394.549656)
			(xy 374.62206 -394.529056) (xy 374.621552 -394.528294) (xy 374.223788 -393.839954) (xy 374.211853 -393.817296)
			(xy 374.194923 -393.768965) (xy 374.186271 -393.718491) (xy 374.185688 -393.692888) (xy 373.643694 -393.692888)
			(xy 373.955818 -394.232892) (xy 373.968641 -394.256226) (xy 373.986862 -394.306248) (xy 373.996123 -394.358673)
			(xy 373.996712 -394.385292) (xy 373.996254 -394.409297) (xy 373.98874 -394.456717) (xy 373.973898 -394.502376)
			(xy 373.952091 -394.545149) (xy 373.923859 -394.583981) (xy 373.889897 -394.617917) (xy 373.851042 -394.646118)
			(xy 373.808252 -394.66789) (xy 373.762581 -394.682697) (xy 373.715156 -394.690172) (xy 373.69115 -394.6906)
			(xy 373.667577 -394.690166) (xy 373.620991 -394.682932) (xy 373.576073 -394.668613) (xy 373.533895 -394.647551)
			(xy 373.495461 -394.620248) (xy 373.461688 -394.587354) (xy 373.433381 -394.549653) (xy 373.42191 -394.529056)
			(xy 373.421402 -394.528294) (xy 373.023638 -393.839954) (xy 373.011778 -393.817269) (xy 372.994922 -393.76894)
			(xy 372.986342 -393.71848) (xy 372.985792 -393.692888) (xy 372.443798 -393.692888) (xy 372.755922 -394.232892)
			(xy 372.768745 -394.256225) (xy 372.786966 -394.306248) (xy 372.796227 -394.358673) (xy 372.796816 -394.385292)
			(xy 372.796354 -394.409297) (xy 372.78884 -394.456716) (xy 372.773998 -394.502375) (xy 372.752192 -394.545147)
			(xy 372.72396 -394.58398) (xy 372.689999 -394.617915) (xy 372.651144 -394.646117) (xy 372.608354 -394.667889)
			(xy 372.562684 -394.682696) (xy 372.51526 -394.690172) (xy 372.491254 -394.6906) (xy 372.467682 -394.690163)
			(xy 372.421095 -394.682929) (xy 372.376178 -394.668611) (xy 372.333999 -394.64755) (xy 372.295566 -394.620247)
			(xy 372.261793 -394.587353) (xy 372.233485 -394.549653) (xy 372.222014 -394.529056) (xy 372.221506 -394.528294)
			(xy 371.823742 -393.839954) (xy 371.811882 -393.817269) (xy 371.795026 -393.76894) (xy 371.786446 -393.71848)
			(xy 371.785896 -393.692888) (xy 371.243902 -393.692888) (xy 371.556026 -394.232892) (xy 371.56885 -394.256225)
			(xy 371.587071 -394.306247) (xy 371.596331 -394.358673) (xy 371.59692 -394.385292) (xy 371.596454 -394.409297)
			(xy 371.588941 -394.456716) (xy 371.574098 -394.502374) (xy 371.552293 -394.545146) (xy 371.524062 -394.583979)
			(xy 371.4901 -394.617914) (xy 371.451246 -394.646115) (xy 371.408457 -394.667888) (xy 371.362788 -394.682695)
			(xy 371.315363 -394.690172) (xy 371.291358 -394.6906) (xy 371.267786 -394.690159) (xy 371.2212 -394.682927)
			(xy 371.176282 -394.668609) (xy 371.134104 -394.647548) (xy 371.09567 -394.620246) (xy 371.061897 -394.587353)
			(xy 371.03359 -394.549653) (xy 371.022118 -394.529056) (xy 371.02161 -394.528294) (xy 370.623846 -393.839954)
			(xy 370.611986 -393.817269) (xy 370.59513 -393.76894) (xy 370.58655 -393.71848) (xy 370.586 -393.692888)
			(xy 354.671418 -393.692888) (xy 354.983542 -394.232892) (xy 354.996367 -394.256224) (xy 355.014587 -394.306247)
			(xy 355.023847 -394.358673) (xy 355.024436 -394.385292) (xy 355.023954 -394.409296) (xy 355.016441 -394.456713)
			(xy 355.0016 -394.50237) (xy 354.979796 -394.545141) (xy 354.951566 -394.583973) (xy 354.917607 -394.617908)
			(xy 354.878755 -394.64611) (xy 354.835968 -394.667883) (xy 354.790301 -394.682692) (xy 354.742879 -394.690171)
			(xy 354.718874 -394.6906) (xy 354.695299 -394.690227) (xy 354.64871 -394.682982) (xy 354.603791 -394.668652)
			(xy 354.561613 -394.64758) (xy 354.52318 -394.620267) (xy 354.489409 -394.587365) (xy 354.461104 -394.549657)
			(xy 354.449634 -394.529056) (xy 354.449126 -394.528294) (xy 354.051362 -393.839954) (xy 354.039504 -393.817268)
			(xy 354.022646 -393.76894) (xy 354.014066 -393.71848) (xy 354.013516 -393.692888) (xy 353.471522 -393.692888)
			(xy 353.783646 -394.232892) (xy 353.796471 -394.256224) (xy 353.814691 -394.306247) (xy 353.823951 -394.358673)
			(xy 353.82454 -394.385292) (xy 353.824054 -394.409296) (xy 353.816541 -394.456713) (xy 353.8017 -394.502369)
			(xy 353.779896 -394.54514) (xy 353.751667 -394.583972) (xy 353.717709 -394.617907) (xy 353.678857 -394.646108)
			(xy 353.636071 -394.667882) (xy 353.590404 -394.682691) (xy 353.542982 -394.69017) (xy 353.518978 -394.6906)
			(xy 353.518724 -394.6906) (xy 353.495151 -394.690187) (xy 353.448563 -394.682949) (xy 353.403645 -394.668627)
			(xy 353.361467 -394.647561) (xy 353.323033 -394.620255) (xy 353.289261 -394.587358) (xy 353.260955 -394.549655)
			(xy 353.249484 -394.529056) (xy 353.248976 -394.528294) (xy 352.851212 -393.839954) (xy 352.839279 -393.817295)
			(xy 352.822347 -393.768965) (xy 352.813695 -393.718491) (xy 352.813112 -393.692888) (xy 352.271372 -393.692888)
			(xy 352.583496 -394.232892) (xy 352.596246 -394.256249) (xy 352.614355 -394.306281) (xy 352.623558 -394.358688)
			(xy 352.624136 -394.385292) (xy 352.62363 -394.409282) (xy 352.616126 -394.45667) (xy 352.601301 -394.502302)
			(xy 352.579521 -394.545053) (xy 352.551322 -394.58387) (xy 352.517397 -394.617798) (xy 352.478583 -394.646002)
			(xy 352.435835 -394.667788) (xy 352.390205 -394.682618) (xy 352.342818 -394.690127) (xy 352.318828 -394.6906)
			(xy 352.295255 -394.690184) (xy 352.248668 -394.682946) (xy 352.20375 -394.668625) (xy 352.161571 -394.64756)
			(xy 352.123138 -394.620254) (xy 352.089365 -394.587357) (xy 352.061059 -394.549654) (xy 352.049588 -394.529056)
			(xy 352.04908 -394.528294) (xy 351.651316 -393.839954) (xy 351.639383 -393.817294) (xy 351.622452 -393.768965)
			(xy 351.613799 -393.718491) (xy 351.613216 -393.692888) (xy 351.071476 -393.692888) (xy 351.3836 -394.232892)
			(xy 351.39635 -394.256249) (xy 351.41446 -394.306281) (xy 351.423662 -394.358688) (xy 351.42424 -394.385292)
			(xy 351.42373 -394.409281) (xy 351.416226 -394.45667) (xy 351.401402 -394.502301) (xy 351.379622 -394.545051)
			(xy 351.351423 -394.583869) (xy 351.317499 -394.617797) (xy 351.278686 -394.646001) (xy 351.235938 -394.667787)
			(xy 351.190309 -394.682617) (xy 351.142921 -394.690127) (xy 351.118932 -394.6906) (xy 351.118678 -394.6906)
			(xy 351.095103 -394.690224) (xy 351.048514 -394.682979) (xy 351.003595 -394.66865) (xy 350.961417 -394.647579)
			(xy 350.922984 -394.620266) (xy 350.889213 -394.587364) (xy 350.860908 -394.549657) (xy 350.849438 -394.529056)
			(xy 350.84893 -394.528294) (xy 350.451166 -393.839954) (xy 350.439308 -393.817268) (xy 350.42245 -393.76894)
			(xy 350.41387 -393.71848) (xy 350.41332 -393.692888) (xy 349.871326 -393.692888) (xy 350.18345 -394.232892)
			(xy 350.196276 -394.256224) (xy 350.214495 -394.306247) (xy 350.223755 -394.358673) (xy 350.224344 -394.385292)
			(xy 350.223854 -394.409296) (xy 350.216341 -394.456712) (xy 350.201501 -394.502368) (xy 350.179697 -394.545139)
			(xy 350.151469 -394.58397) (xy 350.11751 -394.617905) (xy 350.07866 -394.646107) (xy 350.035874 -394.667881)
			(xy 349.990207 -394.68269) (xy 349.942786 -394.69017) (xy 349.918782 -394.6906) (xy 349.895207 -394.690221)
			(xy 349.848619 -394.682977) (xy 349.8037 -394.668648) (xy 349.761521 -394.647577) (xy 349.723088 -394.620265)
			(xy 349.689317 -394.587364) (xy 349.661012 -394.549657) (xy 349.649542 -394.529056) (xy 349.649034 -394.528294)
			(xy 349.25127 -393.839954) (xy 349.239412 -393.817268) (xy 349.222555 -393.768939) (xy 349.213974 -393.71848)
			(xy 349.213424 -393.692888) (xy 348.67143 -393.692888) (xy 348.983554 -394.232892) (xy 348.99638 -394.256224)
			(xy 349.014599 -394.306247) (xy 349.023859 -394.358673) (xy 349.024448 -394.385292) (xy 349.023954 -394.409296)
			(xy 349.016441 -394.456711) (xy 349.001601 -394.502367) (xy 348.979798 -394.545138) (xy 348.95157 -394.583969)
			(xy 348.917612 -394.617904) (xy 348.878762 -394.646106) (xy 348.835977 -394.66788) (xy 348.790311 -394.68269)
			(xy 348.74289 -394.69017) (xy 348.718886 -394.6906) (xy 348.695312 -394.690217) (xy 348.648723 -394.682974)
			(xy 348.603804 -394.668646) (xy 348.561626 -394.647576) (xy 348.523193 -394.620264) (xy 348.489421 -394.587363)
			(xy 348.461116 -394.549656) (xy 348.449646 -394.529056) (xy 348.449138 -394.528294) (xy 348.051374 -393.839954)
			(xy 348.039517 -393.817268) (xy 348.022659 -393.768939) (xy 348.014078 -393.718479) (xy 348.013528 -393.692888)
			(xy 347.47128 -393.692888) (xy 347.783404 -394.232892) (xy 347.796155 -394.256249) (xy 347.814264 -394.306281)
			(xy 347.823466 -394.358688) (xy 347.824044 -394.385292) (xy 347.82353 -394.409281) (xy 347.816026 -394.456669)
			(xy 347.801202 -394.5023) (xy 347.779423 -394.54505) (xy 347.751224 -394.583867) (xy 347.717301 -394.617796)
			(xy 347.678488 -394.646) (xy 347.635741 -394.667785) (xy 347.590112 -394.682616) (xy 347.542725 -394.690127)
			(xy 347.518736 -394.6906) (xy 347.495163 -394.690177) (xy 347.448576 -394.682941) (xy 347.403658 -394.668621)
			(xy 347.36148 -394.647557) (xy 347.323046 -394.620252) (xy 347.289274 -394.587356) (xy 347.260967 -394.549654)
			(xy 347.249496 -394.529056) (xy 347.248988 -394.528294) (xy 346.851224 -393.839954) (xy 346.839292 -393.817294)
			(xy 346.82236 -393.768965) (xy 346.813707 -393.718491) (xy 346.813124 -393.692888) (xy 346.271384 -393.692888)
			(xy 346.583508 -394.232892) (xy 346.596259 -394.256248) (xy 346.614368 -394.306281) (xy 346.62357 -394.358688)
			(xy 346.624148 -394.385292) (xy 346.62363 -394.409281) (xy 346.616126 -394.456669) (xy 346.601303 -394.502299)
			(xy 346.579524 -394.545049) (xy 346.551325 -394.583866) (xy 346.517403 -394.617794) (xy 346.47859 -394.645998)
			(xy 346.435843 -394.667784) (xy 346.390215 -394.682615) (xy 346.342829 -394.690126) (xy 346.31884 -394.6906)
			(xy 346.295267 -394.690174) (xy 346.24868 -394.682939) (xy 346.203763 -394.668618) (xy 346.161584 -394.647555)
			(xy 346.123151 -394.620251) (xy 346.089378 -394.587355) (xy 346.061071 -394.549654) (xy 346.0496 -394.529056)
			(xy 346.049092 -394.528294) (xy 345.651328 -393.839954) (xy 345.639396 -393.817294) (xy 345.622464 -393.768965)
			(xy 345.613811 -393.718491) (xy 345.613228 -393.692888) (xy 345.071488 -393.692888) (xy 345.383612 -394.232892)
			(xy 345.396363 -394.256248) (xy 345.414472 -394.306281) (xy 345.423674 -394.358688) (xy 345.424252 -394.385292)
			(xy 345.42373 -394.409281) (xy 345.416227 -394.456668) (xy 345.401403 -394.502298) (xy 345.379624 -394.545048)
			(xy 345.351427 -394.583865) (xy 345.317504 -394.617793) (xy 345.278692 -394.645997) (xy 345.235946 -394.667783)
			(xy 345.190319 -394.682614) (xy 345.142933 -394.690126) (xy 345.118944 -394.6906) (xy 345.11869 -394.6906)
			(xy 345.095116 -394.690214) (xy 345.048527 -394.682971) (xy 345.003608 -394.668644) (xy 344.96143 -394.647574)
			(xy 344.922997 -394.620263) (xy 344.889226 -394.587363) (xy 344.86092 -394.549656) (xy 344.84945 -394.529056)
			(xy 344.848942 -394.528294) (xy 344.451178 -393.839954) (xy 344.439321 -393.817268) (xy 344.422463 -393.768939)
			(xy 344.413882 -393.718479) (xy 344.413332 -393.692888) (xy 343.871338 -393.692888) (xy 344.183462 -394.232892)
			(xy 344.196289 -394.256224) (xy 344.214508 -394.306247) (xy 344.223767 -394.358673) (xy 344.224356 -394.385292)
			(xy 344.223854 -394.409295) (xy 344.216342 -394.45671) (xy 344.201502 -394.502365) (xy 344.179699 -394.545135)
			(xy 344.151472 -394.583966) (xy 344.117515 -394.617901) (xy 344.078666 -394.646103) (xy 344.035882 -394.667878)
			(xy 343.990217 -394.682688) (xy 343.942798 -394.690169) (xy 343.918794 -394.6906) (xy 343.89522 -394.690211)
			(xy 343.848631 -394.682969) (xy 343.803713 -394.668642) (xy 343.761534 -394.647573) (xy 343.723101 -394.620262)
			(xy 343.68933 -394.587362) (xy 343.661024 -394.549656) (xy 343.649554 -394.529056) (xy 343.649046 -394.528294)
			(xy 343.251282 -393.839954) (xy 343.239425 -393.817268) (xy 343.222567 -393.768939) (xy 343.213986 -393.718479)
			(xy 343.213436 -393.692888) (xy 342.671442 -393.692888) (xy 342.983566 -394.232892) (xy 342.996393 -394.256223)
			(xy 343.014612 -394.306247) (xy 343.023871 -394.358673) (xy 343.02446 -394.385292) (xy 343.024053 -394.4093)
			(xy 343.016538 -394.456724) (xy 343.001693 -394.502388) (xy 342.979882 -394.545164) (xy 342.951644 -394.583999)
			(xy 342.917675 -394.617935) (xy 342.878813 -394.646136) (xy 342.836016 -394.667905) (xy 342.790338 -394.682707)
			(xy 342.742906 -394.690176) (xy 342.718898 -394.6906) (xy 342.695324 -394.690208) (xy 342.648736 -394.682966)
			(xy 342.603817 -394.66864) (xy 342.561639 -394.647571) (xy 342.523206 -394.620261) (xy 342.489434 -394.587361)
			(xy 342.461128 -394.549656) (xy 342.449658 -394.529056) (xy 342.44915 -394.528294) (xy 342.051386 -393.839954)
			(xy 342.03953 -393.817267) (xy 342.022671 -393.768939) (xy 342.01409 -393.718479) (xy 342.01354 -393.692888)
			(xy 341.471292 -393.692888) (xy 341.783416 -394.232892) (xy 341.796168 -394.256248) (xy 341.814276 -394.306281)
			(xy 341.823478 -394.358688) (xy 341.824056 -394.385292) (xy 341.82353 -394.409281) (xy 341.816027 -394.456667)
			(xy 341.801203 -394.502297) (xy 341.779425 -394.545047) (xy 341.751228 -394.583863) (xy 341.717306 -394.617791)
			(xy 341.678494 -394.645996) (xy 341.635749 -394.667782) (xy 341.590122 -394.682614) (xy 341.542737 -394.690126)
			(xy 341.518748 -394.6906) (xy 341.495175 -394.690168) (xy 341.448589 -394.682933) (xy 341.403671 -394.668614)
			(xy 341.361493 -394.647552) (xy 341.323059 -394.620248) (xy 341.289286 -394.587354) (xy 341.260979 -394.549654)
			(xy 341.249508 -394.529056) (xy 341.249 -394.528294) (xy 340.851236 -393.839954) (xy 340.839305 -393.817294)
			(xy 340.822372 -393.768964) (xy 340.813719 -393.718491) (xy 340.813136 -393.692888) (xy 340.271396 -393.692888)
			(xy 340.58352 -394.232892) (xy 340.596272 -394.256248) (xy 340.61438 -394.306281) (xy 340.623582 -394.358688)
			(xy 340.62416 -394.385292) (xy 340.623754 -394.409287) (xy 340.616247 -394.456687) (xy 340.601417 -394.502329)
			(xy 340.579628 -394.545088) (xy 340.551418 -394.583912) (xy 340.517482 -394.617844) (xy 340.478654 -394.646049)
			(xy 340.435892 -394.667832) (xy 340.390248 -394.682657) (xy 340.342847 -394.690157) (xy 340.318852 -394.6906)
			(xy 340.295279 -394.690164) (xy 340.248693 -394.682931) (xy 340.203776 -394.668612) (xy 340.161597 -394.647551)
			(xy 340.123164 -394.620247) (xy 340.089391 -394.587354) (xy 340.061083 -394.549653) (xy 340.049612 -394.529056)
			(xy 340.049104 -394.528294) (xy 339.65134 -393.839954) (xy 339.639409 -393.817293) (xy 339.622476 -393.768964)
			(xy 339.613823 -393.718491) (xy 339.61324 -393.692888) (xy 339.0715 -393.692888) (xy 339.383624 -394.232892)
			(xy 339.396376 -394.256248) (xy 339.414484 -394.30628) (xy 339.423686 -394.358688) (xy 339.424264 -394.385292)
			(xy 339.423854 -394.409287) (xy 339.416347 -394.456687) (xy 339.401517 -394.502328) (xy 339.379729 -394.545087)
			(xy 339.351519 -394.583911) (xy 339.317583 -394.617843) (xy 339.278756 -394.646048) (xy 339.235995 -394.667831)
			(xy 339.190352 -394.682656) (xy 339.142951 -394.690157) (xy 339.118956 -394.6906) (xy 339.118702 -394.6906)
			(xy 339.095128 -394.690205) (xy 339.04854 -394.682963) (xy 339.003621 -394.668638) (xy 338.961443 -394.64757)
			(xy 338.92301 -394.62026) (xy 338.889238 -394.587361) (xy 338.860933 -394.549656) (xy 338.849462 -394.529056)
			(xy 338.848954 -394.528294) (xy 338.45119 -393.839954) (xy 338.439334 -393.817267) (xy 338.422475 -393.768939)
			(xy 338.413894 -393.718479) (xy 338.413344 -393.692888) (xy 337.87135 -393.692888) (xy 338.183474 -394.232892)
			(xy 338.196301 -394.256223) (xy 338.21452 -394.306247) (xy 338.223779 -394.358673) (xy 338.224368 -394.385292)
			(xy 338.223953 -394.4093) (xy 338.216439 -394.456723) (xy 338.201593 -394.502386) (xy 338.179783 -394.545162)
			(xy 338.151546 -394.583996) (xy 338.117579 -394.617932) (xy 338.078717 -394.646133) (xy 338.035921 -394.667903)
			(xy 337.990245 -394.682706) (xy 337.942814 -394.690176) (xy 337.918806 -394.6906) (xy 337.895232 -394.690201)
			(xy 337.848644 -394.682961) (xy 337.803726 -394.668636) (xy 337.761547 -394.647568) (xy 337.723114 -394.620259)
			(xy 337.689342 -394.58736) (xy 337.661037 -394.549655) (xy 337.649566 -394.529056) (xy 337.649058 -394.528294)
			(xy 337.251294 -393.839954) (xy 337.239438 -393.817267) (xy 337.222579 -393.768939) (xy 337.213998 -393.718479)
			(xy 337.213448 -393.692888) (xy 336.671454 -393.692888) (xy 336.983578 -394.232892) (xy 336.996406 -394.256223)
			(xy 337.014624 -394.306247) (xy 337.023883 -394.358673) (xy 337.024472 -394.385292) (xy 337.024053 -394.409299)
			(xy 337.016539 -394.456723) (xy 337.001694 -394.502385) (xy 336.979884 -394.545161) (xy 336.951648 -394.583995)
			(xy 336.91768 -394.617931) (xy 336.87882 -394.646132) (xy 336.836024 -394.667902) (xy 336.790348 -394.682705)
			(xy 336.742918 -394.690175) (xy 336.71891 -394.6906) (xy 336.695336 -394.690198) (xy 336.648748 -394.682958)
			(xy 336.60383 -394.668634) (xy 336.561652 -394.647566) (xy 336.523218 -394.620258) (xy 336.489447 -394.58736)
			(xy 336.461141 -394.549655) (xy 336.44967 -394.529056) (xy 336.449162 -394.528294) (xy 336.051398 -393.839954)
			(xy 336.039542 -393.817267) (xy 336.022683 -393.768939) (xy 336.014102 -393.718479) (xy 336.013552 -393.692888)
			(xy 322.14367 -393.692888) (xy 322.455794 -394.232892) (xy 322.468623 -394.256222) (xy 322.486841 -394.306246)
			(xy 322.496099 -394.358673) (xy 322.496688 -394.385292) (xy 322.496253 -394.409299) (xy 322.488739 -394.45672)
			(xy 322.473895 -394.502381) (xy 322.452087 -394.545156) (xy 322.423852 -394.58399) (xy 322.389887 -394.617925)
			(xy 322.351029 -394.646126) (xy 322.308235 -394.667897) (xy 322.262561 -394.682702) (xy 322.215133 -394.690174)
			(xy 322.191126 -394.6906) (xy 322.167553 -394.690185) (xy 322.120965 -394.682948) (xy 322.076047 -394.668626)
			(xy 322.033869 -394.64756) (xy 321.995436 -394.620254) (xy 321.961663 -394.587357) (xy 321.933357 -394.549655)
			(xy 321.921886 -394.529056) (xy 321.921378 -394.528294) (xy 321.523614 -393.839954) (xy 321.511752 -393.81727)
			(xy 321.494897 -393.76894) (xy 321.486317 -393.71848) (xy 321.485768 -393.692888) (xy 320.943774 -393.692888)
			(xy 321.255898 -394.232892) (xy 321.268719 -394.256226) (xy 321.286942 -394.306248) (xy 321.296203 -394.358674)
			(xy 321.296792 -394.385292) (xy 321.296353 -394.409298) (xy 321.28884 -394.45672) (xy 321.273996 -394.50238)
			(xy 321.252188 -394.545155) (xy 321.223953 -394.583988) (xy 321.189989 -394.617924) (xy 321.151131 -394.646125)
			(xy 321.108338 -394.667896) (xy 321.062664 -394.682701) (xy 321.015237 -394.690174) (xy 320.99123 -394.6906)
			(xy 320.967657 -394.690182) (xy 320.92107 -394.682945) (xy 320.876152 -394.668624) (xy 320.833973 -394.647559)
			(xy 320.79554 -394.620253) (xy 320.761768 -394.587357) (xy 320.733461 -394.549654) (xy 320.72199 -394.529056)
			(xy 320.721482 -394.528294) (xy 320.323718 -393.839954) (xy 320.311856 -393.81727) (xy 320.295001 -393.76894)
			(xy 320.286421 -393.71848) (xy 320.285872 -393.692888) (xy 319.743878 -393.692888) (xy 320.056002 -394.232892)
			(xy 320.068824 -394.256226) (xy 320.087046 -394.306248) (xy 320.096307 -394.358674) (xy 320.096896 -394.385292)
			(xy 320.096453 -394.409298) (xy 320.08894 -394.456719) (xy 320.074096 -394.502379) (xy 320.052288 -394.545153)
			(xy 320.024055 -394.583987) (xy 319.99009 -394.617922) (xy 319.951233 -394.646123) (xy 319.908441 -394.667895)
			(xy 319.862768 -394.6827) (xy 319.815341 -394.690174) (xy 319.791334 -394.6906) (xy 319.79108 -394.6906)
			(xy 319.767505 -394.690222) (xy 319.720916 -394.682978) (xy 319.675997 -394.668649) (xy 319.633819 -394.647578)
			(xy 319.595386 -394.620266) (xy 319.561615 -394.587364) (xy 319.53331 -394.549657) (xy 319.52184 -394.529056)
			(xy 319.521332 -394.528294) (xy 319.123568 -393.839954) (xy 319.111639 -393.817292) (xy 319.094706 -393.768964)
			(xy 319.086052 -393.718491) (xy 319.085468 -393.692888) (xy 318.543728 -393.692888) (xy 318.855852 -394.232892)
			(xy 318.868607 -394.256246) (xy 318.886713 -394.30628) (xy 318.895914 -394.358688) (xy 318.896492 -394.385292)
			(xy 318.896054 -394.409286) (xy 318.888548 -394.456682) (xy 318.87372 -394.502321) (xy 318.851934 -394.545079)
			(xy 318.823728 -394.583901) (xy 318.789795 -394.617833) (xy 318.750972 -394.646038) (xy 318.708214 -394.667823)
			(xy 318.662575 -394.68265) (xy 318.615178 -394.690155) (xy 318.591184 -394.6906) (xy 318.56761 -394.690219)
			(xy 318.521021 -394.682975) (xy 318.476102 -394.668647) (xy 318.433923 -394.647576) (xy 318.395491 -394.620265)
			(xy 318.361719 -394.587363) (xy 318.333414 -394.549656) (xy 318.321944 -394.529056) (xy 318.321436 -394.528294)
			(xy 317.923672 -393.839954) (xy 317.911736 -393.817296) (xy 317.894806 -393.768965) (xy 317.886155 -393.718492)
			(xy 317.885572 -393.692888) (xy 317.343832 -393.692888) (xy 317.655956 -394.232892) (xy 317.668711 -394.256246)
			(xy 317.686817 -394.30628) (xy 317.696018 -394.358688) (xy 317.696596 -394.385292) (xy 317.696154 -394.409286)
			(xy 317.688648 -394.456682) (xy 317.67382 -394.50232) (xy 317.652035 -394.545077) (xy 317.623829 -394.5839)
			(xy 317.589897 -394.617831) (xy 317.551074 -394.646037) (xy 317.508317 -394.667822) (xy 317.462678 -394.682649)
			(xy 317.415282 -394.690155) (xy 317.391288 -394.6906) (xy 317.391034 -394.6906) (xy 317.367461 -394.690179)
			(xy 317.320874 -394.682942) (xy 317.275956 -394.668622) (xy 317.233778 -394.647557) (xy 317.195344 -394.620252)
			(xy 317.161572 -394.587356) (xy 317.133265 -394.549654) (xy 317.121794 -394.529056) (xy 317.121286 -394.528294)
			(xy 316.723522 -393.839954) (xy 316.711661 -393.81727) (xy 316.694805 -393.76894) (xy 316.686226 -393.71848)
			(xy 316.685676 -393.692888) (xy 316.143682 -393.692888) (xy 316.455806 -394.232892) (xy 316.468628 -394.256226)
			(xy 316.48685 -394.306248) (xy 316.496111 -394.358674) (xy 316.4967 -394.385292) (xy 316.496254 -394.409298)
			(xy 316.48874 -394.456718) (xy 316.473896 -394.502378) (xy 316.452089 -394.545152) (xy 316.423856 -394.583985)
			(xy 316.389892 -394.617921) (xy 316.351035 -394.646122) (xy 316.308243 -394.667894) (xy 316.262571 -394.682699)
			(xy 316.215144 -394.690173) (xy 316.191138 -394.6906) (xy 316.167565 -394.690176) (xy 316.120978 -394.68294)
			(xy 316.07606 -394.66862) (xy 316.033882 -394.647556) (xy 315.995448 -394.620251) (xy 315.961676 -394.587356)
			(xy 315.933369 -394.549654) (xy 315.921898 -394.529056) (xy 315.92139 -394.528294) (xy 315.523626 -393.839954)
			(xy 315.511765 -393.81727) (xy 315.494909 -393.76894) (xy 315.48633 -393.71848) (xy 315.48578 -393.692888)
			(xy 314.943786 -393.692888) (xy 315.25591 -394.232892) (xy 315.268732 -394.256226) (xy 315.286954 -394.306248)
			(xy 315.296215 -394.358673) (xy 315.296804 -394.385292) (xy 315.296354 -394.409298) (xy 315.28884 -394.456718)
			(xy 315.273997 -394.502377) (xy 315.25219 -394.545151) (xy 315.223957 -394.583984) (xy 315.189994 -394.61792)
			(xy 315.151137 -394.646121) (xy 315.108346 -394.667893) (xy 315.062674 -394.682698) (xy 315.015248 -394.690173)
			(xy 314.991242 -394.6906) (xy 314.990988 -394.6906) (xy 314.967414 -394.690216) (xy 314.920825 -394.682973)
			(xy 314.875906 -394.668645) (xy 314.833728 -394.647575) (xy 314.795295 -394.620264) (xy 314.761523 -394.587363)
			(xy 314.733218 -394.549656) (xy 314.721748 -394.529056) (xy 314.72124 -394.528294) (xy 314.323476 -393.839954)
			(xy 314.31154 -393.817296) (xy 314.29461 -393.768965) (xy 314.285959 -393.718492) (xy 314.285376 -393.692888)
			(xy 313.74389 -393.692888) (xy 314.056014 -394.232892) (xy 314.068837 -394.256226) (xy 314.087058 -394.306248)
			(xy 314.096319 -394.358673) (xy 314.096908 -394.385292) (xy 314.096454 -394.409298) (xy 314.08894 -394.456717)
			(xy 314.074097 -394.502377) (xy 314.052291 -394.54515) (xy 314.024058 -394.583983) (xy 313.990095 -394.617918)
			(xy 313.95124 -394.646119) (xy 313.908449 -394.667891) (xy 313.862778 -394.682698) (xy 313.815352 -394.690173)
			(xy 313.791346 -394.6906) (xy 313.791092 -394.6906) (xy 313.767518 -394.690213) (xy 313.720929 -394.68297)
			(xy 313.67601 -394.668643) (xy 313.633832 -394.647573) (xy 313.595399 -394.620263) (xy 313.561628 -394.587362)
			(xy 313.533322 -394.549656) (xy 313.521852 -394.529056) (xy 313.521344 -394.528294) (xy 313.12358 -393.839954)
			(xy 313.111644 -393.817296) (xy 313.094715 -393.768965) (xy 313.086063 -393.718492) (xy 313.08548 -393.692888)
			(xy 312.54374 -393.692888) (xy 312.855864 -394.232892) (xy 312.86862 -394.256246) (xy 312.886726 -394.30628)
			(xy 312.895926 -394.358688) (xy 312.896504 -394.385292) (xy 312.896054 -394.409285) (xy 312.888549 -394.456681)
			(xy 312.873721 -394.502319) (xy 312.851936 -394.545075) (xy 312.823731 -394.583897) (xy 312.7898 -394.617829)
			(xy 312.750978 -394.646034) (xy 312.708222 -394.66782) (xy 312.662585 -394.682648) (xy 312.615189 -394.690154)
			(xy 312.591196 -394.6906) (xy 312.590942 -394.6906) (xy 312.567369 -394.690172) (xy 312.520783 -394.682937)
			(xy 312.475865 -394.668617) (xy 312.433686 -394.647554) (xy 312.395253 -394.62025) (xy 312.36148 -394.587355)
			(xy 312.333173 -394.549654) (xy 312.321702 -394.529056) (xy 312.321194 -394.528294) (xy 311.92343 -393.839954)
			(xy 311.911569 -393.81727) (xy 311.894713 -393.76894) (xy 311.886134 -393.71848) (xy 311.885584 -393.692888)
			(xy 311.34359 -393.692888) (xy 311.655714 -394.232892) (xy 311.668537 -394.256226) (xy 311.686758 -394.306248)
			(xy 311.696019 -394.358673) (xy 311.696608 -394.385292) (xy 311.696154 -394.409298) (xy 311.68864 -394.456717)
			(xy 311.673797 -394.502377) (xy 311.651991 -394.54515) (xy 311.623758 -394.583983) (xy 311.589795 -394.617918)
			(xy 311.55094 -394.646119) (xy 311.508149 -394.667891) (xy 311.462478 -394.682698) (xy 311.415052 -394.690173)
			(xy 311.391046 -394.6906) (xy 311.367473 -394.690169) (xy 311.320887 -394.682935) (xy 311.275969 -394.668615)
			(xy 311.233791 -394.647553) (xy 311.195357 -394.620249) (xy 311.161584 -394.587355) (xy 311.133277 -394.549654)
			(xy 311.121806 -394.529056) (xy 311.121298 -394.528294) (xy 310.723534 -393.839954) (xy 310.711674 -393.81727)
			(xy 310.694818 -393.76894) (xy 310.686238 -393.71848) (xy 310.685688 -393.692888) (xy 310.143694 -393.692888)
			(xy 310.455818 -394.232892) (xy 310.468641 -394.256226) (xy 310.486862 -394.306248) (xy 310.496123 -394.358673)
			(xy 310.496712 -394.385292) (xy 310.496254 -394.409297) (xy 310.48874 -394.456717) (xy 310.473898 -394.502376)
			(xy 310.452091 -394.545149) (xy 310.423859 -394.583981) (xy 310.389897 -394.617917) (xy 310.351042 -394.646118)
			(xy 310.308252 -394.66789) (xy 310.262581 -394.682697) (xy 310.215156 -394.690172) (xy 310.19115 -394.6906)
			(xy 310.167577 -394.690166) (xy 310.120991 -394.682932) (xy 310.076073 -394.668613) (xy 310.033895 -394.647551)
			(xy 309.995461 -394.620248) (xy 309.961688 -394.587354) (xy 309.933381 -394.549653) (xy 309.92191 -394.529056)
			(xy 309.921402 -394.528294) (xy 309.523638 -393.839954) (xy 309.511778 -393.817269) (xy 309.494922 -393.76894)
			(xy 309.486342 -393.71848) (xy 309.485792 -393.692888) (xy 308.943544 -393.692888) (xy 309.255668 -394.232892)
			(xy 309.268424 -394.256246) (xy 309.28653 -394.30628) (xy 309.29573 -394.358688) (xy 309.296308 -394.385292)
			(xy 309.295854 -394.409285) (xy 309.288349 -394.45668) (xy 309.273521 -394.502318) (xy 309.251737 -394.545074)
			(xy 309.223532 -394.583896) (xy 309.189602 -394.617827) (xy 309.150781 -394.646033) (xy 309.108025 -394.667818)
			(xy 309.062388 -394.682647) (xy 309.014993 -394.690154) (xy 308.991 -394.6906) (xy 308.967426 -394.690206)
			(xy 308.920838 -394.682965) (xy 308.875919 -394.668639) (xy 308.833741 -394.64757) (xy 308.795308 -394.620261)
			(xy 308.761536 -394.587361) (xy 308.73323 -394.549656) (xy 308.72176 -394.529056) (xy 308.721252 -394.528294)
			(xy 308.323488 -393.839954) (xy 308.311553 -393.817296) (xy 308.294623 -393.768965) (xy 308.285971 -393.718491)
			(xy 308.285388 -393.692888) (xy 307.743648 -393.692888) (xy 308.055772 -394.232892) (xy 308.068528 -394.256246)
			(xy 308.086634 -394.30628) (xy 308.095834 -394.358688) (xy 308.096412 -394.385292) (xy 308.095954 -394.409285)
			(xy 308.088449 -394.45668) (xy 308.073622 -394.502317) (xy 308.051838 -394.545073) (xy 308.023634 -394.583894)
			(xy 307.989703 -394.617826) (xy 307.950883 -394.646032) (xy 307.908128 -394.667817) (xy 307.862491 -394.682646)
			(xy 307.815097 -394.690154) (xy 307.791104 -394.6906) (xy 307.76753 -394.690203) (xy 307.720942 -394.682962)
			(xy 307.676023 -394.668637) (xy 307.633845 -394.647569) (xy 307.595412 -394.62026) (xy 307.56164 -394.587361)
			(xy 307.533335 -394.549656) (xy 307.521864 -394.529056) (xy 307.521356 -394.528294) (xy 307.123592 -393.839954)
			(xy 307.111657 -393.817295) (xy 307.094727 -393.768965) (xy 307.086075 -393.718491) (xy 307.085492 -393.692888)
			(xy 306.543752 -393.692888) (xy 306.855876 -394.232892) (xy 306.868624 -394.25625) (xy 306.886735 -394.306281)
			(xy 306.895938 -394.358688) (xy 306.896516 -394.385292) (xy 306.89603 -394.409283) (xy 306.888525 -394.456673)
			(xy 306.8737 -394.502306) (xy 306.851918 -394.545059) (xy 306.823716 -394.583877) (xy 306.789789 -394.617806)
			(xy 306.750972 -394.646009) (xy 306.708221 -394.667793) (xy 306.662589 -394.682622) (xy 306.615199 -394.690129)
			(xy 306.591208 -394.6906) (xy 306.590954 -394.6906) (xy 306.567382 -394.690163) (xy 306.520795 -394.682929)
			(xy 306.475878 -394.668611) (xy 306.433699 -394.64755) (xy 306.395266 -394.620247) (xy 306.361493 -394.587353)
			(xy 306.333185 -394.549653) (xy 306.321714 -394.529056) (xy 306.321206 -394.528294) (xy 305.923442 -393.839954)
			(xy 305.911582 -393.817269) (xy 305.894726 -393.76894) (xy 305.886146 -393.71848) (xy 305.885596 -393.692888)
			(xy 305.343602 -393.692888) (xy 305.655726 -394.232892) (xy 305.66855 -394.256225) (xy 305.686771 -394.306247)
			(xy 305.696031 -394.358673) (xy 305.69662 -394.385292) (xy 305.696154 -394.409297) (xy 305.688641 -394.456716)
			(xy 305.673798 -394.502374) (xy 305.651993 -394.545146) (xy 305.623762 -394.583979) (xy 305.5898 -394.617914)
			(xy 305.550946 -394.646115) (xy 305.508157 -394.667888) (xy 305.462488 -394.682695) (xy 305.415063 -394.690172)
			(xy 305.391058 -394.6906) (xy 305.367486 -394.690159) (xy 305.3209 -394.682927) (xy 305.275982 -394.668609)
			(xy 305.233804 -394.647548) (xy 305.19537 -394.620246) (xy 305.161597 -394.587353) (xy 305.13329 -394.549653)
			(xy 305.121818 -394.529056) (xy 305.12131 -394.528294) (xy 304.723546 -393.839954) (xy 304.711686 -393.817269)
			(xy 304.69483 -393.76894) (xy 304.68625 -393.71848) (xy 304.6857 -393.692888) (xy 304.143706 -393.692888)
			(xy 304.45583 -394.232892) (xy 304.468654 -394.256225) (xy 304.486875 -394.306247) (xy 304.496135 -394.358673)
			(xy 304.496724 -394.385292) (xy 304.496254 -394.409297) (xy 304.488741 -394.456715) (xy 304.473899 -394.502373)
			(xy 304.452094 -394.545145) (xy 304.423863 -394.583977) (xy 304.389902 -394.617912) (xy 304.351049 -394.646114)
			(xy 304.30826 -394.667887) (xy 304.262591 -394.682694) (xy 304.215167 -394.690172) (xy 304.191162 -394.6906)
			(xy 304.16759 -394.690156) (xy 304.121004 -394.682924) (xy 304.076086 -394.668607) (xy 304.033908 -394.647547)
			(xy 303.995474 -394.620245) (xy 303.961701 -394.587352) (xy 303.933394 -394.549653) (xy 303.921922 -394.529056)
			(xy 303.921414 -394.528294) (xy 303.52365 -393.839954) (xy 303.511791 -393.817269) (xy 303.494934 -393.76894)
			(xy 303.486354 -393.71848) (xy 303.485804 -393.692888) (xy 2.509012 -393.692888) (xy 2.509012 -396.171674)
			(xy 296.901108 -396.171674) (xy 296.901108 -395.308074) (xy 296.901594 -395.280823) (xy 296.90935 -395.226875)
			(xy 296.924705 -395.17458) (xy 296.947347 -395.125003) (xy 296.976813 -395.079153) (xy 297.012504 -395.037962)
			(xy 297.053695 -395.002271) (xy 297.099545 -394.972805) (xy 297.149122 -394.950163) (xy 297.201417 -394.934808)
			(xy 297.255365 -394.927052) (xy 297.309867 -394.927052) (xy 297.363815 -394.934808) (xy 297.41611 -394.950163)
			(xy 297.465687 -394.972805) (xy 297.511537 -395.002271) (xy 297.552728 -395.037962) (xy 297.588419 -395.079153)
			(xy 297.617885 -395.125003) (xy 297.640527 -395.17458) (xy 297.655882 -395.226875) (xy 297.663638 -395.280823)
			(xy 297.664124 -395.308074) (xy 297.664124 -396.171674) (xy 329.428856 -396.171674) (xy 329.428856 -395.308074)
			(xy 329.429342 -395.280823) (xy 329.437098 -395.226875) (xy 329.452453 -395.17458) (xy 329.475095 -395.125003)
			(xy 329.504561 -395.079153) (xy 329.540252 -395.037962) (xy 329.581443 -395.002271) (xy 329.627293 -394.972805)
			(xy 329.67687 -394.950163) (xy 329.729165 -394.934808) (xy 329.783113 -394.927052) (xy 329.837615 -394.927052)
			(xy 329.891563 -394.934808) (xy 329.943858 -394.950163) (xy 329.993435 -394.972805) (xy 330.039285 -395.002271)
			(xy 330.080476 -395.037962) (xy 330.116167 -395.079153) (xy 330.145633 -395.125003) (xy 330.168275 -395.17458)
			(xy 330.18363 -395.226875) (xy 330.191386 -395.280823) (xy 330.191872 -395.308074) (xy 330.191872 -396.171674)
			(xy 364.001304 -396.171674) (xy 364.001304 -395.308074) (xy 364.00179 -395.280823) (xy 364.009546 -395.226875)
			(xy 364.024901 -395.17458) (xy 364.047543 -395.125003) (xy 364.077009 -395.079153) (xy 364.1127 -395.037962)
			(xy 364.153891 -395.002271) (xy 364.199741 -394.972805) (xy 364.249318 -394.950163) (xy 364.301613 -394.934808)
			(xy 364.355561 -394.927052) (xy 364.410063 -394.927052) (xy 364.464011 -394.934808) (xy 364.516306 -394.950163)
			(xy 364.565883 -394.972805) (xy 364.611733 -395.002271) (xy 364.652924 -395.037962) (xy 364.688615 -395.079153)
			(xy 364.718081 -395.125003) (xy 364.740723 -395.17458) (xy 364.756078 -395.226875) (xy 364.763834 -395.280823)
			(xy 364.76432 -395.308074) (xy 364.76432 -396.171674) (xy 396.529052 -396.171674) (xy 396.529052 -395.308074)
			(xy 396.529538 -395.280823) (xy 396.537294 -395.226875) (xy 396.552649 -395.17458) (xy 396.575291 -395.125003)
			(xy 396.604757 -395.079153) (xy 396.640448 -395.037962) (xy 396.681639 -395.002271) (xy 396.727489 -394.972805)
			(xy 396.777066 -394.950163) (xy 396.829361 -394.934808) (xy 396.883309 -394.927052) (xy 396.937811 -394.927052)
			(xy 396.991759 -394.934808) (xy 397.044054 -394.950163) (xy 397.093631 -394.972805) (xy 397.139481 -395.002271)
			(xy 397.180672 -395.037962) (xy 397.216363 -395.079153) (xy 397.245829 -395.125003) (xy 397.268471 -395.17458)
			(xy 397.283826 -395.226875) (xy 397.291582 -395.280823) (xy 397.292068 -395.308074) (xy 397.292068 -396.171674)
			(xy 397.291582 -396.198925) (xy 397.283826 -396.252873) (xy 397.268471 -396.305168) (xy 397.245829 -396.354745)
			(xy 397.216363 -396.400595) (xy 397.180672 -396.441786) (xy 397.139481 -396.477477) (xy 397.093631 -396.506943)
			(xy 397.044054 -396.529585) (xy 396.991759 -396.54494) (xy 396.937811 -396.552696) (xy 396.883309 -396.552696)
			(xy 396.829361 -396.54494) (xy 396.777066 -396.529585) (xy 396.727489 -396.506943) (xy 396.681639 -396.477477)
			(xy 396.640448 -396.441786) (xy 396.604757 -396.400595) (xy 396.575291 -396.354745) (xy 396.552649 -396.305168)
			(xy 396.537294 -396.252873) (xy 396.529538 -396.198925) (xy 396.529052 -396.171674) (xy 364.76432 -396.171674)
			(xy 364.763834 -396.198925) (xy 364.756078 -396.252873) (xy 364.740723 -396.305168) (xy 364.718081 -396.354745)
			(xy 364.688615 -396.400595) (xy 364.652924 -396.441786) (xy 364.611733 -396.477477) (xy 364.565883 -396.506943)
			(xy 364.516306 -396.529585) (xy 364.464011 -396.54494) (xy 364.410063 -396.552696) (xy 364.355561 -396.552696)
			(xy 364.301613 -396.54494) (xy 364.249318 -396.529585) (xy 364.199741 -396.506943) (xy 364.153891 -396.477477)
			(xy 364.1127 -396.441786) (xy 364.077009 -396.400595) (xy 364.047543 -396.354745) (xy 364.024901 -396.305168)
			(xy 364.009546 -396.252873) (xy 364.00179 -396.198925) (xy 364.001304 -396.171674) (xy 330.191872 -396.171674)
			(xy 330.191386 -396.198925) (xy 330.18363 -396.252873) (xy 330.168275 -396.305168) (xy 330.145633 -396.354745)
			(xy 330.116167 -396.400595) (xy 330.080476 -396.441786) (xy 330.039285 -396.477477) (xy 329.993435 -396.506943)
			(xy 329.943858 -396.529585) (xy 329.891563 -396.54494) (xy 329.837615 -396.552696) (xy 329.783113 -396.552696)
			(xy 329.729165 -396.54494) (xy 329.67687 -396.529585) (xy 329.627293 -396.506943) (xy 329.581443 -396.477477)
			(xy 329.540252 -396.441786) (xy 329.504561 -396.400595) (xy 329.475095 -396.354745) (xy 329.452453 -396.305168)
			(xy 329.437098 -396.252873) (xy 329.429342 -396.198925) (xy 329.428856 -396.171674) (xy 297.664124 -396.171674)
			(xy 297.663638 -396.198925) (xy 297.655882 -396.252873) (xy 297.640527 -396.305168) (xy 297.617885 -396.354745)
			(xy 297.588419 -396.400595) (xy 297.552728 -396.441786) (xy 297.511537 -396.477477) (xy 297.465687 -396.506943)
			(xy 297.41611 -396.529585) (xy 297.363815 -396.54494) (xy 297.309867 -396.552696) (xy 297.255365 -396.552696)
			(xy 297.201417 -396.54494) (xy 297.149122 -396.529585) (xy 297.099545 -396.506943) (xy 297.053695 -396.477477)
			(xy 297.012504 -396.441786) (xy 296.976813 -396.400595) (xy 296.947347 -396.354745) (xy 296.924705 -396.305168)
			(xy 296.90935 -396.252873) (xy 296.901594 -396.198925) (xy 296.901108 -396.171674) (xy 2.509012 -396.171674)
			(xy 2.509012 -400.50847) (xy 103.485188 -400.50847) (xy 103.485723 -400.479553) (xy 103.494444 -400.422381)
			(xy 103.511697 -400.367182) (xy 103.537085 -400.315219) (xy 103.570027 -400.267685) (xy 103.609768 -400.225669)
			(xy 103.632254 -400.20748) (xy 103.641069 -400.199881) (xy 103.651246 -400.178974) (xy 103.651812 -400.167348)
			(xy 103.651812 -400.087592) (xy 103.651259 -400.075962) (xy 103.64108 -400.055053) (xy 103.632254 -400.04746)
			(xy 103.609742 -400.029303) (xy 103.57001 -399.987275) (xy 103.537076 -399.939733) (xy 103.511693 -399.887765)
			(xy 103.494443 -399.832562) (xy 103.48572 -399.775388) (xy 103.485188 -399.74647) (xy 103.485674 -399.719201)
			(xy 103.493436 -399.665217) (xy 103.508801 -399.612887) (xy 103.531458 -399.563277) (xy 103.560944 -399.517396)
			(xy 103.596659 -399.476179) (xy 103.637876 -399.440464) (xy 103.683757 -399.410978) (xy 103.733367 -399.388321)
			(xy 103.785697 -399.372956) (xy 103.839681 -399.365194) (xy 103.894219 -399.365194) (xy 103.948203 -399.372956)
			(xy 104.000533 -399.388321) (xy 104.050143 -399.410978) (xy 104.096024 -399.440464) (xy 104.137241 -399.476179)
			(xy 104.172956 -399.517396) (xy 104.202442 -399.563277) (xy 104.225099 -399.612887) (xy 104.240464 -399.665217)
			(xy 104.248226 -399.719201) (xy 104.248712 -399.74647) (xy 104.248206 -399.775388) (xy 104.239479 -399.832561)
			(xy 104.222221 -399.887762) (xy 104.196827 -399.939724) (xy 104.16388 -399.987257) (xy 104.124134 -400.029272)
			(xy 104.101646 -400.04746) (xy 104.092858 -400.055085) (xy 104.082666 -400.075972) (xy 104.082088 -400.087592)
			(xy 104.082088 -400.167348) (xy 104.082618 -400.178981) (xy 104.092814 -400.19989) (xy 104.101646 -400.20748)
			(xy 104.124129 -400.225671) (xy 104.163863 -400.267692) (xy 104.1968 -400.315227) (xy 104.222188 -400.367188)
			(xy 104.239445 -400.422385) (xy 104.248176 -400.479554) (xy 104.248712 -400.50847) (xy 104.248226 -400.535739)
			(xy 104.240464 -400.589723) (xy 104.225099 -400.642053) (xy 104.202442 -400.691663) (xy 104.172956 -400.737544)
			(xy 104.137241 -400.778761) (xy 104.096024 -400.814476) (xy 104.050143 -400.843962) (xy 104.000533 -400.866619)
			(xy 103.948203 -400.881984) (xy 103.894219 -400.889746) (xy 103.839681 -400.889746) (xy 103.785697 -400.881984)
			(xy 103.733367 -400.866619) (xy 103.683757 -400.843962) (xy 103.637876 -400.814476) (xy 103.596659 -400.778761)
			(xy 103.560944 -400.737544) (xy 103.531458 -400.691663) (xy 103.508801 -400.642053) (xy 103.493436 -400.589723)
			(xy 103.485674 -400.535739) (xy 103.485188 -400.50847) (xy 2.509012 -400.50847) (xy 2.509012 -403.371812)
			(xy 2.5095 -403.425034) (xy 2.517117 -403.531207) (xy 2.532283 -403.636566) (xy 2.554922 -403.740575)
			(xy 2.584919 -403.842706) (xy 2.622121 -403.942439) (xy 2.666338 -404.039266) (xy 2.717346 -404.132693)
			(xy 2.774884 -404.222247) (xy 2.838661 -404.307471) (xy 2.908351 -404.387931) (xy 2.945638 -404.425912)
			(xy 3.30962 -404.789894) (xy 37.568898 -404.789894) (xy 37.57287 -404.611651) (xy 37.584778 -404.433762)
			(xy 37.604599 -404.25658) (xy 37.632293 -404.080456) (xy 37.667805 -403.905741) (xy 37.711065 -403.732782)
			(xy 37.761987 -403.561921) (xy 37.82047 -403.393499) (xy 37.886397 -403.227849) (xy 37.959638 -403.0653)
			(xy 38.040048 -402.906175) (xy 38.127466 -402.75079) (xy 38.221719 -402.599454) (xy 38.32262 -402.452466)
			(xy 38.429969 -402.310119) (xy 38.543552 -402.172696) (xy 38.663145 -402.040469) (xy 38.788509 -401.9137)
			(xy 38.919396 -401.792642) (xy 39.055545 -401.677535) (xy 39.196687 -401.568607) (xy 39.342542 -401.466075)
			(xy 39.492819 -401.370141) (xy 39.64722 -401.280998) (xy 39.805439 -401.198821) (xy 39.967162 -401.123773)
			(xy 40.132067 -401.056005) (xy 40.299828 -400.995649) (xy 40.470111 -400.942827) (xy 40.642578 -400.897643)
			(xy 40.816886 -400.860186) (xy 40.99269 -400.830532) (xy 41.16964 -400.808739) (xy 41.347386 -400.794849)
			(xy 41.525573 -400.788892) (xy 41.70385 -400.790878) (xy 41.881861 -400.800804) (xy 42.059253 -400.81865)
			(xy 42.235673 -400.84438) (xy 42.410773 -400.877944) (xy 42.584204 -400.919274) (xy 42.755621 -400.96829)
			(xy 42.924684 -401.024892) (xy 43.091059 -401.08897) (xy 43.254413 -401.160396) (xy 43.414424 -401.239028)
			(xy 43.570773 -401.324709) (xy 43.72315 -401.417271) (xy 43.871253 -401.516528) (xy 44.014787 -401.622285)
			(xy 44.153467 -401.73433) (xy 44.287018 -401.852442) (xy 44.415175 -401.976386) (xy 44.537684 -402.105916)
			(xy 44.654301 -402.240775) (xy 44.764794 -402.380695) (xy 44.868945 -402.525398) (xy 44.966547 -402.674597)
			(xy 45.057405 -402.827996) (xy 45.141339 -402.98529) (xy 45.218184 -403.146166) (xy 45.287785 -403.310307)
			(xy 45.350006 -403.477384) (xy 45.404722 -403.647068) (xy 45.451824 -403.819021) (xy 45.49122 -403.992901)
			(xy 45.522831 -404.168364) (xy 45.546595 -404.34506) (xy 45.559703 -404.491748) (xy 47.413198 -404.491748)
			(xy 47.413198 -404.437252) (xy 47.420953 -404.38331) (xy 47.436306 -404.331021) (xy 47.458943 -404.281449)
			(xy 47.488404 -404.235603) (xy 47.52409 -404.194416) (xy 47.565274 -404.158726) (xy 47.611117 -404.12926)
			(xy 47.660687 -404.106618) (xy 47.712975 -404.091261) (xy 47.766916 -404.083501) (xy 47.794164 -404.083012)
			(xy 48.657764 -404.083012) (xy 48.68502 -404.083432) (xy 48.738978 -404.091186) (xy 48.791283 -404.106539)
			(xy 48.84087 -404.129181) (xy 48.88673 -404.15865) (xy 48.927929 -404.194345) (xy 48.963629 -404.235541)
			(xy 48.993102 -404.281398) (xy 49.015748 -404.330984) (xy 49.031107 -404.383287) (xy 49.038865 -404.437244)
			(xy 49.038865 -404.491752) (xy 50.476375 -404.491752) (xy 50.476375 -404.437248) (xy 50.484132 -404.3833)
			(xy 50.499487 -404.331005) (xy 50.522129 -404.281427) (xy 50.551596 -404.235576) (xy 50.587288 -404.194385)
			(xy 50.628479 -404.158693) (xy 50.67433 -404.129227) (xy 50.723908 -404.106586) (xy 50.776204 -404.091231)
			(xy 50.830152 -404.083475) (xy 50.857404 -404.083012) (xy 51.721004 -404.083012) (xy 51.748256 -404.083458)
			(xy 51.802207 -404.091215) (xy 51.854504 -404.106572) (xy 51.904083 -404.129214) (xy 51.949935 -404.158682)
			(xy 51.991127 -404.194376) (xy 52.02682 -404.235568) (xy 52.056288 -404.281421) (xy 52.07893 -404.331)
			(xy 52.094285 -404.383297) (xy 52.102042 -404.437248) (xy 52.102042 -404.491752) (xy 52.102042 -404.491753)
			(xy 53.539575 -404.491753) (xy 53.539575 -404.437247) (xy 53.547333 -404.383295) (xy 53.562691 -404.330996)
			(xy 53.585335 -404.281416) (xy 53.614806 -404.235563) (xy 53.650502 -404.194371) (xy 53.691698 -404.158679)
			(xy 53.737554 -404.129214) (xy 53.787137 -404.106575) (xy 53.839438 -404.091224) (xy 53.893391 -404.083472)
			(xy 53.920644 -404.083012) (xy 54.784244 -404.083012) (xy 54.811495 -404.083461) (xy 54.86544 -404.091223)
			(xy 54.917733 -404.106583) (xy 54.967307 -404.129227) (xy 55.013154 -404.158696) (xy 55.054341 -404.19439)
			(xy 55.09003 -404.235581) (xy 55.119494 -404.281432) (xy 55.142133 -404.331009) (xy 55.157487 -404.383303)
			(xy 55.165242 -404.437249) (xy 55.165242 -404.491749) (xy 56.602898 -404.491749) (xy 56.602898 -404.437251)
			(xy 56.610654 -404.383308) (xy 56.626007 -404.331017) (xy 56.648646 -404.281443) (xy 56.678109 -404.235596)
			(xy 56.713797 -404.194409) (xy 56.754983 -404.158719) (xy 56.800829 -404.129254) (xy 56.850402 -404.106613)
			(xy 56.902692 -404.091257) (xy 56.956635 -404.083499) (xy 56.983884 -404.083012) (xy 57.847484 -404.083012)
			(xy 57.874739 -404.083434) (xy 57.928695 -404.091189) (xy 57.980997 -404.106545) (xy 58.030582 -404.129188)
			(xy 58.07644 -404.158657) (xy 58.117636 -404.194352) (xy 58.153334 -404.235548) (xy 58.182805 -404.281404)
			(xy 58.20545 -404.330988) (xy 58.220807 -404.38329) (xy 58.228565 -404.437245) (xy 58.228565 -404.491753)
			(xy 59.666075 -404.491753) (xy 59.666075 -404.437247) (xy 59.673833 -404.383297) (xy 59.689189 -404.331)
			(xy 59.711832 -404.281421) (xy 59.741301 -404.235569) (xy 59.776995 -404.194378) (xy 59.818188 -404.158686)
			(xy 59.864042 -404.129221) (xy 59.913623 -404.106581) (xy 59.965921 -404.091227) (xy 60.019871 -404.083474)
			(xy 60.047124 -404.083012) (xy 60.910724 -404.083012) (xy 60.937976 -404.083459) (xy 60.991924 -404.091219)
			(xy 61.044218 -404.106577) (xy 61.093795 -404.129221) (xy 61.139645 -404.158689) (xy 61.180834 -404.194383)
			(xy 61.216525 -404.235575) (xy 61.245991 -404.281426) (xy 61.268631 -404.331004) (xy 61.283986 -404.3833)
			(xy 61.291742 -404.437248) (xy 61.291742 -404.491748) (xy 62.729398 -404.491748) (xy 62.729398 -404.437252)
			(xy 62.737153 -404.38331) (xy 62.752506 -404.331021) (xy 62.775143 -404.281449) (xy 62.804604 -404.235603)
			(xy 62.84029 -404.194416) (xy 62.881474 -404.158726) (xy 62.927317 -404.12926) (xy 62.976887 -404.106618)
			(xy 63.029175 -404.091261) (xy 63.083116 -404.083501) (xy 63.110364 -404.083012) (xy 63.973964 -404.083012)
			(xy 64.00122 -404.083432) (xy 64.055178 -404.091186) (xy 64.107483 -404.106539) (xy 64.15707 -404.129181)
			(xy 64.20293 -404.15865) (xy 64.244129 -404.194345) (xy 64.279829 -404.235541) (xy 64.309302 -404.281398)
			(xy 64.331948 -404.330984) (xy 64.347307 -404.383287) (xy 64.355065 -404.437244) (xy 64.355065 -404.491752)
			(xy 65.792575 -404.491752) (xy 65.792575 -404.437248) (xy 65.800332 -404.3833) (xy 65.815687 -404.331005)
			(xy 65.838329 -404.281427) (xy 65.867796 -404.235576) (xy 65.903488 -404.194385) (xy 65.944679 -404.158693)
			(xy 65.99053 -404.129227) (xy 66.040108 -404.106586) (xy 66.092404 -404.091231) (xy 66.146352 -404.083475)
			(xy 66.173604 -404.083012) (xy 67.037204 -404.083012) (xy 67.064456 -404.083458) (xy 67.118407 -404.091215)
			(xy 67.170704 -404.106572) (xy 67.220283 -404.129214) (xy 67.266135 -404.158682) (xy 67.307327 -404.194376)
			(xy 67.34302 -404.235568) (xy 67.372488 -404.281421) (xy 67.39513 -404.331) (xy 67.410485 -404.383297)
			(xy 67.418242 -404.437248) (xy 67.418242 -404.491752) (xy 67.418242 -404.491753) (xy 68.855775 -404.491753)
			(xy 68.855775 -404.437247) (xy 68.863533 -404.383295) (xy 68.878891 -404.330996) (xy 68.901535 -404.281416)
			(xy 68.931006 -404.235563) (xy 68.966702 -404.194371) (xy 69.007898 -404.158679) (xy 69.053754 -404.129214)
			(xy 69.103337 -404.106575) (xy 69.155638 -404.091224) (xy 69.209591 -404.083472) (xy 69.236844 -404.083012)
			(xy 70.100444 -404.083012) (xy 70.127695 -404.083461) (xy 70.18164 -404.091223) (xy 70.233933 -404.106583)
			(xy 70.283507 -404.129227) (xy 70.329354 -404.158696) (xy 70.370541 -404.19439) (xy 70.40623 -404.235581)
			(xy 70.435694 -404.281432) (xy 70.458333 -404.331009) (xy 70.473687 -404.383303) (xy 70.481442 -404.437249)
			(xy 70.481442 -404.491749) (xy 71.919098 -404.491749) (xy 71.919098 -404.437251) (xy 71.926854 -404.383308)
			(xy 71.942207 -404.331017) (xy 71.964846 -404.281443) (xy 71.994309 -404.235596) (xy 72.029997 -404.194409)
			(xy 72.071183 -404.158719) (xy 72.117029 -404.129254) (xy 72.166602 -404.106613) (xy 72.218892 -404.091257)
			(xy 72.272835 -404.083499) (xy 72.300084 -404.083012) (xy 73.163684 -404.083012) (xy 73.190939 -404.083434)
			(xy 73.244895 -404.091189) (xy 73.297197 -404.106545) (xy 73.346782 -404.129188) (xy 73.39264 -404.158657)
			(xy 73.433836 -404.194352) (xy 73.469534 -404.235548) (xy 73.499005 -404.281404) (xy 73.52165 -404.330988)
			(xy 73.537007 -404.38329) (xy 73.544765 -404.437245) (xy 73.544765 -404.491753) (xy 74.982275 -404.491753)
			(xy 74.982275 -404.437247) (xy 74.990033 -404.383297) (xy 75.005389 -404.331) (xy 75.028032 -404.281421)
			(xy 75.057501 -404.235569) (xy 75.093195 -404.194378) (xy 75.134388 -404.158686) (xy 75.180242 -404.129221)
			(xy 75.229823 -404.106581) (xy 75.282121 -404.091227) (xy 75.336071 -404.083474) (xy 75.363324 -404.083012)
			(xy 76.226924 -404.083012) (xy 76.254176 -404.083459) (xy 76.308124 -404.091219) (xy 76.360418 -404.106577)
			(xy 76.409995 -404.129221) (xy 76.455845 -404.158689) (xy 76.497034 -404.194383) (xy 76.532725 -404.235575)
			(xy 76.562191 -404.281426) (xy 76.584831 -404.331004) (xy 76.600186 -404.3833) (xy 76.607942 -404.437248)
			(xy 76.607942 -404.491748) (xy 78.045598 -404.491748) (xy 78.045598 -404.437252) (xy 78.053353 -404.38331)
			(xy 78.068706 -404.331021) (xy 78.091343 -404.281449) (xy 78.120804 -404.235603) (xy 78.15649 -404.194416)
			(xy 78.197674 -404.158726) (xy 78.243517 -404.12926) (xy 78.293087 -404.106618) (xy 78.345375 -404.091261)
			(xy 78.399316 -404.083501) (xy 78.426564 -404.083012) (xy 79.290164 -404.083012) (xy 79.31742 -404.083432)
			(xy 79.371378 -404.091186) (xy 79.423683 -404.106539) (xy 79.47327 -404.129181) (xy 79.51913 -404.15865)
			(xy 79.560329 -404.194345) (xy 79.596029 -404.235541) (xy 79.625502 -404.281398) (xy 79.648148 -404.330984)
			(xy 79.663507 -404.383287) (xy 79.671265 -404.437244) (xy 79.671265 -404.491752) (xy 81.108775 -404.491752)
			(xy 81.108775 -404.437248) (xy 81.116532 -404.3833) (xy 81.131887 -404.331005) (xy 81.154529 -404.281427)
			(xy 81.183996 -404.235576) (xy 81.219688 -404.194385) (xy 81.260879 -404.158693) (xy 81.30673 -404.129227)
			(xy 81.356308 -404.106586) (xy 81.408604 -404.091231) (xy 81.462552 -404.083475) (xy 81.489804 -404.083012)
			(xy 82.353404 -404.083012) (xy 82.380656 -404.083458) (xy 82.434607 -404.091215) (xy 82.486904 -404.106572)
			(xy 82.536483 -404.129214) (xy 82.582335 -404.158682) (xy 82.623527 -404.194376) (xy 82.65922 -404.235568)
			(xy 82.688688 -404.281421) (xy 82.71133 -404.331) (xy 82.726685 -404.383297) (xy 82.734442 -404.437248)
			(xy 82.734442 -404.491752) (xy 82.734442 -404.491753) (xy 84.171975 -404.491753) (xy 84.171975 -404.437247)
			(xy 84.179733 -404.383295) (xy 84.195091 -404.330996) (xy 84.217735 -404.281416) (xy 84.247206 -404.235563)
			(xy 84.282902 -404.194371) (xy 84.324098 -404.158679) (xy 84.369954 -404.129214) (xy 84.419537 -404.106575)
			(xy 84.471838 -404.091224) (xy 84.525791 -404.083472) (xy 84.553044 -404.083012) (xy 85.416644 -404.083012)
			(xy 85.443895 -404.083461) (xy 85.49784 -404.091223) (xy 85.550133 -404.106583) (xy 85.599707 -404.129227)
			(xy 85.645554 -404.158696) (xy 85.686741 -404.19439) (xy 85.72243 -404.235581) (xy 85.751894 -404.281432)
			(xy 85.774533 -404.331009) (xy 85.789887 -404.383303) (xy 85.797642 -404.437249) (xy 85.797642 -404.491749)
			(xy 87.235298 -404.491749) (xy 87.235298 -404.437251) (xy 87.243054 -404.383308) (xy 87.258407 -404.331017)
			(xy 87.281046 -404.281443) (xy 87.310509 -404.235596) (xy 87.346197 -404.194409) (xy 87.387383 -404.158719)
			(xy 87.433229 -404.129254) (xy 87.482802 -404.106613) (xy 87.535092 -404.091257) (xy 87.589035 -404.083499)
			(xy 87.616284 -404.083012) (xy 88.479884 -404.083012) (xy 88.507139 -404.083434) (xy 88.561095 -404.091189)
			(xy 88.613397 -404.106545) (xy 88.662982 -404.129188) (xy 88.70884 -404.158657) (xy 88.750036 -404.194352)
			(xy 88.785734 -404.235548) (xy 88.815205 -404.281404) (xy 88.83785 -404.330988) (xy 88.853207 -404.38329)
			(xy 88.860965 -404.437245) (xy 88.860965 -404.491753) (xy 90.298475 -404.491753) (xy 90.298475 -404.437247)
			(xy 90.306233 -404.383297) (xy 90.321589 -404.331) (xy 90.344232 -404.281421) (xy 90.373701 -404.235569)
			(xy 90.409395 -404.194378) (xy 90.450588 -404.158686) (xy 90.496442 -404.129221) (xy 90.546023 -404.106581)
			(xy 90.598321 -404.091227) (xy 90.652271 -404.083474) (xy 90.679524 -404.083012) (xy 91.543124 -404.083012)
			(xy 91.570376 -404.083459) (xy 91.624324 -404.091219) (xy 91.676618 -404.106577) (xy 91.726195 -404.129221)
			(xy 91.772045 -404.158689) (xy 91.813234 -404.194383) (xy 91.848925 -404.235575) (xy 91.878391 -404.281426)
			(xy 91.901031 -404.331004) (xy 91.916386 -404.3833) (xy 91.924142 -404.437248) (xy 91.924142 -404.491748)
			(xy 93.361798 -404.491748) (xy 93.361798 -404.437252) (xy 93.369553 -404.38331) (xy 93.384906 -404.331021)
			(xy 93.407543 -404.281449) (xy 93.437004 -404.235603) (xy 93.47269 -404.194416) (xy 93.513874 -404.158726)
			(xy 93.559717 -404.12926) (xy 93.609287 -404.106618) (xy 93.661575 -404.091261) (xy 93.715516 -404.083501)
			(xy 93.742764 -404.083012) (xy 94.606364 -404.083012) (xy 94.63362 -404.083432) (xy 94.687578 -404.091186)
			(xy 94.739883 -404.106539) (xy 94.78947 -404.129181) (xy 94.83533 -404.15865) (xy 94.876529 -404.194345)
			(xy 94.912229 -404.235541) (xy 94.941702 -404.281398) (xy 94.964348 -404.330984) (xy 94.979707 -404.383287)
			(xy 94.987465 -404.437244) (xy 94.987465 -404.491752) (xy 114.513075 -404.491752) (xy 114.513075 -404.437248)
			(xy 114.520832 -404.3833) (xy 114.536188 -404.331004) (xy 114.558829 -404.281426) (xy 114.588296 -404.235575)
			(xy 114.623989 -404.194384) (xy 114.66518 -404.158693) (xy 114.711031 -404.129226) (xy 114.76061 -404.106585)
			(xy 114.812906 -404.091231) (xy 114.866854 -404.083475) (xy 114.894106 -404.083012) (xy 115.757706 -404.083012)
			(xy 115.784958 -404.083458) (xy 115.838908 -404.091216) (xy 115.891205 -404.106572) (xy 115.940784 -404.129215)
			(xy 115.986636 -404.158683) (xy 116.027828 -404.194376) (xy 116.063521 -404.235569) (xy 116.092988 -404.281421)
			(xy 116.11563 -404.331001) (xy 116.130985 -404.383298) (xy 116.138742 -404.437248) (xy 116.138742 -404.491752)
			(xy 116.138742 -404.491754) (xy 117.576275 -404.491754) (xy 117.576275 -404.437246) (xy 117.584033 -404.383294)
			(xy 117.599391 -404.330996) (xy 117.622035 -404.281415) (xy 117.651506 -404.235562) (xy 117.687203 -404.19437)
			(xy 117.728399 -404.158679) (xy 117.774255 -404.129213) (xy 117.823839 -404.106575) (xy 117.876139 -404.091223)
			(xy 117.930092 -404.083472) (xy 117.957346 -404.083012) (xy 118.820946 -404.083012) (xy 118.848197 -404.083461)
			(xy 118.902142 -404.091223) (xy 118.954434 -404.106583) (xy 119.004008 -404.129228) (xy 119.049855 -404.158697)
			(xy 119.091042 -404.194391) (xy 119.12673 -404.235582) (xy 119.156194 -404.281432) (xy 119.178833 -404.331009)
			(xy 119.194187 -404.383303) (xy 119.201942 -404.437249) (xy 119.201942 -404.491749) (xy 120.639598 -404.491749)
			(xy 120.639598 -404.437251) (xy 120.647354 -404.383307) (xy 120.662708 -404.331016) (xy 120.685346 -404.281443)
			(xy 120.71481 -404.235596) (xy 120.750498 -404.194408) (xy 120.791684 -404.158718) (xy 120.83753 -404.129253)
			(xy 120.887103 -404.106612) (xy 120.939394 -404.091257) (xy 120.993337 -404.083499) (xy 121.020586 -404.083012)
			(xy 121.884186 -404.083012) (xy 121.911441 -404.083434) (xy 121.965396 -404.09119) (xy 122.017699 -404.106545)
			(xy 122.067283 -404.129188) (xy 122.113141 -404.158657) (xy 122.154337 -404.194353) (xy 122.190034 -404.235548)
			(xy 122.219505 -404.281405) (xy 122.24215 -404.330988) (xy 122.257507 -404.38329) (xy 122.265265 -404.437245)
			(xy 122.265265 -404.491753) (xy 123.702775 -404.491753) (xy 123.702775 -404.437247) (xy 123.710533 -404.383297)
			(xy 123.725889 -404.331) (xy 123.748532 -404.281421) (xy 123.778001 -404.235569) (xy 123.813696 -404.194377)
			(xy 123.854889 -404.158686) (xy 123.900743 -404.12922) (xy 123.950324 -404.10658) (xy 124.002622 -404.091227)
			(xy 124.056573 -404.083474) (xy 124.083826 -404.083012) (xy 124.947426 -404.083012) (xy 124.974677 -404.08346)
			(xy 125.028625 -404.09122) (xy 125.08092 -404.106578) (xy 125.130496 -404.129222) (xy 125.176346 -404.15869)
			(xy 125.217535 -404.194383) (xy 125.253226 -404.235575) (xy 125.282691 -404.281427) (xy 125.305331 -404.331005)
			(xy 125.320686 -404.3833) (xy 125.328442 -404.437249) (xy 125.328442 -404.491748) (xy 126.766098 -404.491748)
			(xy 126.766098 -404.437252) (xy 126.773853 -404.38331) (xy 126.789206 -404.331021) (xy 126.811843 -404.281448)
			(xy 126.841305 -404.235602) (xy 126.876991 -404.194415) (xy 126.918175 -404.158725) (xy 126.964018 -404.12926)
			(xy 127.013589 -404.106618) (xy 127.065877 -404.091261) (xy 127.119818 -404.083501) (xy 127.147066 -404.083012)
			(xy 128.010666 -404.083012) (xy 128.037922 -404.083433) (xy 128.091879 -404.091186) (xy 128.144184 -404.10654)
			(xy 128.193771 -404.129182) (xy 128.239631 -404.15865) (xy 128.28083 -404.194346) (xy 128.316529 -404.235542)
			(xy 128.346002 -404.281399) (xy 128.368648 -404.330984) (xy 128.384007 -404.383287) (xy 128.391765 -404.437244)
			(xy 128.391765 -404.491752) (xy 129.829275 -404.491752) (xy 129.829275 -404.437248) (xy 129.837032 -404.3833)
			(xy 129.852388 -404.331004) (xy 129.875029 -404.281426) (xy 129.904496 -404.235575) (xy 129.940189 -404.194384)
			(xy 129.98138 -404.158693) (xy 130.027231 -404.129226) (xy 130.07681 -404.106585) (xy 130.129106 -404.091231)
			(xy 130.183054 -404.083475) (xy 130.210306 -404.083012) (xy 131.073906 -404.083012) (xy 131.101158 -404.083458)
			(xy 131.155108 -404.091216) (xy 131.207405 -404.106572) (xy 131.256984 -404.129215) (xy 131.302836 -404.158683)
			(xy 131.344028 -404.194376) (xy 131.379721 -404.235569) (xy 131.409188 -404.281421) (xy 131.43183 -404.331001)
			(xy 131.447185 -404.383298) (xy 131.454942 -404.437248) (xy 131.454942 -404.491752) (xy 131.454942 -404.491754)
			(xy 132.892475 -404.491754) (xy 132.892475 -404.437246) (xy 132.900233 -404.383294) (xy 132.915591 -404.330996)
			(xy 132.938235 -404.281415) (xy 132.967706 -404.235562) (xy 133.003403 -404.19437) (xy 133.044599 -404.158679)
			(xy 133.090455 -404.129213) (xy 133.140039 -404.106575) (xy 133.192339 -404.091223) (xy 133.246292 -404.083472)
			(xy 133.273546 -404.083012) (xy 134.137146 -404.083012) (xy 134.164397 -404.083461) (xy 134.218342 -404.091223)
			(xy 134.270634 -404.106583) (xy 134.320208 -404.129228) (xy 134.366055 -404.158697) (xy 134.407242 -404.194391)
			(xy 134.44293 -404.235582) (xy 134.472394 -404.281432) (xy 134.495033 -404.331009) (xy 134.510387 -404.383303)
			(xy 134.518142 -404.437249) (xy 134.518142 -404.491749) (xy 135.955798 -404.491749) (xy 135.955798 -404.437251)
			(xy 135.963554 -404.383307) (xy 135.978908 -404.331016) (xy 136.001546 -404.281443) (xy 136.03101 -404.235596)
			(xy 136.066698 -404.194408) (xy 136.107884 -404.158718) (xy 136.15373 -404.129253) (xy 136.203303 -404.106612)
			(xy 136.255594 -404.091257) (xy 136.309537 -404.083499) (xy 136.336786 -404.083012) (xy 137.200386 -404.083012)
			(xy 137.227641 -404.083434) (xy 137.281596 -404.09119) (xy 137.333899 -404.106545) (xy 137.383483 -404.129188)
			(xy 137.429341 -404.158657) (xy 137.470537 -404.194353) (xy 137.506234 -404.235548) (xy 137.535705 -404.281405)
			(xy 137.55835 -404.330988) (xy 137.573707 -404.38329) (xy 137.581465 -404.437245) (xy 137.581465 -404.491753)
			(xy 139.018975 -404.491753) (xy 139.018975 -404.437247) (xy 139.026733 -404.383297) (xy 139.042089 -404.331)
			(xy 139.064732 -404.281421) (xy 139.094201 -404.235569) (xy 139.129896 -404.194377) (xy 139.171089 -404.158686)
			(xy 139.216943 -404.12922) (xy 139.266524 -404.10658) (xy 139.318822 -404.091227) (xy 139.372773 -404.083474)
			(xy 139.400026 -404.083012) (xy 140.263626 -404.083012) (xy 140.290877 -404.08346) (xy 140.344825 -404.09122)
			(xy 140.39712 -404.106578) (xy 140.446696 -404.129222) (xy 140.492546 -404.15869) (xy 140.533735 -404.194383)
			(xy 140.569426 -404.235575) (xy 140.598891 -404.281427) (xy 140.621531 -404.331005) (xy 140.636886 -404.3833)
			(xy 140.644642 -404.437249) (xy 140.644642 -404.491748) (xy 142.082298 -404.491748) (xy 142.082298 -404.437252)
			(xy 142.090053 -404.38331) (xy 142.105406 -404.331021) (xy 142.128043 -404.281448) (xy 142.157505 -404.235602)
			(xy 142.193191 -404.194415) (xy 142.234375 -404.158725) (xy 142.280218 -404.12926) (xy 142.329789 -404.106618)
			(xy 142.382077 -404.091261) (xy 142.436018 -404.083501) (xy 142.463266 -404.083012) (xy 143.326866 -404.083012)
			(xy 143.354122 -404.083433) (xy 143.408079 -404.091186) (xy 143.460384 -404.10654) (xy 143.509971 -404.129182)
			(xy 143.555831 -404.15865) (xy 143.59703 -404.194346) (xy 143.632729 -404.235542) (xy 143.662202 -404.281399)
			(xy 143.684848 -404.330984) (xy 143.700207 -404.383287) (xy 143.707965 -404.437244) (xy 143.707965 -404.491752)
			(xy 145.145475 -404.491752) (xy 145.145475 -404.437248) (xy 145.153232 -404.3833) (xy 145.168588 -404.331004)
			(xy 145.191229 -404.281426) (xy 145.220696 -404.235575) (xy 145.256389 -404.194384) (xy 145.29758 -404.158693)
			(xy 145.343431 -404.129226) (xy 145.39301 -404.106585) (xy 145.445306 -404.091231) (xy 145.499254 -404.083475)
			(xy 145.526506 -404.083012) (xy 146.390106 -404.083012) (xy 146.417358 -404.083458) (xy 146.471308 -404.091216)
			(xy 146.523605 -404.106572) (xy 146.573184 -404.129215) (xy 146.619036 -404.158683) (xy 146.660228 -404.194376)
			(xy 146.695921 -404.235569) (xy 146.725388 -404.281421) (xy 146.74803 -404.331001) (xy 146.763385 -404.383298)
			(xy 146.771142 -404.437248) (xy 146.771142 -404.491752) (xy 146.771142 -404.491754) (xy 148.208675 -404.491754)
			(xy 148.208675 -404.437246) (xy 148.216433 -404.383294) (xy 148.231791 -404.330996) (xy 148.254435 -404.281415)
			(xy 148.283906 -404.235562) (xy 148.319603 -404.19437) (xy 148.360799 -404.158679) (xy 148.406655 -404.129213)
			(xy 148.456239 -404.106575) (xy 148.508539 -404.091223) (xy 148.562492 -404.083472) (xy 148.589746 -404.083012)
			(xy 149.453346 -404.083012) (xy 149.480597 -404.083461) (xy 149.534542 -404.091223) (xy 149.586834 -404.106583)
			(xy 149.636408 -404.129228) (xy 149.682255 -404.158697) (xy 149.723442 -404.194391) (xy 149.75913 -404.235582)
			(xy 149.788594 -404.281432) (xy 149.811233 -404.331009) (xy 149.826587 -404.383303) (xy 149.834342 -404.437249)
			(xy 149.834342 -404.491749) (xy 151.271998 -404.491749) (xy 151.271998 -404.437251) (xy 151.279754 -404.383307)
			(xy 151.295108 -404.331016) (xy 151.317746 -404.281443) (xy 151.34721 -404.235596) (xy 151.382898 -404.194408)
			(xy 151.424084 -404.158718) (xy 151.46993 -404.129253) (xy 151.519503 -404.106612) (xy 151.571794 -404.091257)
			(xy 151.625737 -404.083499) (xy 151.652986 -404.083012) (xy 152.516586 -404.083012) (xy 152.543841 -404.083434)
			(xy 152.597796 -404.09119) (xy 152.650099 -404.106545) (xy 152.699683 -404.129188) (xy 152.745541 -404.158657)
			(xy 152.786737 -404.194353) (xy 152.822434 -404.235548) (xy 152.851905 -404.281405) (xy 152.87455 -404.330988)
			(xy 152.889907 -404.38329) (xy 152.897665 -404.437245) (xy 152.897665 -404.491753) (xy 154.335175 -404.491753)
			(xy 154.335175 -404.437247) (xy 154.342933 -404.383297) (xy 154.358289 -404.331) (xy 154.380932 -404.281421)
			(xy 154.410401 -404.235569) (xy 154.446096 -404.194377) (xy 154.487289 -404.158686) (xy 154.533143 -404.12922)
			(xy 154.582724 -404.10658) (xy 154.635022 -404.091227) (xy 154.688973 -404.083474) (xy 154.716226 -404.083012)
			(xy 155.579826 -404.083012) (xy 155.607077 -404.08346) (xy 155.661025 -404.09122) (xy 155.71332 -404.106578)
			(xy 155.762896 -404.129222) (xy 155.808746 -404.15869) (xy 155.849935 -404.194383) (xy 155.885626 -404.235575)
			(xy 155.915091 -404.281427) (xy 155.937731 -404.331005) (xy 155.953086 -404.3833) (xy 155.960842 -404.437249)
			(xy 155.960842 -404.491748) (xy 157.398498 -404.491748) (xy 157.398498 -404.437252) (xy 157.406253 -404.38331)
			(xy 157.421606 -404.331021) (xy 157.444243 -404.281448) (xy 157.473705 -404.235602) (xy 157.509391 -404.194415)
			(xy 157.550575 -404.158725) (xy 157.596418 -404.12926) (xy 157.645989 -404.106618) (xy 157.698277 -404.091261)
			(xy 157.752218 -404.083501) (xy 157.779466 -404.083012) (xy 158.643066 -404.083012) (xy 158.670322 -404.083433)
			(xy 158.724279 -404.091186) (xy 158.776584 -404.10654) (xy 158.826171 -404.129182) (xy 158.872031 -404.15865)
			(xy 158.91323 -404.194346) (xy 158.948929 -404.235542) (xy 158.978402 -404.281399) (xy 159.001048 -404.330984)
			(xy 159.016407 -404.383287) (xy 159.024165 -404.437244) (xy 159.024165 -404.491752) (xy 160.461675 -404.491752)
			(xy 160.461675 -404.437248) (xy 160.469432 -404.3833) (xy 160.484788 -404.331004) (xy 160.507429 -404.281426)
			(xy 160.536896 -404.235575) (xy 160.572589 -404.194384) (xy 160.61378 -404.158693) (xy 160.659631 -404.129226)
			(xy 160.70921 -404.106585) (xy 160.761506 -404.091231) (xy 160.815454 -404.083475) (xy 160.842706 -404.083012)
			(xy 161.706306 -404.083012) (xy 161.733558 -404.083458) (xy 161.787508 -404.091216) (xy 161.839805 -404.106572)
			(xy 161.889384 -404.129215) (xy 161.935236 -404.158683) (xy 161.976428 -404.194376) (xy 162.012121 -404.235569)
			(xy 162.041588 -404.281421) (xy 162.06423 -404.331001) (xy 162.079585 -404.383298) (xy 162.087342 -404.437248)
			(xy 162.087342 -404.491752) (xy 162.079585 -404.545702) (xy 162.06423 -404.597999) (xy 162.041588 -404.647579)
			(xy 162.012121 -404.693431) (xy 161.976428 -404.734624) (xy 161.935236 -404.770317) (xy 161.904774 -404.789894)
			(xy 166.998662 -404.789894) (xy 167.002634 -404.611651) (xy 167.014542 -404.433762) (xy 167.034363 -404.25658)
			(xy 167.062057 -404.080456) (xy 167.097569 -403.905741) (xy 167.140829 -403.732782) (xy 167.191751 -403.561921)
			(xy 167.250234 -403.393499) (xy 167.316161 -403.227849) (xy 167.389402 -403.0653) (xy 167.469812 -402.906175)
			(xy 167.55723 -402.75079) (xy 167.651483 -402.599454) (xy 167.752384 -402.452466) (xy 167.859733 -402.310119)
			(xy 167.973316 -402.172696) (xy 168.092909 -402.040469) (xy 168.218273 -401.9137) (xy 168.34916 -401.792642)
			(xy 168.485309 -401.677535) (xy 168.626451 -401.568607) (xy 168.772306 -401.466075) (xy 168.922583 -401.370141)
			(xy 169.076984 -401.280998) (xy 169.235203 -401.198821) (xy 169.396926 -401.123773) (xy 169.561831 -401.056005)
			(xy 169.729592 -400.995649) (xy 169.899875 -400.942827) (xy 170.072342 -400.897643) (xy 170.24665 -400.860186)
			(xy 170.422454 -400.830532) (xy 170.599404 -400.808739) (xy 170.77715 -400.794849) (xy 170.955337 -400.788892)
			(xy 171.133614 -400.790878) (xy 171.311625 -400.800804) (xy 171.489017 -400.81865) (xy 171.665437 -400.84438)
			(xy 171.840537 -400.877944) (xy 172.013968 -400.919274) (xy 172.185385 -400.96829) (xy 172.354448 -401.024892)
			(xy 172.520823 -401.08897) (xy 172.684177 -401.160396) (xy 172.844188 -401.239028) (xy 173.000537 -401.324709)
			(xy 173.152914 -401.417271) (xy 173.301017 -401.516528) (xy 173.444551 -401.622285) (xy 173.583231 -401.73433)
			(xy 173.716782 -401.852442) (xy 173.844939 -401.976386) (xy 173.967448 -402.105916) (xy 174.084065 -402.240775)
			(xy 174.194558 -402.380695) (xy 174.298709 -402.525398) (xy 174.396311 -402.674597) (xy 174.487169 -402.827996)
			(xy 174.571103 -402.98529) (xy 174.647948 -403.146166) (xy 174.680622 -403.223222) (xy 183.966612 -403.223222)
			(xy 183.966612 -403.222714) (xy 183.967041 -403.181385) (xy 183.974705 -403.099084) (xy 183.989967 -403.017847)
			(xy 184.012697 -402.938376) (xy 184.042698 -402.861355) (xy 184.079712 -402.787448) (xy 184.12342 -402.717292)
			(xy 184.173445 -402.651491) (xy 184.201054 -402.620734) (xy 184.207126 -402.613482) (xy 184.214027 -402.59589)
			(xy 184.214516 -402.586444) (xy 184.214516 -402.555964) (xy 184.214137 -402.546498) (xy 184.207208 -402.528878)
			(xy 184.201054 -402.521674) (xy 184.173435 -402.490923) (xy 184.123404 -402.425124) (xy 184.07969 -402.354969)
			(xy 184.042671 -402.281062) (xy 184.012666 -402.20404) (xy 183.989932 -402.124568) (xy 183.974667 -402.043329)
			(xy 183.967002 -401.961026) (xy 183.967002 -401.878366) (xy 183.974668 -401.796062) (xy 183.989934 -401.714824)
			(xy 184.012668 -401.635352) (xy 184.042675 -401.55833) (xy 184.079695 -401.484423) (xy 184.123409 -401.414268)
			(xy 184.173441 -401.34847) (xy 184.201054 -401.317714) (xy 184.207134 -401.310468) (xy 184.214031 -401.292871)
			(xy 184.214516 -401.283424) (xy 184.214516 -401.252944) (xy 184.214097 -401.243482) (xy 184.207196 -401.225862)
			(xy 184.201054 -401.218654) (xy 184.173435 -401.187907) (xy 184.12342 -401.1221) (xy 184.079722 -401.05194)
			(xy 184.042717 -400.97803) (xy 184.012723 -400.901008) (xy 183.989999 -400.821537) (xy 183.974741 -400.740302)
			(xy 183.967081 -400.658002) (xy 183.966612 -400.616674) (xy 183.967088 -400.575568) (xy 183.974674 -400.493705)
			(xy 183.98978 -400.412892) (xy 184.012276 -400.333817) (xy 184.041971 -400.257154) (xy 184.078611 -400.183558)
			(xy 184.121884 -400.113655) (xy 184.171421 -400.048042) (xy 184.226799 -399.987279) (xy 184.287547 -399.931883)
			(xy 184.353145 -399.882327) (xy 184.423036 -399.839034) (xy 184.496622 -399.802373) (xy 184.573276 -399.772657)
			(xy 184.652345 -399.750138) (xy 184.733154 -399.735009) (xy 184.815014 -399.727399) (xy 184.85612 -399.726912)
			(xy 184.900625 -399.727439) (xy 184.989189 -399.736331) (xy 185.076422 -399.754024) (xy 185.161452 -399.780341)
			(xy 185.243428 -399.815019) (xy 185.321531 -399.857711) (xy 185.394979 -399.90799) (xy 185.463038 -399.965354)
			(xy 185.494422 -399.996914) (xy 185.501871 -400.003965) (xy 185.52075 -400.011949) (xy 185.530998 -400.012408)
			(xy 185.603642 -400.012408) (xy 185.613891 -400.011949) (xy 185.632766 -400.003963) (xy 185.640218 -399.996914)
			(xy 185.671594 -399.965346) (xy 185.739655 -399.907985) (xy 185.813105 -399.857708) (xy 185.891209 -399.815019)
			(xy 185.973186 -399.780344) (xy 186.058217 -399.75403) (xy 186.145451 -399.736341) (xy 186.234015 -399.727453)
			(xy 186.27852 -399.726912) (xy 186.32201 -399.727445) (xy 186.408572 -399.735955) (xy 186.493892 -399.752871)
			(xy 186.577152 -399.778033) (xy 186.65756 -399.811201) (xy 186.734348 -399.852056) (xy 186.806782 -399.900211)
			(xy 186.874171 -399.955204) (xy 186.905392 -399.985484) (xy 186.905646 -399.985738) (xy 186.913054 -399.992282)
			(xy 186.931335 -399.999743) (xy 186.941206 -400.000216) (xy 187.012834 -400.000216) (xy 187.022717 -399.999799)
			(xy 187.041016 -399.992329) (xy 187.048394 -399.985738) (xy 187.048648 -399.985484) (xy 187.079882 -399.955217)
			(xy 187.14727 -399.900227) (xy 187.219703 -399.852074) (xy 187.296489 -399.811218) (xy 187.376895 -399.77805)
			(xy 187.460154 -399.752886) (xy 187.54547 -399.735966) (xy 187.632031 -399.727452) (xy 187.67552 -399.726912)
			(xy 187.716616 -399.727347) (xy 187.798457 -399.734931) (xy 187.87925 -399.750033) (xy 187.958305 -399.772524)
			(xy 188.034948 -399.802212) (xy 188.108525 -399.838843) (xy 188.178409 -399.882106) (xy 188.244005 -399.931632)
			(xy 188.304751 -399.986997) (xy 188.360132 -400.047731) (xy 188.409673 -400.113314) (xy 188.452953 -400.183188)
			(xy 188.489602 -400.256756) (xy 188.519308 -400.333392) (xy 188.541818 -400.412442) (xy 188.556939 -400.493231)
			(xy 188.564543 -400.57507) (xy 188.565028 -400.616166) (xy 188.565028 -400.616674) (xy 188.564581 -400.658002)
			(xy 188.556919 -400.740303) (xy 188.541658 -400.821539) (xy 188.518931 -400.901009) (xy 188.488932 -400.97803)
			(xy 188.451921 -401.051937) (xy 188.408216 -401.122094) (xy 188.358194 -401.187896) (xy 188.330586 -401.218654)
			(xy 188.324524 -401.225913) (xy 188.317616 -401.2435) (xy 188.317124 -401.252944) (xy 188.317124 -401.283424)
			(xy 188.3175 -401.292891) (xy 188.32443 -401.310511) (xy 188.330586 -401.317714) (xy 188.358194 -401.348474)
			(xy 188.408229 -401.414271) (xy 188.451946 -401.484425) (xy 188.488968 -401.558331) (xy 188.518976 -401.635351)
			(xy 188.541712 -401.714823) (xy 188.556979 -401.796062) (xy 188.564645 -401.878365) (xy 188.564646 -401.961026)
			(xy 188.55698 -402.04333) (xy 188.541714 -402.124568) (xy 188.518979 -402.20404) (xy 188.488972 -402.281061)
			(xy 188.45195 -402.354968) (xy 188.408234 -402.425122) (xy 188.3582 -402.490919) (xy 188.330586 -402.521674)
			(xy 188.324516 -402.528927) (xy 188.317612 -402.546518) (xy 188.317124 -402.555964) (xy 188.317124 -402.586444)
			(xy 188.31749 -402.595912) (xy 188.324426 -402.613532) (xy 188.330586 -402.620734) (xy 188.358206 -402.65148)
			(xy 188.40822 -402.717288) (xy 188.451917 -402.787448) (xy 188.488922 -402.861358) (xy 188.518915 -402.93838)
			(xy 188.541639 -403.017851) (xy 188.556897 -403.099086) (xy 188.564559 -403.181386) (xy 188.565028 -403.222714)
			(xy 188.56457 -403.265938) (xy 188.556182 -403.351979) (xy 188.539486 -403.436801) (xy 188.514639 -403.519602)
			(xy 188.481877 -403.599602) (xy 188.441508 -403.676046) (xy 188.393913 -403.748214) (xy 188.339541 -403.815423)
			(xy 188.278905 -403.87704) (xy 188.212577 -403.932484) (xy 188.17717 -403.957282) (xy 188.169401 -403.962991)
			(xy 188.158572 -403.978928) (xy 188.15443 -403.997746) (xy 188.15558 -404.00732) (xy 188.172598 -404.112984)
			(xy 188.191902 -404.134828) (xy 188.20638 -404.138892) (xy 188.235359 -404.147534) (xy 188.292177 -404.168255)
			(xy 188.319918 -404.180294) (xy 188.32986 -404.1841) (xy 188.351124 -404.1841) (xy 188.361066 -404.180294)
			(xy 188.403727 -404.162032) (xy 188.492015 -404.133439) (xy 188.582798 -404.114182) (xy 188.675091 -404.104469)
			(xy 188.721492 -404.10384) (xy 188.767894 -404.104473) (xy 188.860191 -404.114162) (xy 188.950976 -404.133414)
			(xy 189.039262 -404.162019) (xy 189.081918 -404.180294) (xy 189.09186 -404.1841) (xy 189.113124 -404.1841)
			(xy 189.123066 -404.180294) (xy 189.165727 -404.162032) (xy 189.254015 -404.133439) (xy 189.344798 -404.114182)
			(xy 189.437091 -404.104469) (xy 189.483492 -404.10384) (xy 189.524604 -404.10426) (xy 189.606477 -404.111848)
			(xy 189.6873 -404.126959) (xy 189.766384 -404.149465) (xy 189.843053 -404.179173) (xy 189.916654 -404.21583)
			(xy 189.986557 -404.259123) (xy 190.052166 -404.308683) (xy 190.112922 -404.364086) (xy 190.168305 -404.42486)
			(xy 190.217843 -404.490486) (xy 190.261113 -404.560403) (xy 190.297746 -404.634016) (xy 190.327429 -404.710695)
			(xy 190.349908 -404.789786) (xy 190.364993 -404.870614) (xy 190.372553 -404.95249) (xy 190.373 -404.993602)
			(xy 190.372419 -405.039998) (xy 190.362773 -405.132286) (xy 190.343577 -405.22307) (xy 190.315038 -405.311363)
			(xy 190.2968 -405.354028) (xy 190.292994 -405.36397) (xy 190.292995 -405.385234) (xy 190.2968 -405.395176)
			(xy 190.315045 -405.437838) (xy 190.343589 -405.52613) (xy 190.362782 -405.616916) (xy 190.372415 -405.709206)
			(xy 190.373 -405.755602) (xy 190.372419 -405.801998) (xy 190.362773 -405.894286) (xy 190.343577 -405.98507)
			(xy 190.315038 -406.073363) (xy 190.2968 -406.116028) (xy 190.292994 -406.12597) (xy 190.292995 -406.147234)
			(xy 190.2968 -406.157176) (xy 190.315045 -406.199838) (xy 190.343589 -406.28813) (xy 190.362782 -406.378916)
			(xy 190.372415 -406.471206) (xy 190.373 -406.517602) (xy 190.37258 -406.55737) (xy 190.365551 -406.636594)
			(xy 190.351469 -406.714872) (xy 190.330446 -406.791578) (xy 190.302651 -406.866098) (xy 190.285878 -406.902158)
			(xy 190.281544 -406.912659) (xy 190.281545 -406.935345) (xy 190.285878 -406.945846) (xy 190.302637 -406.981911)
			(xy 190.330411 -407.056437) (xy 190.351429 -407.133142) (xy 190.365522 -407.211416) (xy 190.372579 -407.290635)
			(xy 190.373 -407.330402) (xy 190.372419 -407.376798) (xy 190.362773 -407.469086) (xy 190.343577 -407.55987)
			(xy 190.315038 -407.648163) (xy 190.2968 -407.690828) (xy 190.292994 -407.70077) (xy 190.292995 -407.722034)
			(xy 190.2968 -407.731976) (xy 190.315022 -407.774579) (xy 190.34354 -407.862746) (xy 190.362733 -407.953402)
			(xy 190.372392 -408.045562) (xy 190.372573 -408.059382) (xy 196.354192 -408.059382) (xy 196.354769 -408.012986)
			(xy 196.364415 -407.920698) (xy 196.383613 -407.829914) (xy 196.412153 -407.741621) (xy 196.430392 -407.698956)
			(xy 196.434208 -407.689017) (xy 196.434201 -407.66775) (xy 196.430392 -407.657808) (xy 196.412141 -407.615148)
			(xy 196.383599 -407.526855) (xy 196.364407 -407.436069) (xy 196.354776 -407.343778) (xy 196.354192 -407.297382)
			(xy 196.354769 -407.250986) (xy 196.364415 -407.158698) (xy 196.383613 -407.067914) (xy 196.412153 -406.979621)
			(xy 196.430392 -406.936956) (xy 196.434208 -406.927017) (xy 196.434201 -406.90575) (xy 196.430392 -406.895808)
			(xy 196.412141 -406.853148) (xy 196.383599 -406.764855) (xy 196.364407 -406.674069) (xy 196.354776 -406.581778)
			(xy 196.354192 -406.535382) (xy 196.354769 -406.488986) (xy 196.364415 -406.396698) (xy 196.383613 -406.305914)
			(xy 196.412153 -406.217621) (xy 196.430392 -406.174956) (xy 196.434208 -406.165017) (xy 196.434201 -406.14375)
			(xy 196.430392 -406.133808) (xy 196.412141 -406.091148) (xy 196.383599 -406.002855) (xy 196.364407 -405.912069)
			(xy 196.354776 -405.819778) (xy 196.354192 -405.773382) (xy 196.354769 -405.726986) (xy 196.364415 -405.634698)
			(xy 196.383613 -405.543914) (xy 196.412153 -405.455621) (xy 196.430392 -405.412956) (xy 196.434208 -405.403017)
			(xy 196.434201 -405.38175) (xy 196.430392 -405.371808) (xy 196.412164 -405.329208) (xy 196.383648 -405.241039)
			(xy 196.364457 -405.150383) (xy 196.354799 -405.058222) (xy 196.354192 -405.01189) (xy 196.354192 -405.011382)
			(xy 196.354695 -404.970276) (xy 196.362281 -404.888416) (xy 196.377385 -404.807604) (xy 196.39988 -404.72853)
			(xy 196.429573 -404.651868) (xy 196.466212 -404.578272) (xy 196.509483 -404.50837) (xy 196.559018 -404.442758)
			(xy 196.614395 -404.381994) (xy 196.67514 -404.326599) (xy 196.740737 -404.277043) (xy 196.810626 -404.233749)
			(xy 196.88421 -404.197087) (xy 196.960862 -404.16737) (xy 197.039929 -404.14485) (xy 197.120736 -404.12972)
			(xy 197.202594 -404.122108) (xy 197.2437 -404.12162) (xy 197.290102 -404.122252) (xy 197.382399 -404.131941)
			(xy 197.473184 -404.151193) (xy 197.56147 -404.179799) (xy 197.604126 -404.198074) (xy 197.614068 -404.20188)
			(xy 197.635332 -404.20188) (xy 197.645274 -404.198074) (xy 197.673976 -404.185882) (xy 197.682795 -404.181969)
			(xy 197.696833 -404.168752) (xy 197.704997 -404.151285) (xy 197.70598 -404.141686) (xy 197.711314 -404.049992)
			(xy 197.711428 -404.040421) (xy 197.705477 -404.022248) (xy 197.693313 -404.007492) (xy 197.685152 -404.002494)
			(xy 197.647554 -403.981253) (xy 197.576288 -403.932477) (xy 197.510083 -403.877025) (xy 197.449561 -403.81542)
			(xy 197.395292 -403.748241) (xy 197.347788 -403.67612) (xy 197.307493 -403.599737) (xy 197.274789 -403.519809)
			(xy 197.249982 -403.437088) (xy 197.233306 -403.352354) (xy 197.224918 -403.266402) (xy 197.224396 -403.223222)
			(xy 197.224864 -403.181887) (xy 197.232535 -403.099572) (xy 197.247812 -403.018325) (xy 197.270564 -402.938847)
			(xy 197.300593 -402.861823) (xy 197.337642 -402.787918) (xy 197.38139 -402.717771) (xy 197.431459 -402.651987)
			(xy 197.459092 -402.621242) (xy 197.465153 -402.613982) (xy 197.472063 -402.596396) (xy 197.472554 -402.586952)
			(xy 197.472554 -402.556472) (xy 197.472185 -402.547004) (xy 197.465251 -402.529384) (xy 197.459092 -402.522182)
			(xy 197.431443 -402.491454) (xy 197.3814 -402.425653) (xy 197.337673 -402.355495) (xy 197.300638 -402.281587)
			(xy 197.270614 -402.204563) (xy 197.24786 -402.125088) (xy 197.232571 -402.043846) (xy 197.22488 -401.961536)
			(xy 197.224396 -401.920202) (xy 197.224852 -401.878866) (xy 197.232524 -401.796552) (xy 197.247803 -401.715304)
			(xy 197.270556 -401.635826) (xy 197.300588 -401.558802) (xy 197.337638 -401.484897) (xy 197.381388 -401.414751)
			(xy 197.431459 -401.348967) (xy 197.459092 -401.318222) (xy 197.465161 -401.310968) (xy 197.472066 -401.293378)
			(xy 197.472554 -401.283932) (xy 197.472554 -401.253452) (xy 197.472146 -401.243989) (xy 197.465239 -401.226367)
			(xy 197.459092 -401.219162) (xy 197.431482 -401.1884) (xy 197.381436 -401.122604) (xy 197.337705 -401.052453)
			(xy 197.300666 -400.978549) (xy 197.270637 -400.90153) (xy 197.247877 -400.82206) (xy 197.232582 -400.740821)
			(xy 197.224883 -400.658515) (xy 197.224396 -400.617182) (xy 197.224896 -400.576069) (xy 197.232484 -400.494193)
			(xy 197.247594 -400.413367) (xy 197.270097 -400.334279) (xy 197.299801 -400.257605) (xy 197.336453 -400.183999)
			(xy 197.379739 -400.114089) (xy 197.429291 -400.04847) (xy 197.484686 -399.987703) (xy 197.545451 -399.932307)
			(xy 197.611069 -399.882753) (xy 197.680978 -399.839464) (xy 197.754583 -399.802811) (xy 197.831256 -399.773105)
			(xy 197.910343 -399.7506) (xy 197.991169 -399.735487) (xy 198.073045 -399.727897) (xy 198.114158 -399.72742)
			(xy 198.158662 -399.727949) (xy 198.247226 -399.736844) (xy 198.334458 -399.754538) (xy 198.419487 -399.780856)
			(xy 198.501463 -399.815534) (xy 198.579565 -399.858225) (xy 198.653014 -399.908502) (xy 198.721075 -399.965864)
			(xy 198.75246 -399.997422) (xy 198.759931 -400.004447) (xy 198.778793 -400.012446) (xy 198.789036 -400.012916)
			(xy 198.86168 -400.012916) (xy 198.871931 -400.012475) (xy 198.890805 -400.004477) (xy 198.898256 -399.997422)
			(xy 198.929663 -399.965886) (xy 198.997719 -399.908523) (xy 199.071164 -399.858243) (xy 199.149263 -399.81555)
			(xy 199.231236 -399.780871) (xy 199.316263 -399.754552) (xy 199.403493 -399.736858) (xy 199.492055 -399.727964)
			(xy 199.536558 -399.72742) (xy 199.580049 -399.727926) (xy 199.666612 -399.736439) (xy 199.751932 -399.75336)
			(xy 199.835193 -399.778526) (xy 199.915601 -399.811696) (xy 199.992388 -399.852556) (xy 200.064821 -399.900714)
			(xy 200.132209 -399.95571) (xy 200.16343 -399.985992) (xy 200.163684 -399.986246) (xy 200.171078 -399.992808)
			(xy 200.189369 -400.000258) (xy 200.199244 -400.000724) (xy 200.270872 -400.000724) (xy 200.280751 -400.000273)
			(xy 200.29905 -399.992827) (xy 200.306432 -399.986246) (xy 200.306686 -399.985992) (xy 200.337904 -399.955708)
			(xy 200.405295 -399.900719) (xy 200.47773 -399.852567) (xy 200.554518 -399.811713) (xy 200.634927 -399.778547)
			(xy 200.718187 -399.753386) (xy 200.803506 -399.736469) (xy 200.890068 -399.727958) (xy 200.933558 -399.72742)
			(xy 200.974672 -399.727938) (xy 201.056549 -399.735522) (xy 201.137376 -399.750627) (xy 201.216466 -399.773127)
			(xy 201.293142 -399.802827) (xy 201.36675 -399.839476) (xy 201.436663 -399.882761) (xy 201.502283 -399.932312)
			(xy 201.563052 -399.987706) (xy 201.61845 -400.04847) (xy 201.668005 -400.114088) (xy 201.711294 -400.183998)
			(xy 201.747948 -400.257603) (xy 201.777654 -400.334277) (xy 201.800159 -400.413365) (xy 201.81527 -400.494192)
			(xy 201.822859 -400.576068) (xy 201.82332 -400.617182) (xy 201.82285 -400.658517) (xy 201.815179 -400.740831)
			(xy 201.799902 -400.822078) (xy 201.777151 -400.901557) (xy 201.747121 -400.978581) (xy 201.710073 -401.052485)
			(xy 201.666325 -401.122632) (xy 201.616256 -401.188416) (xy 201.588624 -401.219162) (xy 201.582551 -401.226413)
			(xy 201.575651 -401.244006) (xy 201.575162 -401.253452) (xy 201.575162 -401.283932) (xy 201.575549 -401.293397)
			(xy 201.582473 -401.311017) (xy 201.588624 -401.318222) (xy 201.61626 -401.348962) (xy 201.666306 -401.41476)
			(xy 201.710036 -401.484914) (xy 201.747073 -401.558821) (xy 201.777099 -401.635843) (xy 201.799855 -401.715317)
			(xy 201.815145 -401.796559) (xy 201.822837 -401.878868) (xy 201.82332 -401.920202) (xy 201.822863 -401.961538)
			(xy 201.81519 -402.043852) (xy 201.799911 -402.125099) (xy 201.777158 -402.204578) (xy 201.747126 -402.281602)
			(xy 201.710076 -402.355506) (xy 201.666327 -402.425653) (xy 201.616257 -402.491437) (xy 201.588624 -402.522182)
			(xy 201.582543 -402.529427) (xy 201.575647 -402.547025) (xy 201.575162 -402.556472) (xy 201.575162 -402.586952)
			(xy 201.575589 -402.596413) (xy 201.582485 -402.614033) (xy 201.588624 -402.621242) (xy 201.616222 -402.652015)
			(xy 201.66627 -402.717808) (xy 201.710004 -402.787957) (xy 201.747046 -402.861859) (xy 201.777077 -402.938876)
			(xy 201.799838 -403.018346) (xy 201.815134 -403.099584) (xy 201.822833 -403.18189) (xy 201.82332 -403.223222)
			(xy 201.822801 -403.266183) (xy 201.814523 -403.351705) (xy 201.798036 -403.43603) (xy 201.773494 -403.518372)
			(xy 201.741125 -403.597963) (xy 201.701232 -403.674062) (xy 201.654186 -403.745959) (xy 201.600426 -403.812984)
			(xy 201.540453 -403.874513) (xy 201.474826 -403.929971) (xy 201.404156 -403.978842) (xy 201.366882 -404.000208)
			(xy 201.35873 -404.005265) (xy 201.346612 -404.020117) (xy 201.34076 -404.03837) (xy 201.340974 -404.04796)
			(xy 201.348086 -404.154386) (xy 201.365358 -404.178008) (xy 201.379328 -404.183342) (xy 201.417266 -404.198729)
			(xy 201.490382 -404.235572) (xy 201.559803 -404.27898) (xy 201.62494 -404.328584) (xy 201.685242 -404.383965)
			(xy 201.740199 -404.444654) (xy 201.789346 -404.510137) (xy 201.832266 -404.57986) (xy 201.868597 -404.653232)
			(xy 201.89803 -404.729633) (xy 201.920317 -404.808416) (xy 201.935269 -404.888913) (xy 201.942758 -404.970445)
			(xy 201.943208 -405.011382) (xy 201.942619 -405.057777) (xy 201.932976 -405.150066) (xy 201.913781 -405.240849)
			(xy 201.885245 -405.329143) (xy 201.867008 -405.371808) (xy 201.863213 -405.381753) (xy 201.863206 -405.403014)
			(xy 201.867008 -405.412956) (xy 201.885247 -405.455621) (xy 201.913792 -405.543912) (xy 201.932987 -405.634696)
			(xy 201.942622 -405.726986) (xy 201.943208 -405.773382) (xy 201.942619 -405.819777) (xy 201.932976 -405.912066)
			(xy 201.913781 -406.002849) (xy 201.885245 -406.091143) (xy 201.867008 -406.133808) (xy 201.863213 -406.143753)
			(xy 201.863206 -406.165014) (xy 201.867008 -406.174956) (xy 201.885247 -406.217621) (xy 201.913792 -406.305912)
			(xy 201.932987 -406.396696) (xy 201.942622 -406.488986) (xy 201.943208 -406.535382) (xy 201.942619 -406.581777)
			(xy 201.932976 -406.674066) (xy 201.913781 -406.764849) (xy 201.885245 -406.853143) (xy 201.867008 -406.895808)
			(xy 201.863213 -406.905753) (xy 201.863206 -406.927014) (xy 201.867008 -406.936956) (xy 201.885247 -406.979621)
			(xy 201.913792 -407.067912) (xy 201.932987 -407.158696) (xy 201.942622 -407.250986) (xy 201.943208 -407.297382)
			(xy 201.942619 -407.343777) (xy 201.932976 -407.436066) (xy 201.913781 -407.526849) (xy 201.885245 -407.615143)
			(xy 201.867008 -407.657808) (xy 201.863213 -407.667753) (xy 201.863206 -407.689014) (xy 201.867008 -407.698956)
			(xy 201.885224 -407.741561) (xy 201.913743 -407.829728) (xy 201.932938 -407.920383) (xy 201.942599 -408.012542)
			(xy 201.943208 -408.058874) (xy 201.943208 -408.059382) (xy 201.943201 -408.05989) (xy 206.260192 -408.05989)
			(xy 206.260192 -408.059382) (xy 206.260717 -408.017997) (xy 206.268406 -407.935585) (xy 206.283716 -407.854244)
			(xy 206.306513 -407.774675) (xy 206.336602 -407.697568) (xy 206.373723 -407.623589) (xy 206.417553 -407.553377)
			(xy 206.467715 -407.487539) (xy 206.523774 -407.426645) (xy 206.585247 -407.37122) (xy 206.651602 -407.321743)
			(xy 206.722265 -407.278644) (xy 206.796625 -407.242293) (xy 206.87404 -407.213005) (xy 206.953841 -407.191034)
			(xy 206.994506 -407.183336) (xy 207.004634 -407.181051) (xy 207.021956 -407.169641) (xy 207.033359 -407.152314)
			(xy 207.035654 -407.142188) (xy 207.043393 -407.101149) (xy 207.065607 -407.020638) (xy 207.095268 -406.942562)
			(xy 207.132115 -406.86761) (xy 207.175825 -406.796441) (xy 207.226012 -406.729682) (xy 207.282235 -406.66792)
			(xy 207.343998 -406.611699) (xy 207.410759 -406.561513) (xy 207.481929 -406.517805) (xy 207.556881 -406.48096)
			(xy 207.634957 -406.4513) (xy 207.715469 -406.429089) (xy 207.756506 -406.421336) (xy 207.766634 -406.419051)
			(xy 207.783956 -406.407641) (xy 207.795359 -406.390314) (xy 207.797654 -406.380188) (xy 207.804281 -406.344944)
			(xy 207.822478 -406.275571) (xy 207.846186 -406.207884) (xy 207.860392 -406.174956) (xy 207.864208 -406.165017)
			(xy 207.864201 -406.14375) (xy 207.860392 -406.133808) (xy 207.842141 -406.091148) (xy 207.813599 -406.002855)
			(xy 207.794407 -405.912069) (xy 207.784776 -405.819778) (xy 207.784192 -405.773382) (xy 207.784769 -405.726986)
			(xy 207.794415 -405.634698) (xy 207.813613 -405.543914) (xy 207.842153 -405.455621) (xy 207.860392 -405.412956)
			(xy 207.864208 -405.403017) (xy 207.864201 -405.38175) (xy 207.860392 -405.371808) (xy 207.842164 -405.329208)
			(xy 207.813648 -405.241039) (xy 207.794457 -405.150383) (xy 207.784799 -405.058222) (xy 207.784192 -405.01189)
			(xy 207.784192 -405.011382) (xy 207.784669 -404.970705) (xy 207.792097 -404.889692) (xy 207.80689 -404.809694)
			(xy 207.828923 -404.731381) (xy 207.858013 -404.655407) (xy 207.893918 -404.582405) (xy 207.936336 -404.512985)
			(xy 207.984914 -404.447728) (xy 208.039247 -404.387177) (xy 208.09888 -404.33184) (xy 208.163316 -404.282176)
			(xy 208.232016 -404.238603) (xy 208.304407 -404.201482) (xy 208.341976 -404.185882) (xy 208.350795 -404.181969)
			(xy 208.364833 -404.168752) (xy 208.372997 -404.151285) (xy 208.37398 -404.141686) (xy 208.379314 -404.049992)
			(xy 208.379428 -404.040421) (xy 208.373477 -404.022248) (xy 208.361313 -404.007492) (xy 208.353152 -404.002494)
			(xy 208.315554 -403.981253) (xy 208.244288 -403.932477) (xy 208.178083 -403.877025) (xy 208.117561 -403.81542)
			(xy 208.063292 -403.748241) (xy 208.015788 -403.67612) (xy 207.975493 -403.599737) (xy 207.942789 -403.519809)
			(xy 207.917982 -403.437088) (xy 207.901306 -403.352354) (xy 207.892918 -403.266402) (xy 207.892396 -403.223222)
			(xy 207.892864 -403.181887) (xy 207.900535 -403.099572) (xy 207.915812 -403.018325) (xy 207.938564 -402.938847)
			(xy 207.968593 -402.861823) (xy 208.005642 -402.787918) (xy 208.04939 -402.717771) (xy 208.099459 -402.651987)
			(xy 208.127092 -402.621242) (xy 208.133153 -402.613982) (xy 208.140063 -402.596396) (xy 208.140554 -402.586952)
			(xy 208.140554 -402.556472) (xy 208.140185 -402.547004) (xy 208.133251 -402.529384) (xy 208.127092 -402.522182)
			(xy 208.099443 -402.491454) (xy 208.0494 -402.425653) (xy 208.005673 -402.355495) (xy 207.968638 -402.281587)
			(xy 207.938614 -402.204563) (xy 207.91586 -402.125088) (xy 207.900571 -402.043846) (xy 207.89288 -401.961536)
			(xy 207.892396 -401.920202) (xy 207.892852 -401.878866) (xy 207.900524 -401.796552) (xy 207.915803 -401.715304)
			(xy 207.938556 -401.635826) (xy 207.968588 -401.558802) (xy 208.005638 -401.484897) (xy 208.049388 -401.414751)
			(xy 208.099459 -401.348967) (xy 208.127092 -401.318222) (xy 208.133161 -401.310968) (xy 208.140066 -401.293378)
			(xy 208.140554 -401.283932) (xy 208.140554 -401.253452) (xy 208.140146 -401.243989) (xy 208.133239 -401.226367)
			(xy 208.127092 -401.219162) (xy 208.099482 -401.1884) (xy 208.049436 -401.122604) (xy 208.005705 -401.052453)
			(xy 207.968666 -400.978549) (xy 207.938637 -400.90153) (xy 207.915877 -400.82206) (xy 207.900582 -400.740821)
			(xy 207.892883 -400.658515) (xy 207.892396 -400.617182) (xy 207.892896 -400.576069) (xy 207.900484 -400.494193)
			(xy 207.915594 -400.413367) (xy 207.938097 -400.334279) (xy 207.967801 -400.257605) (xy 208.004453 -400.183999)
			(xy 208.047739 -400.114089) (xy 208.097291 -400.04847) (xy 208.152686 -399.987703) (xy 208.213451 -399.932307)
			(xy 208.279069 -399.882753) (xy 208.348978 -399.839464) (xy 208.422583 -399.802811) (xy 208.499256 -399.773105)
			(xy 208.578343 -399.7506) (xy 208.659169 -399.735487) (xy 208.741045 -399.727897) (xy 208.782158 -399.72742)
			(xy 208.826662 -399.727949) (xy 208.915226 -399.736844) (xy 209.002458 -399.754538) (xy 209.087487 -399.780856)
			(xy 209.169463 -399.815534) (xy 209.247565 -399.858225) (xy 209.321014 -399.908502) (xy 209.389075 -399.965864)
			(xy 209.42046 -399.997422) (xy 209.427931 -400.004447) (xy 209.446793 -400.012446) (xy 209.457036 -400.012916)
			(xy 209.52968 -400.012916) (xy 209.539931 -400.012475) (xy 209.558805 -400.004477) (xy 209.566256 -399.997422)
			(xy 209.597663 -399.965886) (xy 209.665719 -399.908523) (xy 209.739164 -399.858243) (xy 209.817263 -399.81555)
			(xy 209.899236 -399.780871) (xy 209.984263 -399.754552) (xy 210.071493 -399.736858) (xy 210.160055 -399.727964)
			(xy 210.204558 -399.72742) (xy 210.248049 -399.727926) (xy 210.334612 -399.736439) (xy 210.419932 -399.75336)
			(xy 210.503193 -399.778526) (xy 210.583601 -399.811696) (xy 210.660388 -399.852556) (xy 210.732821 -399.900714)
			(xy 210.800209 -399.95571) (xy 210.83143 -399.985992) (xy 210.831684 -399.986246) (xy 210.839078 -399.992808)
			(xy 210.857369 -400.000258) (xy 210.867244 -400.000724) (xy 210.938872 -400.000724) (xy 210.948751 -400.000273)
			(xy 210.96705 -399.992827) (xy 210.974432 -399.986246) (xy 210.974686 -399.985992) (xy 211.005904 -399.955708)
			(xy 211.073295 -399.900719) (xy 211.14573 -399.852567) (xy 211.222518 -399.811713) (xy 211.302927 -399.778547)
			(xy 211.386187 -399.753386) (xy 211.471506 -399.736469) (xy 211.558068 -399.727958) (xy 211.601558 -399.72742)
			(xy 211.642672 -399.727938) (xy 211.724549 -399.735522) (xy 211.805376 -399.750627) (xy 211.884466 -399.773127)
			(xy 211.961142 -399.802827) (xy 212.03475 -399.839476) (xy 212.104663 -399.882761) (xy 212.170283 -399.932312)
			(xy 212.231052 -399.987706) (xy 212.28645 -400.04847) (xy 212.336005 -400.114088) (xy 212.379294 -400.183998)
			(xy 212.415948 -400.257603) (xy 212.445654 -400.334277) (xy 212.468159 -400.413365) (xy 212.48327 -400.494192)
			(xy 212.490859 -400.576068) (xy 212.49132 -400.617182) (xy 212.49085 -400.658517) (xy 212.483179 -400.740831)
			(xy 212.467902 -400.822078) (xy 212.445151 -400.901557) (xy 212.415121 -400.978581) (xy 212.378073 -401.052485)
			(xy 212.334325 -401.122632) (xy 212.284256 -401.188416) (xy 212.256624 -401.219162) (xy 212.250551 -401.226413)
			(xy 212.243651 -401.244006) (xy 212.243162 -401.253452) (xy 212.243162 -401.283932) (xy 212.243549 -401.293397)
			(xy 212.250473 -401.311017) (xy 212.256624 -401.318222) (xy 212.28426 -401.348962) (xy 212.334306 -401.41476)
			(xy 212.378036 -401.484914) (xy 212.415073 -401.558821) (xy 212.445099 -401.635843) (xy 212.467855 -401.715317)
			(xy 212.483145 -401.796559) (xy 212.490837 -401.878868) (xy 212.49132 -401.920202) (xy 212.490863 -401.961538)
			(xy 212.48319 -402.043852) (xy 212.467911 -402.125099) (xy 212.445158 -402.204578) (xy 212.415126 -402.281602)
			(xy 212.378076 -402.355506) (xy 212.334327 -402.425653) (xy 212.284257 -402.491437) (xy 212.256624 -402.522182)
			(xy 212.250543 -402.529427) (xy 212.243647 -402.547025) (xy 212.243162 -402.556472) (xy 212.243162 -402.586952)
			(xy 212.243589 -402.596413) (xy 212.250485 -402.614033) (xy 212.256624 -402.621242) (xy 212.284222 -402.652015)
			(xy 212.33427 -402.717808) (xy 212.378004 -402.787957) (xy 212.415046 -402.861859) (xy 212.445077 -402.938876)
			(xy 212.467838 -403.018346) (xy 212.483134 -403.099584) (xy 212.490833 -403.18189) (xy 212.49132 -403.223222)
			(xy 212.490801 -403.266183) (xy 212.482523 -403.351705) (xy 212.466036 -403.43603) (xy 212.441494 -403.518372)
			(xy 212.409125 -403.597963) (xy 212.369232 -403.674062) (xy 212.322186 -403.745959) (xy 212.268426 -403.812984)
			(xy 212.208453 -403.874513) (xy 212.142826 -403.929971) (xy 212.072156 -403.978842) (xy 212.034882 -404.000208)
			(xy 212.02673 -404.005265) (xy 212.014612 -404.020117) (xy 212.00876 -404.03837) (xy 212.008974 -404.04796)
			(xy 212.016086 -404.154386) (xy 212.033358 -404.178008) (xy 212.047328 -404.183342) (xy 212.085266 -404.198729)
			(xy 212.158382 -404.235572) (xy 212.227803 -404.27898) (xy 212.29294 -404.328584) (xy 212.353242 -404.383965)
			(xy 212.408199 -404.444654) (xy 212.457346 -404.510137) (xy 212.500266 -404.57986) (xy 212.536597 -404.653232)
			(xy 212.56603 -404.729633) (xy 212.588317 -404.808416) (xy 212.603269 -404.888913) (xy 212.610758 -404.970445)
			(xy 212.611208 -405.011382) (xy 212.610619 -405.057777) (xy 212.600976 -405.150066) (xy 212.581781 -405.240849)
			(xy 212.553245 -405.329143) (xy 212.535008 -405.371808) (xy 212.531213 -405.381753) (xy 212.531206 -405.403014)
			(xy 212.535008 -405.412956) (xy 212.553247 -405.455621) (xy 212.581792 -405.543912) (xy 212.600987 -405.634696)
			(xy 212.610622 -405.726986) (xy 212.611208 -405.773382) (xy 212.610619 -405.819777) (xy 212.600976 -405.912066)
			(xy 212.581781 -406.002849) (xy 212.553245 -406.091143) (xy 212.535008 -406.133808) (xy 212.531213 -406.143753)
			(xy 212.531206 -406.165014) (xy 212.535008 -406.174956) (xy 212.549234 -406.207876) (xy 212.572955 -406.275561)
			(xy 212.591136 -406.34494) (xy 212.597746 -406.380188) (xy 212.600055 -406.390309) (xy 212.611454 -406.407631)
			(xy 212.628772 -406.419037) (xy 212.638894 -406.421336) (xy 212.679556 -406.42906) (xy 212.75936 -406.451024)
			(xy 212.83678 -406.480305) (xy 212.911146 -406.51665) (xy 212.981814 -406.559745) (xy 213.048174 -406.609217)
			(xy 213.109652 -406.66464) (xy 213.165716 -406.725533) (xy 213.215883 -406.791369) (xy 213.259718 -406.861581)
			(xy 213.296841 -406.935561) (xy 213.326933 -407.012669) (xy 213.349733 -407.092239) (xy 213.365045 -407.173582)
			(xy 213.372734 -407.255996) (xy 213.373208 -407.297382) (xy 213.373208 -407.29789) (xy 213.372596 -407.344222)
			(xy 213.362926 -407.436379) (xy 213.343732 -407.527034) (xy 213.315222 -407.615202) (xy 213.297008 -407.657808)
			(xy 213.293213 -407.667753) (xy 213.293206 -407.689014) (xy 213.297008 -407.698956) (xy 213.315224 -407.741561)
			(xy 213.343743 -407.829728) (xy 213.362938 -407.920383) (xy 213.372599 -408.012542) (xy 213.373208 -408.058874)
			(xy 213.373208 -408.059382) (xy 213.373201 -408.05989) (xy 216.928192 -408.05989) (xy 216.928192 -408.059382)
			(xy 216.928717 -408.017997) (xy 216.936406 -407.935585) (xy 216.951716 -407.854244) (xy 216.974513 -407.774675)
			(xy 217.004602 -407.697568) (xy 217.041723 -407.623589) (xy 217.085553 -407.553377) (xy 217.135715 -407.487539)
			(xy 217.191774 -407.426645) (xy 217.253247 -407.37122) (xy 217.319602 -407.321743) (xy 217.390265 -407.278644)
			(xy 217.464625 -407.242293) (xy 217.54204 -407.213005) (xy 217.621841 -407.191034) (xy 217.662506 -407.183336)
			(xy 217.672634 -407.181051) (xy 217.689956 -407.169641) (xy 217.701359 -407.152314) (xy 217.703654 -407.142188)
			(xy 217.711393 -407.101149) (xy 217.733607 -407.020638) (xy 217.763268 -406.942562) (xy 217.800115 -406.86761)
			(xy 217.843825 -406.796441) (xy 217.894012 -406.729682) (xy 217.950235 -406.66792) (xy 218.011998 -406.611699)
			(xy 218.078759 -406.561513) (xy 218.149929 -406.517805) (xy 218.224881 -406.48096) (xy 218.302957 -406.4513)
			(xy 218.383469 -406.429089) (xy 218.424506 -406.421336) (xy 218.434634 -406.419051) (xy 218.451956 -406.407641)
			(xy 218.463359 -406.390314) (xy 218.465654 -406.380188) (xy 218.472281 -406.344944) (xy 218.490478 -406.275571)
			(xy 218.514186 -406.207884) (xy 218.528392 -406.174956) (xy 218.532208 -406.165017) (xy 218.532201 -406.14375)
			(xy 218.528392 -406.133808) (xy 218.510141 -406.091148) (xy 218.481599 -406.002855) (xy 218.462407 -405.912069)
			(xy 218.452776 -405.819778) (xy 218.452192 -405.773382) (xy 218.452769 -405.726986) (xy 218.462415 -405.634698)
			(xy 218.481613 -405.543914) (xy 218.510153 -405.455621) (xy 218.528392 -405.412956) (xy 218.532208 -405.403017)
			(xy 218.532201 -405.38175) (xy 218.528392 -405.371808) (xy 218.510164 -405.329208) (xy 218.481648 -405.241039)
			(xy 218.462457 -405.150383) (xy 218.452799 -405.058222) (xy 218.452192 -405.01189) (xy 218.452192 -405.011382)
			(xy 218.452669 -404.970705) (xy 218.460097 -404.889692) (xy 218.47489 -404.809694) (xy 218.496923 -404.731381)
			(xy 218.526013 -404.655407) (xy 218.561918 -404.582405) (xy 218.604336 -404.512985) (xy 218.652914 -404.447728)
			(xy 218.707247 -404.387177) (xy 218.76688 -404.33184) (xy 218.831316 -404.282176) (xy 218.900016 -404.238603)
			(xy 218.972407 -404.201482) (xy 219.009976 -404.185882) (xy 219.018795 -404.181969) (xy 219.032833 -404.168752)
			(xy 219.040997 -404.151285) (xy 219.04198 -404.141686) (xy 219.047314 -404.049992) (xy 219.047428 -404.040421)
			(xy 219.041477 -404.022248) (xy 219.029313 -404.007492) (xy 219.021152 -404.002494) (xy 218.983554 -403.981253)
			(xy 218.912288 -403.932477) (xy 218.846083 -403.877025) (xy 218.785561 -403.81542) (xy 218.731292 -403.748241)
			(xy 218.683788 -403.67612) (xy 218.643493 -403.599737) (xy 218.610789 -403.519809) (xy 218.585982 -403.437088)
			(xy 218.569306 -403.352354) (xy 218.560918 -403.266402) (xy 218.560396 -403.223222) (xy 218.560864 -403.181887)
			(xy 218.568535 -403.099572) (xy 218.583812 -403.018325) (xy 218.606564 -402.938847) (xy 218.636593 -402.861823)
			(xy 218.673642 -402.787918) (xy 218.71739 -402.717771) (xy 218.767459 -402.651987) (xy 218.795092 -402.621242)
			(xy 218.801153 -402.613982) (xy 218.808063 -402.596396) (xy 218.808554 -402.586952) (xy 218.808554 -402.556472)
			(xy 218.808185 -402.547004) (xy 218.801251 -402.529384) (xy 218.795092 -402.522182) (xy 218.767443 -402.491454)
			(xy 218.7174 -402.425653) (xy 218.673673 -402.355495) (xy 218.636638 -402.281587) (xy 218.606614 -402.204563)
			(xy 218.58386 -402.125088) (xy 218.568571 -402.043846) (xy 218.56088 -401.961536) (xy 218.560396 -401.920202)
			(xy 218.560852 -401.878866) (xy 218.568524 -401.796552) (xy 218.583803 -401.715304) (xy 218.606556 -401.635826)
			(xy 218.636588 -401.558802) (xy 218.673638 -401.484897) (xy 218.717388 -401.414751) (xy 218.767459 -401.348967)
			(xy 218.795092 -401.318222) (xy 218.801161 -401.310968) (xy 218.808066 -401.293378) (xy 218.808554 -401.283932)
			(xy 218.808554 -401.253452) (xy 218.808146 -401.243989) (xy 218.801239 -401.226367) (xy 218.795092 -401.219162)
			(xy 218.767482 -401.1884) (xy 218.717436 -401.122604) (xy 218.673705 -401.052453) (xy 218.636666 -400.978549)
			(xy 218.606637 -400.90153) (xy 218.583877 -400.82206) (xy 218.568582 -400.740821) (xy 218.560883 -400.658515)
			(xy 218.560396 -400.617182) (xy 218.560896 -400.576069) (xy 218.568484 -400.494193) (xy 218.583594 -400.413367)
			(xy 218.606097 -400.334279) (xy 218.635801 -400.257605) (xy 218.672453 -400.183999) (xy 218.715739 -400.114089)
			(xy 218.765291 -400.04847) (xy 218.820686 -399.987703) (xy 218.881451 -399.932307) (xy 218.947069 -399.882753)
			(xy 219.016978 -399.839464) (xy 219.090583 -399.802811) (xy 219.167256 -399.773105) (xy 219.246343 -399.7506)
			(xy 219.327169 -399.735487) (xy 219.409045 -399.727897) (xy 219.450158 -399.72742) (xy 219.494662 -399.727949)
			(xy 219.583226 -399.736844) (xy 219.670458 -399.754538) (xy 219.755487 -399.780856) (xy 219.837463 -399.815534)
			(xy 219.915565 -399.858225) (xy 219.989014 -399.908502) (xy 220.057075 -399.965864) (xy 220.08846 -399.997422)
			(xy 220.095931 -400.004447) (xy 220.114793 -400.012446) (xy 220.125036 -400.012916) (xy 220.19768 -400.012916)
			(xy 220.207931 -400.012475) (xy 220.226805 -400.004477) (xy 220.234256 -399.997422) (xy 220.265663 -399.965886)
			(xy 220.333719 -399.908523) (xy 220.407164 -399.858243) (xy 220.485263 -399.81555) (xy 220.567236 -399.780871)
			(xy 220.652263 -399.754552) (xy 220.739493 -399.736858) (xy 220.828055 -399.727964) (xy 220.872558 -399.72742)
			(xy 220.916049 -399.727926) (xy 221.002612 -399.736439) (xy 221.087932 -399.75336) (xy 221.171193 -399.778526)
			(xy 221.251601 -399.811696) (xy 221.328388 -399.852556) (xy 221.400821 -399.900714) (xy 221.468209 -399.95571)
			(xy 221.49943 -399.985992) (xy 221.499684 -399.986246) (xy 221.507078 -399.992808) (xy 221.525369 -400.000258)
			(xy 221.535244 -400.000724) (xy 221.606872 -400.000724) (xy 221.616751 -400.000273) (xy 221.63505 -399.992827)
			(xy 221.642432 -399.986246) (xy 221.642686 -399.985992) (xy 221.673904 -399.955708) (xy 221.741295 -399.900719)
			(xy 221.81373 -399.852567) (xy 221.890518 -399.811713) (xy 221.970927 -399.778547) (xy 222.054187 -399.753386)
			(xy 222.139506 -399.736469) (xy 222.226068 -399.727958) (xy 222.269558 -399.72742) (xy 222.310672 -399.727938)
			(xy 222.392549 -399.735522) (xy 222.473376 -399.750627) (xy 222.552466 -399.773127) (xy 222.629142 -399.802827)
			(xy 222.70275 -399.839476) (xy 222.772663 -399.882761) (xy 222.838283 -399.932312) (xy 222.899052 -399.987706)
			(xy 222.95445 -400.04847) (xy 223.004005 -400.114088) (xy 223.047294 -400.183998) (xy 223.083948 -400.257603)
			(xy 223.113654 -400.334277) (xy 223.136159 -400.413365) (xy 223.15127 -400.494192) (xy 223.158859 -400.576068)
			(xy 223.15932 -400.617182) (xy 223.15885 -400.658517) (xy 223.151179 -400.740831) (xy 223.135902 -400.822078)
			(xy 223.113151 -400.901557) (xy 223.083121 -400.978581) (xy 223.046073 -401.052485) (xy 223.002325 -401.122632)
			(xy 222.952256 -401.188416) (xy 222.924624 -401.219162) (xy 222.918551 -401.226413) (xy 222.911651 -401.244006)
			(xy 222.911162 -401.253452) (xy 222.911162 -401.283932) (xy 222.911549 -401.293397) (xy 222.918473 -401.311017)
			(xy 222.924624 -401.318222) (xy 222.95226 -401.348962) (xy 223.002306 -401.41476) (xy 223.046036 -401.484914)
			(xy 223.083073 -401.558821) (xy 223.113099 -401.635843) (xy 223.135855 -401.715317) (xy 223.151145 -401.796559)
			(xy 223.158837 -401.878868) (xy 223.15932 -401.920202) (xy 223.158863 -401.961538) (xy 223.15119 -402.043852)
			(xy 223.135911 -402.125099) (xy 223.113158 -402.204578) (xy 223.083126 -402.281602) (xy 223.046076 -402.355506)
			(xy 223.002327 -402.425653) (xy 222.952257 -402.491437) (xy 222.924624 -402.522182) (xy 222.918543 -402.529427)
			(xy 222.911647 -402.547025) (xy 222.911162 -402.556472) (xy 222.911162 -402.586952) (xy 222.911589 -402.596413)
			(xy 222.918485 -402.614033) (xy 222.924624 -402.621242) (xy 222.952222 -402.652015) (xy 223.00227 -402.717808)
			(xy 223.046004 -402.787957) (xy 223.083046 -402.861859) (xy 223.113077 -402.938876) (xy 223.135838 -403.018346)
			(xy 223.151134 -403.099584) (xy 223.158833 -403.18189) (xy 223.15932 -403.223222) (xy 223.158801 -403.266183)
			(xy 223.150523 -403.351705) (xy 223.134036 -403.43603) (xy 223.109494 -403.518372) (xy 223.077125 -403.597963)
			(xy 223.037232 -403.674062) (xy 222.990186 -403.745959) (xy 222.936426 -403.812984) (xy 222.876453 -403.874513)
			(xy 222.810826 -403.929971) (xy 222.740156 -403.978842) (xy 222.702882 -404.000208) (xy 222.69473 -404.005265)
			(xy 222.682612 -404.020117) (xy 222.67676 -404.03837) (xy 222.676974 -404.04796) (xy 222.684086 -404.154386)
			(xy 222.701358 -404.178008) (xy 222.715328 -404.183342) (xy 222.753266 -404.198729) (xy 222.826382 -404.235572)
			(xy 222.895803 -404.27898) (xy 222.96094 -404.328584) (xy 223.021242 -404.383965) (xy 223.076199 -404.444654)
			(xy 223.125346 -404.510137) (xy 223.168266 -404.57986) (xy 223.204597 -404.653232) (xy 223.23403 -404.729633)
			(xy 223.256317 -404.808416) (xy 223.271269 -404.888913) (xy 223.278758 -404.970445) (xy 223.279208 -405.011382)
			(xy 223.278619 -405.057777) (xy 223.268976 -405.150066) (xy 223.249781 -405.240849) (xy 223.221245 -405.329143)
			(xy 223.203008 -405.371808) (xy 223.199213 -405.381753) (xy 223.199206 -405.403014) (xy 223.203008 -405.412956)
			(xy 223.221247 -405.455621) (xy 223.249792 -405.543912) (xy 223.268987 -405.634696) (xy 223.278622 -405.726986)
			(xy 223.279208 -405.773382) (xy 223.278619 -405.819777) (xy 223.268976 -405.912066) (xy 223.249781 -406.002849)
			(xy 223.221245 -406.091143) (xy 223.203008 -406.133808) (xy 223.199213 -406.143753) (xy 223.199206 -406.165014)
			(xy 223.203008 -406.174956) (xy 223.217234 -406.207876) (xy 223.240955 -406.275561) (xy 223.259136 -406.34494)
			(xy 223.265746 -406.380188) (xy 223.268055 -406.390309) (xy 223.279454 -406.407631) (xy 223.296772 -406.419037)
			(xy 223.306894 -406.421336) (xy 223.347556 -406.42906) (xy 223.42736 -406.451024) (xy 223.50478 -406.480305)
			(xy 223.579146 -406.51665) (xy 223.649814 -406.559745) (xy 223.716174 -406.609217) (xy 223.777652 -406.66464)
			(xy 223.833716 -406.725533) (xy 223.883883 -406.791369) (xy 223.927718 -406.861581) (xy 223.964841 -406.935561)
			(xy 223.994933 -407.012669) (xy 224.017733 -407.092239) (xy 224.033045 -407.173582) (xy 224.040734 -407.255996)
			(xy 224.041208 -407.297382) (xy 224.041208 -407.29789) (xy 224.040596 -407.344222) (xy 224.030926 -407.436379)
			(xy 224.011732 -407.527034) (xy 223.983222 -407.615202) (xy 223.965008 -407.657808) (xy 223.961213 -407.667753)
			(xy 223.961206 -407.689014) (xy 223.965008 -407.698956) (xy 223.983224 -407.741561) (xy 224.011743 -407.829728)
			(xy 224.030938 -407.920383) (xy 224.040599 -408.012542) (xy 224.041208 -408.058874) (xy 224.041208 -408.059382)
			(xy 224.041201 -408.05989) (xy 227.596192 -408.05989) (xy 227.596192 -408.059382) (xy 227.596717 -408.017997)
			(xy 227.604406 -407.935585) (xy 227.619716 -407.854244) (xy 227.642513 -407.774675) (xy 227.672602 -407.697568)
			(xy 227.709723 -407.623589) (xy 227.753553 -407.553377) (xy 227.803715 -407.487539) (xy 227.859774 -407.426645)
			(xy 227.921247 -407.37122) (xy 227.987602 -407.321743) (xy 228.058265 -407.278644) (xy 228.132625 -407.242293)
			(xy 228.21004 -407.213005) (xy 228.289841 -407.191034) (xy 228.330506 -407.183336) (xy 228.340634 -407.181051)
			(xy 228.357956 -407.169641) (xy 228.369359 -407.152314) (xy 228.371654 -407.142188) (xy 228.379393 -407.101149)
			(xy 228.401607 -407.020638) (xy 228.431268 -406.942562) (xy 228.468115 -406.86761) (xy 228.511825 -406.796441)
			(xy 228.562012 -406.729682) (xy 228.618235 -406.66792) (xy 228.679998 -406.611699) (xy 228.746759 -406.561513)
			(xy 228.817929 -406.517805) (xy 228.892881 -406.48096) (xy 228.970957 -406.4513) (xy 229.051469 -406.429089)
			(xy 229.092506 -406.421336) (xy 229.102634 -406.419051) (xy 229.119956 -406.407641) (xy 229.131359 -406.390314)
			(xy 229.133654 -406.380188) (xy 229.140281 -406.344944) (xy 229.158478 -406.275571) (xy 229.182186 -406.207884)
			(xy 229.196392 -406.174956) (xy 229.200208 -406.165017) (xy 229.200201 -406.14375) (xy 229.196392 -406.133808)
			(xy 229.178141 -406.091148) (xy 229.149599 -406.002855) (xy 229.130407 -405.912069) (xy 229.120776 -405.819778)
			(xy 229.120192 -405.773382) (xy 229.120769 -405.726986) (xy 229.130415 -405.634698) (xy 229.149613 -405.543914)
			(xy 229.178153 -405.455621) (xy 229.196392 -405.412956) (xy 229.200208 -405.403017) (xy 229.200201 -405.38175)
			(xy 229.196392 -405.371808) (xy 229.178164 -405.329208) (xy 229.149648 -405.241039) (xy 229.130457 -405.150383)
			(xy 229.120799 -405.058222) (xy 229.120192 -405.01189) (xy 229.120192 -405.011382) (xy 229.120669 -404.970705)
			(xy 229.128097 -404.889692) (xy 229.14289 -404.809694) (xy 229.164923 -404.731381) (xy 229.194013 -404.655407)
			(xy 229.229918 -404.582405) (xy 229.272336 -404.512985) (xy 229.320914 -404.447728) (xy 229.375247 -404.387177)
			(xy 229.43488 -404.33184) (xy 229.499316 -404.282176) (xy 229.568016 -404.238603) (xy 229.640407 -404.201482)
			(xy 229.677976 -404.185882) (xy 229.686795 -404.181969) (xy 229.700833 -404.168752) (xy 229.708997 -404.151285)
			(xy 229.70998 -404.141686) (xy 229.715314 -404.049992) (xy 229.715428 -404.040421) (xy 229.709477 -404.022248)
			(xy 229.697313 -404.007492) (xy 229.689152 -404.002494) (xy 229.651554 -403.981253) (xy 229.580288 -403.932477)
			(xy 229.514083 -403.877025) (xy 229.453561 -403.81542) (xy 229.399292 -403.748241) (xy 229.351788 -403.67612)
			(xy 229.311493 -403.599737) (xy 229.278789 -403.519809) (xy 229.253982 -403.437088) (xy 229.237306 -403.352354)
			(xy 229.228918 -403.266402) (xy 229.228396 -403.223222) (xy 229.228864 -403.181887) (xy 229.236535 -403.099572)
			(xy 229.251812 -403.018325) (xy 229.274564 -402.938847) (xy 229.304593 -402.861823) (xy 229.341642 -402.787918)
			(xy 229.38539 -402.717771) (xy 229.435459 -402.651987) (xy 229.463092 -402.621242) (xy 229.469153 -402.613982)
			(xy 229.476063 -402.596396) (xy 229.476554 -402.586952) (xy 229.476554 -402.556472) (xy 229.476185 -402.547004)
			(xy 229.469251 -402.529384) (xy 229.463092 -402.522182) (xy 229.435443 -402.491454) (xy 229.3854 -402.425653)
			(xy 229.341673 -402.355495) (xy 229.304638 -402.281587) (xy 229.274614 -402.204563) (xy 229.25186 -402.125088)
			(xy 229.236571 -402.043846) (xy 229.22888 -401.961536) (xy 229.228396 -401.920202) (xy 229.228852 -401.878866)
			(xy 229.236524 -401.796552) (xy 229.251803 -401.715304) (xy 229.274556 -401.635826) (xy 229.304588 -401.558802)
			(xy 229.341638 -401.484897) (xy 229.385388 -401.414751) (xy 229.435459 -401.348967) (xy 229.463092 -401.318222)
			(xy 229.469161 -401.310968) (xy 229.476066 -401.293378) (xy 229.476554 -401.283932) (xy 229.476554 -401.253452)
			(xy 229.476146 -401.243989) (xy 229.469239 -401.226367) (xy 229.463092 -401.219162) (xy 229.435482 -401.1884)
			(xy 229.385436 -401.122604) (xy 229.341705 -401.052453) (xy 229.304666 -400.978549) (xy 229.274637 -400.90153)
			(xy 229.251877 -400.82206) (xy 229.236582 -400.740821) (xy 229.228883 -400.658515) (xy 229.228396 -400.617182)
			(xy 229.228896 -400.576069) (xy 229.236484 -400.494193) (xy 229.251594 -400.413367) (xy 229.274097 -400.334279)
			(xy 229.303801 -400.257605) (xy 229.340453 -400.183999) (xy 229.383739 -400.114089) (xy 229.433291 -400.04847)
			(xy 229.488686 -399.987703) (xy 229.549451 -399.932307) (xy 229.615069 -399.882753) (xy 229.684978 -399.839464)
			(xy 229.758583 -399.802811) (xy 229.835256 -399.773105) (xy 229.914343 -399.7506) (xy 229.995169 -399.735487)
			(xy 230.077045 -399.727897) (xy 230.118158 -399.72742) (xy 230.162662 -399.727949) (xy 230.251226 -399.736844)
			(xy 230.338458 -399.754538) (xy 230.423487 -399.780856) (xy 230.505463 -399.815534) (xy 230.583565 -399.858225)
			(xy 230.657014 -399.908502) (xy 230.725075 -399.965864) (xy 230.75646 -399.997422) (xy 230.763931 -400.004447)
			(xy 230.782793 -400.012446) (xy 230.793036 -400.012916) (xy 230.86568 -400.012916) (xy 230.875931 -400.012475)
			(xy 230.894805 -400.004477) (xy 230.902256 -399.997422) (xy 230.933663 -399.965886) (xy 231.001719 -399.908523)
			(xy 231.075164 -399.858243) (xy 231.153263 -399.81555) (xy 231.235236 -399.780871) (xy 231.320263 -399.754552)
			(xy 231.407493 -399.736858) (xy 231.496055 -399.727964) (xy 231.540558 -399.72742) (xy 231.584049 -399.727926)
			(xy 231.670612 -399.736439) (xy 231.755932 -399.75336) (xy 231.839193 -399.778526) (xy 231.919601 -399.811696)
			(xy 231.996388 -399.852556) (xy 232.068821 -399.900714) (xy 232.136209 -399.95571) (xy 232.16743 -399.985992)
			(xy 232.167684 -399.986246) (xy 232.175078 -399.992808) (xy 232.193369 -400.000258) (xy 232.203244 -400.000724)
			(xy 232.274872 -400.000724) (xy 232.284751 -400.000273) (xy 232.30305 -399.992827) (xy 232.310432 -399.986246)
			(xy 232.310686 -399.985992) (xy 232.341904 -399.955708) (xy 232.409295 -399.900719) (xy 232.48173 -399.852567)
			(xy 232.558518 -399.811713) (xy 232.638927 -399.778547) (xy 232.722187 -399.753386) (xy 232.807506 -399.736469)
			(xy 232.894068 -399.727958) (xy 232.937558 -399.72742) (xy 232.978672 -399.727938) (xy 233.060549 -399.735522)
			(xy 233.141376 -399.750627) (xy 233.220466 -399.773127) (xy 233.297142 -399.802827) (xy 233.37075 -399.839476)
			(xy 233.440663 -399.882761) (xy 233.506283 -399.932312) (xy 233.567052 -399.987706) (xy 233.62245 -400.04847)
			(xy 233.672005 -400.114088) (xy 233.715294 -400.183998) (xy 233.751948 -400.257603) (xy 233.781654 -400.334277)
			(xy 233.804159 -400.413365) (xy 233.81927 -400.494192) (xy 233.826859 -400.576068) (xy 233.82732 -400.617182)
			(xy 233.82685 -400.658517) (xy 233.819179 -400.740831) (xy 233.803902 -400.822078) (xy 233.781151 -400.901557)
			(xy 233.751121 -400.978581) (xy 233.714073 -401.052485) (xy 233.670325 -401.122632) (xy 233.620256 -401.188416)
			(xy 233.592624 -401.219162) (xy 233.586551 -401.226413) (xy 233.579651 -401.244006) (xy 233.579162 -401.253452)
			(xy 233.579162 -401.283932) (xy 233.579549 -401.293397) (xy 233.586473 -401.311017) (xy 233.592624 -401.318222)
			(xy 233.62026 -401.348962) (xy 233.670306 -401.41476) (xy 233.714036 -401.484914) (xy 233.751073 -401.558821)
			(xy 233.781099 -401.635843) (xy 233.803855 -401.715317) (xy 233.819145 -401.796559) (xy 233.826837 -401.878868)
			(xy 233.82732 -401.920202) (xy 233.826863 -401.961538) (xy 233.81919 -402.043852) (xy 233.803911 -402.125099)
			(xy 233.781158 -402.204578) (xy 233.751126 -402.281602) (xy 233.714076 -402.355506) (xy 233.670327 -402.425653)
			(xy 233.620257 -402.491437) (xy 233.592624 -402.522182) (xy 233.586543 -402.529427) (xy 233.579647 -402.547025)
			(xy 233.579162 -402.556472) (xy 233.579162 -402.586952) (xy 233.579589 -402.596413) (xy 233.586485 -402.614033)
			(xy 233.592624 -402.621242) (xy 233.620222 -402.652015) (xy 233.67027 -402.717808) (xy 233.714004 -402.787957)
			(xy 233.751046 -402.861859) (xy 233.781077 -402.938876) (xy 233.803838 -403.018346) (xy 233.819134 -403.099584)
			(xy 233.826833 -403.18189) (xy 233.82732 -403.223222) (xy 233.826801 -403.266183) (xy 233.818523 -403.351705)
			(xy 233.802036 -403.43603) (xy 233.777494 -403.518372) (xy 233.745125 -403.597963) (xy 233.705232 -403.674062)
			(xy 233.658186 -403.745959) (xy 233.604426 -403.812984) (xy 233.544453 -403.874513) (xy 233.478826 -403.929971)
			(xy 233.408156 -403.978842) (xy 233.370882 -404.000208) (xy 233.36273 -404.005265) (xy 233.350612 -404.020117)
			(xy 233.34476 -404.03837) (xy 233.344974 -404.04796) (xy 233.352086 -404.154386) (xy 233.369358 -404.178008)
			(xy 233.383328 -404.183342) (xy 233.421266 -404.198729) (xy 233.494382 -404.235572) (xy 233.563803 -404.27898)
			(xy 233.62894 -404.328584) (xy 233.689242 -404.383965) (xy 233.744199 -404.444654) (xy 233.793346 -404.510137)
			(xy 233.836266 -404.57986) (xy 233.872597 -404.653232) (xy 233.90203 -404.729633) (xy 233.924317 -404.808416)
			(xy 233.939269 -404.888913) (xy 233.946758 -404.970445) (xy 233.947208 -405.011382) (xy 233.946619 -405.057777)
			(xy 233.936976 -405.150066) (xy 233.917781 -405.240849) (xy 233.889245 -405.329143) (xy 233.871008 -405.371808)
			(xy 233.867213 -405.381753) (xy 233.867206 -405.403014) (xy 233.871008 -405.412956) (xy 233.889247 -405.455621)
			(xy 233.917792 -405.543912) (xy 233.936987 -405.634696) (xy 233.946622 -405.726986) (xy 233.947208 -405.773382)
			(xy 233.946619 -405.819777) (xy 233.936976 -405.912066) (xy 233.917781 -406.002849) (xy 233.889245 -406.091143)
			(xy 233.871008 -406.133808) (xy 233.867213 -406.143753) (xy 233.867206 -406.165014) (xy 233.871008 -406.174956)
			(xy 233.885234 -406.207876) (xy 233.908955 -406.275561) (xy 233.927136 -406.34494) (xy 233.933746 -406.380188)
			(xy 233.936055 -406.390309) (xy 233.947454 -406.407631) (xy 233.964772 -406.419037) (xy 233.974894 -406.421336)
			(xy 234.015556 -406.42906) (xy 234.09536 -406.451024) (xy 234.17278 -406.480305) (xy 234.247146 -406.51665)
			(xy 234.317814 -406.559745) (xy 234.384174 -406.609217) (xy 234.445652 -406.66464) (xy 234.501716 -406.725533)
			(xy 234.551883 -406.791369) (xy 234.595718 -406.861581) (xy 234.632841 -406.935561) (xy 234.662933 -407.012669)
			(xy 234.685733 -407.092239) (xy 234.701045 -407.173582) (xy 234.708734 -407.255996) (xy 234.709208 -407.297382)
			(xy 234.709208 -407.29789) (xy 234.708596 -407.344222) (xy 234.698926 -407.436379) (xy 234.679732 -407.527034)
			(xy 234.651222 -407.615202) (xy 234.633008 -407.657808) (xy 234.629213 -407.667753) (xy 234.629206 -407.689014)
			(xy 234.633008 -407.698956) (xy 234.651224 -407.741561) (xy 234.679743 -407.829728) (xy 234.698938 -407.920383)
			(xy 234.708599 -408.012542) (xy 234.709208 -408.058874) (xy 234.709208 -408.059382) (xy 234.70867 -408.100487)
			(xy 234.701088 -408.182347) (xy 234.685987 -408.263158) (xy 234.663495 -408.342232) (xy 234.633804 -408.418893)
			(xy 234.597168 -408.492489) (xy 234.5539 -408.562391) (xy 234.504367 -408.628004) (xy 234.448992 -408.688767)
			(xy 234.388249 -408.744164) (xy 234.322654 -408.79372) (xy 234.252767 -408.837014) (xy 234.179184 -408.873676)
			(xy 234.102533 -408.903394) (xy 234.023468 -408.925914) (xy 233.942662 -408.941044) (xy 233.860805 -408.948656)
			(xy 233.8197 -408.949144) (xy 233.773298 -408.948515) (xy 233.681001 -408.938826) (xy 233.590215 -408.919572)
			(xy 233.50193 -408.890965) (xy 233.459274 -408.87269) (xy 233.449332 -408.868884) (xy 233.428068 -408.868884)
			(xy 233.418126 -408.87269) (xy 233.375466 -408.890954) (xy 233.287177 -408.919546) (xy 233.196394 -408.938803)
			(xy 233.104101 -408.948515) (xy 233.0577 -408.949144) (xy 233.011298 -408.948515) (xy 232.919001 -408.938826)
			(xy 232.828215 -408.919572) (xy 232.73993 -408.890965) (xy 232.697274 -408.87269) (xy 232.687332 -408.868884)
			(xy 232.666068 -408.868884) (xy 232.656126 -408.87269) (xy 232.613466 -408.890954) (xy 232.525177 -408.919546)
			(xy 232.434394 -408.938803) (xy 232.342101 -408.948515) (xy 232.2957 -408.949144) (xy 232.249298 -408.948515)
			(xy 232.157001 -408.938826) (xy 232.066215 -408.919572) (xy 231.97793 -408.890965) (xy 231.935274 -408.87269)
			(xy 231.925332 -408.868884) (xy 231.904068 -408.868884) (xy 231.894126 -408.87269) (xy 231.851466 -408.890954)
			(xy 231.763177 -408.919546) (xy 231.672394 -408.938803) (xy 231.580101 -408.948515) (xy 231.5337 -408.949144)
			(xy 231.487298 -408.948515) (xy 231.395001 -408.938826) (xy 231.304215 -408.919572) (xy 231.21593 -408.890965)
			(xy 231.173274 -408.87269) (xy 231.163332 -408.868884) (xy 231.142068 -408.868884) (xy 231.132126 -408.87269)
			(xy 231.089466 -408.890954) (xy 231.001177 -408.919546) (xy 230.910394 -408.938803) (xy 230.818101 -408.948515)
			(xy 230.7717 -408.949144) (xy 230.725298 -408.948515) (xy 230.633001 -408.938826) (xy 230.542215 -408.919572)
			(xy 230.45393 -408.890965) (xy 230.411274 -408.87269) (xy 230.401332 -408.868884) (xy 230.380068 -408.868884)
			(xy 230.370126 -408.87269) (xy 230.327466 -408.890954) (xy 230.239177 -408.919546) (xy 230.148394 -408.938803)
			(xy 230.056101 -408.948515) (xy 230.0097 -408.949144) (xy 229.963298 -408.948515) (xy 229.871001 -408.938826)
			(xy 229.780215 -408.919572) (xy 229.69193 -408.890965) (xy 229.649274 -408.87269) (xy 229.639332 -408.868884)
			(xy 229.618068 -408.868884) (xy 229.608126 -408.87269) (xy 229.565466 -408.890954) (xy 229.477177 -408.919546)
			(xy 229.386394 -408.938803) (xy 229.294101 -408.948515) (xy 229.2477 -408.949144) (xy 229.201298 -408.948515)
			(xy 229.109001 -408.938826) (xy 229.018215 -408.919572) (xy 228.92993 -408.890965) (xy 228.887274 -408.87269)
			(xy 228.877332 -408.868884) (xy 228.856068 -408.868884) (xy 228.846126 -408.87269) (xy 228.803466 -408.890954)
			(xy 228.715177 -408.919546) (xy 228.624394 -408.938803) (xy 228.532101 -408.948515) (xy 228.4857 -408.949144)
			(xy 228.444606 -408.948634) (xy 228.362769 -408.941052) (xy 228.281979 -408.925953) (xy 228.202928 -408.903466)
			(xy 228.126287 -408.873782) (xy 228.052712 -408.837155) (xy 227.98283 -408.793896) (xy 227.917236 -408.744376)
			(xy 227.85649 -408.689016) (xy 227.801109 -408.628288) (xy 227.751568 -408.56271) (xy 227.708286 -408.492841)
			(xy 227.671635 -408.419278) (xy 227.641926 -408.342647) (xy 227.619413 -408.263603) (xy 227.604288 -408.182819)
			(xy 227.59668 -408.100984) (xy 227.596192 -408.05989) (xy 224.041201 -408.05989) (xy 224.04067 -408.100487)
			(xy 224.033088 -408.182347) (xy 224.017987 -408.263158) (xy 223.995495 -408.342232) (xy 223.965804 -408.418893)
			(xy 223.929168 -408.492489) (xy 223.8859 -408.562391) (xy 223.836367 -408.628004) (xy 223.780992 -408.688767)
			(xy 223.720249 -408.744164) (xy 223.654654 -408.79372) (xy 223.584767 -408.837014) (xy 223.511184 -408.873676)
			(xy 223.434533 -408.903394) (xy 223.355468 -408.925914) (xy 223.274662 -408.941044) (xy 223.192805 -408.948656)
			(xy 223.1517 -408.949144) (xy 223.105298 -408.948515) (xy 223.013001 -408.938826) (xy 222.922215 -408.919572)
			(xy 222.83393 -408.890965) (xy 222.791274 -408.87269) (xy 222.781332 -408.868884) (xy 222.760068 -408.868884)
			(xy 222.750126 -408.87269) (xy 222.707466 -408.890954) (xy 222.619177 -408.919546) (xy 222.528394 -408.938803)
			(xy 222.436101 -408.948515) (xy 222.3897 -408.949144) (xy 222.343298 -408.948515) (xy 222.251001 -408.938826)
			(xy 222.160215 -408.919572) (xy 222.07193 -408.890965) (xy 222.029274 -408.87269) (xy 222.019332 -408.868884)
			(xy 221.998068 -408.868884) (xy 221.988126 -408.87269) (xy 221.945466 -408.890954) (xy 221.857177 -408.919546)
			(xy 221.766394 -408.938803) (xy 221.674101 -408.948515) (xy 221.6277 -408.949144) (xy 221.581298 -408.948515)
			(xy 221.489001 -408.938826) (xy 221.398215 -408.919572) (xy 221.30993 -408.890965) (xy 221.267274 -408.87269)
			(xy 221.257332 -408.868884) (xy 221.236068 -408.868884) (xy 221.226126 -408.87269) (xy 221.183466 -408.890954)
			(xy 221.095177 -408.919546) (xy 221.004394 -408.938803) (xy 220.912101 -408.948515) (xy 220.8657 -408.949144)
			(xy 220.819298 -408.948515) (xy 220.727001 -408.938826) (xy 220.636215 -408.919572) (xy 220.54793 -408.890965)
			(xy 220.505274 -408.87269) (xy 220.495332 -408.868884) (xy 220.474068 -408.868884) (xy 220.464126 -408.87269)
			(xy 220.421466 -408.890954) (xy 220.333177 -408.919546) (xy 220.242394 -408.938803) (xy 220.150101 -408.948515)
			(xy 220.1037 -408.949144) (xy 220.057298 -408.948515) (xy 219.965001 -408.938826) (xy 219.874215 -408.919572)
			(xy 219.78593 -408.890965) (xy 219.743274 -408.87269) (xy 219.733332 -408.868884) (xy 219.712068 -408.868884)
			(xy 219.702126 -408.87269) (xy 219.659466 -408.890954) (xy 219.571177 -408.919546) (xy 219.480394 -408.938803)
			(xy 219.388101 -408.948515) (xy 219.3417 -408.949144) (xy 219.295298 -408.948515) (xy 219.203001 -408.938826)
			(xy 219.112215 -408.919572) (xy 219.02393 -408.890965) (xy 218.981274 -408.87269) (xy 218.971332 -408.868884)
			(xy 218.950068 -408.868884) (xy 218.940126 -408.87269) (xy 218.897466 -408.890954) (xy 218.809177 -408.919546)
			(xy 218.718394 -408.938803) (xy 218.626101 -408.948515) (xy 218.5797 -408.949144) (xy 218.533298 -408.948515)
			(xy 218.441001 -408.938826) (xy 218.350215 -408.919572) (xy 218.26193 -408.890965) (xy 218.219274 -408.87269)
			(xy 218.209332 -408.868884) (xy 218.188068 -408.868884) (xy 218.178126 -408.87269) (xy 218.135466 -408.890954)
			(xy 218.047177 -408.919546) (xy 217.956394 -408.938803) (xy 217.864101 -408.948515) (xy 217.8177 -408.949144)
			(xy 217.776606 -408.948634) (xy 217.694769 -408.941052) (xy 217.613979 -408.925953) (xy 217.534928 -408.903466)
			(xy 217.458287 -408.873782) (xy 217.384712 -408.837155) (xy 217.31483 -408.793896) (xy 217.249236 -408.744376)
			(xy 217.18849 -408.689016) (xy 217.133109 -408.628288) (xy 217.083568 -408.56271) (xy 217.040286 -408.492841)
			(xy 217.003635 -408.419278) (xy 216.973926 -408.342647) (xy 216.951413 -408.263603) (xy 216.936288 -408.182819)
			(xy 216.92868 -408.100984) (xy 216.928192 -408.05989) (xy 213.373201 -408.05989) (xy 213.37267 -408.100487)
			(xy 213.365088 -408.182347) (xy 213.349987 -408.263158) (xy 213.327495 -408.342232) (xy 213.297804 -408.418893)
			(xy 213.261168 -408.492489) (xy 213.2179 -408.562391) (xy 213.168367 -408.628004) (xy 213.112992 -408.688767)
			(xy 213.052249 -408.744164) (xy 212.986654 -408.79372) (xy 212.916767 -408.837014) (xy 212.843184 -408.873676)
			(xy 212.766533 -408.903394) (xy 212.687468 -408.925914) (xy 212.606662 -408.941044) (xy 212.524805 -408.948656)
			(xy 212.4837 -408.949144) (xy 212.437298 -408.948515) (xy 212.345001 -408.938826) (xy 212.254215 -408.919572)
			(xy 212.16593 -408.890965) (xy 212.123274 -408.87269) (xy 212.113332 -408.868884) (xy 212.092068 -408.868884)
			(xy 212.082126 -408.87269) (xy 212.039466 -408.890954) (xy 211.951177 -408.919546) (xy 211.860394 -408.938803)
			(xy 211.768101 -408.948515) (xy 211.7217 -408.949144) (xy 211.675298 -408.948515) (xy 211.583001 -408.938826)
			(xy 211.492215 -408.919572) (xy 211.40393 -408.890965) (xy 211.361274 -408.87269) (xy 211.351332 -408.868884)
			(xy 211.330068 -408.868884) (xy 211.320126 -408.87269) (xy 211.277466 -408.890954) (xy 211.189177 -408.919546)
			(xy 211.098394 -408.938803) (xy 211.006101 -408.948515) (xy 210.9597 -408.949144) (xy 210.913298 -408.948515)
			(xy 210.821001 -408.938826) (xy 210.730215 -408.919572) (xy 210.64193 -408.890965) (xy 210.599274 -408.87269)
			(xy 210.589332 -408.868884) (xy 210.568068 -408.868884) (xy 210.558126 -408.87269) (xy 210.515466 -408.890954)
			(xy 210.427177 -408.919546) (xy 210.336394 -408.938803) (xy 210.244101 -408.948515) (xy 210.1977 -408.949144)
			(xy 210.151298 -408.948515) (xy 210.059001 -408.938826) (xy 209.968215 -408.919572) (xy 209.87993 -408.890965)
			(xy 209.837274 -408.87269) (xy 209.827332 -408.868884) (xy 209.806068 -408.868884) (xy 209.796126 -408.87269)
			(xy 209.753466 -408.890954) (xy 209.665177 -408.919546) (xy 209.574394 -408.938803) (xy 209.482101 -408.948515)
			(xy 209.4357 -408.949144) (xy 209.389298 -408.948515) (xy 209.297001 -408.938826) (xy 209.206215 -408.919572)
			(xy 209.11793 -408.890965) (xy 209.075274 -408.87269) (xy 209.065332 -408.868884) (xy 209.044068 -408.868884)
			(xy 209.034126 -408.87269) (xy 208.991466 -408.890954) (xy 208.903177 -408.919546) (xy 208.812394 -408.938803)
			(xy 208.720101 -408.948515) (xy 208.6737 -408.949144) (xy 208.627298 -408.948515) (xy 208.535001 -408.938826)
			(xy 208.444215 -408.919572) (xy 208.35593 -408.890965) (xy 208.313274 -408.87269) (xy 208.303332 -408.868884)
			(xy 208.282068 -408.868884) (xy 208.272126 -408.87269) (xy 208.229466 -408.890954) (xy 208.141177 -408.919546)
			(xy 208.050394 -408.938803) (xy 207.958101 -408.948515) (xy 207.9117 -408.949144) (xy 207.865298 -408.948515)
			(xy 207.773001 -408.938826) (xy 207.682215 -408.919572) (xy 207.59393 -408.890965) (xy 207.551274 -408.87269)
			(xy 207.541332 -408.868884) (xy 207.520068 -408.868884) (xy 207.510126 -408.87269) (xy 207.467466 -408.890954)
			(xy 207.379177 -408.919546) (xy 207.288394 -408.938803) (xy 207.196101 -408.948515) (xy 207.1497 -408.949144)
			(xy 207.108606 -408.948634) (xy 207.026769 -408.941052) (xy 206.945979 -408.925953) (xy 206.866928 -408.903466)
			(xy 206.790287 -408.873782) (xy 206.716712 -408.837155) (xy 206.64683 -408.793896) (xy 206.581236 -408.744376)
			(xy 206.52049 -408.689016) (xy 206.465109 -408.628288) (xy 206.415568 -408.56271) (xy 206.372286 -408.492841)
			(xy 206.335635 -408.419278) (xy 206.305926 -408.342647) (xy 206.283413 -408.263603) (xy 206.268288 -408.182819)
			(xy 206.26068 -408.100984) (xy 206.260192 -408.05989) (xy 201.943201 -408.05989) (xy 201.94267 -408.100487)
			(xy 201.935088 -408.182347) (xy 201.919987 -408.263158) (xy 201.897495 -408.342232) (xy 201.867804 -408.418893)
			(xy 201.831168 -408.492489) (xy 201.7879 -408.562391) (xy 201.738367 -408.628004) (xy 201.682992 -408.688767)
			(xy 201.622249 -408.744164) (xy 201.556654 -408.79372) (xy 201.486767 -408.837014) (xy 201.413184 -408.873676)
			(xy 201.336533 -408.903394) (xy 201.257468 -408.925914) (xy 201.176662 -408.941044) (xy 201.094805 -408.948656)
			(xy 201.0537 -408.949144) (xy 201.007298 -408.948515) (xy 200.915001 -408.938826) (xy 200.824215 -408.919572)
			(xy 200.73593 -408.890965) (xy 200.693274 -408.87269) (xy 200.683332 -408.868884) (xy 200.662068 -408.868884)
			(xy 200.652126 -408.87269) (xy 200.609466 -408.890954) (xy 200.521177 -408.919546) (xy 200.430394 -408.938803)
			(xy 200.338101 -408.948515) (xy 200.2917 -408.949144) (xy 200.245298 -408.948515) (xy 200.153001 -408.938826)
			(xy 200.062215 -408.919572) (xy 199.97393 -408.890965) (xy 199.931274 -408.87269) (xy 199.921332 -408.868884)
			(xy 199.900068 -408.868884) (xy 199.890126 -408.87269) (xy 199.847466 -408.890954) (xy 199.759177 -408.919546)
			(xy 199.668394 -408.938803) (xy 199.576101 -408.948515) (xy 199.5297 -408.949144) (xy 199.483298 -408.948515)
			(xy 199.391001 -408.938826) (xy 199.300215 -408.919572) (xy 199.21193 -408.890965) (xy 199.169274 -408.87269)
			(xy 199.159332 -408.868884) (xy 199.138068 -408.868884) (xy 199.128126 -408.87269) (xy 199.085466 -408.890954)
			(xy 198.997177 -408.919546) (xy 198.906394 -408.938803) (xy 198.814101 -408.948515) (xy 198.7677 -408.949144)
			(xy 198.721298 -408.948515) (xy 198.629001 -408.938826) (xy 198.538215 -408.919572) (xy 198.44993 -408.890965)
			(xy 198.407274 -408.87269) (xy 198.397332 -408.868884) (xy 198.376068 -408.868884) (xy 198.366126 -408.87269)
			(xy 198.323466 -408.890954) (xy 198.235177 -408.919546) (xy 198.144394 -408.938803) (xy 198.052101 -408.948515)
			(xy 198.0057 -408.949144) (xy 197.959298 -408.948515) (xy 197.867001 -408.938826) (xy 197.776215 -408.919572)
			(xy 197.68793 -408.890965) (xy 197.645274 -408.87269) (xy 197.635332 -408.868884) (xy 197.614068 -408.868884)
			(xy 197.604126 -408.87269) (xy 197.561466 -408.890954) (xy 197.473177 -408.919546) (xy 197.382394 -408.938803)
			(xy 197.290101 -408.948515) (xy 197.2437 -408.949144) (xy 197.20259 -408.948648) (xy 197.120722 -408.94106)
			(xy 197.039903 -408.92595) (xy 196.960824 -408.903446) (xy 196.884158 -408.873741) (xy 196.810562 -408.837087)
			(xy 196.740661 -408.793799) (xy 196.675054 -408.744244) (xy 196.6143 -408.688846) (xy 196.558917 -408.628078)
			(xy 196.509378 -408.562459) (xy 196.466106 -408.492548) (xy 196.429471 -408.418942) (xy 196.399784 -408.342269)
			(xy 196.3773 -408.263184) (xy 196.36221 -408.182362) (xy 196.354642 -408.100492) (xy 196.354192 -408.059382)
			(xy 190.372573 -408.059382) (xy 190.373 -408.091894) (xy 190.373 -408.092402) (xy 190.372489 -408.133508)
			(xy 190.364905 -408.215368) (xy 190.349802 -408.296181) (xy 190.327308 -408.375255) (xy 190.297616 -408.451917)
			(xy 190.260978 -408.525513) (xy 190.217707 -408.595415) (xy 190.168173 -408.661028) (xy 190.112797 -408.721791)
			(xy 190.052051 -408.777187) (xy 189.986455 -408.826743) (xy 189.916566 -408.870037) (xy 189.842982 -408.906699)
			(xy 189.76633 -408.936416) (xy 189.687263 -408.958936) (xy 189.606456 -408.974065) (xy 189.524598 -408.981676)
			(xy 189.483492 -408.982164) (xy 189.43709 -408.981537) (xy 189.344793 -408.971846) (xy 189.254007 -408.952593)
			(xy 189.165722 -408.923985) (xy 189.123066 -408.90571) (xy 189.113124 -408.901904) (xy 189.09186 -408.901904)
			(xy 189.081918 -408.90571) (xy 189.039259 -408.923977) (xy 188.95097 -408.952569) (xy 188.860187 -408.971824)
			(xy 188.767893 -408.981535) (xy 188.721492 -408.982164) (xy 188.67509 -408.981537) (xy 188.582793 -408.971846)
			(xy 188.492007 -408.952593) (xy 188.403722 -408.923985) (xy 188.361066 -408.90571) (xy 188.351124 -408.901904)
			(xy 188.32986 -408.901904) (xy 188.319918 -408.90571) (xy 188.277259 -408.923977) (xy 188.18897 -408.952569)
			(xy 188.098187 -408.971824) (xy 188.005893 -408.981535) (xy 187.959492 -408.982164) (xy 187.91309 -408.981537)
			(xy 187.820793 -408.971846) (xy 187.730007 -408.952593) (xy 187.641722 -408.923985) (xy 187.599066 -408.90571)
			(xy 187.589124 -408.901904) (xy 187.56786 -408.901904) (xy 187.557918 -408.90571) (xy 187.515259 -408.923977)
			(xy 187.42697 -408.952569) (xy 187.336187 -408.971824) (xy 187.243893 -408.981535) (xy 187.197492 -408.982164)
			(xy 187.15109 -408.981537) (xy 187.058793 -408.971846) (xy 186.968007 -408.952593) (xy 186.879722 -408.923985)
			(xy 186.837066 -408.90571) (xy 186.827124 -408.901904) (xy 186.80586 -408.901904) (xy 186.795918 -408.90571)
			(xy 186.753259 -408.923977) (xy 186.66497 -408.952569) (xy 186.574187 -408.971824) (xy 186.481893 -408.981535)
			(xy 186.435492 -408.982164) (xy 186.38909 -408.981537) (xy 186.296793 -408.971846) (xy 186.206007 -408.952593)
			(xy 186.117722 -408.923985) (xy 186.075066 -408.90571) (xy 186.065124 -408.901904) (xy 186.04386 -408.901904)
			(xy 186.033918 -408.90571) (xy 185.991259 -408.923977) (xy 185.90297 -408.952569) (xy 185.812187 -408.971824)
			(xy 185.719893 -408.981535) (xy 185.673492 -408.982164) (xy 185.63238 -408.981755) (xy 185.550507 -408.974166)
			(xy 185.469683 -408.959054) (xy 185.3906 -408.936547) (xy 185.31393 -408.906837) (xy 185.24033 -408.870179)
			(xy 185.170427 -408.826885) (xy 185.104818 -408.777325) (xy 185.044063 -408.721921) (xy 184.98868 -408.661146)
			(xy 184.939142 -408.59552) (xy 184.895872 -408.525602) (xy 184.859239 -408.451989) (xy 184.829556 -408.37531)
			(xy 184.807076 -408.296219) (xy 184.791992 -408.21539) (xy 184.784431 -408.133514) (xy 184.783984 -408.092402)
			(xy 184.784568 -408.046006) (xy 184.794213 -407.953718) (xy 184.813409 -407.862934) (xy 184.841946 -407.774641)
			(xy 184.860184 -407.731976) (xy 184.863989 -407.722034) (xy 184.86399 -407.70077) (xy 184.860184 -407.690828)
			(xy 184.841939 -407.648166) (xy 184.813395 -407.559873) (xy 184.794202 -407.469088) (xy 184.784569 -407.376798)
			(xy 184.783984 -407.330402) (xy 184.784407 -407.290634) (xy 184.791436 -407.211411) (xy 184.805517 -407.133132)
			(xy 184.826539 -407.056426) (xy 184.854333 -406.981906) (xy 184.871106 -406.945846) (xy 184.875438 -406.935345)
			(xy 184.875439 -406.912659) (xy 184.871106 -406.902158) (xy 184.854347 -406.866093) (xy 184.826573 -406.791567)
			(xy 184.805556 -406.714862) (xy 184.791462 -406.636588) (xy 184.784405 -406.557369) (xy 184.783984 -406.517602)
			(xy 184.784568 -406.471206) (xy 184.794213 -406.378918) (xy 184.813409 -406.288134) (xy 184.841946 -406.199841)
			(xy 184.860184 -406.157176) (xy 184.863989 -406.147234) (xy 184.86399 -406.12597) (xy 184.860184 -406.116028)
			(xy 184.841939 -406.073366) (xy 184.813395 -405.985073) (xy 184.794202 -405.894288) (xy 184.784569 -405.801998)
			(xy 184.783984 -405.755602) (xy 184.784568 -405.709206) (xy 184.794213 -405.616918) (xy 184.813409 -405.526134)
			(xy 184.841946 -405.437841) (xy 184.860184 -405.395176) (xy 184.863989 -405.385234) (xy 184.86399 -405.36397)
			(xy 184.860184 -405.354028) (xy 184.841962 -405.311425) (xy 184.813445 -405.223258) (xy 184.794252 -405.132602)
			(xy 184.784592 -405.040442) (xy 184.783984 -404.99411) (xy 184.783984 -404.993602) (xy 184.784497 -404.950127)
			(xy 184.792981 -404.863592) (xy 184.809868 -404.778298) (xy 184.834996 -404.695058) (xy 184.868127 -404.614668)
			(xy 184.908943 -404.537893) (xy 184.957056 -404.465468) (xy 185.012005 -404.398082) (xy 185.073268 -404.33638)
			(xy 185.140259 -404.28095) (xy 185.212338 -404.232321) (xy 185.288819 -404.190956) (xy 185.368971 -404.157252)
			(xy 185.452028 -404.131529) (xy 185.5372 -404.114033) (xy 185.623672 -404.104931) (xy 185.667142 -404.104094)
			(xy 185.677625 -404.103496) (xy 185.6968 -404.094996) (xy 185.710988 -404.07955) (xy 185.714894 -404.069804)
			(xy 185.745882 -403.978872) (xy 185.748725 -403.96876) (xy 185.74698 -403.947853) (xy 185.737043 -403.929376)
			(xy 185.729118 -403.922484) (xy 185.70573 -403.903812) (xy 185.661243 -403.863772) (xy 185.640218 -403.842474)
			(xy 185.632756 -403.835439) (xy 185.613887 -403.827446) (xy 185.603642 -403.82698) (xy 185.530998 -403.82698)
			(xy 185.520746 -403.827411) (xy 185.501872 -403.835417) (xy 185.494422 -403.842474) (xy 185.463025 -403.87402)
			(xy 185.394968 -403.931383) (xy 185.321521 -403.981662) (xy 185.24342 -404.024354) (xy 185.161446 -404.059031)
			(xy 185.076418 -404.085348) (xy 184.989186 -404.103041) (xy 184.900624 -404.111933) (xy 184.85612 -404.112476)
			(xy 184.815024 -404.112015) (xy 184.733183 -404.104434) (xy 184.652391 -404.089335) (xy 184.573336 -404.066848)
			(xy 184.496692 -404.037162) (xy 184.423115 -404.000533) (xy 184.35323 -403.957272) (xy 184.287634 -403.907749)
			(xy 184.226887 -403.852384) (xy 184.171506 -403.791652) (xy 184.121965 -403.72607) (xy 184.078685 -403.656197)
			(xy 184.042035 -403.582629) (xy 184.012329 -403.505994) (xy 183.98982 -403.426945) (xy 183.9747 -403.346156)
			(xy 183.967097 -403.264318) (xy 183.966612 -403.223222) (xy 174.680622 -403.223222) (xy 174.717549 -403.310307)
			(xy 174.77977 -403.477384) (xy 174.834486 -403.647068) (xy 174.881588 -403.819021) (xy 174.920984 -403.992901)
			(xy 174.952595 -404.168364) (xy 174.976359 -404.34506) (xy 174.992227 -404.52264) (xy 175.000169 -404.70075)
			(xy 175.000666 -404.789894) (xy 175.000169 -404.879038) (xy 174.992227 -405.057148) (xy 174.976359 -405.234728)
			(xy 174.952595 -405.411424) (xy 174.920984 -405.586887) (xy 174.881588 -405.760767) (xy 174.834486 -405.93272)
			(xy 174.77977 -406.102404) (xy 174.717549 -406.269481) (xy 174.647948 -406.433622) (xy 174.571103 -406.594498)
			(xy 174.487169 -406.751792) (xy 174.396311 -406.905191) (xy 174.298709 -407.05439) (xy 174.194558 -407.199093)
			(xy 174.084065 -407.339013) (xy 173.967448 -407.473872) (xy 173.844939 -407.603402) (xy 173.716782 -407.727346)
			(xy 173.583231 -407.845458) (xy 173.444551 -407.957503) (xy 173.301017 -408.06326) (xy 173.152914 -408.162517)
			(xy 173.000537 -408.255079) (xy 172.844188 -408.34076) (xy 172.684177 -408.419392) (xy 172.520823 -408.490818)
			(xy 172.354448 -408.554896) (xy 172.185385 -408.611498) (xy 172.013968 -408.660514) (xy 171.840537 -408.701844)
			(xy 171.665437 -408.735408) (xy 171.489017 -408.761138) (xy 171.311625 -408.778984) (xy 171.133614 -408.78891)
			(xy 170.955337 -408.790896) (xy 170.77715 -408.784939) (xy 170.599404 -408.771049) (xy 170.422454 -408.749256)
			(xy 170.24665 -408.719602) (xy 170.072342 -408.682145) (xy 169.899875 -408.636961) (xy 169.729592 -408.584139)
			(xy 169.561831 -408.523783) (xy 169.396926 -408.456015) (xy 169.235203 -408.380967) (xy 169.076984 -408.29879)
			(xy 168.922583 -408.209647) (xy 168.772306 -408.113713) (xy 168.626451 -408.011181) (xy 168.485309 -407.902253)
			(xy 168.34916 -407.787146) (xy 168.218273 -407.666088) (xy 168.092909 -407.539319) (xy 167.973316 -407.407092)
			(xy 167.859733 -407.269669) (xy 167.752384 -407.127322) (xy 167.651483 -406.980334) (xy 167.55723 -406.828998)
			(xy 167.469812 -406.673613) (xy 167.389402 -406.514488) (xy 167.316161 -406.351939) (xy 167.250234 -406.186289)
			(xy 167.191751 -406.017867) (xy 167.140829 -405.847006) (xy 167.097569 -405.674047) (xy 167.062057 -405.499332)
			(xy 167.034363 -405.323208) (xy 167.014542 -405.146026) (xy 167.002634 -404.968137) (xy 166.998662 -404.789894)
			(xy 161.904774 -404.789894) (xy 161.889384 -404.799785) (xy 161.839805 -404.822428) (xy 161.787508 -404.837784)
			(xy 161.733558 -404.845542) (xy 161.706306 -404.846028) (xy 160.842706 -404.846028) (xy 160.815454 -404.845525)
			(xy 160.761506 -404.837769) (xy 160.70921 -404.822415) (xy 160.659631 -404.799774) (xy 160.61378 -404.770307)
			(xy 160.572589 -404.734616) (xy 160.536896 -404.693425) (xy 160.507429 -404.647574) (xy 160.484788 -404.597996)
			(xy 160.469432 -404.5457) (xy 160.461675 -404.491752) (xy 159.024165 -404.491752) (xy 159.024165 -404.491756)
			(xy 159.016407 -404.545713) (xy 159.001048 -404.598016) (xy 158.978402 -404.647601) (xy 158.948929 -404.693458)
			(xy 158.91323 -404.734654) (xy 158.872031 -404.77035) (xy 158.826171 -404.799818) (xy 158.776584 -404.82246)
			(xy 158.724279 -404.837814) (xy 158.670322 -404.845567) (xy 158.643066 -404.846028) (xy 157.779466 -404.846028)
			(xy 157.752218 -404.845499) (xy 157.698277 -404.837739) (xy 157.645989 -404.822382) (xy 157.596418 -404.79974)
			(xy 157.550575 -404.770275) (xy 157.509391 -404.734585) (xy 157.473705 -404.693398) (xy 157.444243 -404.647552)
			(xy 157.421606 -404.597979) (xy 157.406253 -404.54569) (xy 157.398498 -404.491748) (xy 155.960842 -404.491748)
			(xy 155.960842 -404.491751) (xy 155.953086 -404.5457) (xy 155.937731 -404.597995) (xy 155.915091 -404.647573)
			(xy 155.885626 -404.693425) (xy 155.849935 -404.734617) (xy 155.808746 -404.77031) (xy 155.762896 -404.799778)
			(xy 155.71332 -404.822422) (xy 155.661025 -404.83778) (xy 155.607077 -404.84554) (xy 155.579826 -404.846028)
			(xy 154.716226 -404.846028) (xy 154.688973 -404.845526) (xy 154.635022 -404.837773) (xy 154.582724 -404.82242)
			(xy 154.533143 -404.79978) (xy 154.487289 -404.770314) (xy 154.446096 -404.734623) (xy 154.410401 -404.693431)
			(xy 154.380932 -404.647579) (xy 154.358289 -404.598) (xy 154.342933 -404.545703) (xy 154.335175 -404.491753)
			(xy 152.897665 -404.491753) (xy 152.897665 -404.491755) (xy 152.889907 -404.54571) (xy 152.87455 -404.598012)
			(xy 152.851905 -404.647595) (xy 152.822434 -404.693452) (xy 152.786737 -404.734647) (xy 152.745541 -404.770343)
			(xy 152.699683 -404.799812) (xy 152.650099 -404.822455) (xy 152.597796 -404.83781) (xy 152.543841 -404.845566)
			(xy 152.516586 -404.846028) (xy 151.652986 -404.846028) (xy 151.625737 -404.845501) (xy 151.571794 -404.837743)
			(xy 151.519503 -404.822388) (xy 151.46993 -404.799747) (xy 151.424084 -404.770282) (xy 151.382898 -404.734592)
			(xy 151.34721 -404.693404) (xy 151.317746 -404.647557) (xy 151.295108 -404.597984) (xy 151.279754 -404.545693)
			(xy 151.271998 -404.491749) (xy 149.834342 -404.491749) (xy 149.834342 -404.491751) (xy 149.826587 -404.545697)
			(xy 149.811233 -404.597991) (xy 149.788594 -404.647568) (xy 149.75913 -404.693418) (xy 149.723442 -404.734609)
			(xy 149.682255 -404.770303) (xy 149.636408 -404.799772) (xy 149.586834 -404.822417) (xy 149.534542 -404.837777)
			(xy 149.480597 -404.845539) (xy 149.453346 -404.846028) (xy 148.589746 -404.846028) (xy 148.562492 -404.845528)
			(xy 148.508539 -404.837777) (xy 148.456239 -404.822425) (xy 148.406655 -404.799787) (xy 148.360799 -404.770321)
			(xy 148.319603 -404.73463) (xy 148.283906 -404.693438) (xy 148.254435 -404.647585) (xy 148.231791 -404.598004)
			(xy 148.216433 -404.545706) (xy 148.208675 -404.491754) (xy 146.771142 -404.491754) (xy 146.763385 -404.545702)
			(xy 146.74803 -404.597999) (xy 146.725388 -404.647579) (xy 146.695921 -404.693431) (xy 146.660228 -404.734624)
			(xy 146.619036 -404.770317) (xy 146.573184 -404.799785) (xy 146.523605 -404.822428) (xy 146.471308 -404.837784)
			(xy 146.417358 -404.845542) (xy 146.390106 -404.846028) (xy 145.526506 -404.846028) (xy 145.499254 -404.845525)
			(xy 145.445306 -404.837769) (xy 145.39301 -404.822415) (xy 145.343431 -404.799774) (xy 145.29758 -404.770307)
			(xy 145.256389 -404.734616) (xy 145.220696 -404.693425) (xy 145.191229 -404.647574) (xy 145.168588 -404.597996)
			(xy 145.153232 -404.5457) (xy 145.145475 -404.491752) (xy 143.707965 -404.491752) (xy 143.707965 -404.491756)
			(xy 143.700207 -404.545713) (xy 143.684848 -404.598016) (xy 143.662202 -404.647601) (xy 143.632729 -404.693458)
			(xy 143.59703 -404.734654) (xy 143.555831 -404.77035) (xy 143.509971 -404.799818) (xy 143.460384 -404.82246)
			(xy 143.408079 -404.837814) (xy 143.354122 -404.845567) (xy 143.326866 -404.846028) (xy 142.463266 -404.846028)
			(xy 142.436018 -404.845499) (xy 142.382077 -404.837739) (xy 142.329789 -404.822382) (xy 142.280218 -404.79974)
			(xy 142.234375 -404.770275) (xy 142.193191 -404.734585) (xy 142.157505 -404.693398) (xy 142.128043 -404.647552)
			(xy 142.105406 -404.597979) (xy 142.090053 -404.54569) (xy 142.082298 -404.491748) (xy 140.644642 -404.491748)
			(xy 140.644642 -404.491751) (xy 140.636886 -404.5457) (xy 140.621531 -404.597995) (xy 140.598891 -404.647573)
			(xy 140.569426 -404.693425) (xy 140.533735 -404.734617) (xy 140.492546 -404.77031) (xy 140.446696 -404.799778)
			(xy 140.39712 -404.822422) (xy 140.344825 -404.83778) (xy 140.290877 -404.84554) (xy 140.263626 -404.846028)
			(xy 139.400026 -404.846028) (xy 139.372773 -404.845526) (xy 139.318822 -404.837773) (xy 139.266524 -404.82242)
			(xy 139.216943 -404.79978) (xy 139.171089 -404.770314) (xy 139.129896 -404.734623) (xy 139.094201 -404.693431)
			(xy 139.064732 -404.647579) (xy 139.042089 -404.598) (xy 139.026733 -404.545703) (xy 139.018975 -404.491753)
			(xy 137.581465 -404.491753) (xy 137.581465 -404.491755) (xy 137.573707 -404.54571) (xy 137.55835 -404.598012)
			(xy 137.535705 -404.647595) (xy 137.506234 -404.693452) (xy 137.470537 -404.734647) (xy 137.429341 -404.770343)
			(xy 137.383483 -404.799812) (xy 137.333899 -404.822455) (xy 137.281596 -404.83781) (xy 137.227641 -404.845566)
			(xy 137.200386 -404.846028) (xy 136.336786 -404.846028) (xy 136.309537 -404.845501) (xy 136.255594 -404.837743)
			(xy 136.203303 -404.822388) (xy 136.15373 -404.799747) (xy 136.107884 -404.770282) (xy 136.066698 -404.734592)
			(xy 136.03101 -404.693404) (xy 136.001546 -404.647557) (xy 135.978908 -404.597984) (xy 135.963554 -404.545693)
			(xy 135.955798 -404.491749) (xy 134.518142 -404.491749) (xy 134.518142 -404.491751) (xy 134.510387 -404.545697)
			(xy 134.495033 -404.597991) (xy 134.472394 -404.647568) (xy 134.44293 -404.693418) (xy 134.407242 -404.734609)
			(xy 134.366055 -404.770303) (xy 134.320208 -404.799772) (xy 134.270634 -404.822417) (xy 134.218342 -404.837777)
			(xy 134.164397 -404.845539) (xy 134.137146 -404.846028) (xy 133.273546 -404.846028) (xy 133.246292 -404.845528)
			(xy 133.192339 -404.837777) (xy 133.140039 -404.822425) (xy 133.090455 -404.799787) (xy 133.044599 -404.770321)
			(xy 133.003403 -404.73463) (xy 132.967706 -404.693438) (xy 132.938235 -404.647585) (xy 132.915591 -404.598004)
			(xy 132.900233 -404.545706) (xy 132.892475 -404.491754) (xy 131.454942 -404.491754) (xy 131.447185 -404.545702)
			(xy 131.43183 -404.597999) (xy 131.409188 -404.647579) (xy 131.379721 -404.693431) (xy 131.344028 -404.734624)
			(xy 131.302836 -404.770317) (xy 131.256984 -404.799785) (xy 131.207405 -404.822428) (xy 131.155108 -404.837784)
			(xy 131.101158 -404.845542) (xy 131.073906 -404.846028) (xy 130.210306 -404.846028) (xy 130.183054 -404.845525)
			(xy 130.129106 -404.837769) (xy 130.07681 -404.822415) (xy 130.027231 -404.799774) (xy 129.98138 -404.770307)
			(xy 129.940189 -404.734616) (xy 129.904496 -404.693425) (xy 129.875029 -404.647574) (xy 129.852388 -404.597996)
			(xy 129.837032 -404.5457) (xy 129.829275 -404.491752) (xy 128.391765 -404.491752) (xy 128.391765 -404.491756)
			(xy 128.384007 -404.545713) (xy 128.368648 -404.598016) (xy 128.346002 -404.647601) (xy 128.316529 -404.693458)
			(xy 128.28083 -404.734654) (xy 128.239631 -404.77035) (xy 128.193771 -404.799818) (xy 128.144184 -404.82246)
			(xy 128.091879 -404.837814) (xy 128.037922 -404.845567) (xy 128.010666 -404.846028) (xy 127.147066 -404.846028)
			(xy 127.119818 -404.845499) (xy 127.065877 -404.837739) (xy 127.013589 -404.822382) (xy 126.964018 -404.79974)
			(xy 126.918175 -404.770275) (xy 126.876991 -404.734585) (xy 126.841305 -404.693398) (xy 126.811843 -404.647552)
			(xy 126.789206 -404.597979) (xy 126.773853 -404.54569) (xy 126.766098 -404.491748) (xy 125.328442 -404.491748)
			(xy 125.328442 -404.491751) (xy 125.320686 -404.5457) (xy 125.305331 -404.597995) (xy 125.282691 -404.647573)
			(xy 125.253226 -404.693425) (xy 125.217535 -404.734617) (xy 125.176346 -404.77031) (xy 125.130496 -404.799778)
			(xy 125.08092 -404.822422) (xy 125.028625 -404.83778) (xy 124.974677 -404.84554) (xy 124.947426 -404.846028)
			(xy 124.083826 -404.846028) (xy 124.056573 -404.845526) (xy 124.002622 -404.837773) (xy 123.950324 -404.82242)
			(xy 123.900743 -404.79978) (xy 123.854889 -404.770314) (xy 123.813696 -404.734623) (xy 123.778001 -404.693431)
			(xy 123.748532 -404.647579) (xy 123.725889 -404.598) (xy 123.710533 -404.545703) (xy 123.702775 -404.491753)
			(xy 122.265265 -404.491753) (xy 122.265265 -404.491755) (xy 122.257507 -404.54571) (xy 122.24215 -404.598012)
			(xy 122.219505 -404.647595) (xy 122.190034 -404.693452) (xy 122.154337 -404.734647) (xy 122.113141 -404.770343)
			(xy 122.067283 -404.799812) (xy 122.017699 -404.822455) (xy 121.965396 -404.83781) (xy 121.911441 -404.845566)
			(xy 121.884186 -404.846028) (xy 121.020586 -404.846028) (xy 120.993337 -404.845501) (xy 120.939394 -404.837743)
			(xy 120.887103 -404.822388) (xy 120.83753 -404.799747) (xy 120.791684 -404.770282) (xy 120.750498 -404.734592)
			(xy 120.71481 -404.693404) (xy 120.685346 -404.647557) (xy 120.662708 -404.597984) (xy 120.647354 -404.545693)
			(xy 120.639598 -404.491749) (xy 119.201942 -404.491749) (xy 119.201942 -404.491751) (xy 119.194187 -404.545697)
			(xy 119.178833 -404.597991) (xy 119.156194 -404.647568) (xy 119.12673 -404.693418) (xy 119.091042 -404.734609)
			(xy 119.049855 -404.770303) (xy 119.004008 -404.799772) (xy 118.954434 -404.822417) (xy 118.902142 -404.837777)
			(xy 118.848197 -404.845539) (xy 118.820946 -404.846028) (xy 117.957346 -404.846028) (xy 117.930092 -404.845528)
			(xy 117.876139 -404.837777) (xy 117.823839 -404.822425) (xy 117.774255 -404.799787) (xy 117.728399 -404.770321)
			(xy 117.687203 -404.73463) (xy 117.651506 -404.693438) (xy 117.622035 -404.647585) (xy 117.599391 -404.598004)
			(xy 117.584033 -404.545706) (xy 117.576275 -404.491754) (xy 116.138742 -404.491754) (xy 116.130985 -404.545702)
			(xy 116.11563 -404.597999) (xy 116.092988 -404.647579) (xy 116.063521 -404.693431) (xy 116.027828 -404.734624)
			(xy 115.986636 -404.770317) (xy 115.940784 -404.799785) (xy 115.891205 -404.822428) (xy 115.838908 -404.837784)
			(xy 115.784958 -404.845542) (xy 115.757706 -404.846028) (xy 114.894106 -404.846028) (xy 114.866854 -404.845525)
			(xy 114.812906 -404.837769) (xy 114.76061 -404.822415) (xy 114.711031 -404.799774) (xy 114.66518 -404.770307)
			(xy 114.623989 -404.734616) (xy 114.588296 -404.693425) (xy 114.558829 -404.647574) (xy 114.536188 -404.597996)
			(xy 114.520832 -404.5457) (xy 114.513075 -404.491752) (xy 94.987465 -404.491752) (xy 94.987465 -404.491756)
			(xy 94.979707 -404.545713) (xy 94.964348 -404.598016) (xy 94.941702 -404.647602) (xy 94.912229 -404.693459)
			(xy 94.876529 -404.734655) (xy 94.83533 -404.77035) (xy 94.78947 -404.799819) (xy 94.739883 -404.822461)
			(xy 94.687578 -404.837814) (xy 94.63362 -404.845568) (xy 94.606364 -404.846028) (xy 93.742764 -404.846028)
			(xy 93.715516 -404.845499) (xy 93.661575 -404.837739) (xy 93.609287 -404.822382) (xy 93.559717 -404.79974)
			(xy 93.513874 -404.770274) (xy 93.47269 -404.734584) (xy 93.437004 -404.693397) (xy 93.407543 -404.647551)
			(xy 93.384906 -404.597979) (xy 93.369553 -404.54569) (xy 93.361798 -404.491748) (xy 91.924142 -404.491748)
			(xy 91.924142 -404.491752) (xy 91.916386 -404.5457) (xy 91.901031 -404.597996) (xy 91.878391 -404.647574)
			(xy 91.848925 -404.693425) (xy 91.813234 -404.734617) (xy 91.772045 -404.770311) (xy 91.726195 -404.799779)
			(xy 91.676618 -404.822423) (xy 91.624324 -404.837781) (xy 91.570376 -404.845541) (xy 91.543124 -404.846028)
			(xy 90.679524 -404.846028) (xy 90.652271 -404.845526) (xy 90.598321 -404.837773) (xy 90.546023 -404.822419)
			(xy 90.496442 -404.799779) (xy 90.450588 -404.770314) (xy 90.409395 -404.734622) (xy 90.373701 -404.693431)
			(xy 90.344232 -404.647579) (xy 90.321589 -404.598) (xy 90.306233 -404.545703) (xy 90.298475 -404.491753)
			(xy 88.860965 -404.491753) (xy 88.860965 -404.491755) (xy 88.853207 -404.54571) (xy 88.83785 -404.598012)
			(xy 88.815205 -404.647596) (xy 88.785734 -404.693452) (xy 88.750036 -404.734648) (xy 88.70884 -404.770343)
			(xy 88.662982 -404.799812) (xy 88.613397 -404.822455) (xy 88.561095 -404.837811) (xy 88.507139 -404.845566)
			(xy 88.479884 -404.846028) (xy 87.616284 -404.846028) (xy 87.589035 -404.845501) (xy 87.535092 -404.837743)
			(xy 87.482802 -404.822387) (xy 87.433229 -404.799746) (xy 87.387383 -404.770281) (xy 87.346197 -404.734591)
			(xy 87.310509 -404.693404) (xy 87.281046 -404.647557) (xy 87.258407 -404.597983) (xy 87.243054 -404.545692)
			(xy 87.235298 -404.491749) (xy 85.797642 -404.491749) (xy 85.797642 -404.491751) (xy 85.789887 -404.545697)
			(xy 85.774533 -404.597991) (xy 85.751894 -404.647568) (xy 85.72243 -404.693419) (xy 85.686741 -404.73461)
			(xy 85.645554 -404.770304) (xy 85.599707 -404.799773) (xy 85.550133 -404.822417) (xy 85.49784 -404.837777)
			(xy 85.443895 -404.845539) (xy 85.416644 -404.846028) (xy 84.553044 -404.846028) (xy 84.525791 -404.845528)
			(xy 84.471838 -404.837776) (xy 84.419537 -404.822425) (xy 84.369954 -404.799786) (xy 84.324098 -404.770321)
			(xy 84.282902 -404.734629) (xy 84.247206 -404.693437) (xy 84.217735 -404.647584) (xy 84.195091 -404.598004)
			(xy 84.179733 -404.545705) (xy 84.171975 -404.491753) (xy 82.734442 -404.491753) (xy 82.726685 -404.545703)
			(xy 82.71133 -404.598) (xy 82.688688 -404.647579) (xy 82.65922 -404.693432) (xy 82.623527 -404.734624)
			(xy 82.582335 -404.770318) (xy 82.536483 -404.799786) (xy 82.486904 -404.822428) (xy 82.434607 -404.837785)
			(xy 82.380656 -404.845542) (xy 82.353404 -404.846028) (xy 81.489804 -404.846028) (xy 81.462552 -404.845525)
			(xy 81.408604 -404.837769) (xy 81.356308 -404.822414) (xy 81.30673 -404.799773) (xy 81.260879 -404.770307)
			(xy 81.219688 -404.734615) (xy 81.183996 -404.693424) (xy 81.154529 -404.647573) (xy 81.131887 -404.597995)
			(xy 81.116532 -404.5457) (xy 81.108775 -404.491752) (xy 79.671265 -404.491752) (xy 79.671265 -404.491756)
			(xy 79.663507 -404.545713) (xy 79.648148 -404.598016) (xy 79.625502 -404.647602) (xy 79.596029 -404.693459)
			(xy 79.560329 -404.734655) (xy 79.51913 -404.77035) (xy 79.47327 -404.799819) (xy 79.423683 -404.822461)
			(xy 79.371378 -404.837814) (xy 79.31742 -404.845568) (xy 79.290164 -404.846028) (xy 78.426564 -404.846028)
			(xy 78.399316 -404.845499) (xy 78.345375 -404.837739) (xy 78.293087 -404.822382) (xy 78.243517 -404.79974)
			(xy 78.197674 -404.770274) (xy 78.15649 -404.734584) (xy 78.120804 -404.693397) (xy 78.091343 -404.647551)
			(xy 78.068706 -404.597979) (xy 78.053353 -404.54569) (xy 78.045598 -404.491748) (xy 76.607942 -404.491748)
			(xy 76.607942 -404.491752) (xy 76.600186 -404.5457) (xy 76.584831 -404.597996) (xy 76.562191 -404.647574)
			(xy 76.532725 -404.693425) (xy 76.497034 -404.734617) (xy 76.455845 -404.770311) (xy 76.409995 -404.799779)
			(xy 76.360418 -404.822423) (xy 76.308124 -404.837781) (xy 76.254176 -404.845541) (xy 76.226924 -404.846028)
			(xy 75.363324 -404.846028) (xy 75.336071 -404.845526) (xy 75.282121 -404.837773) (xy 75.229823 -404.822419)
			(xy 75.180242 -404.799779) (xy 75.134388 -404.770314) (xy 75.093195 -404.734622) (xy 75.057501 -404.693431)
			(xy 75.028032 -404.647579) (xy 75.005389 -404.598) (xy 74.990033 -404.545703) (xy 74.982275 -404.491753)
			(xy 73.544765 -404.491753) (xy 73.544765 -404.491755) (xy 73.537007 -404.54571) (xy 73.52165 -404.598012)
			(xy 73.499005 -404.647596) (xy 73.469534 -404.693452) (xy 73.433836 -404.734648) (xy 73.39264 -404.770343)
			(xy 73.346782 -404.799812) (xy 73.297197 -404.822455) (xy 73.244895 -404.837811) (xy 73.190939 -404.845566)
			(xy 73.163684 -404.846028) (xy 72.300084 -404.846028) (xy 72.272835 -404.845501) (xy 72.218892 -404.837743)
			(xy 72.166602 -404.822387) (xy 72.117029 -404.799746) (xy 72.071183 -404.770281) (xy 72.029997 -404.734591)
			(xy 71.994309 -404.693404) (xy 71.964846 -404.647557) (xy 71.942207 -404.597983) (xy 71.926854 -404.545692)
			(xy 71.919098 -404.491749) (xy 70.481442 -404.491749) (xy 70.481442 -404.491751) (xy 70.473687 -404.545697)
			(xy 70.458333 -404.597991) (xy 70.435694 -404.647568) (xy 70.40623 -404.693419) (xy 70.370541 -404.73461)
			(xy 70.329354 -404.770304) (xy 70.283507 -404.799773) (xy 70.233933 -404.822417) (xy 70.18164 -404.837777)
			(xy 70.127695 -404.845539) (xy 70.100444 -404.846028) (xy 69.236844 -404.846028) (xy 69.209591 -404.845528)
			(xy 69.155638 -404.837776) (xy 69.103337 -404.822425) (xy 69.053754 -404.799786) (xy 69.007898 -404.770321)
			(xy 68.966702 -404.734629) (xy 68.931006 -404.693437) (xy 68.901535 -404.647584) (xy 68.878891 -404.598004)
			(xy 68.863533 -404.545705) (xy 68.855775 -404.491753) (xy 67.418242 -404.491753) (xy 67.410485 -404.545703)
			(xy 67.39513 -404.598) (xy 67.372488 -404.647579) (xy 67.34302 -404.693432) (xy 67.307327 -404.734624)
			(xy 67.266135 -404.770318) (xy 67.220283 -404.799786) (xy 67.170704 -404.822428) (xy 67.118407 -404.837785)
			(xy 67.064456 -404.845542) (xy 67.037204 -404.846028) (xy 66.173604 -404.846028) (xy 66.146352 -404.845525)
			(xy 66.092404 -404.837769) (xy 66.040108 -404.822414) (xy 65.99053 -404.799773) (xy 65.944679 -404.770307)
			(xy 65.903488 -404.734615) (xy 65.867796 -404.693424) (xy 65.838329 -404.647573) (xy 65.815687 -404.597995)
			(xy 65.800332 -404.5457) (xy 65.792575 -404.491752) (xy 64.355065 -404.491752) (xy 64.355065 -404.491756)
			(xy 64.347307 -404.545713) (xy 64.331948 -404.598016) (xy 64.309302 -404.647602) (xy 64.279829 -404.693459)
			(xy 64.244129 -404.734655) (xy 64.20293 -404.77035) (xy 64.15707 -404.799819) (xy 64.107483 -404.822461)
			(xy 64.055178 -404.837814) (xy 64.00122 -404.845568) (xy 63.973964 -404.846028) (xy 63.110364 -404.846028)
			(xy 63.083116 -404.845499) (xy 63.029175 -404.837739) (xy 62.976887 -404.822382) (xy 62.927317 -404.79974)
			(xy 62.881474 -404.770274) (xy 62.84029 -404.734584) (xy 62.804604 -404.693397) (xy 62.775143 -404.647551)
			(xy 62.752506 -404.597979) (xy 62.737153 -404.54569) (xy 62.729398 -404.491748) (xy 61.291742 -404.491748)
			(xy 61.291742 -404.491752) (xy 61.283986 -404.5457) (xy 61.268631 -404.597996) (xy 61.245991 -404.647574)
			(xy 61.216525 -404.693425) (xy 61.180834 -404.734617) (xy 61.139645 -404.770311) (xy 61.093795 -404.799779)
			(xy 61.044218 -404.822423) (xy 60.991924 -404.837781) (xy 60.937976 -404.845541) (xy 60.910724 -404.846028)
			(xy 60.047124 -404.846028) (xy 60.019871 -404.845526) (xy 59.965921 -404.837773) (xy 59.913623 -404.822419)
			(xy 59.864042 -404.799779) (xy 59.818188 -404.770314) (xy 59.776995 -404.734622) (xy 59.741301 -404.693431)
			(xy 59.711832 -404.647579) (xy 59.689189 -404.598) (xy 59.673833 -404.545703) (xy 59.666075 -404.491753)
			(xy 58.228565 -404.491753) (xy 58.228565 -404.491755) (xy 58.220807 -404.54571) (xy 58.20545 -404.598012)
			(xy 58.182805 -404.647596) (xy 58.153334 -404.693452) (xy 58.117636 -404.734648) (xy 58.07644 -404.770343)
			(xy 58.030582 -404.799812) (xy 57.980997 -404.822455) (xy 57.928695 -404.837811) (xy 57.874739 -404.845566)
			(xy 57.847484 -404.846028) (xy 56.983884 -404.846028) (xy 56.956635 -404.845501) (xy 56.902692 -404.837743)
			(xy 56.850402 -404.822387) (xy 56.800829 -404.799746) (xy 56.754983 -404.770281) (xy 56.713797 -404.734591)
			(xy 56.678109 -404.693404) (xy 56.648646 -404.647557) (xy 56.626007 -404.597983) (xy 56.610654 -404.545692)
			(xy 56.602898 -404.491749) (xy 55.165242 -404.491749) (xy 55.165242 -404.491751) (xy 55.157487 -404.545697)
			(xy 55.142133 -404.597991) (xy 55.119494 -404.647568) (xy 55.09003 -404.693419) (xy 55.054341 -404.73461)
			(xy 55.013154 -404.770304) (xy 54.967307 -404.799773) (xy 54.917733 -404.822417) (xy 54.86544 -404.837777)
			(xy 54.811495 -404.845539) (xy 54.784244 -404.846028) (xy 53.920644 -404.846028) (xy 53.893391 -404.845528)
			(xy 53.839438 -404.837776) (xy 53.787137 -404.822425) (xy 53.737554 -404.799786) (xy 53.691698 -404.770321)
			(xy 53.650502 -404.734629) (xy 53.614806 -404.693437) (xy 53.585335 -404.647584) (xy 53.562691 -404.598004)
			(xy 53.547333 -404.545705) (xy 53.539575 -404.491753) (xy 52.102042 -404.491753) (xy 52.094285 -404.545703)
			(xy 52.07893 -404.598) (xy 52.056288 -404.647579) (xy 52.02682 -404.693432) (xy 51.991127 -404.734624)
			(xy 51.949935 -404.770318) (xy 51.904083 -404.799786) (xy 51.854504 -404.822428) (xy 51.802207 -404.837785)
			(xy 51.748256 -404.845542) (xy 51.721004 -404.846028) (xy 50.857404 -404.846028) (xy 50.830152 -404.845525)
			(xy 50.776204 -404.837769) (xy 50.723908 -404.822414) (xy 50.67433 -404.799773) (xy 50.628479 -404.770307)
			(xy 50.587288 -404.734615) (xy 50.551596 -404.693424) (xy 50.522129 -404.647573) (xy 50.499487 -404.597995)
			(xy 50.484132 -404.5457) (xy 50.476375 -404.491752) (xy 49.038865 -404.491752) (xy 49.038865 -404.491756)
			(xy 49.031107 -404.545713) (xy 49.015748 -404.598016) (xy 48.993102 -404.647602) (xy 48.963629 -404.693459)
			(xy 48.927929 -404.734655) (xy 48.88673 -404.77035) (xy 48.84087 -404.799819) (xy 48.791283 -404.822461)
			(xy 48.738978 -404.837814) (xy 48.68502 -404.845568) (xy 48.657764 -404.846028) (xy 47.794164 -404.846028)
			(xy 47.766916 -404.845499) (xy 47.712975 -404.837739) (xy 47.660687 -404.822382) (xy 47.611117 -404.79974)
			(xy 47.565274 -404.770274) (xy 47.52409 -404.734584) (xy 47.488404 -404.693397) (xy 47.458943 -404.647551)
			(xy 47.436306 -404.597979) (xy 47.420953 -404.54569) (xy 47.413198 -404.491748) (xy 45.559703 -404.491748)
			(xy 45.562463 -404.52264) (xy 45.570405 -404.70075) (xy 45.570902 -404.789894) (xy 45.570405 -404.879038)
			(xy 45.562463 -405.057148) (xy 45.546595 -405.234728) (xy 45.522831 -405.411424) (xy 45.49122 -405.586887)
			(xy 45.479552 -405.638385) (xy 104.009796 -405.638385) (xy 104.013672 -405.584006) (xy 104.025246 -405.530732)
			(xy 104.044281 -405.479646) (xy 104.070391 -405.431789) (xy 104.103044 -405.388132) (xy 104.121966 -405.368506)
			(xy 104.732582 -404.757636) (xy 104.75423 -404.736857) (xy 104.802784 -404.701606) (xy 104.856253 -404.67438)
			(xy 104.91332 -404.655848) (xy 104.972583 -404.646465) (xy 105.002584 -404.645876) (xy 105.029856 -404.646316)
			(xy 105.083846 -404.654077) (xy 105.136181 -404.669444) (xy 105.185797 -404.692102) (xy 105.231683 -404.721592)
			(xy 105.272904 -404.757312) (xy 105.308622 -404.798535) (xy 105.338108 -404.844422) (xy 105.360764 -404.894039)
			(xy 105.376127 -404.946376) (xy 105.383885 -405.000366) (xy 105.384346 -405.027638) (xy 105.383744 -405.057639)
			(xy 105.374371 -405.116904) (xy 105.355845 -405.173974) (xy 105.328623 -405.227445) (xy 105.29971 -405.267273)
			(xy 106.824184 -405.267273) (xy 106.824184 -405.212727) (xy 106.831947 -405.158735) (xy 106.847315 -405.106398)
			(xy 106.869976 -405.05678) (xy 106.899467 -405.010893) (xy 106.935189 -404.969671) (xy 106.976414 -404.933951)
			(xy 107.022303 -404.904463) (xy 107.071922 -404.881806) (xy 107.12426 -404.866441) (xy 107.178252 -404.858682)
			(xy 107.205526 -404.85822) (xy 108.069126 -404.85822) (xy 108.096393 -404.858744) (xy 108.150371 -404.866508)
			(xy 108.202695 -404.881875) (xy 108.2523 -404.904532) (xy 108.298175 -404.934017) (xy 108.339388 -404.969731)
			(xy 108.375098 -405.010946) (xy 108.404581 -405.056823) (xy 108.427234 -405.106429) (xy 108.442597 -405.158754)
			(xy 108.450358 -405.212733) (xy 108.450358 -405.267267) (xy 108.442597 -405.321246) (xy 108.427234 -405.373571)
			(xy 108.404581 -405.423177) (xy 108.375098 -405.469054) (xy 108.339388 -405.510269) (xy 108.298175 -405.545983)
			(xy 108.2523 -405.575468) (xy 108.202695 -405.598125) (xy 108.150371 -405.613492) (xy 108.096393 -405.621256)
			(xy 108.069126 -405.621744) (xy 107.205526 -405.621744) (xy 107.178252 -405.621318) (xy 107.12426 -405.613559)
			(xy 107.071922 -405.598194) (xy 107.022303 -405.575537) (xy 106.976414 -405.546049) (xy 106.935189 -405.510329)
			(xy 106.899467 -405.469107) (xy 106.869976 -405.42322) (xy 106.847315 -405.373602) (xy 106.831947 -405.321265)
			(xy 106.824184 -405.267273) (xy 105.29971 -405.267273) (xy 105.293374 -405.276001) (xy 105.272586 -405.29764)
			(xy 104.661716 -405.908256) (xy 104.642167 -405.927256) (xy 104.598511 -405.959909) (xy 104.550654 -405.986019)
			(xy 104.499568 -406.005054) (xy 104.446294 -406.016628) (xy 104.391915 -406.020504) (xy 104.337538 -406.016603)
			(xy 104.284269 -406.005006) (xy 104.233192 -405.985949) (xy 104.185346 -405.959818) (xy 104.141704 -405.927145)
			(xy 104.103155 -405.888596) (xy 104.070482 -405.844954) (xy 104.044351 -405.797108) (xy 104.025294 -405.746031)
			(xy 104.013697 -405.692762) (xy 104.009796 -405.638385) (xy 45.479552 -405.638385) (xy 45.451824 -405.760767)
			(xy 45.404722 -405.93272) (xy 45.350006 -406.102404) (xy 45.287785 -406.269481) (xy 45.218184 -406.433622)
			(xy 45.141339 -406.594498) (xy 45.057405 -406.751792) (xy 44.966547 -406.905191) (xy 44.883756 -407.031749)
			(xy 48.944798 -407.031749) (xy 48.944798 -406.977251) (xy 48.952554 -406.923308) (xy 48.967907 -406.871017)
			(xy 48.990546 -406.821443) (xy 49.020009 -406.775596) (xy 49.055697 -406.734409) (xy 49.096883 -406.698719)
			(xy 49.142729 -406.669254) (xy 49.192302 -406.646613) (xy 49.244592 -406.631257) (xy 49.298535 -406.623499)
			(xy 49.325784 -406.623012) (xy 50.189384 -406.623012) (xy 50.216639 -406.623434) (xy 50.270595 -406.631189)
			(xy 50.322897 -406.646545) (xy 50.372482 -406.669188) (xy 50.41834 -406.698657) (xy 50.459536 -406.734352)
			(xy 50.495234 -406.775548) (xy 50.524705 -406.821404) (xy 50.54735 -406.870988) (xy 50.562707 -406.92329)
			(xy 50.570465 -406.977245) (xy 50.570465 -407.031753) (xy 52.007975 -407.031753) (xy 52.007975 -406.977247)
			(xy 52.015733 -406.923297) (xy 52.031089 -406.871) (xy 52.053732 -406.821421) (xy 52.083201 -406.775569)
			(xy 52.118895 -406.734378) (xy 52.160088 -406.698686) (xy 52.205942 -406.669221) (xy 52.255523 -406.646581)
			(xy 52.307821 -406.631227) (xy 52.361771 -406.623474) (xy 52.389024 -406.623012) (xy 53.252624 -406.623012)
			(xy 53.279876 -406.623459) (xy 53.333824 -406.631219) (xy 53.386118 -406.646577) (xy 53.435695 -406.669221)
			(xy 53.481545 -406.698689) (xy 53.522734 -406.734383) (xy 53.558425 -406.775575) (xy 53.587891 -406.821426)
			(xy 53.610531 -406.871004) (xy 53.625886 -406.9233) (xy 53.633642 -406.977248) (xy 53.633642 -407.031748)
			(xy 55.071298 -407.031748) (xy 55.071298 -406.977252) (xy 55.079053 -406.92331) (xy 55.094406 -406.871021)
			(xy 55.117043 -406.821449) (xy 55.146504 -406.775603) (xy 55.18219 -406.734416) (xy 55.223374 -406.698726)
			(xy 55.269217 -406.66926) (xy 55.318787 -406.646618) (xy 55.371075 -406.631261) (xy 55.425016 -406.623501)
			(xy 55.452264 -406.623012) (xy 56.315864 -406.623012) (xy 56.34312 -406.623432) (xy 56.397078 -406.631186)
			(xy 56.449383 -406.646539) (xy 56.49897 -406.669181) (xy 56.54483 -406.69865) (xy 56.586029 -406.734345)
			(xy 56.621729 -406.775541) (xy 56.651202 -406.821398) (xy 56.673848 -406.870984) (xy 56.689207 -406.923287)
			(xy 56.696965 -406.977244) (xy 56.696965 -407.031752) (xy 58.134475 -407.031752) (xy 58.134475 -406.977248)
			(xy 58.142232 -406.9233) (xy 58.157587 -406.871005) (xy 58.180229 -406.821427) (xy 58.209696 -406.775576)
			(xy 58.245388 -406.734385) (xy 58.286579 -406.698693) (xy 58.33243 -406.669227) (xy 58.382008 -406.646586)
			(xy 58.434304 -406.631231) (xy 58.488252 -406.623475) (xy 58.515504 -406.623012) (xy 59.379104 -406.623012)
			(xy 59.406356 -406.623458) (xy 59.460307 -406.631215) (xy 59.512604 -406.646572) (xy 59.562183 -406.669214)
			(xy 59.608035 -406.698682) (xy 59.649227 -406.734376) (xy 59.68492 -406.775568) (xy 59.714388 -406.821421)
			(xy 59.73703 -406.871) (xy 59.752385 -406.923297) (xy 59.760142 -406.977248) (xy 59.760142 -407.031752)
			(xy 59.760142 -407.031753) (xy 61.197675 -407.031753) (xy 61.197675 -406.977247) (xy 61.205433 -406.923295)
			(xy 61.220791 -406.870996) (xy 61.243435 -406.821416) (xy 61.272906 -406.775563) (xy 61.308602 -406.734371)
			(xy 61.349798 -406.698679) (xy 61.395654 -406.669214) (xy 61.445237 -406.646575) (xy 61.497538 -406.631224)
			(xy 61.551491 -406.623472) (xy 61.578744 -406.623012) (xy 62.442344 -406.623012) (xy 62.469595 -406.623461)
			(xy 62.52354 -406.631223) (xy 62.575833 -406.646583) (xy 62.625407 -406.669227) (xy 62.671254 -406.698696)
			(xy 62.712441 -406.73439) (xy 62.74813 -406.775581) (xy 62.777594 -406.821432) (xy 62.800233 -406.871009)
			(xy 62.815587 -406.923303) (xy 62.823342 -406.977249) (xy 62.823342 -407.031749) (xy 64.260998 -407.031749)
			(xy 64.260998 -406.977251) (xy 64.268754 -406.923308) (xy 64.284107 -406.871017) (xy 64.306746 -406.821443)
			(xy 64.336209 -406.775596) (xy 64.371897 -406.734409) (xy 64.413083 -406.698719) (xy 64.458929 -406.669254)
			(xy 64.508502 -406.646613) (xy 64.560792 -406.631257) (xy 64.614735 -406.623499) (xy 64.641984 -406.623012)
			(xy 65.505584 -406.623012) (xy 65.532839 -406.623434) (xy 65.586795 -406.631189) (xy 65.639097 -406.646545)
			(xy 65.688682 -406.669188) (xy 65.73454 -406.698657) (xy 65.775736 -406.734352) (xy 65.811434 -406.775548)
			(xy 65.840905 -406.821404) (xy 65.86355 -406.870988) (xy 65.878907 -406.92329) (xy 65.886665 -406.977245)
			(xy 65.886665 -407.031753) (xy 67.324175 -407.031753) (xy 67.324175 -406.977247) (xy 67.331933 -406.923297)
			(xy 67.347289 -406.871) (xy 67.369932 -406.821421) (xy 67.399401 -406.775569) (xy 67.435095 -406.734378)
			(xy 67.476288 -406.698686) (xy 67.522142 -406.669221) (xy 67.571723 -406.646581) (xy 67.624021 -406.631227)
			(xy 67.677971 -406.623474) (xy 67.705224 -406.623012) (xy 68.568824 -406.623012) (xy 68.596076 -406.623459)
			(xy 68.650024 -406.631219) (xy 68.702318 -406.646577) (xy 68.751895 -406.669221) (xy 68.797745 -406.698689)
			(xy 68.838934 -406.734383) (xy 68.874625 -406.775575) (xy 68.904091 -406.821426) (xy 68.926731 -406.871004)
			(xy 68.942086 -406.9233) (xy 68.949842 -406.977248) (xy 68.949842 -407.031748) (xy 70.387498 -407.031748)
			(xy 70.387498 -406.977252) (xy 70.395253 -406.92331) (xy 70.410606 -406.871021) (xy 70.433243 -406.821449)
			(xy 70.462704 -406.775603) (xy 70.49839 -406.734416) (xy 70.539574 -406.698726) (xy 70.585417 -406.66926)
			(xy 70.634987 -406.646618) (xy 70.687275 -406.631261) (xy 70.741216 -406.623501) (xy 70.768464 -406.623012)
			(xy 71.632064 -406.623012) (xy 71.65932 -406.623432) (xy 71.713278 -406.631186) (xy 71.765583 -406.646539)
			(xy 71.81517 -406.669181) (xy 71.86103 -406.69865) (xy 71.902229 -406.734345) (xy 71.937929 -406.775541)
			(xy 71.967402 -406.821398) (xy 71.990048 -406.870984) (xy 72.005407 -406.923287) (xy 72.013165 -406.977244)
			(xy 72.013165 -407.031752) (xy 73.450675 -407.031752) (xy 73.450675 -406.977248) (xy 73.458432 -406.9233)
			(xy 73.473787 -406.871005) (xy 73.496429 -406.821427) (xy 73.525896 -406.775576) (xy 73.561588 -406.734385)
			(xy 73.602779 -406.698693) (xy 73.64863 -406.669227) (xy 73.698208 -406.646586) (xy 73.750504 -406.631231)
			(xy 73.804452 -406.623475) (xy 73.831704 -406.623012) (xy 74.695304 -406.623012) (xy 74.722556 -406.623458)
			(xy 74.776507 -406.631215) (xy 74.828804 -406.646572) (xy 74.878383 -406.669214) (xy 74.924235 -406.698682)
			(xy 74.965427 -406.734376) (xy 75.00112 -406.775568) (xy 75.030588 -406.821421) (xy 75.05323 -406.871)
			(xy 75.068585 -406.923297) (xy 75.076342 -406.977248) (xy 75.076342 -407.031752) (xy 75.076342 -407.031753)
			(xy 76.513875 -407.031753) (xy 76.513875 -406.977247) (xy 76.521633 -406.923295) (xy 76.536991 -406.870996)
			(xy 76.559635 -406.821416) (xy 76.589106 -406.775563) (xy 76.624802 -406.734371) (xy 76.665998 -406.698679)
			(xy 76.711854 -406.669214) (xy 76.761437 -406.646575) (xy 76.813738 -406.631224) (xy 76.867691 -406.623472)
			(xy 76.894944 -406.623012) (xy 77.758544 -406.623012) (xy 77.785795 -406.623461) (xy 77.83974 -406.631223)
			(xy 77.892033 -406.646583) (xy 77.941607 -406.669227) (xy 77.987454 -406.698696) (xy 78.028641 -406.73439)
			(xy 78.06433 -406.775581) (xy 78.093794 -406.821432) (xy 78.116433 -406.871009) (xy 78.131787 -406.923303)
			(xy 78.139542 -406.977249) (xy 78.139542 -407.031749) (xy 79.577198 -407.031749) (xy 79.577198 -406.977251)
			(xy 79.584954 -406.923308) (xy 79.600307 -406.871017) (xy 79.622946 -406.821443) (xy 79.652409 -406.775596)
			(xy 79.688097 -406.734409) (xy 79.729283 -406.698719) (xy 79.775129 -406.669254) (xy 79.824702 -406.646613)
			(xy 79.876992 -406.631257) (xy 79.930935 -406.623499) (xy 79.958184 -406.623012) (xy 80.821784 -406.623012)
			(xy 80.849039 -406.623434) (xy 80.902995 -406.631189) (xy 80.955297 -406.646545) (xy 81.004882 -406.669188)
			(xy 81.05074 -406.698657) (xy 81.091936 -406.734352) (xy 81.127634 -406.775548) (xy 81.157105 -406.821404)
			(xy 81.17975 -406.870988) (xy 81.195107 -406.92329) (xy 81.202865 -406.977245) (xy 81.202865 -407.031753)
			(xy 82.640375 -407.031753) (xy 82.640375 -406.977247) (xy 82.648133 -406.923297) (xy 82.663489 -406.871)
			(xy 82.686132 -406.821421) (xy 82.715601 -406.775569) (xy 82.751295 -406.734378) (xy 82.792488 -406.698686)
			(xy 82.838342 -406.669221) (xy 82.887923 -406.646581) (xy 82.940221 -406.631227) (xy 82.994171 -406.623474)
			(xy 83.021424 -406.623012) (xy 83.885024 -406.623012) (xy 83.912276 -406.623459) (xy 83.966224 -406.631219)
			(xy 84.018518 -406.646577) (xy 84.068095 -406.669221) (xy 84.113945 -406.698689) (xy 84.155134 -406.734383)
			(xy 84.190825 -406.775575) (xy 84.220291 -406.821426) (xy 84.242931 -406.871004) (xy 84.258286 -406.9233)
			(xy 84.266042 -406.977248) (xy 84.266042 -407.031748) (xy 85.703698 -407.031748) (xy 85.703698 -406.977252)
			(xy 85.711453 -406.92331) (xy 85.726806 -406.871021) (xy 85.749443 -406.821449) (xy 85.778904 -406.775603)
			(xy 85.81459 -406.734416) (xy 85.855774 -406.698726) (xy 85.901617 -406.66926) (xy 85.951187 -406.646618)
			(xy 86.003475 -406.631261) (xy 86.057416 -406.623501) (xy 86.084664 -406.623012) (xy 86.948264 -406.623012)
			(xy 86.97552 -406.623432) (xy 87.029478 -406.631186) (xy 87.081783 -406.646539) (xy 87.13137 -406.669181)
			(xy 87.17723 -406.69865) (xy 87.218429 -406.734345) (xy 87.254129 -406.775541) (xy 87.283602 -406.821398)
			(xy 87.306248 -406.870984) (xy 87.321607 -406.923287) (xy 87.329365 -406.977244) (xy 87.329365 -407.031752)
			(xy 88.766875 -407.031752) (xy 88.766875 -406.977248) (xy 88.774632 -406.9233) (xy 88.789987 -406.871005)
			(xy 88.812629 -406.821427) (xy 88.842096 -406.775576) (xy 88.877788 -406.734385) (xy 88.918979 -406.698693)
			(xy 88.96483 -406.669227) (xy 89.014408 -406.646586) (xy 89.066704 -406.631231) (xy 89.120652 -406.623475)
			(xy 89.147904 -406.623012) (xy 90.011504 -406.623012) (xy 90.038756 -406.623458) (xy 90.092707 -406.631215)
			(xy 90.145004 -406.646572) (xy 90.194583 -406.669214) (xy 90.240435 -406.698682) (xy 90.281627 -406.734376)
			(xy 90.31732 -406.775568) (xy 90.346788 -406.821421) (xy 90.36943 -406.871) (xy 90.384785 -406.923297)
			(xy 90.392542 -406.977248) (xy 90.392542 -407.031752) (xy 90.392542 -407.031753) (xy 91.830075 -407.031753)
			(xy 91.830075 -406.977247) (xy 91.837833 -406.923295) (xy 91.853191 -406.870996) (xy 91.875835 -406.821416)
			(xy 91.905306 -406.775563) (xy 91.941002 -406.734371) (xy 91.982198 -406.698679) (xy 92.028054 -406.669214)
			(xy 92.077637 -406.646575) (xy 92.129938 -406.631224) (xy 92.183891 -406.623472) (xy 92.211144 -406.623012)
			(xy 93.074744 -406.623012) (xy 93.101995 -406.623461) (xy 93.15594 -406.631223) (xy 93.208233 -406.646583)
			(xy 93.257807 -406.669227) (xy 93.303654 -406.698696) (xy 93.344841 -406.73439) (xy 93.38053 -406.775581)
			(xy 93.409994 -406.821432) (xy 93.432633 -406.871009) (xy 93.447987 -406.923303) (xy 93.455742 -406.977249)
			(xy 93.455742 -407.031749) (xy 94.893398 -407.031749) (xy 94.893398 -406.977251) (xy 94.901154 -406.923308)
			(xy 94.916507 -406.871017) (xy 94.939146 -406.821443) (xy 94.968609 -406.775596) (xy 95.004297 -406.734409)
			(xy 95.045483 -406.698719) (xy 95.091329 -406.669254) (xy 95.140902 -406.646613) (xy 95.193192 -406.631257)
			(xy 95.247135 -406.623499) (xy 95.274384 -406.623012) (xy 96.137984 -406.623012) (xy 96.165239 -406.623434)
			(xy 96.219195 -406.631189) (xy 96.271497 -406.646545) (xy 96.321082 -406.669188) (xy 96.36694 -406.698657)
			(xy 96.408136 -406.734352) (xy 96.443834 -406.775548) (xy 96.473305 -406.821404) (xy 96.49595 -406.870988)
			(xy 96.511307 -406.92329) (xy 96.519065 -406.977245) (xy 96.519065 -407.031753) (xy 116.044675 -407.031753)
			(xy 116.044675 -406.977247) (xy 116.052433 -406.923297) (xy 116.067789 -406.871) (xy 116.090432 -406.821421)
			(xy 116.119901 -406.775569) (xy 116.155596 -406.734377) (xy 116.196789 -406.698686) (xy 116.242643 -406.66922)
			(xy 116.292224 -406.64658) (xy 116.344522 -406.631227) (xy 116.398473 -406.623474) (xy 116.425726 -406.623012)
			(xy 117.289326 -406.623012) (xy 117.316577 -406.62346) (xy 117.370525 -406.63122) (xy 117.42282 -406.646578)
			(xy 117.472396 -406.669222) (xy 117.518246 -406.69869) (xy 117.559435 -406.734383) (xy 117.595126 -406.775575)
			(xy 117.624591 -406.821427) (xy 117.647231 -406.871005) (xy 117.662586 -406.9233) (xy 117.670342 -406.977249)
			(xy 117.670342 -407.031748) (xy 119.107998 -407.031748) (xy 119.107998 -406.977252) (xy 119.115753 -406.92331)
			(xy 119.131106 -406.871021) (xy 119.153743 -406.821448) (xy 119.183205 -406.775602) (xy 119.218891 -406.734415)
			(xy 119.260075 -406.698725) (xy 119.305918 -406.66926) (xy 119.355489 -406.646618) (xy 119.407777 -406.631261)
			(xy 119.461718 -406.623501) (xy 119.488966 -406.623012) (xy 120.352566 -406.623012) (xy 120.379822 -406.623433)
			(xy 120.433779 -406.631186) (xy 120.486084 -406.64654) (xy 120.535671 -406.669182) (xy 120.581531 -406.69865)
			(xy 120.62273 -406.734346) (xy 120.658429 -406.775542) (xy 120.687902 -406.821399) (xy 120.710548 -406.870984)
			(xy 120.725907 -406.923287) (xy 120.733665 -406.977244) (xy 120.733665 -407.031752) (xy 122.171175 -407.031752)
			(xy 122.171175 -406.977248) (xy 122.178932 -406.9233) (xy 122.194288 -406.871004) (xy 122.216929 -406.821426)
			(xy 122.246396 -406.775575) (xy 122.282089 -406.734384) (xy 122.32328 -406.698693) (xy 122.369131 -406.669226)
			(xy 122.41871 -406.646585) (xy 122.471006 -406.631231) (xy 122.524954 -406.623475) (xy 122.552206 -406.623012)
			(xy 123.415806 -406.623012) (xy 123.443058 -406.623458) (xy 123.497008 -406.631216) (xy 123.549305 -406.646572)
			(xy 123.598884 -406.669215) (xy 123.644736 -406.698683) (xy 123.685928 -406.734376) (xy 123.721621 -406.775569)
			(xy 123.751088 -406.821421) (xy 123.77373 -406.871001) (xy 123.789085 -406.923298) (xy 123.796842 -406.977248)
			(xy 123.796842 -407.031752) (xy 123.796842 -407.031754) (xy 125.234375 -407.031754) (xy 125.234375 -406.977246)
			(xy 125.242133 -406.923294) (xy 125.257491 -406.870996) (xy 125.280135 -406.821415) (xy 125.309606 -406.775562)
			(xy 125.345303 -406.73437) (xy 125.386499 -406.698679) (xy 125.432355 -406.669213) (xy 125.481939 -406.646575)
			(xy 125.534239 -406.631223) (xy 125.588192 -406.623472) (xy 125.615446 -406.623012) (xy 126.479046 -406.623012)
			(xy 126.506297 -406.623461) (xy 126.560242 -406.631223) (xy 126.612534 -406.646583) (xy 126.662108 -406.669228)
			(xy 126.707955 -406.698697) (xy 126.749142 -406.734391) (xy 126.78483 -406.775582) (xy 126.814294 -406.821432)
			(xy 126.836933 -406.871009) (xy 126.852287 -406.923303) (xy 126.860042 -406.977249) (xy 126.860042 -407.031749)
			(xy 128.297698 -407.031749) (xy 128.297698 -406.977251) (xy 128.305454 -406.923307) (xy 128.320808 -406.871016)
			(xy 128.343446 -406.821443) (xy 128.37291 -406.775596) (xy 128.408598 -406.734408) (xy 128.449784 -406.698718)
			(xy 128.49563 -406.669253) (xy 128.545203 -406.646612) (xy 128.597494 -406.631257) (xy 128.651437 -406.623499)
			(xy 128.678686 -406.623012) (xy 129.542286 -406.623012) (xy 129.569541 -406.623434) (xy 129.623496 -406.63119)
			(xy 129.675799 -406.646545) (xy 129.725383 -406.669188) (xy 129.771241 -406.698657) (xy 129.812437 -406.734353)
			(xy 129.848134 -406.775548) (xy 129.877605 -406.821405) (xy 129.90025 -406.870988) (xy 129.915607 -406.92329)
			(xy 129.923365 -406.977245) (xy 129.923365 -407.031753) (xy 131.360875 -407.031753) (xy 131.360875 -406.977247)
			(xy 131.368633 -406.923297) (xy 131.383989 -406.871) (xy 131.406632 -406.821421) (xy 131.436101 -406.775569)
			(xy 131.471796 -406.734377) (xy 131.512989 -406.698686) (xy 131.558843 -406.66922) (xy 131.608424 -406.64658)
			(xy 131.660722 -406.631227) (xy 131.714673 -406.623474) (xy 131.741926 -406.623012) (xy 132.605526 -406.623012)
			(xy 132.632777 -406.62346) (xy 132.686725 -406.63122) (xy 132.73902 -406.646578) (xy 132.788596 -406.669222)
			(xy 132.834446 -406.69869) (xy 132.875635 -406.734383) (xy 132.911326 -406.775575) (xy 132.940791 -406.821427)
			(xy 132.963431 -406.871005) (xy 132.978786 -406.9233) (xy 132.986542 -406.977249) (xy 132.986542 -407.031748)
			(xy 134.424198 -407.031748) (xy 134.424198 -406.977252) (xy 134.431953 -406.92331) (xy 134.447306 -406.871021)
			(xy 134.469943 -406.821448) (xy 134.499405 -406.775602) (xy 134.535091 -406.734415) (xy 134.576275 -406.698725)
			(xy 134.622118 -406.66926) (xy 134.671689 -406.646618) (xy 134.723977 -406.631261) (xy 134.777918 -406.623501)
			(xy 134.805166 -406.623012) (xy 135.668766 -406.623012) (xy 135.696022 -406.623433) (xy 135.749979 -406.631186)
			(xy 135.802284 -406.64654) (xy 135.851871 -406.669182) (xy 135.897731 -406.69865) (xy 135.93893 -406.734346)
			(xy 135.974629 -406.775542) (xy 136.004102 -406.821399) (xy 136.026748 -406.870984) (xy 136.042107 -406.923287)
			(xy 136.049865 -406.977244) (xy 136.049865 -407.031752) (xy 137.487375 -407.031752) (xy 137.487375 -406.977248)
			(xy 137.495132 -406.9233) (xy 137.510488 -406.871004) (xy 137.533129 -406.821426) (xy 137.562596 -406.775575)
			(xy 137.598289 -406.734384) (xy 137.63948 -406.698693) (xy 137.685331 -406.669226) (xy 137.73491 -406.646585)
			(xy 137.787206 -406.631231) (xy 137.841154 -406.623475) (xy 137.868406 -406.623012) (xy 138.732006 -406.623012)
			(xy 138.759258 -406.623458) (xy 138.813208 -406.631216) (xy 138.865505 -406.646572) (xy 138.915084 -406.669215)
			(xy 138.960936 -406.698683) (xy 139.002128 -406.734376) (xy 139.037821 -406.775569) (xy 139.067288 -406.821421)
			(xy 139.08993 -406.871001) (xy 139.105285 -406.923298) (xy 139.113042 -406.977248) (xy 139.113042 -407.031752)
			(xy 139.113042 -407.031754) (xy 140.550575 -407.031754) (xy 140.550575 -406.977246) (xy 140.558333 -406.923294)
			(xy 140.573691 -406.870996) (xy 140.596335 -406.821415) (xy 140.625806 -406.775562) (xy 140.661503 -406.73437)
			(xy 140.702699 -406.698679) (xy 140.748555 -406.669213) (xy 140.798139 -406.646575) (xy 140.850439 -406.631223)
			(xy 140.904392 -406.623472) (xy 140.931646 -406.623012) (xy 141.795246 -406.623012) (xy 141.822497 -406.623461)
			(xy 141.876442 -406.631223) (xy 141.928734 -406.646583) (xy 141.978308 -406.669228) (xy 142.024155 -406.698697)
			(xy 142.065342 -406.734391) (xy 142.10103 -406.775582) (xy 142.130494 -406.821432) (xy 142.153133 -406.871009)
			(xy 142.168487 -406.923303) (xy 142.176242 -406.977249) (xy 142.176242 -407.031749) (xy 143.613898 -407.031749)
			(xy 143.613898 -406.977251) (xy 143.621654 -406.923307) (xy 143.637008 -406.871016) (xy 143.659646 -406.821443)
			(xy 143.68911 -406.775596) (xy 143.724798 -406.734408) (xy 143.765984 -406.698718) (xy 143.81183 -406.669253)
			(xy 143.861403 -406.646612) (xy 143.913694 -406.631257) (xy 143.967637 -406.623499) (xy 143.994886 -406.623012)
			(xy 144.858486 -406.623012) (xy 144.885741 -406.623434) (xy 144.939696 -406.63119) (xy 144.991999 -406.646545)
			(xy 145.041583 -406.669188) (xy 145.087441 -406.698657) (xy 145.128637 -406.734353) (xy 145.164334 -406.775548)
			(xy 145.193805 -406.821405) (xy 145.21645 -406.870988) (xy 145.231807 -406.92329) (xy 145.239565 -406.977245)
			(xy 145.239565 -407.031753) (xy 146.677075 -407.031753) (xy 146.677075 -406.977247) (xy 146.684833 -406.923297)
			(xy 146.700189 -406.871) (xy 146.722832 -406.821421) (xy 146.752301 -406.775569) (xy 146.787996 -406.734377)
			(xy 146.829189 -406.698686) (xy 146.875043 -406.66922) (xy 146.924624 -406.64658) (xy 146.976922 -406.631227)
			(xy 147.030873 -406.623474) (xy 147.058126 -406.623012) (xy 147.921726 -406.623012) (xy 147.948977 -406.62346)
			(xy 148.002925 -406.63122) (xy 148.05522 -406.646578) (xy 148.104796 -406.669222) (xy 148.150646 -406.69869)
			(xy 148.191835 -406.734383) (xy 148.227526 -406.775575) (xy 148.256991 -406.821427) (xy 148.279631 -406.871005)
			(xy 148.294986 -406.9233) (xy 148.302742 -406.977249) (xy 148.302742 -407.031748) (xy 149.740398 -407.031748)
			(xy 149.740398 -406.977252) (xy 149.748153 -406.92331) (xy 149.763506 -406.871021) (xy 149.786143 -406.821448)
			(xy 149.815605 -406.775602) (xy 149.851291 -406.734415) (xy 149.892475 -406.698725) (xy 149.938318 -406.66926)
			(xy 149.987889 -406.646618) (xy 150.040177 -406.631261) (xy 150.094118 -406.623501) (xy 150.121366 -406.623012)
			(xy 150.984966 -406.623012) (xy 151.012222 -406.623433) (xy 151.066179 -406.631186) (xy 151.118484 -406.64654)
			(xy 151.168071 -406.669182) (xy 151.213931 -406.69865) (xy 151.25513 -406.734346) (xy 151.290829 -406.775542)
			(xy 151.320302 -406.821399) (xy 151.342948 -406.870984) (xy 151.358307 -406.923287) (xy 151.366065 -406.977244)
			(xy 151.366065 -407.031752) (xy 152.803575 -407.031752) (xy 152.803575 -406.977248) (xy 152.811332 -406.9233)
			(xy 152.826688 -406.871004) (xy 152.849329 -406.821426) (xy 152.878796 -406.775575) (xy 152.914489 -406.734384)
			(xy 152.95568 -406.698693) (xy 153.001531 -406.669226) (xy 153.05111 -406.646585) (xy 153.103406 -406.631231)
			(xy 153.157354 -406.623475) (xy 153.184606 -406.623012) (xy 154.048206 -406.623012) (xy 154.075458 -406.623458)
			(xy 154.129408 -406.631216) (xy 154.181705 -406.646572) (xy 154.231284 -406.669215) (xy 154.277136 -406.698683)
			(xy 154.318328 -406.734376) (xy 154.354021 -406.775569) (xy 154.383488 -406.821421) (xy 154.40613 -406.871001)
			(xy 154.421485 -406.923298) (xy 154.429242 -406.977248) (xy 154.429242 -407.031752) (xy 154.429242 -407.031754)
			(xy 155.866775 -407.031754) (xy 155.866775 -406.977246) (xy 155.874533 -406.923294) (xy 155.889891 -406.870996)
			(xy 155.912535 -406.821415) (xy 155.942006 -406.775562) (xy 155.977703 -406.73437) (xy 156.018899 -406.698679)
			(xy 156.064755 -406.669213) (xy 156.114339 -406.646575) (xy 156.166639 -406.631223) (xy 156.220592 -406.623472)
			(xy 156.247846 -406.623012) (xy 157.111446 -406.623012) (xy 157.138697 -406.623461) (xy 157.192642 -406.631223)
			(xy 157.244934 -406.646583) (xy 157.294508 -406.669228) (xy 157.340355 -406.698697) (xy 157.381542 -406.734391)
			(xy 157.41723 -406.775582) (xy 157.446694 -406.821432) (xy 157.469333 -406.871009) (xy 157.484687 -406.923303)
			(xy 157.492442 -406.977249) (xy 157.492442 -407.031749) (xy 158.930098 -407.031749) (xy 158.930098 -406.977251)
			(xy 158.937854 -406.923307) (xy 158.953208 -406.871016) (xy 158.975846 -406.821443) (xy 159.00531 -406.775596)
			(xy 159.040998 -406.734408) (xy 159.082184 -406.698718) (xy 159.12803 -406.669253) (xy 159.177603 -406.646612)
			(xy 159.229894 -406.631257) (xy 159.283837 -406.623499) (xy 159.311086 -406.623012) (xy 160.174686 -406.623012)
			(xy 160.201941 -406.623434) (xy 160.255896 -406.63119) (xy 160.308199 -406.646545) (xy 160.357783 -406.669188)
			(xy 160.403641 -406.698657) (xy 160.444837 -406.734353) (xy 160.480534 -406.775548) (xy 160.510005 -406.821405)
			(xy 160.53265 -406.870988) (xy 160.548007 -406.92329) (xy 160.555765 -406.977245) (xy 160.555765 -407.031753)
			(xy 161.993275 -407.031753) (xy 161.993275 -406.977247) (xy 162.001033 -406.923297) (xy 162.016389 -406.871)
			(xy 162.039032 -406.821421) (xy 162.068501 -406.775569) (xy 162.104196 -406.734377) (xy 162.145389 -406.698686)
			(xy 162.191243 -406.66922) (xy 162.240824 -406.64658) (xy 162.293122 -406.631227) (xy 162.347073 -406.623474)
			(xy 162.374326 -406.623012) (xy 163.237926 -406.623012) (xy 163.265177 -406.62346) (xy 163.319125 -406.63122)
			(xy 163.37142 -406.646578) (xy 163.420996 -406.669222) (xy 163.466846 -406.69869) (xy 163.508035 -406.734383)
			(xy 163.543726 -406.775575) (xy 163.573191 -406.821427) (xy 163.595831 -406.871005) (xy 163.611186 -406.9233)
			(xy 163.618942 -406.977249) (xy 163.618942 -407.031751) (xy 163.611186 -407.0857) (xy 163.595831 -407.137995)
			(xy 163.573191 -407.187573) (xy 163.543726 -407.233425) (xy 163.508035 -407.274617) (xy 163.466846 -407.31031)
			(xy 163.420996 -407.339778) (xy 163.37142 -407.362422) (xy 163.319125 -407.37778) (xy 163.265177 -407.38554)
			(xy 163.237926 -407.386028) (xy 162.374326 -407.386028) (xy 162.347073 -407.385526) (xy 162.293122 -407.377773)
			(xy 162.240824 -407.36242) (xy 162.191243 -407.33978) (xy 162.145389 -407.310314) (xy 162.104196 -407.274623)
			(xy 162.068501 -407.233431) (xy 162.039032 -407.187579) (xy 162.016389 -407.138) (xy 162.001033 -407.085703)
			(xy 161.993275 -407.031753) (xy 160.555765 -407.031753) (xy 160.555765 -407.031755) (xy 160.548007 -407.08571)
			(xy 160.53265 -407.138012) (xy 160.510005 -407.187595) (xy 160.480534 -407.233452) (xy 160.444837 -407.274647)
			(xy 160.403641 -407.310343) (xy 160.357783 -407.339812) (xy 160.308199 -407.362455) (xy 160.255896 -407.37781)
			(xy 160.201941 -407.385566) (xy 160.174686 -407.386028) (xy 159.311086 -407.386028) (xy 159.283837 -407.385501)
			(xy 159.229894 -407.377743) (xy 159.177603 -407.362388) (xy 159.12803 -407.339747) (xy 159.082184 -407.310282)
			(xy 159.040998 -407.274592) (xy 159.00531 -407.233404) (xy 158.975846 -407.187557) (xy 158.953208 -407.137984)
			(xy 158.937854 -407.085693) (xy 158.930098 -407.031749) (xy 157.492442 -407.031749) (xy 157.492442 -407.031751)
			(xy 157.484687 -407.085697) (xy 157.469333 -407.137991) (xy 157.446694 -407.187568) (xy 157.41723 -407.233418)
			(xy 157.381542 -407.274609) (xy 157.340355 -407.310303) (xy 157.294508 -407.339772) (xy 157.244934 -407.362417)
			(xy 157.192642 -407.377777) (xy 157.138697 -407.385539) (xy 157.111446 -407.386028) (xy 156.247846 -407.386028)
			(xy 156.220592 -407.385528) (xy 156.166639 -407.377777) (xy 156.114339 -407.362425) (xy 156.064755 -407.339787)
			(xy 156.018899 -407.310321) (xy 155.977703 -407.27463) (xy 155.942006 -407.233438) (xy 155.912535 -407.187585)
			(xy 155.889891 -407.138004) (xy 155.874533 -407.085706) (xy 155.866775 -407.031754) (xy 154.429242 -407.031754)
			(xy 154.421485 -407.085702) (xy 154.40613 -407.137999) (xy 154.383488 -407.187579) (xy 154.354021 -407.233431)
			(xy 154.318328 -407.274624) (xy 154.277136 -407.310317) (xy 154.231284 -407.339785) (xy 154.181705 -407.362428)
			(xy 154.129408 -407.377784) (xy 154.075458 -407.385542) (xy 154.048206 -407.386028) (xy 153.184606 -407.386028)
			(xy 153.157354 -407.385525) (xy 153.103406 -407.377769) (xy 153.05111 -407.362415) (xy 153.001531 -407.339774)
			(xy 152.95568 -407.310307) (xy 152.914489 -407.274616) (xy 152.878796 -407.233425) (xy 152.849329 -407.187574)
			(xy 152.826688 -407.137996) (xy 152.811332 -407.0857) (xy 152.803575 -407.031752) (xy 151.366065 -407.031752)
			(xy 151.366065 -407.031756) (xy 151.358307 -407.085713) (xy 151.342948 -407.138016) (xy 151.320302 -407.187601)
			(xy 151.290829 -407.233458) (xy 151.25513 -407.274654) (xy 151.213931 -407.31035) (xy 151.168071 -407.339818)
			(xy 151.118484 -407.36246) (xy 151.066179 -407.377814) (xy 151.012222 -407.385567) (xy 150.984966 -407.386028)
			(xy 150.121366 -407.386028) (xy 150.094118 -407.385499) (xy 150.040177 -407.377739) (xy 149.987889 -407.362382)
			(xy 149.938318 -407.33974) (xy 149.892475 -407.310275) (xy 149.851291 -407.274585) (xy 149.815605 -407.233398)
			(xy 149.786143 -407.187552) (xy 149.763506 -407.137979) (xy 149.748153 -407.08569) (xy 149.740398 -407.031748)
			(xy 148.302742 -407.031748) (xy 148.302742 -407.031751) (xy 148.294986 -407.0857) (xy 148.279631 -407.137995)
			(xy 148.256991 -407.187573) (xy 148.227526 -407.233425) (xy 148.191835 -407.274617) (xy 148.150646 -407.31031)
			(xy 148.104796 -407.339778) (xy 148.05522 -407.362422) (xy 148.002925 -407.37778) (xy 147.948977 -407.38554)
			(xy 147.921726 -407.386028) (xy 147.058126 -407.386028) (xy 147.030873 -407.385526) (xy 146.976922 -407.377773)
			(xy 146.924624 -407.36242) (xy 146.875043 -407.33978) (xy 146.829189 -407.310314) (xy 146.787996 -407.274623)
			(xy 146.752301 -407.233431) (xy 146.722832 -407.187579) (xy 146.700189 -407.138) (xy 146.684833 -407.085703)
			(xy 146.677075 -407.031753) (xy 145.239565 -407.031753) (xy 145.239565 -407.031755) (xy 145.231807 -407.08571)
			(xy 145.21645 -407.138012) (xy 145.193805 -407.187595) (xy 145.164334 -407.233452) (xy 145.128637 -407.274647)
			(xy 145.087441 -407.310343) (xy 145.041583 -407.339812) (xy 144.991999 -407.362455) (xy 144.939696 -407.37781)
			(xy 144.885741 -407.385566) (xy 144.858486 -407.386028) (xy 143.994886 -407.386028) (xy 143.967637 -407.385501)
			(xy 143.913694 -407.377743) (xy 143.861403 -407.362388) (xy 143.81183 -407.339747) (xy 143.765984 -407.310282)
			(xy 143.724798 -407.274592) (xy 143.68911 -407.233404) (xy 143.659646 -407.187557) (xy 143.637008 -407.137984)
			(xy 143.621654 -407.085693) (xy 143.613898 -407.031749) (xy 142.176242 -407.031749) (xy 142.176242 -407.031751)
			(xy 142.168487 -407.085697) (xy 142.153133 -407.137991) (xy 142.130494 -407.187568) (xy 142.10103 -407.233418)
			(xy 142.065342 -407.274609) (xy 142.024155 -407.310303) (xy 141.978308 -407.339772) (xy 141.928734 -407.362417)
			(xy 141.876442 -407.377777) (xy 141.822497 -407.385539) (xy 141.795246 -407.386028) (xy 140.931646 -407.386028)
			(xy 140.904392 -407.385528) (xy 140.850439 -407.377777) (xy 140.798139 -407.362425) (xy 140.748555 -407.339787)
			(xy 140.702699 -407.310321) (xy 140.661503 -407.27463) (xy 140.625806 -407.233438) (xy 140.596335 -407.187585)
			(xy 140.573691 -407.138004) (xy 140.558333 -407.085706) (xy 140.550575 -407.031754) (xy 139.113042 -407.031754)
			(xy 139.105285 -407.085702) (xy 139.08993 -407.137999) (xy 139.067288 -407.187579) (xy 139.037821 -407.233431)
			(xy 139.002128 -407.274624) (xy 138.960936 -407.310317) (xy 138.915084 -407.339785) (xy 138.865505 -407.362428)
			(xy 138.813208 -407.377784) (xy 138.759258 -407.385542) (xy 138.732006 -407.386028) (xy 137.868406 -407.386028)
			(xy 137.841154 -407.385525) (xy 137.787206 -407.377769) (xy 137.73491 -407.362415) (xy 137.685331 -407.339774)
			(xy 137.63948 -407.310307) (xy 137.598289 -407.274616) (xy 137.562596 -407.233425) (xy 137.533129 -407.187574)
			(xy 137.510488 -407.137996) (xy 137.495132 -407.0857) (xy 137.487375 -407.031752) (xy 136.049865 -407.031752)
			(xy 136.049865 -407.031756) (xy 136.042107 -407.085713) (xy 136.026748 -407.138016) (xy 136.004102 -407.187601)
			(xy 135.974629 -407.233458) (xy 135.93893 -407.274654) (xy 135.897731 -407.31035) (xy 135.851871 -407.339818)
			(xy 135.802284 -407.36246) (xy 135.749979 -407.377814) (xy 135.696022 -407.385567) (xy 135.668766 -407.386028)
			(xy 134.805166 -407.386028) (xy 134.777918 -407.385499) (xy 134.723977 -407.377739) (xy 134.671689 -407.362382)
			(xy 134.622118 -407.33974) (xy 134.576275 -407.310275) (xy 134.535091 -407.274585) (xy 134.499405 -407.233398)
			(xy 134.469943 -407.187552) (xy 134.447306 -407.137979) (xy 134.431953 -407.08569) (xy 134.424198 -407.031748)
			(xy 132.986542 -407.031748) (xy 132.986542 -407.031751) (xy 132.978786 -407.0857) (xy 132.963431 -407.137995)
			(xy 132.940791 -407.187573) (xy 132.911326 -407.233425) (xy 132.875635 -407.274617) (xy 132.834446 -407.31031)
			(xy 132.788596 -407.339778) (xy 132.73902 -407.362422) (xy 132.686725 -407.37778) (xy 132.632777 -407.38554)
			(xy 132.605526 -407.386028) (xy 131.741926 -407.386028) (xy 131.714673 -407.385526) (xy 131.660722 -407.377773)
			(xy 131.608424 -407.36242) (xy 131.558843 -407.33978) (xy 131.512989 -407.310314) (xy 131.471796 -407.274623)
			(xy 131.436101 -407.233431) (xy 131.406632 -407.187579) (xy 131.383989 -407.138) (xy 131.368633 -407.085703)
			(xy 131.360875 -407.031753) (xy 129.923365 -407.031753) (xy 129.923365 -407.031755) (xy 129.915607 -407.08571)
			(xy 129.90025 -407.138012) (xy 129.877605 -407.187595) (xy 129.848134 -407.233452) (xy 129.812437 -407.274647)
			(xy 129.771241 -407.310343) (xy 129.725383 -407.339812) (xy 129.675799 -407.362455) (xy 129.623496 -407.37781)
			(xy 129.569541 -407.385566) (xy 129.542286 -407.386028) (xy 128.678686 -407.386028) (xy 128.651437 -407.385501)
			(xy 128.597494 -407.377743) (xy 128.545203 -407.362388) (xy 128.49563 -407.339747) (xy 128.449784 -407.310282)
			(xy 128.408598 -407.274592) (xy 128.37291 -407.233404) (xy 128.343446 -407.187557) (xy 128.320808 -407.137984)
			(xy 128.305454 -407.085693) (xy 128.297698 -407.031749) (xy 126.860042 -407.031749) (xy 126.860042 -407.031751)
			(xy 126.852287 -407.085697) (xy 126.836933 -407.137991) (xy 126.814294 -407.187568) (xy 126.78483 -407.233418)
			(xy 126.749142 -407.274609) (xy 126.707955 -407.310303) (xy 126.662108 -407.339772) (xy 126.612534 -407.362417)
			(xy 126.560242 -407.377777) (xy 126.506297 -407.385539) (xy 126.479046 -407.386028) (xy 125.615446 -407.386028)
			(xy 125.588192 -407.385528) (xy 125.534239 -407.377777) (xy 125.481939 -407.362425) (xy 125.432355 -407.339787)
			(xy 125.386499 -407.310321) (xy 125.345303 -407.27463) (xy 125.309606 -407.233438) (xy 125.280135 -407.187585)
			(xy 125.257491 -407.138004) (xy 125.242133 -407.085706) (xy 125.234375 -407.031754) (xy 123.796842 -407.031754)
			(xy 123.789085 -407.085702) (xy 123.77373 -407.137999) (xy 123.751088 -407.187579) (xy 123.721621 -407.233431)
			(xy 123.685928 -407.274624) (xy 123.644736 -407.310317) (xy 123.598884 -407.339785) (xy 123.549305 -407.362428)
			(xy 123.497008 -407.377784) (xy 123.443058 -407.385542) (xy 123.415806 -407.386028) (xy 122.552206 -407.386028)
			(xy 122.524954 -407.385525) (xy 122.471006 -407.377769) (xy 122.41871 -407.362415) (xy 122.369131 -407.339774)
			(xy 122.32328 -407.310307) (xy 122.282089 -407.274616) (xy 122.246396 -407.233425) (xy 122.216929 -407.187574)
			(xy 122.194288 -407.137996) (xy 122.178932 -407.0857) (xy 122.171175 -407.031752) (xy 120.733665 -407.031752)
			(xy 120.733665 -407.031756) (xy 120.725907 -407.085713) (xy 120.710548 -407.138016) (xy 120.687902 -407.187601)
			(xy 120.658429 -407.233458) (xy 120.62273 -407.274654) (xy 120.581531 -407.31035) (xy 120.535671 -407.339818)
			(xy 120.486084 -407.36246) (xy 120.433779 -407.377814) (xy 120.379822 -407.385567) (xy 120.352566 -407.386028)
			(xy 119.488966 -407.386028) (xy 119.461718 -407.385499) (xy 119.407777 -407.377739) (xy 119.355489 -407.362382)
			(xy 119.305918 -407.33974) (xy 119.260075 -407.310275) (xy 119.218891 -407.274585) (xy 119.183205 -407.233398)
			(xy 119.153743 -407.187552) (xy 119.131106 -407.137979) (xy 119.115753 -407.08569) (xy 119.107998 -407.031748)
			(xy 117.670342 -407.031748) (xy 117.670342 -407.031751) (xy 117.662586 -407.0857) (xy 117.647231 -407.137995)
			(xy 117.624591 -407.187573) (xy 117.595126 -407.233425) (xy 117.559435 -407.274617) (xy 117.518246 -407.31031)
			(xy 117.472396 -407.339778) (xy 117.42282 -407.362422) (xy 117.370525 -407.37778) (xy 117.316577 -407.38554)
			(xy 117.289326 -407.386028) (xy 116.425726 -407.386028) (xy 116.398473 -407.385526) (xy 116.344522 -407.377773)
			(xy 116.292224 -407.36242) (xy 116.242643 -407.33978) (xy 116.196789 -407.310314) (xy 116.155596 -407.274623)
			(xy 116.119901 -407.233431) (xy 116.090432 -407.187579) (xy 116.067789 -407.138) (xy 116.052433 -407.085703)
			(xy 116.044675 -407.031753) (xy 96.519065 -407.031753) (xy 96.519065 -407.031755) (xy 96.511307 -407.08571)
			(xy 96.49595 -407.138012) (xy 96.473305 -407.187596) (xy 96.443834 -407.233452) (xy 96.408136 -407.274648)
			(xy 96.36694 -407.310343) (xy 96.321082 -407.339812) (xy 96.271497 -407.362455) (xy 96.219195 -407.377811)
			(xy 96.165239 -407.385566) (xy 96.137984 -407.386028) (xy 95.274384 -407.386028) (xy 95.247135 -407.385501)
			(xy 95.193192 -407.377743) (xy 95.140902 -407.362387) (xy 95.091329 -407.339746) (xy 95.045483 -407.310281)
			(xy 95.004297 -407.274591) (xy 94.968609 -407.233404) (xy 94.939146 -407.187557) (xy 94.916507 -407.137983)
			(xy 94.901154 -407.085692) (xy 94.893398 -407.031749) (xy 93.455742 -407.031749) (xy 93.455742 -407.031751)
			(xy 93.447987 -407.085697) (xy 93.432633 -407.137991) (xy 93.409994 -407.187568) (xy 93.38053 -407.233419)
			(xy 93.344841 -407.27461) (xy 93.303654 -407.310304) (xy 93.257807 -407.339773) (xy 93.208233 -407.362417)
			(xy 93.15594 -407.377777) (xy 93.101995 -407.385539) (xy 93.074744 -407.386028) (xy 92.211144 -407.386028)
			(xy 92.183891 -407.385528) (xy 92.129938 -407.377776) (xy 92.077637 -407.362425) (xy 92.028054 -407.339786)
			(xy 91.982198 -407.310321) (xy 91.941002 -407.274629) (xy 91.905306 -407.233437) (xy 91.875835 -407.187584)
			(xy 91.853191 -407.138004) (xy 91.837833 -407.085705) (xy 91.830075 -407.031753) (xy 90.392542 -407.031753)
			(xy 90.384785 -407.085703) (xy 90.36943 -407.138) (xy 90.346788 -407.187579) (xy 90.31732 -407.233432)
			(xy 90.281627 -407.274624) (xy 90.240435 -407.310318) (xy 90.194583 -407.339786) (xy 90.145004 -407.362428)
			(xy 90.092707 -407.377785) (xy 90.038756 -407.385542) (xy 90.011504 -407.386028) (xy 89.147904 -407.386028)
			(xy 89.120652 -407.385525) (xy 89.066704 -407.377769) (xy 89.014408 -407.362414) (xy 88.96483 -407.339773)
			(xy 88.918979 -407.310307) (xy 88.877788 -407.274615) (xy 88.842096 -407.233424) (xy 88.812629 -407.187573)
			(xy 88.789987 -407.137995) (xy 88.774632 -407.0857) (xy 88.766875 -407.031752) (xy 87.329365 -407.031752)
			(xy 87.329365 -407.031756) (xy 87.321607 -407.085713) (xy 87.306248 -407.138016) (xy 87.283602 -407.187602)
			(xy 87.254129 -407.233459) (xy 87.218429 -407.274655) (xy 87.17723 -407.31035) (xy 87.13137 -407.339819)
			(xy 87.081783 -407.362461) (xy 87.029478 -407.377814) (xy 86.97552 -407.385568) (xy 86.948264 -407.386028)
			(xy 86.084664 -407.386028) (xy 86.057416 -407.385499) (xy 86.003475 -407.377739) (xy 85.951187 -407.362382)
			(xy 85.901617 -407.33974) (xy 85.855774 -407.310274) (xy 85.81459 -407.274584) (xy 85.778904 -407.233397)
			(xy 85.749443 -407.187551) (xy 85.726806 -407.137979) (xy 85.711453 -407.08569) (xy 85.703698 -407.031748)
			(xy 84.266042 -407.031748) (xy 84.266042 -407.031752) (xy 84.258286 -407.0857) (xy 84.242931 -407.137996)
			(xy 84.220291 -407.187574) (xy 84.190825 -407.233425) (xy 84.155134 -407.274617) (xy 84.113945 -407.310311)
			(xy 84.068095 -407.339779) (xy 84.018518 -407.362423) (xy 83.966224 -407.377781) (xy 83.912276 -407.385541)
			(xy 83.885024 -407.386028) (xy 83.021424 -407.386028) (xy 82.994171 -407.385526) (xy 82.940221 -407.377773)
			(xy 82.887923 -407.362419) (xy 82.838342 -407.339779) (xy 82.792488 -407.310314) (xy 82.751295 -407.274622)
			(xy 82.715601 -407.233431) (xy 82.686132 -407.187579) (xy 82.663489 -407.138) (xy 82.648133 -407.085703)
			(xy 82.640375 -407.031753) (xy 81.202865 -407.031753) (xy 81.202865 -407.031755) (xy 81.195107 -407.08571)
			(xy 81.17975 -407.138012) (xy 81.157105 -407.187596) (xy 81.127634 -407.233452) (xy 81.091936 -407.274648)
			(xy 81.05074 -407.310343) (xy 81.004882 -407.339812) (xy 80.955297 -407.362455) (xy 80.902995 -407.377811)
			(xy 80.849039 -407.385566) (xy 80.821784 -407.386028) (xy 79.958184 -407.386028) (xy 79.930935 -407.385501)
			(xy 79.876992 -407.377743) (xy 79.824702 -407.362387) (xy 79.775129 -407.339746) (xy 79.729283 -407.310281)
			(xy 79.688097 -407.274591) (xy 79.652409 -407.233404) (xy 79.622946 -407.187557) (xy 79.600307 -407.137983)
			(xy 79.584954 -407.085692) (xy 79.577198 -407.031749) (xy 78.139542 -407.031749) (xy 78.139542 -407.031751)
			(xy 78.131787 -407.085697) (xy 78.116433 -407.137991) (xy 78.093794 -407.187568) (xy 78.06433 -407.233419)
			(xy 78.028641 -407.27461) (xy 77.987454 -407.310304) (xy 77.941607 -407.339773) (xy 77.892033 -407.362417)
			(xy 77.83974 -407.377777) (xy 77.785795 -407.385539) (xy 77.758544 -407.386028) (xy 76.894944 -407.386028)
			(xy 76.867691 -407.385528) (xy 76.813738 -407.377776) (xy 76.761437 -407.362425) (xy 76.711854 -407.339786)
			(xy 76.665998 -407.310321) (xy 76.624802 -407.274629) (xy 76.589106 -407.233437) (xy 76.559635 -407.187584)
			(xy 76.536991 -407.138004) (xy 76.521633 -407.085705) (xy 76.513875 -407.031753) (xy 75.076342 -407.031753)
			(xy 75.068585 -407.085703) (xy 75.05323 -407.138) (xy 75.030588 -407.187579) (xy 75.00112 -407.233432)
			(xy 74.965427 -407.274624) (xy 74.924235 -407.310318) (xy 74.878383 -407.339786) (xy 74.828804 -407.362428)
			(xy 74.776507 -407.377785) (xy 74.722556 -407.385542) (xy 74.695304 -407.386028) (xy 73.831704 -407.386028)
			(xy 73.804452 -407.385525) (xy 73.750504 -407.377769) (xy 73.698208 -407.362414) (xy 73.64863 -407.339773)
			(xy 73.602779 -407.310307) (xy 73.561588 -407.274615) (xy 73.525896 -407.233424) (xy 73.496429 -407.187573)
			(xy 73.473787 -407.137995) (xy 73.458432 -407.0857) (xy 73.450675 -407.031752) (xy 72.013165 -407.031752)
			(xy 72.013165 -407.031756) (xy 72.005407 -407.085713) (xy 71.990048 -407.138016) (xy 71.967402 -407.187602)
			(xy 71.937929 -407.233459) (xy 71.902229 -407.274655) (xy 71.86103 -407.31035) (xy 71.81517 -407.339819)
			(xy 71.765583 -407.362461) (xy 71.713278 -407.377814) (xy 71.65932 -407.385568) (xy 71.632064 -407.386028)
			(xy 70.768464 -407.386028) (xy 70.741216 -407.385499) (xy 70.687275 -407.377739) (xy 70.634987 -407.362382)
			(xy 70.585417 -407.33974) (xy 70.539574 -407.310274) (xy 70.49839 -407.274584) (xy 70.462704 -407.233397)
			(xy 70.433243 -407.187551) (xy 70.410606 -407.137979) (xy 70.395253 -407.08569) (xy 70.387498 -407.031748)
			(xy 68.949842 -407.031748) (xy 68.949842 -407.031752) (xy 68.942086 -407.0857) (xy 68.926731 -407.137996)
			(xy 68.904091 -407.187574) (xy 68.874625 -407.233425) (xy 68.838934 -407.274617) (xy 68.797745 -407.310311)
			(xy 68.751895 -407.339779) (xy 68.702318 -407.362423) (xy 68.650024 -407.377781) (xy 68.596076 -407.385541)
			(xy 68.568824 -407.386028) (xy 67.705224 -407.386028) (xy 67.677971 -407.385526) (xy 67.624021 -407.377773)
			(xy 67.571723 -407.362419) (xy 67.522142 -407.339779) (xy 67.476288 -407.310314) (xy 67.435095 -407.274622)
			(xy 67.399401 -407.233431) (xy 67.369932 -407.187579) (xy 67.347289 -407.138) (xy 67.331933 -407.085703)
			(xy 67.324175 -407.031753) (xy 65.886665 -407.031753) (xy 65.886665 -407.031755) (xy 65.878907 -407.08571)
			(xy 65.86355 -407.138012) (xy 65.840905 -407.187596) (xy 65.811434 -407.233452) (xy 65.775736 -407.274648)
			(xy 65.73454 -407.310343) (xy 65.688682 -407.339812) (xy 65.639097 -407.362455) (xy 65.586795 -407.377811)
			(xy 65.532839 -407.385566) (xy 65.505584 -407.386028) (xy 64.641984 -407.386028) (xy 64.614735 -407.385501)
			(xy 64.560792 -407.377743) (xy 64.508502 -407.362387) (xy 64.458929 -407.339746) (xy 64.413083 -407.310281)
			(xy 64.371897 -407.274591) (xy 64.336209 -407.233404) (xy 64.306746 -407.187557) (xy 64.284107 -407.137983)
			(xy 64.268754 -407.085692) (xy 64.260998 -407.031749) (xy 62.823342 -407.031749) (xy 62.823342 -407.031751)
			(xy 62.815587 -407.085697) (xy 62.800233 -407.137991) (xy 62.777594 -407.187568) (xy 62.74813 -407.233419)
			(xy 62.712441 -407.27461) (xy 62.671254 -407.310304) (xy 62.625407 -407.339773) (xy 62.575833 -407.362417)
			(xy 62.52354 -407.377777) (xy 62.469595 -407.385539) (xy 62.442344 -407.386028) (xy 61.578744 -407.386028)
			(xy 61.551491 -407.385528) (xy 61.497538 -407.377776) (xy 61.445237 -407.362425) (xy 61.395654 -407.339786)
			(xy 61.349798 -407.310321) (xy 61.308602 -407.274629) (xy 61.272906 -407.233437) (xy 61.243435 -407.187584)
			(xy 61.220791 -407.138004) (xy 61.205433 -407.085705) (xy 61.197675 -407.031753) (xy 59.760142 -407.031753)
			(xy 59.752385 -407.085703) (xy 59.73703 -407.138) (xy 59.714388 -407.187579) (xy 59.68492 -407.233432)
			(xy 59.649227 -407.274624) (xy 59.608035 -407.310318) (xy 59.562183 -407.339786) (xy 59.512604 -407.362428)
			(xy 59.460307 -407.377785) (xy 59.406356 -407.385542) (xy 59.379104 -407.386028) (xy 58.515504 -407.386028)
			(xy 58.488252 -407.385525) (xy 58.434304 -407.377769) (xy 58.382008 -407.362414) (xy 58.33243 -407.339773)
			(xy 58.286579 -407.310307) (xy 58.245388 -407.274615) (xy 58.209696 -407.233424) (xy 58.180229 -407.187573)
			(xy 58.157587 -407.137995) (xy 58.142232 -407.0857) (xy 58.134475 -407.031752) (xy 56.696965 -407.031752)
			(xy 56.696965 -407.031756) (xy 56.689207 -407.085713) (xy 56.673848 -407.138016) (xy 56.651202 -407.187602)
			(xy 56.621729 -407.233459) (xy 56.586029 -407.274655) (xy 56.54483 -407.31035) (xy 56.49897 -407.339819)
			(xy 56.449383 -407.362461) (xy 56.397078 -407.377814) (xy 56.34312 -407.385568) (xy 56.315864 -407.386028)
			(xy 55.452264 -407.386028) (xy 55.425016 -407.385499) (xy 55.371075 -407.377739) (xy 55.318787 -407.362382)
			(xy 55.269217 -407.33974) (xy 55.223374 -407.310274) (xy 55.18219 -407.274584) (xy 55.146504 -407.233397)
			(xy 55.117043 -407.187551) (xy 55.094406 -407.137979) (xy 55.079053 -407.08569) (xy 55.071298 -407.031748)
			(xy 53.633642 -407.031748) (xy 53.633642 -407.031752) (xy 53.625886 -407.0857) (xy 53.610531 -407.137996)
			(xy 53.587891 -407.187574) (xy 53.558425 -407.233425) (xy 53.522734 -407.274617) (xy 53.481545 -407.310311)
			(xy 53.435695 -407.339779) (xy 53.386118 -407.362423) (xy 53.333824 -407.377781) (xy 53.279876 -407.385541)
			(xy 53.252624 -407.386028) (xy 52.389024 -407.386028) (xy 52.361771 -407.385526) (xy 52.307821 -407.377773)
			(xy 52.255523 -407.362419) (xy 52.205942 -407.339779) (xy 52.160088 -407.310314) (xy 52.118895 -407.274622)
			(xy 52.083201 -407.233431) (xy 52.053732 -407.187579) (xy 52.031089 -407.138) (xy 52.015733 -407.085703)
			(xy 52.007975 -407.031753) (xy 50.570465 -407.031753) (xy 50.570465 -407.031755) (xy 50.562707 -407.08571)
			(xy 50.54735 -407.138012) (xy 50.524705 -407.187596) (xy 50.495234 -407.233452) (xy 50.459536 -407.274648)
			(xy 50.41834 -407.310343) (xy 50.372482 -407.339812) (xy 50.322897 -407.362455) (xy 50.270595 -407.377811)
			(xy 50.216639 -407.385566) (xy 50.189384 -407.386028) (xy 49.325784 -407.386028) (xy 49.298535 -407.385501)
			(xy 49.244592 -407.377743) (xy 49.192302 -407.362387) (xy 49.142729 -407.339746) (xy 49.096883 -407.310281)
			(xy 49.055697 -407.274591) (xy 49.020009 -407.233404) (xy 48.990546 -407.187557) (xy 48.967907 -407.137983)
			(xy 48.952554 -407.085692) (xy 48.944798 -407.031749) (xy 44.883756 -407.031749) (xy 44.868945 -407.05439)
			(xy 44.764794 -407.199093) (xy 44.654301 -407.339013) (xy 44.537684 -407.473872) (xy 44.415175 -407.603402)
			(xy 44.287018 -407.727346) (xy 44.153467 -407.845458) (xy 44.014787 -407.957503) (xy 43.871253 -408.06326)
			(xy 43.72315 -408.162517) (xy 43.570773 -408.255079) (xy 43.414424 -408.34076) (xy 43.254413 -408.419392)
			(xy 43.091059 -408.490818) (xy 42.924684 -408.554896) (xy 42.755621 -408.611498) (xy 42.584204 -408.660514)
			(xy 42.410773 -408.701844) (xy 42.235673 -408.735408) (xy 42.059253 -408.761138) (xy 41.881861 -408.778984)
			(xy 41.70385 -408.78891) (xy 41.525573 -408.790896) (xy 41.347386 -408.784939) (xy 41.16964 -408.771049)
			(xy 40.99269 -408.749256) (xy 40.816886 -408.719602) (xy 40.642578 -408.682145) (xy 40.470111 -408.636961)
			(xy 40.299828 -408.584139) (xy 40.132067 -408.523783) (xy 39.967162 -408.456015) (xy 39.805439 -408.380967)
			(xy 39.64722 -408.29879) (xy 39.492819 -408.209647) (xy 39.342542 -408.113713) (xy 39.196687 -408.011181)
			(xy 39.055545 -407.902253) (xy 38.919396 -407.787146) (xy 38.788509 -407.666088) (xy 38.663145 -407.539319)
			(xy 38.543552 -407.407092) (xy 38.429969 -407.269669) (xy 38.32262 -407.127322) (xy 38.221719 -406.980334)
			(xy 38.127466 -406.828998) (xy 38.040048 -406.673613) (xy 37.959638 -406.514488) (xy 37.886397 -406.351939)
			(xy 37.82047 -406.186289) (xy 37.761987 -406.017867) (xy 37.711065 -405.847006) (xy 37.667805 -405.674047)
			(xy 37.632293 -405.499332) (xy 37.604599 -405.323208) (xy 37.584778 -405.146026) (xy 37.57287 -404.968137)
			(xy 37.568898 -404.789894) (xy 3.30962 -404.789894) (xy 6.274054 -407.754328) (xy 6.323479 -407.804444)
			(xy 6.417291 -407.909404) (xy 6.50507 -408.019459) (xy 6.58654 -408.134261) (xy 6.661445 -408.253452)
			(xy 6.72955 -408.376654) (xy 6.79064 -408.503481) (xy 6.844523 -408.633534) (xy 6.891029 -408.766403)
			(xy 6.930013 -408.901671) (xy 6.961351 -409.038912) (xy 6.984945 -409.177694) (xy 7.00072 -409.31758)
			(xy 7.008628 -409.458131) (xy 7.00913 -409.528518) (xy 7.00913 -409.563824) (xy 102.192836 -409.563824)
			(xy 102.192836 -408.700224) (xy 102.193322 -408.672955) (xy 102.201084 -408.618971) (xy 102.216449 -408.566641)
			(xy 102.239106 -408.517031) (xy 102.268592 -408.47115) (xy 102.304307 -408.429933) (xy 102.345524 -408.394218)
			(xy 102.391405 -408.364732) (xy 102.441015 -408.342075) (xy 102.493345 -408.32671) (xy 102.547329 -408.318948)
			(xy 102.601867 -408.318948) (xy 102.655851 -408.32671) (xy 102.708181 -408.342075) (xy 102.757791 -408.364732)
			(xy 102.803672 -408.394218) (xy 102.844889 -408.429933) (xy 102.880604 -408.47115) (xy 102.91009 -408.517031)
			(xy 102.932747 -408.566641) (xy 102.948112 -408.618971) (xy 102.955874 -408.672955) (xy 102.95636 -408.700224)
			(xy 102.95636 -409.563824) (xy 102.955874 -409.591093) (xy 102.948112 -409.645077) (xy 102.932747 -409.697407)
			(xy 102.91009 -409.747017) (xy 102.880604 -409.792898) (xy 102.844889 -409.834115) (xy 102.803672 -409.86983)
			(xy 102.757791 -409.899316) (xy 102.748244 -409.903676) (xy 110.559596 -409.903676) (xy 110.559596 -409.040076)
			(xy 110.560082 -409.012825) (xy 110.567838 -408.958877) (xy 110.583193 -408.906582) (xy 110.605835 -408.857005)
			(xy 110.635301 -408.811155) (xy 110.670992 -408.769964) (xy 110.712183 -408.734273) (xy 110.758033 -408.704807)
			(xy 110.80761 -408.682165) (xy 110.859905 -408.66681) (xy 110.913853 -408.659054) (xy 110.968355 -408.659054)
			(xy 111.022303 -408.66681) (xy 111.074598 -408.682165) (xy 111.124175 -408.704807) (xy 111.170025 -408.734273)
			(xy 111.211216 -408.769964) (xy 111.246907 -408.811155) (xy 111.276373 -408.857005) (xy 111.299015 -408.906582)
			(xy 111.31437 -408.958877) (xy 111.322126 -409.012825) (xy 111.322612 -409.040076) (xy 111.322612 -409.903676)
			(xy 111.322126 -409.930927) (xy 111.31437 -409.984875) (xy 111.299015 -410.03717) (xy 111.28975 -410.057456)
			(xy 116.044623 -410.057456) (xy 116.044623 -410.002944) (xy 116.052381 -409.948986) (xy 116.06774 -409.896681)
			(xy 116.090386 -409.847095) (xy 116.119859 -409.801237) (xy 116.155559 -409.76004) (xy 116.196758 -409.724344)
			(xy 116.242618 -409.694874) (xy 116.292206 -409.672231) (xy 116.344511 -409.656876) (xy 116.39847 -409.649121)
			(xy 116.425726 -409.64866) (xy 117.289326 -409.64866) (xy 117.316574 -409.649212) (xy 117.370514 -409.656971)
			(xy 117.422801 -409.672327) (xy 117.472371 -409.694968) (xy 117.518214 -409.724432) (xy 117.559398 -409.760121)
			(xy 117.595084 -409.801307) (xy 117.624545 -409.847152) (xy 117.647182 -409.896723) (xy 117.662535 -409.949011)
			(xy 117.67029 -410.002952) (xy 117.67029 -410.057448) (xy 117.670289 -410.057452) (xy 119.107946 -410.057452)
			(xy 119.107946 -410.002948) (xy 119.115702 -409.948999) (xy 119.131057 -409.896702) (xy 119.153697 -409.847123)
			(xy 119.183163 -409.801271) (xy 119.218854 -409.760078) (xy 119.260043 -409.724383) (xy 119.305893 -409.694914)
			(xy 119.35547 -409.672269) (xy 119.407765 -409.656909) (xy 119.461714 -409.649148) (xy 119.488966 -409.64866)
			(xy 120.352566 -409.64866) (xy 120.379818 -409.649185) (xy 120.433768 -409.656937) (xy 120.486066 -409.672289)
			(xy 120.535646 -409.694928) (xy 120.5815 -409.724392) (xy 120.622693 -409.760083) (xy 120.658387 -409.801273)
			(xy 120.687856 -409.847124) (xy 120.710499 -409.896702) (xy 120.725855 -409.948999) (xy 120.733613 -410.002948)
			(xy 120.733613 -410.057452) (xy 120.733613 -410.057455) (xy 122.171123 -410.057455) (xy 122.171123 -410.002945)
			(xy 122.178881 -409.948989) (xy 122.194238 -409.896686) (xy 122.216883 -409.847101) (xy 122.246354 -409.801244)
			(xy 122.282052 -409.760047) (xy 122.323249 -409.724351) (xy 122.369106 -409.69488) (xy 122.418691 -409.672236)
			(xy 122.470994 -409.656879) (xy 122.524951 -409.649123) (xy 122.552206 -409.64866) (xy 123.415806 -409.64866)
			(xy 123.443055 -409.649211) (xy 123.496997 -409.656967) (xy 123.549287 -409.672321) (xy 123.598859 -409.694961)
			(xy 123.644705 -409.724425) (xy 123.685891 -409.760113) (xy 123.721579 -409.8013) (xy 123.751042 -409.847146)
			(xy 123.773681 -409.896719) (xy 123.789034 -409.949009) (xy 123.79679 -410.002951) (xy 123.79679 -410.057449)
			(xy 123.796789 -410.057457) (xy 125.234323 -410.057457) (xy 125.234323 -410.002943) (xy 125.242082 -409.948983)
			(xy 125.257442 -409.896677) (xy 125.280089 -409.84709) (xy 125.309564 -409.801231) (xy 125.345266 -409.760033)
			(xy 125.386467 -409.724337) (xy 125.43233 -409.694867) (xy 125.48192 -409.672225) (xy 125.534228 -409.656872)
			(xy 125.588189 -409.64912) (xy 125.615446 -409.64866) (xy 126.479046 -409.64866) (xy 126.506293 -409.649213)
			(xy 126.560231 -409.656975) (xy 126.612516 -409.672332) (xy 126.662083 -409.694974) (xy 126.707924 -409.724439)
			(xy 126.749105 -409.760128) (xy 126.784788 -409.801313) (xy 126.814248 -409.847157) (xy 126.836884 -409.896727)
			(xy 126.852235 -409.949014) (xy 126.85999 -410.002953) (xy 126.85999 -410.057447) (xy 126.859989 -410.057453)
			(xy 128.297646 -410.057453) (xy 128.297646 -410.002947) (xy 128.305403 -409.948996) (xy 128.320758 -409.896698)
			(xy 128.3434 -409.847118) (xy 128.372868 -409.801264) (xy 128.408561 -409.760071) (xy 128.449753 -409.724376)
			(xy 128.495605 -409.694907) (xy 128.545185 -409.672263) (xy 128.597482 -409.656906) (xy 128.651433 -409.649147)
			(xy 128.678686 -409.64866) (xy 129.542286 -409.64866) (xy 129.569537 -409.649186) (xy 129.623485 -409.656941)
			(xy 129.67578 -409.672295) (xy 129.725358 -409.694934) (xy 129.771209 -409.724399) (xy 129.8124 -409.76009)
			(xy 129.848092 -409.80128) (xy 129.877559 -409.84713) (xy 129.900201 -409.896707) (xy 129.915556 -409.949001)
			(xy 129.923313 -410.002949) (xy 129.923313 -410.057451) (xy 129.923312 -410.057456) (xy 131.360823 -410.057456)
			(xy 131.360823 -410.002944) (xy 131.368581 -409.948986) (xy 131.38394 -409.896681) (xy 131.406586 -409.847095)
			(xy 131.436059 -409.801237) (xy 131.471759 -409.76004) (xy 131.512958 -409.724344) (xy 131.558818 -409.694874)
			(xy 131.608406 -409.672231) (xy 131.660711 -409.656876) (xy 131.71467 -409.649121) (xy 131.741926 -409.64866)
			(xy 132.605526 -409.64866) (xy 132.632774 -409.649212) (xy 132.686714 -409.656971) (xy 132.739001 -409.672327)
			(xy 132.788571 -409.694968) (xy 132.834414 -409.724432) (xy 132.875598 -409.760121) (xy 132.911284 -409.801307)
			(xy 132.940745 -409.847152) (xy 132.963382 -409.896723) (xy 132.978735 -409.949011) (xy 132.98649 -410.002952)
			(xy 132.98649 -410.057448) (xy 132.986489 -410.057452) (xy 134.424146 -410.057452) (xy 134.424146 -410.002948)
			(xy 134.431902 -409.948999) (xy 134.447257 -409.896702) (xy 134.469897 -409.847123) (xy 134.499363 -409.801271)
			(xy 134.535054 -409.760078) (xy 134.576243 -409.724383) (xy 134.622093 -409.694914) (xy 134.67167 -409.672269)
			(xy 134.723965 -409.656909) (xy 134.777914 -409.649148) (xy 134.805166 -409.64866) (xy 135.668766 -409.64866)
			(xy 135.696018 -409.649185) (xy 135.749968 -409.656937) (xy 135.802266 -409.672289) (xy 135.851846 -409.694928)
			(xy 135.8977 -409.724392) (xy 135.938893 -409.760083) (xy 135.974587 -409.801273) (xy 136.004056 -409.847124)
			(xy 136.026699 -409.896702) (xy 136.042055 -409.948999) (xy 136.049813 -410.002948) (xy 136.049813 -410.057452)
			(xy 136.049813 -410.057455) (xy 137.487323 -410.057455) (xy 137.487323 -410.002945) (xy 137.495081 -409.948989)
			(xy 137.510438 -409.896686) (xy 137.533083 -409.847101) (xy 137.562554 -409.801244) (xy 137.598252 -409.760047)
			(xy 137.639449 -409.724351) (xy 137.685306 -409.69488) (xy 137.734891 -409.672236) (xy 137.787194 -409.656879)
			(xy 137.841151 -409.649123) (xy 137.868406 -409.64866) (xy 138.732006 -409.64866) (xy 138.759255 -409.649211)
			(xy 138.813197 -409.656967) (xy 138.865487 -409.672321) (xy 138.915059 -409.694961) (xy 138.960905 -409.724425)
			(xy 139.002091 -409.760113) (xy 139.037779 -409.8013) (xy 139.067242 -409.847146) (xy 139.089881 -409.896719)
			(xy 139.105234 -409.949009) (xy 139.11299 -410.002951) (xy 139.11299 -410.057449) (xy 139.112989 -410.057457)
			(xy 140.550523 -410.057457) (xy 140.550523 -410.002943) (xy 140.558282 -409.948983) (xy 140.573642 -409.896677)
			(xy 140.596289 -409.84709) (xy 140.625764 -409.801231) (xy 140.661466 -409.760033) (xy 140.702667 -409.724337)
			(xy 140.74853 -409.694867) (xy 140.79812 -409.672225) (xy 140.850428 -409.656872) (xy 140.904389 -409.64912)
			(xy 140.931646 -409.64866) (xy 141.795246 -409.64866) (xy 141.822493 -409.649213) (xy 141.876431 -409.656975)
			(xy 141.928716 -409.672332) (xy 141.978283 -409.694974) (xy 142.024124 -409.724439) (xy 142.065305 -409.760128)
			(xy 142.100988 -409.801313) (xy 142.130448 -409.847157) (xy 142.153084 -409.896727) (xy 142.168435 -409.949014)
			(xy 142.17619 -410.002953) (xy 142.17619 -410.057447) (xy 142.176189 -410.057453) (xy 143.613846 -410.057453)
			(xy 143.613846 -410.002947) (xy 143.621603 -409.948996) (xy 143.636958 -409.896698) (xy 143.6596 -409.847118)
			(xy 143.689068 -409.801264) (xy 143.724761 -409.760071) (xy 143.765953 -409.724376) (xy 143.811805 -409.694907)
			(xy 143.861385 -409.672263) (xy 143.913682 -409.656906) (xy 143.967633 -409.649147) (xy 143.994886 -409.64866)
			(xy 144.858486 -409.64866) (xy 144.885737 -409.649186) (xy 144.939685 -409.656941) (xy 144.99198 -409.672295)
			(xy 145.041558 -409.694934) (xy 145.087409 -409.724399) (xy 145.1286 -409.76009) (xy 145.164292 -409.80128)
			(xy 145.193759 -409.84713) (xy 145.216401 -409.896707) (xy 145.231756 -409.949001) (xy 145.239513 -410.002949)
			(xy 145.239513 -410.057451) (xy 145.239512 -410.057456) (xy 146.677023 -410.057456) (xy 146.677023 -410.002944)
			(xy 146.684781 -409.948986) (xy 146.70014 -409.896681) (xy 146.722786 -409.847095) (xy 146.752259 -409.801237)
			(xy 146.787959 -409.76004) (xy 146.829158 -409.724344) (xy 146.875018 -409.694874) (xy 146.924606 -409.672231)
			(xy 146.976911 -409.656876) (xy 147.03087 -409.649121) (xy 147.058126 -409.64866) (xy 147.921726 -409.64866)
			(xy 147.948974 -409.649212) (xy 148.002914 -409.656971) (xy 148.055201 -409.672327) (xy 148.104771 -409.694968)
			(xy 148.150614 -409.724432) (xy 148.191798 -409.760121) (xy 148.227484 -409.801307) (xy 148.256945 -409.847152)
			(xy 148.279582 -409.896723) (xy 148.294935 -409.949011) (xy 148.30269 -410.002952) (xy 148.30269 -410.057448)
			(xy 148.302689 -410.057452) (xy 149.740346 -410.057452) (xy 149.740346 -410.002948) (xy 149.748102 -409.948999)
			(xy 149.763457 -409.896702) (xy 149.786097 -409.847123) (xy 149.815563 -409.801271) (xy 149.851254 -409.760078)
			(xy 149.892443 -409.724383) (xy 149.938293 -409.694914) (xy 149.98787 -409.672269) (xy 150.040165 -409.656909)
			(xy 150.094114 -409.649148) (xy 150.121366 -409.64866) (xy 150.984966 -409.64866) (xy 151.012218 -409.649185)
			(xy 151.066168 -409.656937) (xy 151.118466 -409.672289) (xy 151.168046 -409.694928) (xy 151.2139 -409.724392)
			(xy 151.255093 -409.760083) (xy 151.290787 -409.801273) (xy 151.320256 -409.847124) (xy 151.342899 -409.896702)
			(xy 151.358255 -409.948999) (xy 151.366013 -410.002948) (xy 151.366013 -410.057452) (xy 151.366013 -410.057455)
			(xy 152.803523 -410.057455) (xy 152.803523 -410.002945) (xy 152.811281 -409.948989) (xy 152.826638 -409.896686)
			(xy 152.849283 -409.847101) (xy 152.878754 -409.801244) (xy 152.914452 -409.760047) (xy 152.955649 -409.724351)
			(xy 153.001506 -409.69488) (xy 153.051091 -409.672236) (xy 153.103394 -409.656879) (xy 153.157351 -409.649123)
			(xy 153.184606 -409.64866) (xy 154.048206 -409.64866) (xy 154.075455 -409.649211) (xy 154.129397 -409.656967)
			(xy 154.181687 -409.672321) (xy 154.231259 -409.694961) (xy 154.277105 -409.724425) (xy 154.318291 -409.760113)
			(xy 154.353979 -409.8013) (xy 154.383442 -409.847146) (xy 154.406081 -409.896719) (xy 154.421434 -409.949009)
			(xy 154.42919 -410.002951) (xy 154.42919 -410.057449) (xy 154.429189 -410.057457) (xy 155.866723 -410.057457)
			(xy 155.866723 -410.002943) (xy 155.874482 -409.948983) (xy 155.889842 -409.896677) (xy 155.912489 -409.84709)
			(xy 155.941964 -409.801231) (xy 155.977666 -409.760033) (xy 156.018867 -409.724337) (xy 156.06473 -409.694867)
			(xy 156.11432 -409.672225) (xy 156.166628 -409.656872) (xy 156.220589 -409.64912) (xy 156.247846 -409.64866)
			(xy 157.111446 -409.64866) (xy 157.138693 -409.649213) (xy 157.192631 -409.656975) (xy 157.244916 -409.672332)
			(xy 157.294483 -409.694974) (xy 157.340324 -409.724439) (xy 157.381505 -409.760128) (xy 157.417188 -409.801313)
			(xy 157.446648 -409.847157) (xy 157.469284 -409.896727) (xy 157.484635 -409.949014) (xy 157.49239 -410.002953)
			(xy 157.49239 -410.057447) (xy 157.492389 -410.057453) (xy 158.930046 -410.057453) (xy 158.930046 -410.002947)
			(xy 158.937803 -409.948996) (xy 158.953158 -409.896698) (xy 158.9758 -409.847118) (xy 159.005268 -409.801264)
			(xy 159.040961 -409.760071) (xy 159.082153 -409.724376) (xy 159.128005 -409.694907) (xy 159.177585 -409.672263)
			(xy 159.229882 -409.656906) (xy 159.283833 -409.649147) (xy 159.311086 -409.64866) (xy 160.174686 -409.64866)
			(xy 160.201937 -409.649186) (xy 160.255885 -409.656941) (xy 160.30818 -409.672295) (xy 160.357758 -409.694934)
			(xy 160.403609 -409.724399) (xy 160.4448 -409.76009) (xy 160.480492 -409.80128) (xy 160.509959 -409.84713)
			(xy 160.532601 -409.896707) (xy 160.547956 -409.949001) (xy 160.555713 -410.002949) (xy 160.555713 -410.057451)
			(xy 160.555712 -410.057456) (xy 161.993223 -410.057456) (xy 161.993223 -410.002944) (xy 162.000981 -409.948986)
			(xy 162.01634 -409.896681) (xy 162.038986 -409.847095) (xy 162.068459 -409.801237) (xy 162.104159 -409.76004)
			(xy 162.145358 -409.724344) (xy 162.191218 -409.694874) (xy 162.240806 -409.672231) (xy 162.293111 -409.656876)
			(xy 162.34707 -409.649121) (xy 162.374326 -409.64866) (xy 163.237926 -409.64866) (xy 163.265174 -409.649212)
			(xy 163.319114 -409.656971) (xy 163.371401 -409.672327) (xy 163.420971 -409.694968) (xy 163.466814 -409.724432)
			(xy 163.507998 -409.760121) (xy 163.543684 -409.801307) (xy 163.573145 -409.847152) (xy 163.595782 -409.896723)
			(xy 163.611135 -409.949011) (xy 163.61889 -410.002952) (xy 163.61889 -410.057448) (xy 163.611135 -410.111389)
			(xy 163.595782 -410.163677) (xy 163.573145 -410.213248) (xy 163.543684 -410.259093) (xy 163.507998 -410.300279)
			(xy 163.466814 -410.335968) (xy 163.420971 -410.365432) (xy 163.371401 -410.388073) (xy 163.319114 -410.403429)
			(xy 163.265174 -410.411188) (xy 163.237926 -410.411676) (xy 162.374326 -410.411676) (xy 162.34707 -410.411279)
			(xy 162.293111 -410.403524) (xy 162.240806 -410.388169) (xy 162.191218 -410.365526) (xy 162.145358 -410.336056)
			(xy 162.104159 -410.30036) (xy 162.068459 -410.259163) (xy 162.038986 -410.213305) (xy 162.01634 -410.163719)
			(xy 162.000981 -410.111414) (xy 161.993223 -410.057456) (xy 160.555712 -410.057456) (xy 160.547956 -410.111399)
			(xy 160.532601 -410.163693) (xy 160.509959 -410.21327) (xy 160.480492 -410.25912) (xy 160.4448 -410.30031)
			(xy 160.403609 -410.336001) (xy 160.357758 -410.365466) (xy 160.30818 -410.388105) (xy 160.255885 -410.403459)
			(xy 160.201937 -410.411214) (xy 160.174686 -410.411676) (xy 159.311086 -410.411676) (xy 159.283833 -410.411253)
			(xy 159.229882 -410.403494) (xy 159.177585 -410.388137) (xy 159.128005 -410.365493) (xy 159.082153 -410.336024)
			(xy 159.040961 -410.300329) (xy 159.005268 -410.259136) (xy 158.9758 -410.213282) (xy 158.953158 -410.163702)
			(xy 158.937803 -410.111404) (xy 158.930046 -410.057453) (xy 157.492389 -410.057453) (xy 157.484635 -410.111386)
			(xy 157.469284 -410.163673) (xy 157.446648 -410.213243) (xy 157.417188 -410.259087) (xy 157.381505 -410.300272)
			(xy 157.340324 -410.335961) (xy 157.294483 -410.365426) (xy 157.244916 -410.388068) (xy 157.192631 -410.403425)
			(xy 157.138693 -410.411187) (xy 157.111446 -410.411676) (xy 156.247846 -410.411676) (xy 156.220589 -410.41128)
			(xy 156.166628 -410.403528) (xy 156.11432 -410.388175) (xy 156.06473 -410.365533) (xy 156.018867 -410.336063)
			(xy 155.977666 -410.300367) (xy 155.941964 -410.259169) (xy 155.912489 -410.21331) (xy 155.889842 -410.163723)
			(xy 155.874482 -410.111417) (xy 155.866723 -410.057457) (xy 154.429189 -410.057457) (xy 154.421434 -410.111391)
			(xy 154.406081 -410.163681) (xy 154.383442 -410.213254) (xy 154.353979 -410.2591) (xy 154.318291 -410.300287)
			(xy 154.277105 -410.335975) (xy 154.231259 -410.365439) (xy 154.181687 -410.388079) (xy 154.129397 -410.403433)
			(xy 154.075455 -410.411189) (xy 154.048206 -410.411676) (xy 153.184606 -410.411676) (xy 153.157351 -410.411277)
			(xy 153.103394 -410.403521) (xy 153.051091 -410.388164) (xy 153.001506 -410.36552) (xy 152.955649 -410.336049)
			(xy 152.914452 -410.300353) (xy 152.878754 -410.259156) (xy 152.849283 -410.213299) (xy 152.826638 -410.163714)
			(xy 152.811281 -410.111411) (xy 152.803523 -410.057455) (xy 151.366013 -410.057455) (xy 151.358255 -410.111402)
			(xy 151.342899 -410.163698) (xy 151.320256 -410.213276) (xy 151.290787 -410.259127) (xy 151.255093 -410.300317)
			(xy 151.2139 -410.336008) (xy 151.168046 -410.365472) (xy 151.118466 -410.388111) (xy 151.066168 -410.403463)
			(xy 151.012218 -410.411215) (xy 150.984966 -410.411676) (xy 150.121366 -410.411676) (xy 150.094114 -410.411252)
			(xy 150.040165 -410.403491) (xy 149.98787 -410.388131) (xy 149.938293 -410.365486) (xy 149.892443 -410.336017)
			(xy 149.851254 -410.300322) (xy 149.815563 -410.259129) (xy 149.786097 -410.213277) (xy 149.763457 -410.163698)
			(xy 149.748102 -410.111401) (xy 149.740346 -410.057452) (xy 148.302689 -410.057452) (xy 148.294935 -410.111389)
			(xy 148.279582 -410.163677) (xy 148.256945 -410.213248) (xy 148.227484 -410.259093) (xy 148.191798 -410.300279)
			(xy 148.150614 -410.335968) (xy 148.104771 -410.365432) (xy 148.055201 -410.388073) (xy 148.002914 -410.403429)
			(xy 147.948974 -410.411188) (xy 147.921726 -410.411676) (xy 147.058126 -410.411676) (xy 147.03087 -410.411279)
			(xy 146.976911 -410.403524) (xy 146.924606 -410.388169) (xy 146.875018 -410.365526) (xy 146.829158 -410.336056)
			(xy 146.787959 -410.30036) (xy 146.752259 -410.259163) (xy 146.722786 -410.213305) (xy 146.70014 -410.163719)
			(xy 146.684781 -410.111414) (xy 146.677023 -410.057456) (xy 145.239512 -410.057456) (xy 145.231756 -410.111399)
			(xy 145.216401 -410.163693) (xy 145.193759 -410.21327) (xy 145.164292 -410.25912) (xy 145.1286 -410.30031)
			(xy 145.087409 -410.336001) (xy 145.041558 -410.365466) (xy 144.99198 -410.388105) (xy 144.939685 -410.403459)
			(xy 144.885737 -410.411214) (xy 144.858486 -410.411676) (xy 143.994886 -410.411676) (xy 143.967633 -410.411253)
			(xy 143.913682 -410.403494) (xy 143.861385 -410.388137) (xy 143.811805 -410.365493) (xy 143.765953 -410.336024)
			(xy 143.724761 -410.300329) (xy 143.689068 -410.259136) (xy 143.6596 -410.213282) (xy 143.636958 -410.163702)
			(xy 143.621603 -410.111404) (xy 143.613846 -410.057453) (xy 142.176189 -410.057453) (xy 142.168435 -410.111386)
			(xy 142.153084 -410.163673) (xy 142.130448 -410.213243) (xy 142.100988 -410.259087) (xy 142.065305 -410.300272)
			(xy 142.024124 -410.335961) (xy 141.978283 -410.365426) (xy 141.928716 -410.388068) (xy 141.876431 -410.403425)
			(xy 141.822493 -410.411187) (xy 141.795246 -410.411676) (xy 140.931646 -410.411676) (xy 140.904389 -410.41128)
			(xy 140.850428 -410.403528) (xy 140.79812 -410.388175) (xy 140.74853 -410.365533) (xy 140.702667 -410.336063)
			(xy 140.661466 -410.300367) (xy 140.625764 -410.259169) (xy 140.596289 -410.21331) (xy 140.573642 -410.163723)
			(xy 140.558282 -410.111417) (xy 140.550523 -410.057457) (xy 139.112989 -410.057457) (xy 139.105234 -410.111391)
			(xy 139.089881 -410.163681) (xy 139.067242 -410.213254) (xy 139.037779 -410.2591) (xy 139.002091 -410.300287)
			(xy 138.960905 -410.335975) (xy 138.915059 -410.365439) (xy 138.865487 -410.388079) (xy 138.813197 -410.403433)
			(xy 138.759255 -410.411189) (xy 138.732006 -410.411676) (xy 137.868406 -410.411676) (xy 137.841151 -410.411277)
			(xy 137.787194 -410.403521) (xy 137.734891 -410.388164) (xy 137.685306 -410.36552) (xy 137.639449 -410.336049)
			(xy 137.598252 -410.300353) (xy 137.562554 -410.259156) (xy 137.533083 -410.213299) (xy 137.510438 -410.163714)
			(xy 137.495081 -410.111411) (xy 137.487323 -410.057455) (xy 136.049813 -410.057455) (xy 136.042055 -410.111402)
			(xy 136.026699 -410.163698) (xy 136.004056 -410.213276) (xy 135.974587 -410.259127) (xy 135.938893 -410.300317)
			(xy 135.8977 -410.336008) (xy 135.851846 -410.365472) (xy 135.802266 -410.388111) (xy 135.749968 -410.403463)
			(xy 135.696018 -410.411215) (xy 135.668766 -410.411676) (xy 134.805166 -410.411676) (xy 134.777914 -410.411252)
			(xy 134.723965 -410.403491) (xy 134.67167 -410.388131) (xy 134.622093 -410.365486) (xy 134.576243 -410.336017)
			(xy 134.535054 -410.300322) (xy 134.499363 -410.259129) (xy 134.469897 -410.213277) (xy 134.447257 -410.163698)
			(xy 134.431902 -410.111401) (xy 134.424146 -410.057452) (xy 132.986489 -410.057452) (xy 132.978735 -410.111389)
			(xy 132.963382 -410.163677) (xy 132.940745 -410.213248) (xy 132.911284 -410.259093) (xy 132.875598 -410.300279)
			(xy 132.834414 -410.335968) (xy 132.788571 -410.365432) (xy 132.739001 -410.388073) (xy 132.686714 -410.403429)
			(xy 132.632774 -410.411188) (xy 132.605526 -410.411676) (xy 131.741926 -410.411676) (xy 131.71467 -410.411279)
			(xy 131.660711 -410.403524) (xy 131.608406 -410.388169) (xy 131.558818 -410.365526) (xy 131.512958 -410.336056)
			(xy 131.471759 -410.30036) (xy 131.436059 -410.259163) (xy 131.406586 -410.213305) (xy 131.38394 -410.163719)
			(xy 131.368581 -410.111414) (xy 131.360823 -410.057456) (xy 129.923312 -410.057456) (xy 129.915556 -410.111399)
			(xy 129.900201 -410.163693) (xy 129.877559 -410.21327) (xy 129.848092 -410.25912) (xy 129.8124 -410.30031)
			(xy 129.771209 -410.336001) (xy 129.725358 -410.365466) (xy 129.67578 -410.388105) (xy 129.623485 -410.403459)
			(xy 129.569537 -410.411214) (xy 129.542286 -410.411676) (xy 128.678686 -410.411676) (xy 128.651433 -410.411253)
			(xy 128.597482 -410.403494) (xy 128.545185 -410.388137) (xy 128.495605 -410.365493) (xy 128.449753 -410.336024)
			(xy 128.408561 -410.300329) (xy 128.372868 -410.259136) (xy 128.3434 -410.213282) (xy 128.320758 -410.163702)
			(xy 128.305403 -410.111404) (xy 128.297646 -410.057453) (xy 126.859989 -410.057453) (xy 126.852235 -410.111386)
			(xy 126.836884 -410.163673) (xy 126.814248 -410.213243) (xy 126.784788 -410.259087) (xy 126.749105 -410.300272)
			(xy 126.707924 -410.335961) (xy 126.662083 -410.365426) (xy 126.612516 -410.388068) (xy 126.560231 -410.403425)
			(xy 126.506293 -410.411187) (xy 126.479046 -410.411676) (xy 125.615446 -410.411676) (xy 125.588189 -410.41128)
			(xy 125.534228 -410.403528) (xy 125.48192 -410.388175) (xy 125.43233 -410.365533) (xy 125.386467 -410.336063)
			(xy 125.345266 -410.300367) (xy 125.309564 -410.259169) (xy 125.280089 -410.21331) (xy 125.257442 -410.163723)
			(xy 125.242082 -410.111417) (xy 125.234323 -410.057457) (xy 123.796789 -410.057457) (xy 123.789034 -410.111391)
			(xy 123.773681 -410.163681) (xy 123.751042 -410.213254) (xy 123.721579 -410.2591) (xy 123.685891 -410.300287)
			(xy 123.644705 -410.335975) (xy 123.598859 -410.365439) (xy 123.549287 -410.388079) (xy 123.496997 -410.403433)
			(xy 123.443055 -410.411189) (xy 123.415806 -410.411676) (xy 122.552206 -410.411676) (xy 122.524951 -410.411277)
			(xy 122.470994 -410.403521) (xy 122.418691 -410.388164) (xy 122.369106 -410.36552) (xy 122.323249 -410.336049)
			(xy 122.282052 -410.300353) (xy 122.246354 -410.259156) (xy 122.216883 -410.213299) (xy 122.194238 -410.163714)
			(xy 122.178881 -410.111411) (xy 122.171123 -410.057455) (xy 120.733613 -410.057455) (xy 120.725855 -410.111402)
			(xy 120.710499 -410.163698) (xy 120.687856 -410.213276) (xy 120.658387 -410.259127) (xy 120.622693 -410.300317)
			(xy 120.5815 -410.336008) (xy 120.535646 -410.365472) (xy 120.486066 -410.388111) (xy 120.433768 -410.403463)
			(xy 120.379818 -410.411215) (xy 120.352566 -410.411676) (xy 119.488966 -410.411676) (xy 119.461714 -410.411252)
			(xy 119.407765 -410.403491) (xy 119.35547 -410.388131) (xy 119.305893 -410.365486) (xy 119.260043 -410.336017)
			(xy 119.218854 -410.300322) (xy 119.183163 -410.259129) (xy 119.153697 -410.213277) (xy 119.131057 -410.163698)
			(xy 119.115702 -410.111401) (xy 119.107946 -410.057452) (xy 117.670289 -410.057452) (xy 117.662535 -410.111389)
			(xy 117.647182 -410.163677) (xy 117.624545 -410.213248) (xy 117.595084 -410.259093) (xy 117.559398 -410.300279)
			(xy 117.518214 -410.335968) (xy 117.472371 -410.365432) (xy 117.422801 -410.388073) (xy 117.370514 -410.403429)
			(xy 117.316574 -410.411188) (xy 117.289326 -410.411676) (xy 116.425726 -410.411676) (xy 116.39847 -410.411279)
			(xy 116.344511 -410.403524) (xy 116.292206 -410.388169) (xy 116.242618 -410.365526) (xy 116.196758 -410.336056)
			(xy 116.155559 -410.30036) (xy 116.119859 -410.259163) (xy 116.090386 -410.213305) (xy 116.06774 -410.163719)
			(xy 116.052381 -410.111414) (xy 116.044623 -410.057456) (xy 111.28975 -410.057456) (xy 111.276373 -410.086747)
			(xy 111.246907 -410.132597) (xy 111.211216 -410.173788) (xy 111.170025 -410.209479) (xy 111.124175 -410.238945)
			(xy 111.074598 -410.261587) (xy 111.022303 -410.276942) (xy 110.968355 -410.284698) (xy 110.913853 -410.284698)
			(xy 110.859905 -410.276942) (xy 110.80761 -410.261587) (xy 110.758033 -410.238945) (xy 110.712183 -410.209479)
			(xy 110.670992 -410.173788) (xy 110.635301 -410.132597) (xy 110.605835 -410.086747) (xy 110.583193 -410.03717)
			(xy 110.567838 -409.984875) (xy 110.560082 -409.930927) (xy 110.559596 -409.903676) (xy 102.748244 -409.903676)
			(xy 102.708181 -409.921973) (xy 102.655851 -409.937338) (xy 102.601867 -409.9451) (xy 102.547329 -409.9451)
			(xy 102.493345 -409.937338) (xy 102.441015 -409.921973) (xy 102.391405 -409.899316) (xy 102.345524 -409.86983)
			(xy 102.304307 -409.834115) (xy 102.268592 -409.792898) (xy 102.239106 -409.747017) (xy 102.216449 -409.697407)
			(xy 102.201084 -409.645077) (xy 102.193322 -409.591093) (xy 102.192836 -409.563824) (xy 7.00913 -409.563824)
			(xy 7.00913 -410.057453) (xy 48.944746 -410.057453) (xy 48.944746 -410.002947) (xy 48.952503 -409.948996)
			(xy 48.967858 -409.896698) (xy 48.9905 -409.847118) (xy 49.019967 -409.801265) (xy 49.05566 -409.760071)
			(xy 49.096852 -409.724377) (xy 49.142704 -409.694908) (xy 49.192283 -409.672264) (xy 49.244581 -409.656906)
			(xy 49.298531 -409.649147) (xy 49.325784 -409.64866) (xy 50.189384 -409.64866) (xy 50.216635 -409.649186)
			(xy 50.270583 -409.656941) (xy 50.322879 -409.672294) (xy 50.372457 -409.694934) (xy 50.418308 -409.724399)
			(xy 50.459499 -409.760089) (xy 50.495192 -409.801279) (xy 50.524659 -409.847129) (xy 50.5473 -409.896706)
			(xy 50.562656 -409.949001) (xy 50.570413 -410.002949) (xy 50.570413 -410.057451) (xy 50.570412 -410.057456)
			(xy 52.007923 -410.057456) (xy 52.007923 -410.002944) (xy 52.015681 -409.948986) (xy 52.03104 -409.896682)
			(xy 52.053686 -409.847096) (xy 52.083159 -409.801238) (xy 52.118858 -409.760041) (xy 52.160057 -409.724344)
			(xy 52.205917 -409.694874) (xy 52.255504 -409.672231) (xy 52.30781 -409.656876) (xy 52.361768 -409.649121)
			(xy 52.389024 -409.64866) (xy 53.252624 -409.64866) (xy 53.279872 -409.649212) (xy 53.333812 -409.65697)
			(xy 53.3861 -409.672326) (xy 53.43567 -409.694967) (xy 53.481513 -409.724431) (xy 53.522697 -409.76012)
			(xy 53.558383 -409.801306) (xy 53.587845 -409.847151) (xy 53.610482 -409.896723) (xy 53.625835 -409.949011)
			(xy 53.63359 -410.002952) (xy 53.63359 -410.057448) (xy 53.633589 -410.057452) (xy 55.071246 -410.057452)
			(xy 55.071246 -410.002948) (xy 55.079002 -409.948999) (xy 55.094357 -409.896703) (xy 55.116997 -409.847124)
			(xy 55.146462 -409.801271) (xy 55.182153 -409.760079) (xy 55.223342 -409.724384) (xy 55.269192 -409.694914)
			(xy 55.318769 -409.672269) (xy 55.371064 -409.65691) (xy 55.425012 -409.649148) (xy 55.452264 -409.64866)
			(xy 56.315864 -409.64866) (xy 56.343116 -409.649185) (xy 56.397067 -409.656937) (xy 56.449364 -409.672289)
			(xy 56.498945 -409.694927) (xy 56.544799 -409.724392) (xy 56.585992 -409.760082) (xy 56.621687 -409.801273)
			(xy 56.651156 -409.847124) (xy 56.673799 -409.896702) (xy 56.689155 -409.948998) (xy 56.696913 -410.002948)
			(xy 56.696913 -410.057452) (xy 56.696913 -410.057455) (xy 58.134423 -410.057455) (xy 58.134423 -410.002945)
			(xy 58.142181 -409.948989) (xy 58.157538 -409.896686) (xy 58.180183 -409.847102) (xy 58.209654 -409.801244)
			(xy 58.245351 -409.760048) (xy 58.286548 -409.724351) (xy 58.332405 -409.694881) (xy 58.38199 -409.672237)
			(xy 58.434293 -409.65688) (xy 58.488249 -409.649123) (xy 58.515504 -409.64866) (xy 59.379104 -409.64866)
			(xy 59.406353 -409.64921) (xy 59.460295 -409.656967) (xy 59.512585 -409.672321) (xy 59.562158 -409.69496)
			(xy 59.608004 -409.724424) (xy 59.64919 -409.760113) (xy 59.684878 -409.801299) (xy 59.714342 -409.847146)
			(xy 59.73698 -409.896718) (xy 59.752334 -409.949008) (xy 59.76009 -410.002951) (xy 59.76009 -410.057449)
			(xy 59.760089 -410.057457) (xy 61.197623 -410.057457) (xy 61.197623 -410.002943) (xy 61.205382 -409.948983)
			(xy 61.220741 -409.896678) (xy 61.243389 -409.84709) (xy 61.272864 -409.801231) (xy 61.308565 -409.760034)
			(xy 61.349767 -409.724337) (xy 61.395629 -409.694868) (xy 61.445219 -409.672226) (xy 61.497527 -409.656872)
			(xy 61.551487 -409.64912) (xy 61.578744 -409.64866) (xy 62.442344 -409.64866) (xy 62.469591 -409.649213)
			(xy 62.523529 -409.656974) (xy 62.575814 -409.672332) (xy 62.625382 -409.694973) (xy 62.671223 -409.724438)
			(xy 62.712404 -409.760127) (xy 62.748088 -409.801313) (xy 62.777548 -409.847157) (xy 62.800184 -409.896727)
			(xy 62.815535 -409.949014) (xy 62.82329 -410.002953) (xy 62.82329 -410.057447) (xy 62.823289 -410.057453)
			(xy 64.260946 -410.057453) (xy 64.260946 -410.002947) (xy 64.268703 -409.948996) (xy 64.284058 -409.896698)
			(xy 64.3067 -409.847118) (xy 64.336167 -409.801265) (xy 64.37186 -409.760071) (xy 64.413052 -409.724377)
			(xy 64.458904 -409.694908) (xy 64.508483 -409.672264) (xy 64.560781 -409.656906) (xy 64.614731 -409.649147)
			(xy 64.641984 -409.64866) (xy 65.505584 -409.64866) (xy 65.532835 -409.649186) (xy 65.586783 -409.656941)
			(xy 65.639079 -409.672294) (xy 65.688657 -409.694934) (xy 65.734508 -409.724399) (xy 65.775699 -409.760089)
			(xy 65.811392 -409.801279) (xy 65.840859 -409.847129) (xy 65.8635 -409.896706) (xy 65.878856 -409.949001)
			(xy 65.886613 -410.002949) (xy 65.886613 -410.057451) (xy 65.886612 -410.057456) (xy 67.324123 -410.057456)
			(xy 67.324123 -410.002944) (xy 67.331881 -409.948986) (xy 67.34724 -409.896682) (xy 67.369886 -409.847096)
			(xy 67.399359 -409.801238) (xy 67.435058 -409.760041) (xy 67.476257 -409.724344) (xy 67.522117 -409.694874)
			(xy 67.571704 -409.672231) (xy 67.62401 -409.656876) (xy 67.677968 -409.649121) (xy 67.705224 -409.64866)
			(xy 68.568824 -409.64866) (xy 68.596072 -409.649212) (xy 68.650012 -409.65697) (xy 68.7023 -409.672326)
			(xy 68.75187 -409.694967) (xy 68.797713 -409.724431) (xy 68.838897 -409.76012) (xy 68.874583 -409.801306)
			(xy 68.904045 -409.847151) (xy 68.926682 -409.896723) (xy 68.942035 -409.949011) (xy 68.94979 -410.002952)
			(xy 68.94979 -410.057448) (xy 68.949789 -410.057452) (xy 70.387446 -410.057452) (xy 70.387446 -410.002948)
			(xy 70.395202 -409.948999) (xy 70.410557 -409.896703) (xy 70.433197 -409.847124) (xy 70.462662 -409.801271)
			(xy 70.498353 -409.760079) (xy 70.539542 -409.724384) (xy 70.585392 -409.694914) (xy 70.634969 -409.672269)
			(xy 70.687264 -409.65691) (xy 70.741212 -409.649148) (xy 70.768464 -409.64866) (xy 71.632064 -409.64866)
			(xy 71.659316 -409.649185) (xy 71.713267 -409.656937) (xy 71.765564 -409.672289) (xy 71.815145 -409.694927)
			(xy 71.860999 -409.724392) (xy 71.902192 -409.760082) (xy 71.937887 -409.801273) (xy 71.967356 -409.847124)
			(xy 71.989999 -409.896702) (xy 72.005355 -409.948998) (xy 72.013113 -410.002948) (xy 72.013113 -410.057452)
			(xy 72.013113 -410.057455) (xy 73.450623 -410.057455) (xy 73.450623 -410.002945) (xy 73.458381 -409.948989)
			(xy 73.473738 -409.896686) (xy 73.496383 -409.847102) (xy 73.525854 -409.801244) (xy 73.561551 -409.760048)
			(xy 73.602748 -409.724351) (xy 73.648605 -409.694881) (xy 73.69819 -409.672237) (xy 73.750493 -409.65688)
			(xy 73.804449 -409.649123) (xy 73.831704 -409.64866) (xy 74.695304 -409.64866) (xy 74.722553 -409.64921)
			(xy 74.776495 -409.656967) (xy 74.828785 -409.672321) (xy 74.878358 -409.69496) (xy 74.924204 -409.724424)
			(xy 74.96539 -409.760113) (xy 75.001078 -409.801299) (xy 75.030542 -409.847146) (xy 75.05318 -409.896718)
			(xy 75.068534 -409.949008) (xy 75.07629 -410.002951) (xy 75.07629 -410.057449) (xy 75.076289 -410.057457)
			(xy 76.513823 -410.057457) (xy 76.513823 -410.002943) (xy 76.521582 -409.948983) (xy 76.536941 -409.896678)
			(xy 76.559589 -409.84709) (xy 76.589064 -409.801231) (xy 76.624765 -409.760034) (xy 76.665967 -409.724337)
			(xy 76.711829 -409.694868) (xy 76.761419 -409.672226) (xy 76.813727 -409.656872) (xy 76.867687 -409.64912)
			(xy 76.894944 -409.64866) (xy 77.758544 -409.64866) (xy 77.785791 -409.649213) (xy 77.839729 -409.656974)
			(xy 77.892014 -409.672332) (xy 77.941582 -409.694973) (xy 77.987423 -409.724438) (xy 78.028604 -409.760127)
			(xy 78.064288 -409.801313) (xy 78.093748 -409.847157) (xy 78.116384 -409.896727) (xy 78.131735 -409.949014)
			(xy 78.13949 -410.002953) (xy 78.13949 -410.057447) (xy 78.139489 -410.057453) (xy 79.577146 -410.057453)
			(xy 79.577146 -410.002947) (xy 79.584903 -409.948996) (xy 79.600258 -409.896698) (xy 79.6229 -409.847118)
			(xy 79.652367 -409.801265) (xy 79.68806 -409.760071) (xy 79.729252 -409.724377) (xy 79.775104 -409.694908)
			(xy 79.824683 -409.672264) (xy 79.876981 -409.656906) (xy 79.930931 -409.649147) (xy 79.958184 -409.64866)
			(xy 80.821784 -409.64866) (xy 80.849035 -409.649186) (xy 80.902983 -409.656941) (xy 80.955279 -409.672294)
			(xy 81.004857 -409.694934) (xy 81.050708 -409.724399) (xy 81.091899 -409.760089) (xy 81.127592 -409.801279)
			(xy 81.157059 -409.847129) (xy 81.1797 -409.896706) (xy 81.195056 -409.949001) (xy 81.202813 -410.002949)
			(xy 81.202813 -410.057451) (xy 81.202812 -410.057456) (xy 82.640323 -410.057456) (xy 82.640323 -410.002944)
			(xy 82.648081 -409.948986) (xy 82.66344 -409.896682) (xy 82.686086 -409.847096) (xy 82.715559 -409.801238)
			(xy 82.751258 -409.760041) (xy 82.792457 -409.724344) (xy 82.838317 -409.694874) (xy 82.887904 -409.672231)
			(xy 82.94021 -409.656876) (xy 82.994168 -409.649121) (xy 83.021424 -409.64866) (xy 83.885024 -409.64866)
			(xy 83.912272 -409.649212) (xy 83.966212 -409.65697) (xy 84.0185 -409.672326) (xy 84.06807 -409.694967)
			(xy 84.113913 -409.724431) (xy 84.155097 -409.76012) (xy 84.190783 -409.801306) (xy 84.220245 -409.847151)
			(xy 84.242882 -409.896723) (xy 84.258235 -409.949011) (xy 84.26599 -410.002952) (xy 84.26599 -410.057448)
			(xy 84.265989 -410.057452) (xy 85.703646 -410.057452) (xy 85.703646 -410.002948) (xy 85.711402 -409.948999)
			(xy 85.726757 -409.896703) (xy 85.749397 -409.847124) (xy 85.778862 -409.801271) (xy 85.814553 -409.760079)
			(xy 85.855742 -409.724384) (xy 85.901592 -409.694914) (xy 85.951169 -409.672269) (xy 86.003464 -409.65691)
			(xy 86.057412 -409.649148) (xy 86.084664 -409.64866) (xy 86.948264 -409.64866) (xy 86.975516 -409.649185)
			(xy 87.029467 -409.656937) (xy 87.081764 -409.672289) (xy 87.131345 -409.694927) (xy 87.177199 -409.724392)
			(xy 87.218392 -409.760082) (xy 87.254087 -409.801273) (xy 87.283556 -409.847124) (xy 87.306199 -409.896702)
			(xy 87.321555 -409.948998) (xy 87.329313 -410.002948) (xy 87.329313 -410.057452) (xy 87.329313 -410.057455)
			(xy 88.766823 -410.057455) (xy 88.766823 -410.002945) (xy 88.774581 -409.948989) (xy 88.789938 -409.896686)
			(xy 88.812583 -409.847102) (xy 88.842054 -409.801244) (xy 88.877751 -409.760048) (xy 88.918948 -409.724351)
			(xy 88.964805 -409.694881) (xy 89.01439 -409.672237) (xy 89.066693 -409.65688) (xy 89.120649 -409.649123)
			(xy 89.147904 -409.64866) (xy 90.011504 -409.64866) (xy 90.038753 -409.64921) (xy 90.092695 -409.656967)
			(xy 90.144985 -409.672321) (xy 90.194558 -409.69496) (xy 90.240404 -409.724424) (xy 90.28159 -409.760113)
			(xy 90.317278 -409.801299) (xy 90.346742 -409.847146) (xy 90.36938 -409.896718) (xy 90.384734 -409.949008)
			(xy 90.39249 -410.002951) (xy 90.39249 -410.057449) (xy 90.392489 -410.057457) (xy 91.830023 -410.057457)
			(xy 91.830023 -410.002943) (xy 91.837782 -409.948983) (xy 91.853141 -409.896678) (xy 91.875789 -409.84709)
			(xy 91.905264 -409.801231) (xy 91.940965 -409.760034) (xy 91.982167 -409.724337) (xy 92.028029 -409.694868)
			(xy 92.077619 -409.672226) (xy 92.129927 -409.656872) (xy 92.183887 -409.64912) (xy 92.211144 -409.64866)
			(xy 93.074744 -409.64866) (xy 93.101991 -409.649213) (xy 93.155929 -409.656974) (xy 93.208214 -409.672332)
			(xy 93.257782 -409.694973) (xy 93.303623 -409.724438) (xy 93.344804 -409.760127) (xy 93.380488 -409.801313)
			(xy 93.409948 -409.847157) (xy 93.432584 -409.896727) (xy 93.447935 -409.949014) (xy 93.45569 -410.002953)
			(xy 93.45569 -410.057447) (xy 93.455689 -410.057453) (xy 94.893346 -410.057453) (xy 94.893346 -410.002947)
			(xy 94.901103 -409.948996) (xy 94.916458 -409.896698) (xy 94.9391 -409.847118) (xy 94.968567 -409.801265)
			(xy 95.00426 -409.760071) (xy 95.045452 -409.724377) (xy 95.091304 -409.694908) (xy 95.140883 -409.672264)
			(xy 95.193181 -409.656906) (xy 95.247131 -409.649147) (xy 95.274384 -409.64866) (xy 96.137984 -409.64866)
			(xy 96.165235 -409.649186) (xy 96.219183 -409.656941) (xy 96.271479 -409.672294) (xy 96.321057 -409.694934)
			(xy 96.366908 -409.724399) (xy 96.408099 -409.760089) (xy 96.443792 -409.801279) (xy 96.473259 -409.847129)
			(xy 96.4959 -409.896706) (xy 96.511256 -409.949001) (xy 96.519013 -410.002949) (xy 96.519013 -410.057451)
			(xy 96.511256 -410.111399) (xy 96.4959 -410.163694) (xy 96.473259 -410.213271) (xy 96.443792 -410.259121)
			(xy 96.408099 -410.300311) (xy 96.366908 -410.336001) (xy 96.321057 -410.365466) (xy 96.271479 -410.388106)
			(xy 96.219183 -410.403459) (xy 96.165235 -410.411214) (xy 96.137984 -410.411676) (xy 95.274384 -410.411676)
			(xy 95.247131 -410.411253) (xy 95.193181 -410.403494) (xy 95.140883 -410.388136) (xy 95.091304 -410.365492)
			(xy 95.045452 -410.336023) (xy 95.00426 -410.300329) (xy 94.968567 -410.259135) (xy 94.9391 -410.213282)
			(xy 94.916458 -410.163702) (xy 94.901103 -410.111404) (xy 94.893346 -410.057453) (xy 93.455689 -410.057453)
			(xy 93.447935 -410.111386) (xy 93.432584 -410.163673) (xy 93.409948 -410.213243) (xy 93.380488 -410.259087)
			(xy 93.344804 -410.300273) (xy 93.303623 -410.335962) (xy 93.257782 -410.365427) (xy 93.208214 -410.388068)
			(xy 93.155929 -410.403426) (xy 93.101991 -410.411187) (xy 93.074744 -410.411676) (xy 92.211144 -410.411676)
			(xy 92.183887 -410.41128) (xy 92.129927 -410.403528) (xy 92.077619 -410.388174) (xy 92.028029 -410.365532)
			(xy 91.982167 -410.336063) (xy 91.940965 -410.300366) (xy 91.905264 -410.259169) (xy 91.875789 -410.21331)
			(xy 91.853141 -410.163722) (xy 91.837782 -410.111417) (xy 91.830023 -410.057457) (xy 90.392489 -410.057457)
			(xy 90.384734 -410.111392) (xy 90.36938 -410.163682) (xy 90.346742 -410.213254) (xy 90.317278 -410.259101)
			(xy 90.28159 -410.300287) (xy 90.240404 -410.335976) (xy 90.194558 -410.36544) (xy 90.144985 -410.388079)
			(xy 90.092695 -410.403433) (xy 90.038753 -410.41119) (xy 90.011504 -410.411676) (xy 89.147904 -410.411676)
			(xy 89.120649 -410.411277) (xy 89.066693 -410.40352) (xy 89.01439 -410.388163) (xy 88.964805 -410.365519)
			(xy 88.918948 -410.336049) (xy 88.877751 -410.300352) (xy 88.842054 -410.259156) (xy 88.812583 -410.213298)
			(xy 88.789938 -410.163714) (xy 88.774581 -410.111411) (xy 88.766823 -410.057455) (xy 87.329313 -410.057455)
			(xy 87.321555 -410.111402) (xy 87.306199 -410.163698) (xy 87.283556 -410.213276) (xy 87.254087 -410.259127)
			(xy 87.218392 -410.300318) (xy 87.177199 -410.336008) (xy 87.131345 -410.365473) (xy 87.081764 -410.388111)
			(xy 87.029467 -410.403463) (xy 86.975516 -410.411215) (xy 86.948264 -410.411676) (xy 86.084664 -410.411676)
			(xy 86.057412 -410.411252) (xy 86.003464 -410.40349) (xy 85.951169 -410.388131) (xy 85.901592 -410.365486)
			(xy 85.855742 -410.336016) (xy 85.814553 -410.300321) (xy 85.778862 -410.259129) (xy 85.749397 -410.213276)
			(xy 85.726757 -410.163697) (xy 85.711402 -410.111401) (xy 85.703646 -410.057452) (xy 84.265989 -410.057452)
			(xy 84.258235 -410.111389) (xy 84.242882 -410.163677) (xy 84.220245 -410.213249) (xy 84.190783 -410.259094)
			(xy 84.155097 -410.30028) (xy 84.113913 -410.335969) (xy 84.06807 -410.365433) (xy 84.0185 -410.388074)
			(xy 83.966212 -410.40343) (xy 83.912272 -410.411188) (xy 83.885024 -410.411676) (xy 83.021424 -410.411676)
			(xy 82.994168 -410.411279) (xy 82.94021 -410.403524) (xy 82.887904 -410.388169) (xy 82.838317 -410.365526)
			(xy 82.792457 -410.336056) (xy 82.751258 -410.300359) (xy 82.715559 -410.259162) (xy 82.686086 -410.213304)
			(xy 82.66344 -410.163718) (xy 82.648081 -410.111414) (xy 82.640323 -410.057456) (xy 81.202812 -410.057456)
			(xy 81.195056 -410.111399) (xy 81.1797 -410.163694) (xy 81.157059 -410.213271) (xy 81.127592 -410.259121)
			(xy 81.091899 -410.300311) (xy 81.050708 -410.336001) (xy 81.004857 -410.365466) (xy 80.955279 -410.388106)
			(xy 80.902983 -410.403459) (xy 80.849035 -410.411214) (xy 80.821784 -410.411676) (xy 79.958184 -410.411676)
			(xy 79.930931 -410.411253) (xy 79.876981 -410.403494) (xy 79.824683 -410.388136) (xy 79.775104 -410.365492)
			(xy 79.729252 -410.336023) (xy 79.68806 -410.300329) (xy 79.652367 -410.259135) (xy 79.6229 -410.213282)
			(xy 79.600258 -410.163702) (xy 79.584903 -410.111404) (xy 79.577146 -410.057453) (xy 78.139489 -410.057453)
			(xy 78.131735 -410.111386) (xy 78.116384 -410.163673) (xy 78.093748 -410.213243) (xy 78.064288 -410.259087)
			(xy 78.028604 -410.300273) (xy 77.987423 -410.335962) (xy 77.941582 -410.365427) (xy 77.892014 -410.388068)
			(xy 77.839729 -410.403426) (xy 77.785791 -410.411187) (xy 77.758544 -410.411676) (xy 76.894944 -410.411676)
			(xy 76.867687 -410.41128) (xy 76.813727 -410.403528) (xy 76.761419 -410.388174) (xy 76.711829 -410.365532)
			(xy 76.665967 -410.336063) (xy 76.624765 -410.300366) (xy 76.589064 -410.259169) (xy 76.559589 -410.21331)
			(xy 76.536941 -410.163722) (xy 76.521582 -410.111417) (xy 76.513823 -410.057457) (xy 75.076289 -410.057457)
			(xy 75.068534 -410.111392) (xy 75.05318 -410.163682) (xy 75.030542 -410.213254) (xy 75.001078 -410.259101)
			(xy 74.96539 -410.300287) (xy 74.924204 -410.335976) (xy 74.878358 -410.36544) (xy 74.828785 -410.388079)
			(xy 74.776495 -410.403433) (xy 74.722553 -410.41119) (xy 74.695304 -410.411676) (xy 73.831704 -410.411676)
			(xy 73.804449 -410.411277) (xy 73.750493 -410.40352) (xy 73.69819 -410.388163) (xy 73.648605 -410.365519)
			(xy 73.602748 -410.336049) (xy 73.561551 -410.300352) (xy 73.525854 -410.259156) (xy 73.496383 -410.213298)
			(xy 73.473738 -410.163714) (xy 73.458381 -410.111411) (xy 73.450623 -410.057455) (xy 72.013113 -410.057455)
			(xy 72.005355 -410.111402) (xy 71.989999 -410.163698) (xy 71.967356 -410.213276) (xy 71.937887 -410.259127)
			(xy 71.902192 -410.300318) (xy 71.860999 -410.336008) (xy 71.815145 -410.365473) (xy 71.765564 -410.388111)
			(xy 71.713267 -410.403463) (xy 71.659316 -410.411215) (xy 71.632064 -410.411676) (xy 70.768464 -410.411676)
			(xy 70.741212 -410.411252) (xy 70.687264 -410.40349) (xy 70.634969 -410.388131) (xy 70.585392 -410.365486)
			(xy 70.539542 -410.336016) (xy 70.498353 -410.300321) (xy 70.462662 -410.259129) (xy 70.433197 -410.213276)
			(xy 70.410557 -410.163697) (xy 70.395202 -410.111401) (xy 70.387446 -410.057452) (xy 68.949789 -410.057452)
			(xy 68.942035 -410.111389) (xy 68.926682 -410.163677) (xy 68.904045 -410.213249) (xy 68.874583 -410.259094)
			(xy 68.838897 -410.30028) (xy 68.797713 -410.335969) (xy 68.75187 -410.365433) (xy 68.7023 -410.388074)
			(xy 68.650012 -410.40343) (xy 68.596072 -410.411188) (xy 68.568824 -410.411676) (xy 67.705224 -410.411676)
			(xy 67.677968 -410.411279) (xy 67.62401 -410.403524) (xy 67.571704 -410.388169) (xy 67.522117 -410.365526)
			(xy 67.476257 -410.336056) (xy 67.435058 -410.300359) (xy 67.399359 -410.259162) (xy 67.369886 -410.213304)
			(xy 67.34724 -410.163718) (xy 67.331881 -410.111414) (xy 67.324123 -410.057456) (xy 65.886612 -410.057456)
			(xy 65.878856 -410.111399) (xy 65.8635 -410.163694) (xy 65.840859 -410.213271) (xy 65.811392 -410.259121)
			(xy 65.775699 -410.300311) (xy 65.734508 -410.336001) (xy 65.688657 -410.365466) (xy 65.639079 -410.388106)
			(xy 65.586783 -410.403459) (xy 65.532835 -410.411214) (xy 65.505584 -410.411676) (xy 64.641984 -410.411676)
			(xy 64.614731 -410.411253) (xy 64.560781 -410.403494) (xy 64.508483 -410.388136) (xy 64.458904 -410.365492)
			(xy 64.413052 -410.336023) (xy 64.37186 -410.300329) (xy 64.336167 -410.259135) (xy 64.3067 -410.213282)
			(xy 64.284058 -410.163702) (xy 64.268703 -410.111404) (xy 64.260946 -410.057453) (xy 62.823289 -410.057453)
			(xy 62.815535 -410.111386) (xy 62.800184 -410.163673) (xy 62.777548 -410.213243) (xy 62.748088 -410.259087)
			(xy 62.712404 -410.300273) (xy 62.671223 -410.335962) (xy 62.625382 -410.365427) (xy 62.575814 -410.388068)
			(xy 62.523529 -410.403426) (xy 62.469591 -410.411187) (xy 62.442344 -410.411676) (xy 61.578744 -410.411676)
			(xy 61.551487 -410.41128) (xy 61.497527 -410.403528) (xy 61.445219 -410.388174) (xy 61.395629 -410.365532)
			(xy 61.349767 -410.336063) (xy 61.308565 -410.300366) (xy 61.272864 -410.259169) (xy 61.243389 -410.21331)
			(xy 61.220741 -410.163722) (xy 61.205382 -410.111417) (xy 61.197623 -410.057457) (xy 59.760089 -410.057457)
			(xy 59.752334 -410.111392) (xy 59.73698 -410.163682) (xy 59.714342 -410.213254) (xy 59.684878 -410.259101)
			(xy 59.64919 -410.300287) (xy 59.608004 -410.335976) (xy 59.562158 -410.36544) (xy 59.512585 -410.388079)
			(xy 59.460295 -410.403433) (xy 59.406353 -410.41119) (xy 59.379104 -410.411676) (xy 58.515504 -410.411676)
			(xy 58.488249 -410.411277) (xy 58.434293 -410.40352) (xy 58.38199 -410.388163) (xy 58.332405 -410.365519)
			(xy 58.286548 -410.336049) (xy 58.245351 -410.300352) (xy 58.209654 -410.259156) (xy 58.180183 -410.213298)
			(xy 58.157538 -410.163714) (xy 58.142181 -410.111411) (xy 58.134423 -410.057455) (xy 56.696913 -410.057455)
			(xy 56.689155 -410.111402) (xy 56.673799 -410.163698) (xy 56.651156 -410.213276) (xy 56.621687 -410.259127)
			(xy 56.585992 -410.300318) (xy 56.544799 -410.336008) (xy 56.498945 -410.365473) (xy 56.449364 -410.388111)
			(xy 56.397067 -410.403463) (xy 56.343116 -410.411215) (xy 56.315864 -410.411676) (xy 55.452264 -410.411676)
			(xy 55.425012 -410.411252) (xy 55.371064 -410.40349) (xy 55.318769 -410.388131) (xy 55.269192 -410.365486)
			(xy 55.223342 -410.336016) (xy 55.182153 -410.300321) (xy 55.146462 -410.259129) (xy 55.116997 -410.213276)
			(xy 55.094357 -410.163697) (xy 55.079002 -410.111401) (xy 55.071246 -410.057452) (xy 53.633589 -410.057452)
			(xy 53.625835 -410.111389) (xy 53.610482 -410.163677) (xy 53.587845 -410.213249) (xy 53.558383 -410.259094)
			(xy 53.522697 -410.30028) (xy 53.481513 -410.335969) (xy 53.43567 -410.365433) (xy 53.3861 -410.388074)
			(xy 53.333812 -410.40343) (xy 53.279872 -410.411188) (xy 53.252624 -410.411676) (xy 52.389024 -410.411676)
			(xy 52.361768 -410.411279) (xy 52.30781 -410.403524) (xy 52.255504 -410.388169) (xy 52.205917 -410.365526)
			(xy 52.160057 -410.336056) (xy 52.118858 -410.300359) (xy 52.083159 -410.259162) (xy 52.053686 -410.213304)
			(xy 52.03104 -410.163718) (xy 52.015681 -410.111414) (xy 52.007923 -410.057456) (xy 50.570412 -410.057456)
			(xy 50.562656 -410.111399) (xy 50.5473 -410.163694) (xy 50.524659 -410.213271) (xy 50.495192 -410.259121)
			(xy 50.459499 -410.300311) (xy 50.418308 -410.336001) (xy 50.372457 -410.365466) (xy 50.322879 -410.388106)
			(xy 50.270583 -410.403459) (xy 50.216635 -410.411214) (xy 50.189384 -410.411676) (xy 49.325784 -410.411676)
			(xy 49.298531 -410.411253) (xy 49.244581 -410.403494) (xy 49.192283 -410.388136) (xy 49.142704 -410.365492)
			(xy 49.096852 -410.336023) (xy 49.05566 -410.300329) (xy 49.019967 -410.259135) (xy 48.9905 -410.213282)
			(xy 48.967858 -410.163702) (xy 48.952503 -410.111404) (xy 48.944746 -410.057453) (xy 7.00913 -410.057453)
			(xy 7.00913 -413.4485) (xy 38.974268 -413.4485) (xy 38.974268 -412.5849) (xy 38.974754 -412.557631)
			(xy 38.982516 -412.503647) (xy 38.997881 -412.451317) (xy 39.020538 -412.401707) (xy 39.050024 -412.355826)
			(xy 39.085739 -412.314609) (xy 39.126956 -412.278894) (xy 39.172837 -412.249408) (xy 39.222447 -412.226751)
			(xy 39.274777 -412.211386) (xy 39.328761 -412.203624) (xy 39.383299 -412.203624) (xy 39.437283 -412.211386)
			(xy 39.489613 -412.226751) (xy 39.539223 -412.249408) (xy 39.585104 -412.278894) (xy 39.626321 -412.314609)
			(xy 39.662036 -412.355826) (xy 39.691522 -412.401707) (xy 39.714179 -412.451317) (xy 39.729544 -412.503647)
			(xy 39.737306 -412.557631) (xy 39.737792 -412.5849) (xy 39.737792 -412.597452) (xy 47.413146 -412.597452)
			(xy 47.413146 -412.542948) (xy 47.420902 -412.488999) (xy 47.436257 -412.436703) (xy 47.458897 -412.387124)
			(xy 47.488362 -412.341271) (xy 47.524053 -412.300079) (xy 47.565242 -412.264384) (xy 47.611092 -412.234914)
			(xy 47.660669 -412.212269) (xy 47.712964 -412.19691) (xy 47.766912 -412.189148) (xy 47.794164 -412.18866)
			(xy 48.657764 -412.18866) (xy 48.685016 -412.189185) (xy 48.738967 -412.196937) (xy 48.791264 -412.212289)
			(xy 48.840845 -412.234927) (xy 48.886699 -412.264392) (xy 48.927892 -412.300082) (xy 48.963587 -412.341273)
			(xy 48.993056 -412.387124) (xy 49.015699 -412.436702) (xy 49.031055 -412.488998) (xy 49.038813 -412.542948)
			(xy 49.038813 -412.597452) (xy 49.038813 -412.597455) (xy 50.476323 -412.597455) (xy 50.476323 -412.542945)
			(xy 50.484081 -412.488989) (xy 50.499438 -412.436686) (xy 50.522083 -412.387102) (xy 50.551554 -412.341244)
			(xy 50.587251 -412.300048) (xy 50.628448 -412.264351) (xy 50.674305 -412.234881) (xy 50.72389 -412.212237)
			(xy 50.776193 -412.19688) (xy 50.830149 -412.189123) (xy 50.857404 -412.18866) (xy 51.721004 -412.18866)
			(xy 51.748253 -412.18921) (xy 51.802195 -412.196967) (xy 51.854485 -412.212321) (xy 51.904058 -412.23496)
			(xy 51.949904 -412.264424) (xy 51.99109 -412.300113) (xy 52.026778 -412.341299) (xy 52.056242 -412.387146)
			(xy 52.07888 -412.436718) (xy 52.094234 -412.489008) (xy 52.10199 -412.542951) (xy 52.10199 -412.597449)
			(xy 52.101989 -412.597457) (xy 53.539523 -412.597457) (xy 53.539523 -412.542943) (xy 53.547282 -412.488983)
			(xy 53.562641 -412.436678) (xy 53.585289 -412.38709) (xy 53.614764 -412.341231) (xy 53.650465 -412.300034)
			(xy 53.691667 -412.264337) (xy 53.737529 -412.234868) (xy 53.787119 -412.212226) (xy 53.839427 -412.196872)
			(xy 53.893387 -412.18912) (xy 53.920644 -412.18866) (xy 54.784244 -412.18866) (xy 54.811491 -412.189213)
			(xy 54.865429 -412.196974) (xy 54.917714 -412.212332) (xy 54.967282 -412.234973) (xy 55.013123 -412.264438)
			(xy 55.054304 -412.300127) (xy 55.089988 -412.341313) (xy 55.119448 -412.387157) (xy 55.142084 -412.436727)
			(xy 55.157435 -412.489014) (xy 55.16519 -412.542953) (xy 55.16519 -412.597447) (xy 55.165189 -412.597453)
			(xy 56.602846 -412.597453) (xy 56.602846 -412.542947) (xy 56.610603 -412.488996) (xy 56.625958 -412.436698)
			(xy 56.6486 -412.387118) (xy 56.678067 -412.341265) (xy 56.71376 -412.300071) (xy 56.754952 -412.264377)
			(xy 56.800804 -412.234908) (xy 56.850383 -412.212264) (xy 56.902681 -412.196906) (xy 56.956631 -412.189147)
			(xy 56.983884 -412.18866) (xy 57.847484 -412.18866) (xy 57.874735 -412.189186) (xy 57.928683 -412.196941)
			(xy 57.980979 -412.212294) (xy 58.030557 -412.234934) (xy 58.076408 -412.264399) (xy 58.117599 -412.300089)
			(xy 58.153292 -412.341279) (xy 58.182759 -412.387129) (xy 58.2054 -412.436706) (xy 58.220756 -412.489001)
			(xy 58.228513 -412.542949) (xy 58.228513 -412.597451) (xy 58.228512 -412.597456) (xy 59.666023 -412.597456)
			(xy 59.666023 -412.542944) (xy 59.673781 -412.488986) (xy 59.68914 -412.436682) (xy 59.711786 -412.387096)
			(xy 59.741259 -412.341238) (xy 59.776958 -412.300041) (xy 59.818157 -412.264344) (xy 59.864017 -412.234874)
			(xy 59.913604 -412.212231) (xy 59.96591 -412.196876) (xy 60.019868 -412.189121) (xy 60.047124 -412.18866)
			(xy 60.910724 -412.18866) (xy 60.937972 -412.189212) (xy 60.991912 -412.19697) (xy 61.0442 -412.212326)
			(xy 61.09377 -412.234967) (xy 61.139613 -412.264431) (xy 61.180797 -412.30012) (xy 61.216483 -412.341306)
			(xy 61.245945 -412.387151) (xy 61.268582 -412.436723) (xy 61.283935 -412.489011) (xy 61.29169 -412.542952)
			(xy 61.29169 -412.597448) (xy 61.291689 -412.597452) (xy 62.729346 -412.597452) (xy 62.729346 -412.542948)
			(xy 62.737102 -412.488999) (xy 62.752457 -412.436703) (xy 62.775097 -412.387124) (xy 62.804562 -412.341271)
			(xy 62.840253 -412.300079) (xy 62.881442 -412.264384) (xy 62.927292 -412.234914) (xy 62.976869 -412.212269)
			(xy 63.029164 -412.19691) (xy 63.083112 -412.189148) (xy 63.110364 -412.18866) (xy 63.973964 -412.18866)
			(xy 64.001216 -412.189185) (xy 64.055167 -412.196937) (xy 64.107464 -412.212289) (xy 64.157045 -412.234927)
			(xy 64.202899 -412.264392) (xy 64.244092 -412.300082) (xy 64.279787 -412.341273) (xy 64.309256 -412.387124)
			(xy 64.331899 -412.436702) (xy 64.347255 -412.488998) (xy 64.355013 -412.542948) (xy 64.355013 -412.597452)
			(xy 64.355013 -412.597455) (xy 65.792523 -412.597455) (xy 65.792523 -412.542945) (xy 65.800281 -412.488989)
			(xy 65.815638 -412.436686) (xy 65.838283 -412.387102) (xy 65.867754 -412.341244) (xy 65.903451 -412.300048)
			(xy 65.944648 -412.264351) (xy 65.990505 -412.234881) (xy 66.04009 -412.212237) (xy 66.092393 -412.19688)
			(xy 66.146349 -412.189123) (xy 66.173604 -412.18866) (xy 67.037204 -412.18866) (xy 67.064453 -412.18921)
			(xy 67.118395 -412.196967) (xy 67.170685 -412.212321) (xy 67.220258 -412.23496) (xy 67.266104 -412.264424)
			(xy 67.30729 -412.300113) (xy 67.342978 -412.341299) (xy 67.372442 -412.387146) (xy 67.39508 -412.436718)
			(xy 67.410434 -412.489008) (xy 67.41819 -412.542951) (xy 67.41819 -412.597449) (xy 67.418189 -412.597457)
			(xy 68.855723 -412.597457) (xy 68.855723 -412.542943) (xy 68.863482 -412.488983) (xy 68.878841 -412.436678)
			(xy 68.901489 -412.38709) (xy 68.930964 -412.341231) (xy 68.966665 -412.300034) (xy 69.007867 -412.264337)
			(xy 69.053729 -412.234868) (xy 69.103319 -412.212226) (xy 69.155627 -412.196872) (xy 69.209587 -412.18912)
			(xy 69.236844 -412.18866) (xy 70.100444 -412.18866) (xy 70.127691 -412.189213) (xy 70.181629 -412.196974)
			(xy 70.233914 -412.212332) (xy 70.283482 -412.234973) (xy 70.329323 -412.264438) (xy 70.370504 -412.300127)
			(xy 70.406188 -412.341313) (xy 70.435648 -412.387157) (xy 70.458284 -412.436727) (xy 70.473635 -412.489014)
			(xy 70.48139 -412.542953) (xy 70.48139 -412.597447) (xy 70.481389 -412.597453) (xy 71.919046 -412.597453)
			(xy 71.919046 -412.542947) (xy 71.926803 -412.488996) (xy 71.942158 -412.436698) (xy 71.9648 -412.387118)
			(xy 71.994267 -412.341265) (xy 72.02996 -412.300071) (xy 72.071152 -412.264377) (xy 72.117004 -412.234908)
			(xy 72.166583 -412.212264) (xy 72.218881 -412.196906) (xy 72.272831 -412.189147) (xy 72.300084 -412.18866)
			(xy 73.163684 -412.18866) (xy 73.190935 -412.189186) (xy 73.244883 -412.196941) (xy 73.297179 -412.212294)
			(xy 73.346757 -412.234934) (xy 73.392608 -412.264399) (xy 73.433799 -412.300089) (xy 73.469492 -412.341279)
			(xy 73.498959 -412.387129) (xy 73.5216 -412.436706) (xy 73.536956 -412.489001) (xy 73.544713 -412.542949)
			(xy 73.544713 -412.597451) (xy 73.544712 -412.597456) (xy 74.982223 -412.597456) (xy 74.982223 -412.542944)
			(xy 74.989981 -412.488986) (xy 75.00534 -412.436682) (xy 75.027986 -412.387096) (xy 75.057459 -412.341238)
			(xy 75.093158 -412.300041) (xy 75.134357 -412.264344) (xy 75.180217 -412.234874) (xy 75.229804 -412.212231)
			(xy 75.28211 -412.196876) (xy 75.336068 -412.189121) (xy 75.363324 -412.18866) (xy 76.226924 -412.18866)
			(xy 76.254172 -412.189212) (xy 76.308112 -412.19697) (xy 76.3604 -412.212326) (xy 76.40997 -412.234967)
			(xy 76.455813 -412.264431) (xy 76.496997 -412.30012) (xy 76.532683 -412.341306) (xy 76.562145 -412.387151)
			(xy 76.584782 -412.436723) (xy 76.600135 -412.489011) (xy 76.60789 -412.542952) (xy 76.60789 -412.597448)
			(xy 76.607889 -412.597452) (xy 78.045546 -412.597452) (xy 78.045546 -412.542948) (xy 78.053302 -412.488999)
			(xy 78.068657 -412.436703) (xy 78.091297 -412.387124) (xy 78.120762 -412.341271) (xy 78.156453 -412.300079)
			(xy 78.197642 -412.264384) (xy 78.243492 -412.234914) (xy 78.293069 -412.212269) (xy 78.345364 -412.19691)
			(xy 78.399312 -412.189148) (xy 78.426564 -412.18866) (xy 79.290164 -412.18866) (xy 79.317416 -412.189185)
			(xy 79.371367 -412.196937) (xy 79.423664 -412.212289) (xy 79.473245 -412.234927) (xy 79.519099 -412.264392)
			(xy 79.560292 -412.300082) (xy 79.595987 -412.341273) (xy 79.625456 -412.387124) (xy 79.648099 -412.436702)
			(xy 79.663455 -412.488998) (xy 79.671213 -412.542948) (xy 79.671213 -412.597452) (xy 79.671213 -412.597455)
			(xy 81.108723 -412.597455) (xy 81.108723 -412.542945) (xy 81.116481 -412.488989) (xy 81.131838 -412.436686)
			(xy 81.154483 -412.387102) (xy 81.183954 -412.341244) (xy 81.219651 -412.300048) (xy 81.260848 -412.264351)
			(xy 81.306705 -412.234881) (xy 81.35629 -412.212237) (xy 81.408593 -412.19688) (xy 81.462549 -412.189123)
			(xy 81.489804 -412.18866) (xy 82.353404 -412.18866) (xy 82.380653 -412.18921) (xy 82.434595 -412.196967)
			(xy 82.486885 -412.212321) (xy 82.536458 -412.23496) (xy 82.582304 -412.264424) (xy 82.62349 -412.300113)
			(xy 82.659178 -412.341299) (xy 82.688642 -412.387146) (xy 82.71128 -412.436718) (xy 82.726634 -412.489008)
			(xy 82.73439 -412.542951) (xy 82.73439 -412.597449) (xy 82.734389 -412.597457) (xy 84.171923 -412.597457)
			(xy 84.171923 -412.542943) (xy 84.179682 -412.488983) (xy 84.195041 -412.436678) (xy 84.217689 -412.38709)
			(xy 84.247164 -412.341231) (xy 84.282865 -412.300034) (xy 84.324067 -412.264337) (xy 84.369929 -412.234868)
			(xy 84.419519 -412.212226) (xy 84.471827 -412.196872) (xy 84.525787 -412.18912) (xy 84.553044 -412.18866)
			(xy 85.416644 -412.18866) (xy 85.443891 -412.189213) (xy 85.497829 -412.196974) (xy 85.550114 -412.212332)
			(xy 85.599682 -412.234973) (xy 85.645523 -412.264438) (xy 85.686704 -412.300127) (xy 85.722388 -412.341313)
			(xy 85.751848 -412.387157) (xy 85.774484 -412.436727) (xy 85.789835 -412.489014) (xy 85.79759 -412.542953)
			(xy 85.79759 -412.597447) (xy 85.797589 -412.597453) (xy 87.235246 -412.597453) (xy 87.235246 -412.542947)
			(xy 87.243003 -412.488996) (xy 87.258358 -412.436698) (xy 87.281 -412.387118) (xy 87.310467 -412.341265)
			(xy 87.34616 -412.300071) (xy 87.387352 -412.264377) (xy 87.433204 -412.234908) (xy 87.482783 -412.212264)
			(xy 87.535081 -412.196906) (xy 87.589031 -412.189147) (xy 87.616284 -412.18866) (xy 88.479884 -412.18866)
			(xy 88.507135 -412.189186) (xy 88.561083 -412.196941) (xy 88.613379 -412.212294) (xy 88.662957 -412.234934)
			(xy 88.708808 -412.264399) (xy 88.749999 -412.300089) (xy 88.785692 -412.341279) (xy 88.815159 -412.387129)
			(xy 88.8378 -412.436706) (xy 88.853156 -412.489001) (xy 88.860913 -412.542949) (xy 88.860913 -412.597451)
			(xy 88.860912 -412.597456) (xy 90.298423 -412.597456) (xy 90.298423 -412.542944) (xy 90.306181 -412.488986)
			(xy 90.32154 -412.436682) (xy 90.344186 -412.387096) (xy 90.373659 -412.341238) (xy 90.409358 -412.300041)
			(xy 90.450557 -412.264344) (xy 90.496417 -412.234874) (xy 90.546004 -412.212231) (xy 90.59831 -412.196876)
			(xy 90.652268 -412.189121) (xy 90.679524 -412.18866) (xy 91.543124 -412.18866) (xy 91.570372 -412.189212)
			(xy 91.624312 -412.19697) (xy 91.6766 -412.212326) (xy 91.72617 -412.234967) (xy 91.772013 -412.264431)
			(xy 91.813197 -412.30012) (xy 91.848883 -412.341306) (xy 91.878345 -412.387151) (xy 91.900982 -412.436723)
			(xy 91.916335 -412.489011) (xy 91.92409 -412.542952) (xy 91.92409 -412.597448) (xy 91.924089 -412.597452)
			(xy 93.361746 -412.597452) (xy 93.361746 -412.542948) (xy 93.369502 -412.488999) (xy 93.384857 -412.436703)
			(xy 93.407497 -412.387124) (xy 93.436962 -412.341271) (xy 93.472653 -412.300079) (xy 93.513842 -412.264384)
			(xy 93.559692 -412.234914) (xy 93.609269 -412.212269) (xy 93.661564 -412.19691) (xy 93.715512 -412.189148)
			(xy 93.742764 -412.18866) (xy 94.606364 -412.18866) (xy 94.633616 -412.189185) (xy 94.687567 -412.196937)
			(xy 94.739864 -412.212289) (xy 94.789445 -412.234927) (xy 94.835299 -412.264392) (xy 94.876492 -412.300082)
			(xy 94.912187 -412.341273) (xy 94.941656 -412.387124) (xy 94.964299 -412.436702) (xy 94.979655 -412.488998)
			(xy 94.987413 -412.542948) (xy 94.987413 -412.597452) (xy 94.987413 -412.597455) (xy 114.513023 -412.597455)
			(xy 114.513023 -412.542945) (xy 114.520781 -412.488989) (xy 114.536138 -412.436686) (xy 114.558783 -412.387101)
			(xy 114.588254 -412.341244) (xy 114.623952 -412.300047) (xy 114.665149 -412.264351) (xy 114.711006 -412.23488)
			(xy 114.760591 -412.212236) (xy 114.812894 -412.196879) (xy 114.866851 -412.189123) (xy 114.894106 -412.18866)
			(xy 115.757706 -412.18866) (xy 115.784955 -412.189211) (xy 115.838897 -412.196967) (xy 115.891187 -412.212321)
			(xy 115.940759 -412.234961) (xy 115.986605 -412.264425) (xy 116.027791 -412.300113) (xy 116.063479 -412.3413)
			(xy 116.092942 -412.387146) (xy 116.115581 -412.436719) (xy 116.130934 -412.489009) (xy 116.13869 -412.542951)
			(xy 116.13869 -412.597449) (xy 116.138689 -412.597457) (xy 117.576223 -412.597457) (xy 117.576223 -412.542943)
			(xy 117.583982 -412.488983) (xy 117.599342 -412.436677) (xy 117.621989 -412.38709) (xy 117.651464 -412.341231)
			(xy 117.687166 -412.300033) (xy 117.728367 -412.264337) (xy 117.77423 -412.234867) (xy 117.82382 -412.212225)
			(xy 117.876128 -412.196872) (xy 117.930089 -412.18912) (xy 117.957346 -412.18866) (xy 118.820946 -412.18866)
			(xy 118.848193 -412.189213) (xy 118.902131 -412.196975) (xy 118.954416 -412.212332) (xy 119.003983 -412.234974)
			(xy 119.049824 -412.264439) (xy 119.091005 -412.300128) (xy 119.126688 -412.341313) (xy 119.156148 -412.387157)
			(xy 119.178784 -412.436727) (xy 119.194135 -412.489014) (xy 119.20189 -412.542953) (xy 119.20189 -412.597447)
			(xy 119.201889 -412.597453) (xy 120.639546 -412.597453) (xy 120.639546 -412.542947) (xy 120.647303 -412.488996)
			(xy 120.662658 -412.436698) (xy 120.6853 -412.387118) (xy 120.714768 -412.341264) (xy 120.750461 -412.300071)
			(xy 120.791653 -412.264376) (xy 120.837505 -412.234907) (xy 120.887085 -412.212263) (xy 120.939382 -412.196906)
			(xy 120.993333 -412.189147) (xy 121.020586 -412.18866) (xy 121.884186 -412.18866) (xy 121.911437 -412.189186)
			(xy 121.965385 -412.196941) (xy 122.01768 -412.212295) (xy 122.067258 -412.234934) (xy 122.113109 -412.264399)
			(xy 122.1543 -412.30009) (xy 122.189992 -412.34128) (xy 122.219459 -412.38713) (xy 122.242101 -412.436707)
			(xy 122.257456 -412.489001) (xy 122.265213 -412.542949) (xy 122.265213 -412.597451) (xy 122.265212 -412.597456)
			(xy 123.702723 -412.597456) (xy 123.702723 -412.542944) (xy 123.710481 -412.488986) (xy 123.72584 -412.436681)
			(xy 123.748486 -412.387095) (xy 123.777959 -412.341237) (xy 123.813659 -412.30004) (xy 123.854858 -412.264344)
			(xy 123.900718 -412.234874) (xy 123.950306 -412.212231) (xy 124.002611 -412.196876) (xy 124.05657 -412.189121)
			(xy 124.083826 -412.18866) (xy 124.947426 -412.18866) (xy 124.974674 -412.189212) (xy 125.028614 -412.196971)
			(xy 125.080901 -412.212327) (xy 125.130471 -412.234968) (xy 125.176314 -412.264432) (xy 125.217498 -412.300121)
			(xy 125.253184 -412.341307) (xy 125.282645 -412.387152) (xy 125.305282 -412.436723) (xy 125.320635 -412.489011)
			(xy 125.32839 -412.542952) (xy 125.32839 -412.597448) (xy 125.328389 -412.597452) (xy 126.766046 -412.597452)
			(xy 126.766046 -412.542948) (xy 126.773802 -412.488999) (xy 126.789157 -412.436702) (xy 126.811797 -412.387123)
			(xy 126.841263 -412.341271) (xy 126.876954 -412.300078) (xy 126.918143 -412.264383) (xy 126.963993 -412.234914)
			(xy 127.01357 -412.212269) (xy 127.065865 -412.196909) (xy 127.119814 -412.189148) (xy 127.147066 -412.18866)
			(xy 128.010666 -412.18866) (xy 128.037918 -412.189185) (xy 128.091868 -412.196937) (xy 128.144166 -412.212289)
			(xy 128.193746 -412.234928) (xy 128.2396 -412.264392) (xy 128.280793 -412.300083) (xy 128.316487 -412.341273)
			(xy 128.345956 -412.387124) (xy 128.368599 -412.436702) (xy 128.383955 -412.488999) (xy 128.391713 -412.542948)
			(xy 128.391713 -412.597452) (xy 128.391713 -412.597455) (xy 129.829223 -412.597455) (xy 129.829223 -412.542945)
			(xy 129.836981 -412.488989) (xy 129.852338 -412.436686) (xy 129.874983 -412.387101) (xy 129.904454 -412.341244)
			(xy 129.940152 -412.300047) (xy 129.981349 -412.264351) (xy 130.027206 -412.23488) (xy 130.076791 -412.212236)
			(xy 130.129094 -412.196879) (xy 130.183051 -412.189123) (xy 130.210306 -412.18866) (xy 131.073906 -412.18866)
			(xy 131.101155 -412.189211) (xy 131.155097 -412.196967) (xy 131.207387 -412.212321) (xy 131.256959 -412.234961)
			(xy 131.302805 -412.264425) (xy 131.343991 -412.300113) (xy 131.379679 -412.3413) (xy 131.409142 -412.387146)
			(xy 131.431781 -412.436719) (xy 131.447134 -412.489009) (xy 131.45489 -412.542951) (xy 131.45489 -412.597449)
			(xy 131.454889 -412.597457) (xy 132.892423 -412.597457) (xy 132.892423 -412.542943) (xy 132.900182 -412.488983)
			(xy 132.915542 -412.436677) (xy 132.938189 -412.38709) (xy 132.967664 -412.341231) (xy 133.003366 -412.300033)
			(xy 133.044567 -412.264337) (xy 133.09043 -412.234867) (xy 133.14002 -412.212225) (xy 133.192328 -412.196872)
			(xy 133.246289 -412.18912) (xy 133.273546 -412.18866) (xy 134.137146 -412.18866) (xy 134.164393 -412.189213)
			(xy 134.218331 -412.196975) (xy 134.270616 -412.212332) (xy 134.320183 -412.234974) (xy 134.366024 -412.264439)
			(xy 134.407205 -412.300128) (xy 134.442888 -412.341313) (xy 134.472348 -412.387157) (xy 134.494984 -412.436727)
			(xy 134.510335 -412.489014) (xy 134.51809 -412.542953) (xy 134.51809 -412.597447) (xy 134.518089 -412.597453)
			(xy 135.955746 -412.597453) (xy 135.955746 -412.542947) (xy 135.963503 -412.488996) (xy 135.978858 -412.436698)
			(xy 136.0015 -412.387118) (xy 136.030968 -412.341264) (xy 136.066661 -412.300071) (xy 136.107853 -412.264376)
			(xy 136.153705 -412.234907) (xy 136.203285 -412.212263) (xy 136.255582 -412.196906) (xy 136.309533 -412.189147)
			(xy 136.336786 -412.18866) (xy 137.200386 -412.18866) (xy 137.227637 -412.189186) (xy 137.281585 -412.196941)
			(xy 137.33388 -412.212295) (xy 137.383458 -412.234934) (xy 137.429309 -412.264399) (xy 137.4705 -412.30009)
			(xy 137.506192 -412.34128) (xy 137.535659 -412.38713) (xy 137.558301 -412.436707) (xy 137.573656 -412.489001)
			(xy 137.581413 -412.542949) (xy 137.581413 -412.597451) (xy 137.581412 -412.597456) (xy 139.018923 -412.597456)
			(xy 139.018923 -412.542944) (xy 139.026681 -412.488986) (xy 139.04204 -412.436681) (xy 139.064686 -412.387095)
			(xy 139.094159 -412.341237) (xy 139.129859 -412.30004) (xy 139.171058 -412.264344) (xy 139.216918 -412.234874)
			(xy 139.266506 -412.212231) (xy 139.318811 -412.196876) (xy 139.37277 -412.189121) (xy 139.400026 -412.18866)
			(xy 140.263626 -412.18866) (xy 140.290874 -412.189212) (xy 140.344814 -412.196971) (xy 140.397101 -412.212327)
			(xy 140.446671 -412.234968) (xy 140.492514 -412.264432) (xy 140.533698 -412.300121) (xy 140.569384 -412.341307)
			(xy 140.598845 -412.387152) (xy 140.621482 -412.436723) (xy 140.636835 -412.489011) (xy 140.64459 -412.542952)
			(xy 140.64459 -412.597448) (xy 140.644589 -412.597452) (xy 142.082246 -412.597452) (xy 142.082246 -412.542948)
			(xy 142.090002 -412.488999) (xy 142.105357 -412.436702) (xy 142.127997 -412.387123) (xy 142.157463 -412.341271)
			(xy 142.193154 -412.300078) (xy 142.234343 -412.264383) (xy 142.280193 -412.234914) (xy 142.32977 -412.212269)
			(xy 142.382065 -412.196909) (xy 142.436014 -412.189148) (xy 142.463266 -412.18866) (xy 143.326866 -412.18866)
			(xy 143.354118 -412.189185) (xy 143.408068 -412.196937) (xy 143.460366 -412.212289) (xy 143.509946 -412.234928)
			(xy 143.5558 -412.264392) (xy 143.596993 -412.300083) (xy 143.632687 -412.341273) (xy 143.662156 -412.387124)
			(xy 143.684799 -412.436702) (xy 143.700155 -412.488999) (xy 143.707913 -412.542948) (xy 143.707913 -412.597452)
			(xy 143.707913 -412.597455) (xy 145.145423 -412.597455) (xy 145.145423 -412.542945) (xy 145.153181 -412.488989)
			(xy 145.168538 -412.436686) (xy 145.191183 -412.387101) (xy 145.220654 -412.341244) (xy 145.256352 -412.300047)
			(xy 145.297549 -412.264351) (xy 145.343406 -412.23488) (xy 145.392991 -412.212236) (xy 145.445294 -412.196879)
			(xy 145.499251 -412.189123) (xy 145.526506 -412.18866) (xy 146.390106 -412.18866) (xy 146.417355 -412.189211)
			(xy 146.471297 -412.196967) (xy 146.523587 -412.212321) (xy 146.573159 -412.234961) (xy 146.619005 -412.264425)
			(xy 146.660191 -412.300113) (xy 146.695879 -412.3413) (xy 146.725342 -412.387146) (xy 146.747981 -412.436719)
			(xy 146.763334 -412.489009) (xy 146.77109 -412.542951) (xy 146.77109 -412.597449) (xy 146.771089 -412.597457)
			(xy 148.208623 -412.597457) (xy 148.208623 -412.542943) (xy 148.216382 -412.488983) (xy 148.231742 -412.436677)
			(xy 148.254389 -412.38709) (xy 148.283864 -412.341231) (xy 148.319566 -412.300033) (xy 148.360767 -412.264337)
			(xy 148.40663 -412.234867) (xy 148.45622 -412.212225) (xy 148.508528 -412.196872) (xy 148.562489 -412.18912)
			(xy 148.589746 -412.18866) (xy 149.453346 -412.18866) (xy 149.480593 -412.189213) (xy 149.534531 -412.196975)
			(xy 149.586816 -412.212332) (xy 149.636383 -412.234974) (xy 149.682224 -412.264439) (xy 149.723405 -412.300128)
			(xy 149.759088 -412.341313) (xy 149.788548 -412.387157) (xy 149.811184 -412.436727) (xy 149.826535 -412.489014)
			(xy 149.83429 -412.542953) (xy 149.83429 -412.597447) (xy 149.834289 -412.597453) (xy 151.271946 -412.597453)
			(xy 151.271946 -412.542947) (xy 151.279703 -412.488996) (xy 151.295058 -412.436698) (xy 151.3177 -412.387118)
			(xy 151.347168 -412.341264) (xy 151.382861 -412.300071) (xy 151.424053 -412.264376) (xy 151.469905 -412.234907)
			(xy 151.519485 -412.212263) (xy 151.571782 -412.196906) (xy 151.625733 -412.189147) (xy 151.652986 -412.18866)
			(xy 152.516586 -412.18866) (xy 152.543837 -412.189186) (xy 152.597785 -412.196941) (xy 152.65008 -412.212295)
			(xy 152.699658 -412.234934) (xy 152.745509 -412.264399) (xy 152.7867 -412.30009) (xy 152.822392 -412.34128)
			(xy 152.851859 -412.38713) (xy 152.874501 -412.436707) (xy 152.889856 -412.489001) (xy 152.897613 -412.542949)
			(xy 152.897613 -412.597451) (xy 152.897612 -412.597456) (xy 154.335123 -412.597456) (xy 154.335123 -412.542944)
			(xy 154.342881 -412.488986) (xy 154.35824 -412.436681) (xy 154.380886 -412.387095) (xy 154.410359 -412.341237)
			(xy 154.446059 -412.30004) (xy 154.487258 -412.264344) (xy 154.533118 -412.234874) (xy 154.582706 -412.212231)
			(xy 154.635011 -412.196876) (xy 154.68897 -412.189121) (xy 154.716226 -412.18866) (xy 155.579826 -412.18866)
			(xy 155.607074 -412.189212) (xy 155.661014 -412.196971) (xy 155.713301 -412.212327) (xy 155.762871 -412.234968)
			(xy 155.808714 -412.264432) (xy 155.849898 -412.300121) (xy 155.885584 -412.341307) (xy 155.915045 -412.387152)
			(xy 155.937682 -412.436723) (xy 155.953035 -412.489011) (xy 155.96079 -412.542952) (xy 155.96079 -412.597448)
			(xy 155.960789 -412.597452) (xy 157.398446 -412.597452) (xy 157.398446 -412.542948) (xy 157.406202 -412.488999)
			(xy 157.421557 -412.436702) (xy 157.444197 -412.387123) (xy 157.473663 -412.341271) (xy 157.509354 -412.300078)
			(xy 157.550543 -412.264383) (xy 157.596393 -412.234914) (xy 157.64597 -412.212269) (xy 157.698265 -412.196909)
			(xy 157.752214 -412.189148) (xy 157.779466 -412.18866) (xy 158.643066 -412.18866) (xy 158.670318 -412.189185)
			(xy 158.724268 -412.196937) (xy 158.776566 -412.212289) (xy 158.826146 -412.234928) (xy 158.872 -412.264392)
			(xy 158.913193 -412.300083) (xy 158.948887 -412.341273) (xy 158.978356 -412.387124) (xy 159.000999 -412.436702)
			(xy 159.016355 -412.488999) (xy 159.024113 -412.542948) (xy 159.024113 -412.597452) (xy 159.024113 -412.597455)
			(xy 160.461623 -412.597455) (xy 160.461623 -412.542945) (xy 160.469381 -412.488989) (xy 160.484738 -412.436686)
			(xy 160.507383 -412.387101) (xy 160.536854 -412.341244) (xy 160.572552 -412.300047) (xy 160.613749 -412.264351)
			(xy 160.659606 -412.23488) (xy 160.709191 -412.212236) (xy 160.761494 -412.196879) (xy 160.815451 -412.189123)
			(xy 160.842706 -412.18866) (xy 161.706306 -412.18866) (xy 161.733555 -412.189211) (xy 161.787497 -412.196967)
			(xy 161.839787 -412.212321) (xy 161.889359 -412.234961) (xy 161.935205 -412.264425) (xy 161.976391 -412.300113)
			(xy 162.012079 -412.3413) (xy 162.041542 -412.387146) (xy 162.064181 -412.436719) (xy 162.079534 -412.489009)
			(xy 162.08729 -412.542951) (xy 162.08729 -412.597449) (xy 162.079534 -412.651391) (xy 162.064181 -412.703681)
			(xy 162.041542 -412.753254) (xy 162.012079 -412.7991) (xy 161.976391 -412.840287) (xy 161.935205 -412.875975)
			(xy 161.889359 -412.905439) (xy 161.839787 -412.928079) (xy 161.787497 -412.943433) (xy 161.733555 -412.951189)
			(xy 161.706306 -412.951676) (xy 160.842706 -412.951676) (xy 160.815451 -412.951277) (xy 160.761494 -412.943521)
			(xy 160.709191 -412.928164) (xy 160.659606 -412.90552) (xy 160.613749 -412.876049) (xy 160.572552 -412.840353)
			(xy 160.536854 -412.799156) (xy 160.507383 -412.753299) (xy 160.484738 -412.703714) (xy 160.469381 -412.651411)
			(xy 160.461623 -412.597455) (xy 159.024113 -412.597455) (xy 159.016355 -412.651402) (xy 159.000999 -412.703698)
			(xy 158.978356 -412.753276) (xy 158.948887 -412.799127) (xy 158.913193 -412.840317) (xy 158.872 -412.876008)
			(xy 158.826146 -412.905472) (xy 158.776566 -412.928111) (xy 158.724268 -412.943463) (xy 158.670318 -412.951215)
			(xy 158.643066 -412.951676) (xy 157.779466 -412.951676) (xy 157.752214 -412.951252) (xy 157.698265 -412.943491)
			(xy 157.64597 -412.928131) (xy 157.596393 -412.905486) (xy 157.550543 -412.876017) (xy 157.509354 -412.840322)
			(xy 157.473663 -412.799129) (xy 157.444197 -412.753277) (xy 157.421557 -412.703698) (xy 157.406202 -412.651401)
			(xy 157.398446 -412.597452) (xy 155.960789 -412.597452) (xy 155.953035 -412.651389) (xy 155.937682 -412.703677)
			(xy 155.915045 -412.753248) (xy 155.885584 -412.799093) (xy 155.849898 -412.840279) (xy 155.808714 -412.875968)
			(xy 155.762871 -412.905432) (xy 155.713301 -412.928073) (xy 155.661014 -412.943429) (xy 155.607074 -412.951188)
			(xy 155.579826 -412.951676) (xy 154.716226 -412.951676) (xy 154.68897 -412.951279) (xy 154.635011 -412.943524)
			(xy 154.582706 -412.928169) (xy 154.533118 -412.905526) (xy 154.487258 -412.876056) (xy 154.446059 -412.84036)
			(xy 154.410359 -412.799163) (xy 154.380886 -412.753305) (xy 154.35824 -412.703719) (xy 154.342881 -412.651414)
			(xy 154.335123 -412.597456) (xy 152.897612 -412.597456) (xy 152.889856 -412.651399) (xy 152.874501 -412.703693)
			(xy 152.851859 -412.75327) (xy 152.822392 -412.79912) (xy 152.7867 -412.84031) (xy 152.745509 -412.876001)
			(xy 152.699658 -412.905466) (xy 152.65008 -412.928105) (xy 152.597785 -412.943459) (xy 152.543837 -412.951214)
			(xy 152.516586 -412.951676) (xy 151.652986 -412.951676) (xy 151.625733 -412.951253) (xy 151.571782 -412.943494)
			(xy 151.519485 -412.928137) (xy 151.469905 -412.905493) (xy 151.424053 -412.876024) (xy 151.382861 -412.840329)
			(xy 151.347168 -412.799136) (xy 151.3177 -412.753282) (xy 151.295058 -412.703702) (xy 151.279703 -412.651404)
			(xy 151.271946 -412.597453) (xy 149.834289 -412.597453) (xy 149.826535 -412.651386) (xy 149.811184 -412.703673)
			(xy 149.788548 -412.753243) (xy 149.759088 -412.799087) (xy 149.723405 -412.840272) (xy 149.682224 -412.875961)
			(xy 149.636383 -412.905426) (xy 149.586816 -412.928068) (xy 149.534531 -412.943425) (xy 149.480593 -412.951187)
			(xy 149.453346 -412.951676) (xy 148.589746 -412.951676) (xy 148.562489 -412.95128) (xy 148.508528 -412.943528)
			(xy 148.45622 -412.928175) (xy 148.40663 -412.905533) (xy 148.360767 -412.876063) (xy 148.319566 -412.840367)
			(xy 148.283864 -412.799169) (xy 148.254389 -412.75331) (xy 148.231742 -412.703723) (xy 148.216382 -412.651417)
			(xy 148.208623 -412.597457) (xy 146.771089 -412.597457) (xy 146.763334 -412.651391) (xy 146.747981 -412.703681)
			(xy 146.725342 -412.753254) (xy 146.695879 -412.7991) (xy 146.660191 -412.840287) (xy 146.619005 -412.875975)
			(xy 146.573159 -412.905439) (xy 146.523587 -412.928079) (xy 146.471297 -412.943433) (xy 146.417355 -412.951189)
			(xy 146.390106 -412.951676) (xy 145.526506 -412.951676) (xy 145.499251 -412.951277) (xy 145.445294 -412.943521)
			(xy 145.392991 -412.928164) (xy 145.343406 -412.90552) (xy 145.297549 -412.876049) (xy 145.256352 -412.840353)
			(xy 145.220654 -412.799156) (xy 145.191183 -412.753299) (xy 145.168538 -412.703714) (xy 145.153181 -412.651411)
			(xy 145.145423 -412.597455) (xy 143.707913 -412.597455) (xy 143.700155 -412.651402) (xy 143.684799 -412.703698)
			(xy 143.662156 -412.753276) (xy 143.632687 -412.799127) (xy 143.596993 -412.840317) (xy 143.5558 -412.876008)
			(xy 143.509946 -412.905472) (xy 143.460366 -412.928111) (xy 143.408068 -412.943463) (xy 143.354118 -412.951215)
			(xy 143.326866 -412.951676) (xy 142.463266 -412.951676) (xy 142.436014 -412.951252) (xy 142.382065 -412.943491)
			(xy 142.32977 -412.928131) (xy 142.280193 -412.905486) (xy 142.234343 -412.876017) (xy 142.193154 -412.840322)
			(xy 142.157463 -412.799129) (xy 142.127997 -412.753277) (xy 142.105357 -412.703698) (xy 142.090002 -412.651401)
			(xy 142.082246 -412.597452) (xy 140.644589 -412.597452) (xy 140.636835 -412.651389) (xy 140.621482 -412.703677)
			(xy 140.598845 -412.753248) (xy 140.569384 -412.799093) (xy 140.533698 -412.840279) (xy 140.492514 -412.875968)
			(xy 140.446671 -412.905432) (xy 140.397101 -412.928073) (xy 140.344814 -412.943429) (xy 140.290874 -412.951188)
			(xy 140.263626 -412.951676) (xy 139.400026 -412.951676) (xy 139.37277 -412.951279) (xy 139.318811 -412.943524)
			(xy 139.266506 -412.928169) (xy 139.216918 -412.905526) (xy 139.171058 -412.876056) (xy 139.129859 -412.84036)
			(xy 139.094159 -412.799163) (xy 139.064686 -412.753305) (xy 139.04204 -412.703719) (xy 139.026681 -412.651414)
			(xy 139.018923 -412.597456) (xy 137.581412 -412.597456) (xy 137.573656 -412.651399) (xy 137.558301 -412.703693)
			(xy 137.535659 -412.75327) (xy 137.506192 -412.79912) (xy 137.4705 -412.84031) (xy 137.429309 -412.876001)
			(xy 137.383458 -412.905466) (xy 137.33388 -412.928105) (xy 137.281585 -412.943459) (xy 137.227637 -412.951214)
			(xy 137.200386 -412.951676) (xy 136.336786 -412.951676) (xy 136.309533 -412.951253) (xy 136.255582 -412.943494)
			(xy 136.203285 -412.928137) (xy 136.153705 -412.905493) (xy 136.107853 -412.876024) (xy 136.066661 -412.840329)
			(xy 136.030968 -412.799136) (xy 136.0015 -412.753282) (xy 135.978858 -412.703702) (xy 135.963503 -412.651404)
			(xy 135.955746 -412.597453) (xy 134.518089 -412.597453) (xy 134.510335 -412.651386) (xy 134.494984 -412.703673)
			(xy 134.472348 -412.753243) (xy 134.442888 -412.799087) (xy 134.407205 -412.840272) (xy 134.366024 -412.875961)
			(xy 134.320183 -412.905426) (xy 134.270616 -412.928068) (xy 134.218331 -412.943425) (xy 134.164393 -412.951187)
			(xy 134.137146 -412.951676) (xy 133.273546 -412.951676) (xy 133.246289 -412.95128) (xy 133.192328 -412.943528)
			(xy 133.14002 -412.928175) (xy 133.09043 -412.905533) (xy 133.044567 -412.876063) (xy 133.003366 -412.840367)
			(xy 132.967664 -412.799169) (xy 132.938189 -412.75331) (xy 132.915542 -412.703723) (xy 132.900182 -412.651417)
			(xy 132.892423 -412.597457) (xy 131.454889 -412.597457) (xy 131.447134 -412.651391) (xy 131.431781 -412.703681)
			(xy 131.409142 -412.753254) (xy 131.379679 -412.7991) (xy 131.343991 -412.840287) (xy 131.302805 -412.875975)
			(xy 131.256959 -412.905439) (xy 131.207387 -412.928079) (xy 131.155097 -412.943433) (xy 131.101155 -412.951189)
			(xy 131.073906 -412.951676) (xy 130.210306 -412.951676) (xy 130.183051 -412.951277) (xy 130.129094 -412.943521)
			(xy 130.076791 -412.928164) (xy 130.027206 -412.90552) (xy 129.981349 -412.876049) (xy 129.940152 -412.840353)
			(xy 129.904454 -412.799156) (xy 129.874983 -412.753299) (xy 129.852338 -412.703714) (xy 129.836981 -412.651411)
			(xy 129.829223 -412.597455) (xy 128.391713 -412.597455) (xy 128.383955 -412.651402) (xy 128.368599 -412.703698)
			(xy 128.345956 -412.753276) (xy 128.316487 -412.799127) (xy 128.280793 -412.840317) (xy 128.2396 -412.876008)
			(xy 128.193746 -412.905472) (xy 128.144166 -412.928111) (xy 128.091868 -412.943463) (xy 128.037918 -412.951215)
			(xy 128.010666 -412.951676) (xy 127.147066 -412.951676) (xy 127.119814 -412.951252) (xy 127.065865 -412.943491)
			(xy 127.01357 -412.928131) (xy 126.963993 -412.905486) (xy 126.918143 -412.876017) (xy 126.876954 -412.840322)
			(xy 126.841263 -412.799129) (xy 126.811797 -412.753277) (xy 126.789157 -412.703698) (xy 126.773802 -412.651401)
			(xy 126.766046 -412.597452) (xy 125.328389 -412.597452) (xy 125.320635 -412.651389) (xy 125.305282 -412.703677)
			(xy 125.282645 -412.753248) (xy 125.253184 -412.799093) (xy 125.217498 -412.840279) (xy 125.176314 -412.875968)
			(xy 125.130471 -412.905432) (xy 125.080901 -412.928073) (xy 125.028614 -412.943429) (xy 124.974674 -412.951188)
			(xy 124.947426 -412.951676) (xy 124.083826 -412.951676) (xy 124.05657 -412.951279) (xy 124.002611 -412.943524)
			(xy 123.950306 -412.928169) (xy 123.900718 -412.905526) (xy 123.854858 -412.876056) (xy 123.813659 -412.84036)
			(xy 123.777959 -412.799163) (xy 123.748486 -412.753305) (xy 123.72584 -412.703719) (xy 123.710481 -412.651414)
			(xy 123.702723 -412.597456) (xy 122.265212 -412.597456) (xy 122.257456 -412.651399) (xy 122.242101 -412.703693)
			(xy 122.219459 -412.75327) (xy 122.189992 -412.79912) (xy 122.1543 -412.84031) (xy 122.113109 -412.876001)
			(xy 122.067258 -412.905466) (xy 122.01768 -412.928105) (xy 121.965385 -412.943459) (xy 121.911437 -412.951214)
			(xy 121.884186 -412.951676) (xy 121.020586 -412.951676) (xy 120.993333 -412.951253) (xy 120.939382 -412.943494)
			(xy 120.887085 -412.928137) (xy 120.837505 -412.905493) (xy 120.791653 -412.876024) (xy 120.750461 -412.840329)
			(xy 120.714768 -412.799136) (xy 120.6853 -412.753282) (xy 120.662658 -412.703702) (xy 120.647303 -412.651404)
			(xy 120.639546 -412.597453) (xy 119.201889 -412.597453) (xy 119.194135 -412.651386) (xy 119.178784 -412.703673)
			(xy 119.156148 -412.753243) (xy 119.126688 -412.799087) (xy 119.091005 -412.840272) (xy 119.049824 -412.875961)
			(xy 119.003983 -412.905426) (xy 118.954416 -412.928068) (xy 118.902131 -412.943425) (xy 118.848193 -412.951187)
			(xy 118.820946 -412.951676) (xy 117.957346 -412.951676) (xy 117.930089 -412.95128) (xy 117.876128 -412.943528)
			(xy 117.82382 -412.928175) (xy 117.77423 -412.905533) (xy 117.728367 -412.876063) (xy 117.687166 -412.840367)
			(xy 117.651464 -412.799169) (xy 117.621989 -412.75331) (xy 117.599342 -412.703723) (xy 117.583982 -412.651417)
			(xy 117.576223 -412.597457) (xy 116.138689 -412.597457) (xy 116.130934 -412.651391) (xy 116.115581 -412.703681)
			(xy 116.092942 -412.753254) (xy 116.063479 -412.7991) (xy 116.027791 -412.840287) (xy 115.986605 -412.875975)
			(xy 115.940759 -412.905439) (xy 115.891187 -412.928079) (xy 115.838897 -412.943433) (xy 115.784955 -412.951189)
			(xy 115.757706 -412.951676) (xy 114.894106 -412.951676) (xy 114.866851 -412.951277) (xy 114.812894 -412.943521)
			(xy 114.760591 -412.928164) (xy 114.711006 -412.90552) (xy 114.665149 -412.876049) (xy 114.623952 -412.840353)
			(xy 114.588254 -412.799156) (xy 114.558783 -412.753299) (xy 114.536138 -412.703714) (xy 114.520781 -412.651411)
			(xy 114.513023 -412.597455) (xy 94.987413 -412.597455) (xy 94.979655 -412.651402) (xy 94.964299 -412.703698)
			(xy 94.941656 -412.753276) (xy 94.912187 -412.799127) (xy 94.876492 -412.840318) (xy 94.835299 -412.876008)
			(xy 94.789445 -412.905473) (xy 94.739864 -412.928111) (xy 94.687567 -412.943463) (xy 94.633616 -412.951215)
			(xy 94.606364 -412.951676) (xy 93.742764 -412.951676) (xy 93.715512 -412.951252) (xy 93.661564 -412.94349)
			(xy 93.609269 -412.928131) (xy 93.559692 -412.905486) (xy 93.513842 -412.876016) (xy 93.472653 -412.840321)
			(xy 93.436962 -412.799129) (xy 93.407497 -412.753276) (xy 93.384857 -412.703697) (xy 93.369502 -412.651401)
			(xy 93.361746 -412.597452) (xy 91.924089 -412.597452) (xy 91.916335 -412.651389) (xy 91.900982 -412.703677)
			(xy 91.878345 -412.753249) (xy 91.848883 -412.799094) (xy 91.813197 -412.84028) (xy 91.772013 -412.875969)
			(xy 91.72617 -412.905433) (xy 91.6766 -412.928074) (xy 91.624312 -412.94343) (xy 91.570372 -412.951188)
			(xy 91.543124 -412.951676) (xy 90.679524 -412.951676) (xy 90.652268 -412.951279) (xy 90.59831 -412.943524)
			(xy 90.546004 -412.928169) (xy 90.496417 -412.905526) (xy 90.450557 -412.876056) (xy 90.409358 -412.840359)
			(xy 90.373659 -412.799162) (xy 90.344186 -412.753304) (xy 90.32154 -412.703718) (xy 90.306181 -412.651414)
			(xy 90.298423 -412.597456) (xy 88.860912 -412.597456) (xy 88.853156 -412.651399) (xy 88.8378 -412.703694)
			(xy 88.815159 -412.753271) (xy 88.785692 -412.799121) (xy 88.749999 -412.840311) (xy 88.708808 -412.876001)
			(xy 88.662957 -412.905466) (xy 88.613379 -412.928106) (xy 88.561083 -412.943459) (xy 88.507135 -412.951214)
			(xy 88.479884 -412.951676) (xy 87.616284 -412.951676) (xy 87.589031 -412.951253) (xy 87.535081 -412.943494)
			(xy 87.482783 -412.928136) (xy 87.433204 -412.905492) (xy 87.387352 -412.876023) (xy 87.34616 -412.840329)
			(xy 87.310467 -412.799135) (xy 87.281 -412.753282) (xy 87.258358 -412.703702) (xy 87.243003 -412.651404)
			(xy 87.235246 -412.597453) (xy 85.797589 -412.597453) (xy 85.789835 -412.651386) (xy 85.774484 -412.703673)
			(xy 85.751848 -412.753243) (xy 85.722388 -412.799087) (xy 85.686704 -412.840273) (xy 85.645523 -412.875962)
			(xy 85.599682 -412.905427) (xy 85.550114 -412.928068) (xy 85.497829 -412.943426) (xy 85.443891 -412.951187)
			(xy 85.416644 -412.951676) (xy 84.553044 -412.951676) (xy 84.525787 -412.95128) (xy 84.471827 -412.943528)
			(xy 84.419519 -412.928174) (xy 84.369929 -412.905532) (xy 84.324067 -412.876063) (xy 84.282865 -412.840366)
			(xy 84.247164 -412.799169) (xy 84.217689 -412.75331) (xy 84.195041 -412.703722) (xy 84.179682 -412.651417)
			(xy 84.171923 -412.597457) (xy 82.734389 -412.597457) (xy 82.726634 -412.651392) (xy 82.71128 -412.703682)
			(xy 82.688642 -412.753254) (xy 82.659178 -412.799101) (xy 82.62349 -412.840287) (xy 82.582304 -412.875976)
			(xy 82.536458 -412.90544) (xy 82.486885 -412.928079) (xy 82.434595 -412.943433) (xy 82.380653 -412.95119)
			(xy 82.353404 -412.951676) (xy 81.489804 -412.951676) (xy 81.462549 -412.951277) (xy 81.408593 -412.94352)
			(xy 81.35629 -412.928163) (xy 81.306705 -412.905519) (xy 81.260848 -412.876049) (xy 81.219651 -412.840352)
			(xy 81.183954 -412.799156) (xy 81.154483 -412.753298) (xy 81.131838 -412.703714) (xy 81.116481 -412.651411)
			(xy 81.108723 -412.597455) (xy 79.671213 -412.597455) (xy 79.663455 -412.651402) (xy 79.648099 -412.703698)
			(xy 79.625456 -412.753276) (xy 79.595987 -412.799127) (xy 79.560292 -412.840318) (xy 79.519099 -412.876008)
			(xy 79.473245 -412.905473) (xy 79.423664 -412.928111) (xy 79.371367 -412.943463) (xy 79.317416 -412.951215)
			(xy 79.290164 -412.951676) (xy 78.426564 -412.951676) (xy 78.399312 -412.951252) (xy 78.345364 -412.94349)
			(xy 78.293069 -412.928131) (xy 78.243492 -412.905486) (xy 78.197642 -412.876016) (xy 78.156453 -412.840321)
			(xy 78.120762 -412.799129) (xy 78.091297 -412.753276) (xy 78.068657 -412.703697) (xy 78.053302 -412.651401)
			(xy 78.045546 -412.597452) (xy 76.607889 -412.597452) (xy 76.600135 -412.651389) (xy 76.584782 -412.703677)
			(xy 76.562145 -412.753249) (xy 76.532683 -412.799094) (xy 76.496997 -412.84028) (xy 76.455813 -412.875969)
			(xy 76.40997 -412.905433) (xy 76.3604 -412.928074) (xy 76.308112 -412.94343) (xy 76.254172 -412.951188)
			(xy 76.226924 -412.951676) (xy 75.363324 -412.951676) (xy 75.336068 -412.951279) (xy 75.28211 -412.943524)
			(xy 75.229804 -412.928169) (xy 75.180217 -412.905526) (xy 75.134357 -412.876056) (xy 75.093158 -412.840359)
			(xy 75.057459 -412.799162) (xy 75.027986 -412.753304) (xy 75.00534 -412.703718) (xy 74.989981 -412.651414)
			(xy 74.982223 -412.597456) (xy 73.544712 -412.597456) (xy 73.536956 -412.651399) (xy 73.5216 -412.703694)
			(xy 73.498959 -412.753271) (xy 73.469492 -412.799121) (xy 73.433799 -412.840311) (xy 73.392608 -412.876001)
			(xy 73.346757 -412.905466) (xy 73.297179 -412.928106) (xy 73.244883 -412.943459) (xy 73.190935 -412.951214)
			(xy 73.163684 -412.951676) (xy 72.300084 -412.951676) (xy 72.272831 -412.951253) (xy 72.218881 -412.943494)
			(xy 72.166583 -412.928136) (xy 72.117004 -412.905492) (xy 72.071152 -412.876023) (xy 72.02996 -412.840329)
			(xy 71.994267 -412.799135) (xy 71.9648 -412.753282) (xy 71.942158 -412.703702) (xy 71.926803 -412.651404)
			(xy 71.919046 -412.597453) (xy 70.481389 -412.597453) (xy 70.473635 -412.651386) (xy 70.458284 -412.703673)
			(xy 70.435648 -412.753243) (xy 70.406188 -412.799087) (xy 70.370504 -412.840273) (xy 70.329323 -412.875962)
			(xy 70.283482 -412.905427) (xy 70.233914 -412.928068) (xy 70.181629 -412.943426) (xy 70.127691 -412.951187)
			(xy 70.100444 -412.951676) (xy 69.236844 -412.951676) (xy 69.209587 -412.95128) (xy 69.155627 -412.943528)
			(xy 69.103319 -412.928174) (xy 69.053729 -412.905532) (xy 69.007867 -412.876063) (xy 68.966665 -412.840366)
			(xy 68.930964 -412.799169) (xy 68.901489 -412.75331) (xy 68.878841 -412.703722) (xy 68.863482 -412.651417)
			(xy 68.855723 -412.597457) (xy 67.418189 -412.597457) (xy 67.410434 -412.651392) (xy 67.39508 -412.703682)
			(xy 67.372442 -412.753254) (xy 67.342978 -412.799101) (xy 67.30729 -412.840287) (xy 67.266104 -412.875976)
			(xy 67.220258 -412.90544) (xy 67.170685 -412.928079) (xy 67.118395 -412.943433) (xy 67.064453 -412.95119)
			(xy 67.037204 -412.951676) (xy 66.173604 -412.951676) (xy 66.146349 -412.951277) (xy 66.092393 -412.94352)
			(xy 66.04009 -412.928163) (xy 65.990505 -412.905519) (xy 65.944648 -412.876049) (xy 65.903451 -412.840352)
			(xy 65.867754 -412.799156) (xy 65.838283 -412.753298) (xy 65.815638 -412.703714) (xy 65.800281 -412.651411)
			(xy 65.792523 -412.597455) (xy 64.355013 -412.597455) (xy 64.347255 -412.651402) (xy 64.331899 -412.703698)
			(xy 64.309256 -412.753276) (xy 64.279787 -412.799127) (xy 64.244092 -412.840318) (xy 64.202899 -412.876008)
			(xy 64.157045 -412.905473) (xy 64.107464 -412.928111) (xy 64.055167 -412.943463) (xy 64.001216 -412.951215)
			(xy 63.973964 -412.951676) (xy 63.110364 -412.951676) (xy 63.083112 -412.951252) (xy 63.029164 -412.94349)
			(xy 62.976869 -412.928131) (xy 62.927292 -412.905486) (xy 62.881442 -412.876016) (xy 62.840253 -412.840321)
			(xy 62.804562 -412.799129) (xy 62.775097 -412.753276) (xy 62.752457 -412.703697) (xy 62.737102 -412.651401)
			(xy 62.729346 -412.597452) (xy 61.291689 -412.597452) (xy 61.283935 -412.651389) (xy 61.268582 -412.703677)
			(xy 61.245945 -412.753249) (xy 61.216483 -412.799094) (xy 61.180797 -412.84028) (xy 61.139613 -412.875969)
			(xy 61.09377 -412.905433) (xy 61.0442 -412.928074) (xy 60.991912 -412.94343) (xy 60.937972 -412.951188)
			(xy 60.910724 -412.951676) (xy 60.047124 -412.951676) (xy 60.019868 -412.951279) (xy 59.96591 -412.943524)
			(xy 59.913604 -412.928169) (xy 59.864017 -412.905526) (xy 59.818157 -412.876056) (xy 59.776958 -412.840359)
			(xy 59.741259 -412.799162) (xy 59.711786 -412.753304) (xy 59.68914 -412.703718) (xy 59.673781 -412.651414)
			(xy 59.666023 -412.597456) (xy 58.228512 -412.597456) (xy 58.220756 -412.651399) (xy 58.2054 -412.703694)
			(xy 58.182759 -412.753271) (xy 58.153292 -412.799121) (xy 58.117599 -412.840311) (xy 58.076408 -412.876001)
			(xy 58.030557 -412.905466) (xy 57.980979 -412.928106) (xy 57.928683 -412.943459) (xy 57.874735 -412.951214)
			(xy 57.847484 -412.951676) (xy 56.983884 -412.951676) (xy 56.956631 -412.951253) (xy 56.902681 -412.943494)
			(xy 56.850383 -412.928136) (xy 56.800804 -412.905492) (xy 56.754952 -412.876023) (xy 56.71376 -412.840329)
			(xy 56.678067 -412.799135) (xy 56.6486 -412.753282) (xy 56.625958 -412.703702) (xy 56.610603 -412.651404)
			(xy 56.602846 -412.597453) (xy 55.165189 -412.597453) (xy 55.157435 -412.651386) (xy 55.142084 -412.703673)
			(xy 55.119448 -412.753243) (xy 55.089988 -412.799087) (xy 55.054304 -412.840273) (xy 55.013123 -412.875962)
			(xy 54.967282 -412.905427) (xy 54.917714 -412.928068) (xy 54.865429 -412.943426) (xy 54.811491 -412.951187)
			(xy 54.784244 -412.951676) (xy 53.920644 -412.951676) (xy 53.893387 -412.95128) (xy 53.839427 -412.943528)
			(xy 53.787119 -412.928174) (xy 53.737529 -412.905532) (xy 53.691667 -412.876063) (xy 53.650465 -412.840366)
			(xy 53.614764 -412.799169) (xy 53.585289 -412.75331) (xy 53.562641 -412.703722) (xy 53.547282 -412.651417)
			(xy 53.539523 -412.597457) (xy 52.101989 -412.597457) (xy 52.094234 -412.651392) (xy 52.07888 -412.703682)
			(xy 52.056242 -412.753254) (xy 52.026778 -412.799101) (xy 51.99109 -412.840287) (xy 51.949904 -412.875976)
			(xy 51.904058 -412.90544) (xy 51.854485 -412.928079) (xy 51.802195 -412.943433) (xy 51.748253 -412.95119)
			(xy 51.721004 -412.951676) (xy 50.857404 -412.951676) (xy 50.830149 -412.951277) (xy 50.776193 -412.94352)
			(xy 50.72389 -412.928163) (xy 50.674305 -412.905519) (xy 50.628448 -412.876049) (xy 50.587251 -412.840352)
			(xy 50.551554 -412.799156) (xy 50.522083 -412.753298) (xy 50.499438 -412.703714) (xy 50.484081 -412.651411)
			(xy 50.476323 -412.597455) (xy 49.038813 -412.597455) (xy 49.031055 -412.651402) (xy 49.015699 -412.703698)
			(xy 48.993056 -412.753276) (xy 48.963587 -412.799127) (xy 48.927892 -412.840318) (xy 48.886699 -412.876008)
			(xy 48.840845 -412.905473) (xy 48.791264 -412.928111) (xy 48.738967 -412.943463) (xy 48.685016 -412.951215)
			(xy 48.657764 -412.951676) (xy 47.794164 -412.951676) (xy 47.766912 -412.951252) (xy 47.712964 -412.94349)
			(xy 47.660669 -412.928131) (xy 47.611092 -412.905486) (xy 47.565242 -412.876016) (xy 47.524053 -412.840321)
			(xy 47.488362 -412.799129) (xy 47.458897 -412.753276) (xy 47.436257 -412.703697) (xy 47.420902 -412.651401)
			(xy 47.413146 -412.597452) (xy 39.737792 -412.597452) (xy 39.737792 -413.4485) (xy 39.737556 -413.461769)
			(xy 105.629431 -413.461769) (xy 105.629431 -413.407231) (xy 105.637193 -413.353247) (xy 105.652559 -413.300918)
			(xy 105.675215 -413.251308) (xy 105.704702 -413.205427) (xy 105.740417 -413.16421) (xy 105.781635 -413.128496)
			(xy 105.827517 -413.099011) (xy 105.877127 -413.076355) (xy 105.929457 -413.060991) (xy 105.983441 -413.053231)
			(xy 106.01071 -413.052768) (xy 106.87431 -413.052768) (xy 106.901581 -413.053195) (xy 106.955568 -413.060959)
			(xy 107.0079 -413.076326) (xy 107.057513 -413.098985) (xy 107.103396 -413.128473) (xy 107.144616 -413.164191)
			(xy 107.180333 -413.205412) (xy 107.20982 -413.251296) (xy 107.232477 -413.300909) (xy 107.247844 -413.353242)
			(xy 107.255606 -413.407229) (xy 107.255606 -413.461771) (xy 107.247844 -413.515758) (xy 107.232477 -413.568091)
			(xy 107.20982 -413.617704) (xy 107.180333 -413.663588) (xy 107.144616 -413.704809) (xy 107.103396 -413.740527)
			(xy 107.057513 -413.770015) (xy 107.0079 -413.792674) (xy 106.955568 -413.808041) (xy 106.901581 -413.815805)
			(xy 106.87431 -413.816292) (xy 106.01071 -413.816292) (xy 105.983441 -413.815769) (xy 105.929457 -413.808009)
			(xy 105.877127 -413.792645) (xy 105.827517 -413.769989) (xy 105.781635 -413.740504) (xy 105.740417 -413.70479)
			(xy 105.704702 -413.663573) (xy 105.675215 -413.617692) (xy 105.652559 -413.568082) (xy 105.637193 -413.515753)
			(xy 105.629431 -413.461769) (xy 39.737556 -413.461769) (xy 39.737306 -413.475769) (xy 39.729544 -413.529753)
			(xy 39.714179 -413.582083) (xy 39.691522 -413.631693) (xy 39.662036 -413.677574) (xy 39.626321 -413.718791)
			(xy 39.585104 -413.754506) (xy 39.539223 -413.783992) (xy 39.489613 -413.806649) (xy 39.437283 -413.822014)
			(xy 39.383299 -413.829776) (xy 39.328761 -413.829776) (xy 39.274777 -413.822014) (xy 39.222447 -413.806649)
			(xy 39.172837 -413.783992) (xy 39.126956 -413.754506) (xy 39.085739 -413.718791) (xy 39.050024 -413.677574)
			(xy 39.020538 -413.631693) (xy 38.997881 -413.582083) (xy 38.982516 -413.529753) (xy 38.974754 -413.475769)
			(xy 38.974268 -413.4485) (xy 7.00913 -413.4485) (xy 7.00913 -415.383726) (xy 41.206928 -415.383726)
			(xy 41.206928 -414.520126) (xy 41.207414 -414.492857) (xy 41.215176 -414.438873) (xy 41.230541 -414.386543)
			(xy 41.253198 -414.336933) (xy 41.282684 -414.291052) (xy 41.318399 -414.249835) (xy 41.359616 -414.21412)
			(xy 41.405497 -414.184634) (xy 41.455107 -414.161977) (xy 41.507437 -414.146612) (xy 41.561421 -414.13885)
			(xy 41.615959 -414.13885) (xy 41.669943 -414.146612) (xy 41.722273 -414.161977) (xy 41.771883 -414.184634)
			(xy 41.817764 -414.21412) (xy 41.858981 -414.249835) (xy 41.894696 -414.291052) (xy 41.924182 -414.336933)
			(xy 41.946839 -414.386543) (xy 41.962204 -414.438873) (xy 41.969966 -414.492857) (xy 41.970452 -414.520126)
			(xy 41.970452 -415.383726) (xy 41.969966 -415.410995) (xy 41.962204 -415.464979) (xy 41.946839 -415.517309)
			(xy 41.924182 -415.566919) (xy 41.894696 -415.6128) (xy 41.858981 -415.654017) (xy 41.817764 -415.689732)
			(xy 41.771883 -415.719218) (xy 41.722273 -415.741875) (xy 41.669943 -415.75724) (xy 41.615959 -415.765002)
			(xy 41.561421 -415.765002) (xy 41.507437 -415.75724) (xy 41.455107 -415.741875) (xy 41.405497 -415.719218)
			(xy 41.359616 -415.689732) (xy 41.318399 -415.654017) (xy 41.282684 -415.6128) (xy 41.253198 -415.566919)
			(xy 41.230541 -415.517309) (xy 41.215176 -415.464979) (xy 41.207414 -415.410995) (xy 41.206928 -415.383726)
			(xy 7.00913 -415.383726) (xy 7.00913 -417.465002) (xy 35.832796 -417.465002) (xy 35.832796 -416.601402)
			(xy 35.833282 -416.574151) (xy 35.841038 -416.520203) (xy 35.856393 -416.467908) (xy 35.879035 -416.418331)
			(xy 35.908501 -416.372481) (xy 35.944192 -416.33129) (xy 35.985383 -416.295599) (xy 36.031233 -416.266133)
			(xy 36.08081 -416.243491) (xy 36.133105 -416.228136) (xy 36.187053 -416.22038) (xy 36.241555 -416.22038)
			(xy 36.295503 -416.228136) (xy 36.347798 -416.243491) (xy 36.397375 -416.266133) (xy 36.443225 -416.295599)
			(xy 36.484416 -416.33129) (xy 36.520107 -416.372481) (xy 36.549573 -416.418331) (xy 36.572215 -416.467908)
			(xy 36.58757 -416.520203) (xy 36.595326 -416.574151) (xy 36.595812 -416.601402) (xy 36.595812 -417.436808)
			(xy 48.812704 -417.436808) (xy 48.812704 -416.573208) (xy 48.81319 -416.545939) (xy 48.820952 -416.491955)
			(xy 48.836317 -416.439625) (xy 48.858974 -416.390015) (xy 48.88846 -416.344134) (xy 48.924175 -416.302917)
			(xy 48.965392 -416.267202) (xy 49.011273 -416.237716) (xy 49.060883 -416.215059) (xy 49.113213 -416.199694)
			(xy 49.167197 -416.191932) (xy 49.221735 -416.191932) (xy 49.275719 -416.199694) (xy 49.328049 -416.215059)
			(xy 49.377659 -416.237716) (xy 49.42354 -416.267202) (xy 49.464757 -416.302917) (xy 49.500472 -416.344134)
			(xy 49.529958 -416.390015) (xy 49.552615 -416.439625) (xy 49.56798 -416.491955) (xy 49.575742 -416.545939)
			(xy 49.576228 -416.573208) (xy 49.576228 -417.436808) (xy 49.575742 -417.464077) (xy 49.56798 -417.518061)
			(xy 49.552615 -417.570391) (xy 49.529958 -417.620001) (xy 49.500472 -417.665882) (xy 49.464757 -417.707099)
			(xy 49.42354 -417.742814) (xy 49.377659 -417.7723) (xy 49.328049 -417.794957) (xy 49.275719 -417.810322)
			(xy 49.221735 -417.818084) (xy 49.167197 -417.818084) (xy 49.113213 -417.810322) (xy 49.060883 -417.794957)
			(xy 49.011273 -417.7723) (xy 48.965392 -417.742814) (xy 48.924175 -417.707099) (xy 48.88846 -417.665882)
			(xy 48.858974 -417.620001) (xy 48.836317 -417.570391) (xy 48.820952 -417.518061) (xy 48.81319 -417.464077)
			(xy 48.812704 -417.436808) (xy 36.595812 -417.436808) (xy 36.595812 -417.465002) (xy 36.595326 -417.492253)
			(xy 36.58757 -417.546201) (xy 36.572215 -417.598496) (xy 36.549573 -417.648073) (xy 36.520107 -417.693923)
			(xy 36.484416 -417.735114) (xy 36.443225 -417.770805) (xy 36.397375 -417.800271) (xy 36.347798 -417.822913)
			(xy 36.295503 -417.838268) (xy 36.241555 -417.846024) (xy 36.187053 -417.846024) (xy 36.133105 -417.838268)
			(xy 36.08081 -417.822913) (xy 36.031233 -417.800271) (xy 35.985383 -417.770805) (xy 35.944192 -417.735114)
			(xy 35.908501 -417.693923) (xy 35.879035 -417.648073) (xy 35.856393 -417.598496) (xy 35.841038 -417.546201)
			(xy 35.833282 -417.492253) (xy 35.832796 -417.465002) (xy 7.00913 -417.465002) (xy 7.00913 -419.64102)
			(xy 51.809904 -419.64102) (xy 51.809904 -418.77742) (xy 51.81039 -418.750151) (xy 51.818152 -418.696167)
			(xy 51.833517 -418.643837) (xy 51.856174 -418.594227) (xy 51.88566 -418.548346) (xy 51.921375 -418.507129)
			(xy 51.962592 -418.471414) (xy 52.008473 -418.441928) (xy 52.058083 -418.419271) (xy 52.110413 -418.403906)
			(xy 52.164397 -418.396144) (xy 52.218935 -418.396144) (xy 52.272919 -418.403906) (xy 52.325249 -418.419271)
			(xy 52.374859 -418.441928) (xy 52.42074 -418.471414) (xy 52.461957 -418.507129) (xy 52.497672 -418.548346)
			(xy 52.527158 -418.594227) (xy 52.549815 -418.643837) (xy 52.56518 -418.696167) (xy 52.572942 -418.750151)
			(xy 52.573428 -418.77742) (xy 52.573428 -419.64102) (xy 52.572942 -419.668289) (xy 52.56518 -419.722273)
			(xy 52.549815 -419.774603) (xy 52.527158 -419.824213) (xy 52.497672 -419.870094) (xy 52.461957 -419.911311)
			(xy 52.42074 -419.947026) (xy 52.374859 -419.976512) (xy 52.325249 -419.999169) (xy 52.272919 -420.014534)
			(xy 52.218935 -420.022296) (xy 52.164397 -420.022296) (xy 52.110413 -420.014534) (xy 52.058083 -419.999169)
			(xy 52.008473 -419.976512) (xy 51.962592 -419.947026) (xy 51.921375 -419.911311) (xy 51.88566 -419.870094)
			(xy 51.856174 -419.824213) (xy 51.833517 -419.774603) (xy 51.818152 -419.722273) (xy 51.81039 -419.668289)
			(xy 51.809904 -419.64102) (xy 7.00913 -419.64102) (xy 7.00913 -421.200326) (xy 10.01268 -421.200326)
			(xy 10.01268 -420.336726) (xy 10.013166 -420.309475) (xy 10.020922 -420.255527) (xy 10.036277 -420.203232)
			(xy 10.058919 -420.153655) (xy 10.088385 -420.107805) (xy 10.124076 -420.066614) (xy 10.165267 -420.030923)
			(xy 10.211117 -420.001457) (xy 10.260694 -419.978815) (xy 10.312989 -419.96346) (xy 10.366937 -419.955704)
			(xy 10.421439 -419.955704) (xy 10.475387 -419.96346) (xy 10.527682 -419.978815) (xy 10.577259 -420.001457)
			(xy 10.623109 -420.030923) (xy 10.6643 -420.066614) (xy 10.699991 -420.107805) (xy 10.729457 -420.153655)
			(xy 10.752099 -420.203232) (xy 10.767454 -420.255527) (xy 10.77521 -420.309475) (xy 10.775696 -420.336726)
			(xy 10.775696 -421.200326) (xy 10.77521 -421.227577) (xy 10.769122 -421.269922) (xy 21.420836 -421.269922)
			(xy 21.420836 -420.406322) (xy 21.421322 -420.379071) (xy 21.429078 -420.325123) (xy 21.444433 -420.272828)
			(xy 21.467075 -420.223251) (xy 21.496541 -420.177401) (xy 21.532232 -420.13621) (xy 21.573423 -420.100519)
			(xy 21.619273 -420.071053) (xy 21.66885 -420.048411) (xy 21.721145 -420.033056) (xy 21.775093 -420.0253)
			(xy 21.829595 -420.0253) (xy 21.883543 -420.033056) (xy 21.935838 -420.048411) (xy 21.985415 -420.071053)
			(xy 22.031265 -420.100519) (xy 22.072456 -420.13621) (xy 22.108147 -420.177401) (xy 22.137613 -420.223251)
			(xy 22.160255 -420.272828) (xy 22.17561 -420.325123) (xy 22.183366 -420.379071) (xy 22.183852 -420.406322)
			(xy 22.183852 -420.760398) (xy 58.141108 -420.760398) (xy 58.141108 -418.218874) (xy 58.141589 -418.206761)
			(xy 58.14908 -418.183722) (xy 58.16332 -418.164123) (xy 58.182918 -418.149882) (xy 58.205957 -418.14239)
			(xy 58.21807 -418.141912) (xy 59.15787 -418.141912) (xy 59.169989 -418.142385) (xy 59.193042 -418.149866)
			(xy 59.212655 -418.164105) (xy 59.226908 -418.183708) (xy 59.234406 -418.206756) (xy 59.234832 -418.218874)
			(xy 59.234832 -420.760398) (xy 59.234438 -420.772524) (xy 59.226942 -420.795587) (xy 59.212685 -420.815205)
			(xy 59.193062 -420.829455) (xy 59.169996 -420.836942) (xy 59.15787 -420.83736) (xy 58.21807 -420.83736)
			(xy 58.205954 -420.836914) (xy 58.182909 -420.829418) (xy 58.163308 -420.81517) (xy 58.149067 -420.795562)
			(xy 58.141581 -420.772515) (xy 58.141108 -420.760398) (xy 22.183852 -420.760398) (xy 22.183852 -421.269922)
			(xy 22.183366 -421.297173) (xy 22.17561 -421.351121) (xy 22.160255 -421.403416) (xy 22.137613 -421.452993)
			(xy 22.108147 -421.498843) (xy 22.072456 -421.540034) (xy 22.031265 -421.575725) (xy 21.985415 -421.605191)
			(xy 21.935838 -421.627833) (xy 21.883543 -421.643188) (xy 21.829595 -421.650944) (xy 21.775093 -421.650944)
			(xy 21.721145 -421.643188) (xy 21.66885 -421.627833) (xy 21.619273 -421.605191) (xy 21.573423 -421.575725)
			(xy 21.532232 -421.540034) (xy 21.496541 -421.498843) (xy 21.467075 -421.452993) (xy 21.444433 -421.403416)
			(xy 21.429078 -421.351121) (xy 21.421322 -421.297173) (xy 21.420836 -421.269922) (xy 10.769122 -421.269922)
			(xy 10.767454 -421.281525) (xy 10.752099 -421.33382) (xy 10.729457 -421.383397) (xy 10.699991 -421.429247)
			(xy 10.6643 -421.470438) (xy 10.623109 -421.506129) (xy 10.577259 -421.535595) (xy 10.527682 -421.558237)
			(xy 10.475387 -421.573592) (xy 10.421439 -421.581348) (xy 10.366937 -421.581348) (xy 10.312989 -421.573592)
			(xy 10.260694 -421.558237) (xy 10.211117 -421.535595) (xy 10.165267 -421.506129) (xy 10.124076 -421.470438)
			(xy 10.088385 -421.429247) (xy 10.058919 -421.383397) (xy 10.036277 -421.33382) (xy 10.020922 -421.281525)
			(xy 10.013166 -421.227577) (xy 10.01268 -421.200326) (xy 7.00913 -421.200326) (xy 7.00913 -422.130474)
			(xy 24.87676 -422.130474) (xy 24.87676 -421.266874) (xy 24.877246 -421.239605) (xy 24.885008 -421.185621)
			(xy 24.900373 -421.133291) (xy 24.92303 -421.083681) (xy 24.952516 -421.0378) (xy 24.988231 -420.996583)
			(xy 25.029448 -420.960868) (xy 25.075329 -420.931382) (xy 25.124939 -420.908725) (xy 25.177269 -420.89336)
			(xy 25.231253 -420.885598) (xy 25.285791 -420.885598) (xy 25.339775 -420.89336) (xy 25.392105 -420.908725)
			(xy 25.441715 -420.931382) (xy 25.487596 -420.960868) (xy 25.528813 -420.996583) (xy 25.564528 -421.0378)
			(xy 25.594014 -421.083681) (xy 25.616671 -421.133291) (xy 25.632036 -421.185621) (xy 25.639798 -421.239605)
			(xy 25.640284 -421.266874) (xy 25.640284 -421.726974) (xy 27.323192 -421.726974) (xy 27.323192 -421.672426)
			(xy 27.330955 -421.618434) (xy 27.346324 -421.566097) (xy 27.368985 -421.51648) (xy 27.398477 -421.470593)
			(xy 27.4342 -421.429371) (xy 27.475427 -421.393652) (xy 27.521317 -421.364165) (xy 27.570936 -421.341509)
			(xy 27.623276 -421.326146) (xy 27.677268 -421.318389) (xy 27.704542 -421.317928) (xy 28.568142 -421.317928)
			(xy 28.595409 -421.318437) (xy 28.649386 -421.326204) (xy 28.701709 -421.341572) (xy 28.751313 -421.36423)
			(xy 28.797187 -421.393716) (xy 28.838399 -421.429431) (xy 28.874109 -421.470646) (xy 28.90359 -421.516524)
			(xy 28.926243 -421.56613) (xy 28.941605 -421.618455) (xy 28.949366 -421.672433) (xy 28.949366 -421.726967)
			(xy 28.941605 -421.780945) (xy 28.926243 -421.83327) (xy 28.90359 -421.882876) (xy 28.874109 -421.928754)
			(xy 28.838399 -421.969969) (xy 28.797187 -422.005684) (xy 28.751313 -422.03517) (xy 28.701709 -422.057828)
			(xy 28.649386 -422.073196) (xy 28.595409 -422.080963) (xy 28.568142 -422.081452) (xy 27.704542 -422.081452)
			(xy 27.677268 -422.081011) (xy 27.623276 -422.073254) (xy 27.570936 -422.057891) (xy 27.521317 -422.035235)
			(xy 27.475427 -422.005748) (xy 27.4342 -421.970029) (xy 27.398477 -421.928807) (xy 27.368985 -421.88292)
			(xy 27.346324 -421.833303) (xy 27.330955 -421.780966) (xy 27.323192 -421.726974) (xy 25.640284 -421.726974)
			(xy 25.640284 -422.130474) (xy 25.639798 -422.157743) (xy 25.632036 -422.211727) (xy 25.616671 -422.264057)
			(xy 25.594014 -422.313667) (xy 25.564528 -422.359548) (xy 25.528813 -422.400765) (xy 25.487596 -422.43648)
			(xy 25.441715 -422.465966) (xy 25.392105 -422.488623) (xy 25.339775 -422.503988) (xy 25.285791 -422.51175)
			(xy 25.231253 -422.51175) (xy 25.177269 -422.503988) (xy 25.124939 -422.488623) (xy 25.075329 -422.465966)
			(xy 25.029448 -422.43648) (xy 24.988231 -422.400765) (xy 24.952516 -422.359548) (xy 24.92303 -422.313667)
			(xy 24.900373 -422.264057) (xy 24.885008 -422.211727) (xy 24.877246 -422.157743) (xy 24.87676 -422.130474)
			(xy 7.00913 -422.130474) (xy 7.00913 -422.66627) (xy 38.762906 -422.66627) (xy 38.762906 -422.61173)
			(xy 38.770668 -422.557744) (xy 38.786034 -422.505412) (xy 38.808691 -422.4558) (xy 38.838178 -422.409918)
			(xy 38.873894 -422.368698) (xy 38.915113 -422.332981) (xy 38.960995 -422.303494) (xy 39.010607 -422.280836)
			(xy 39.062938 -422.26547) (xy 39.116924 -422.257707) (xy 39.144194 -422.25722) (xy 40.007794 -422.25722)
			(xy 40.035064 -422.257719) (xy 40.089049 -422.26548) (xy 40.14138 -422.280845) (xy 40.190991 -422.303501)
			(xy 40.236874 -422.332987) (xy 40.278093 -422.368703) (xy 40.313809 -422.409921) (xy 40.343296 -422.455803)
			(xy 40.365953 -422.505414) (xy 40.381319 -422.557745) (xy 40.389081 -422.61173) (xy 40.389081 -422.66627)
			(xy 40.381319 -422.720255) (xy 40.365953 -422.772586) (xy 40.343296 -422.822197) (xy 40.313809 -422.868079)
			(xy 40.278093 -422.909297) (xy 40.236874 -422.945013) (xy 40.190991 -422.974499) (xy 40.14138 -422.997155)
			(xy 40.089049 -423.01252) (xy 40.035064 -423.020281) (xy 40.007794 -423.020744) (xy 39.144194 -423.020744)
			(xy 39.116924 -423.020293) (xy 39.062938 -423.01253) (xy 39.010607 -422.997164) (xy 38.960995 -422.974506)
			(xy 38.915113 -422.945019) (xy 38.873894 -422.909302) (xy 38.838178 -422.868082) (xy 38.808691 -422.8222)
			(xy 38.786034 -422.772588) (xy 38.770668 -422.720256) (xy 38.762906 -422.66627) (xy 7.00913 -422.66627)
			(xy 7.00913 -423.057828) (xy 41.652952 -423.057828) (xy 41.652952 -422.194228) (xy 41.653438 -422.166959)
			(xy 41.6612 -422.112975) (xy 41.676565 -422.060645) (xy 41.699222 -422.011035) (xy 41.728708 -421.965154)
			(xy 41.764423 -421.923937) (xy 41.80564 -421.888222) (xy 41.851521 -421.858736) (xy 41.901131 -421.836079)
			(xy 41.953461 -421.820714) (xy 42.007445 -421.812952) (xy 42.061983 -421.812952) (xy 42.115967 -421.820714)
			(xy 42.168297 -421.836079) (xy 42.217907 -421.858736) (xy 42.263788 -421.888222) (xy 42.305005 -421.923937)
			(xy 42.34072 -421.965154) (xy 42.370206 -422.011035) (xy 42.392863 -422.060645) (xy 42.408228 -422.112975)
			(xy 42.41599 -422.166959) (xy 42.416476 -422.194228) (xy 42.416476 -423.057828) (xy 42.41599 -423.085097)
			(xy 42.408228 -423.139081) (xy 42.392863 -423.191411) (xy 42.370206 -423.241021) (xy 42.34072 -423.286902)
			(xy 42.305005 -423.328119) (xy 42.263788 -423.363834) (xy 42.217907 -423.39332) (xy 42.168297 -423.415977)
			(xy 42.115967 -423.431342) (xy 42.061983 -423.439104) (xy 42.007445 -423.439104) (xy 41.953461 -423.431342)
			(xy 41.901131 -423.415977) (xy 41.851521 -423.39332) (xy 41.80564 -423.363834) (xy 41.764423 -423.328119)
			(xy 41.728708 -423.286902) (xy 41.699222 -423.241021) (xy 41.676565 -423.191411) (xy 41.6612 -423.139081)
			(xy 41.653438 -423.085097) (xy 41.652952 -423.057828) (xy 7.00913 -423.057828) (xy 7.00913 -425.887642)
			(xy 10.204704 -425.887642) (xy 10.204704 -425.024042) (xy 10.20519 -424.996773) (xy 10.212952 -424.942789)
			(xy 10.228317 -424.890459) (xy 10.250974 -424.840849) (xy 10.28046 -424.794968) (xy 10.316175 -424.753751)
			(xy 10.357392 -424.718036) (xy 10.403273 -424.68855) (xy 10.452883 -424.665893) (xy 10.505213 -424.650528)
			(xy 10.559197 -424.642766) (xy 10.613735 -424.642766) (xy 10.667719 -424.650528) (xy 10.720049 -424.665893)
			(xy 10.769659 -424.68855) (xy 10.81554 -424.718036) (xy 10.856757 -424.753751) (xy 10.892472 -424.794968)
			(xy 10.921958 -424.840849) (xy 10.944615 -424.890459) (xy 10.95998 -424.942789) (xy 10.967742 -424.996773)
			(xy 10.968228 -425.024042) (xy 10.968228 -425.328334) (xy 21.942552 -425.328334) (xy 21.942552 -424.464734)
			(xy 21.943038 -424.437465) (xy 21.9508 -424.383481) (xy 21.966165 -424.331151) (xy 21.988822 -424.281541)
			(xy 22.018308 -424.23566) (xy 22.054023 -424.194443) (xy 22.09524 -424.158728) (xy 22.141121 -424.129242)
			(xy 22.190731 -424.106585) (xy 22.243061 -424.09122) (xy 22.297045 -424.083458) (xy 22.351583 -424.083458)
			(xy 22.405567 -424.09122) (xy 22.457897 -424.106585) (xy 22.507507 -424.129242) (xy 22.553388 -424.158728)
			(xy 22.594605 -424.194443) (xy 22.63032 -424.23566) (xy 22.659806 -424.281541) (xy 22.682463 -424.331151)
			(xy 22.691108 -424.360594) (xy 58.141108 -424.360594) (xy 58.141108 -421.81907) (xy 58.141586 -421.806957)
			(xy 58.149077 -421.783918) (xy 58.163319 -421.764319) (xy 58.182918 -421.750077) (xy 58.205957 -421.742586)
			(xy 58.21807 -421.742108) (xy 59.15787 -421.742108) (xy 59.16998 -421.742637) (xy 59.193017 -421.750112)
			(xy 59.207184 -421.760396) (xy 60.141104 -421.760396) (xy 60.141104 -419.218872) (xy 60.141493 -419.206761)
			(xy 60.149 -419.183732) (xy 60.163269 -419.164159) (xy 60.182896 -419.149966) (xy 60.205954 -419.142547)
			(xy 60.218066 -419.142164) (xy 61.157866 -419.142164) (xy 61.169956 -419.142637) (xy 61.19296 -419.150087)
			(xy 61.212542 -419.164271) (xy 61.226793 -419.183805) (xy 61.234322 -419.206783) (xy 61.234828 -419.218872)
			(xy 61.234828 -421.760396) (xy 61.234381 -421.772502) (xy 61.226886 -421.795524) (xy 61.212631 -421.815095)
			(xy 61.193018 -421.829291) (xy 61.169973 -421.836717) (xy 61.157866 -421.837104) (xy 60.218066 -421.837104)
			(xy 60.205979 -421.836623) (xy 60.182985 -421.829162) (xy 60.163409 -421.814977) (xy 60.149158 -421.79545)
			(xy 60.141619 -421.772481) (xy 60.141104 -421.760396) (xy 59.207184 -421.760396) (xy 59.212617 -421.76434)
			(xy 59.22686 -421.783929) (xy 59.234354 -421.80696) (xy 59.234832 -421.81907) (xy 59.234832 -424.360594)
			(xy 62.1411 -424.360594) (xy 62.1411 -421.81907) (xy 62.141585 -421.806958) (xy 62.149076 -421.78392)
			(xy 62.163316 -421.764322) (xy 62.182913 -421.75008) (xy 62.20595 -421.742587) (xy 62.218062 -421.742108)
			(xy 63.157862 -421.742108) (xy 63.16998 -421.742592) (xy 63.193032 -421.75007) (xy 63.207258 -421.760396)
			(xy 68.141088 -421.760396) (xy 68.141088 -419.218872) (xy 68.141492 -419.206763) (xy 68.148998 -419.183737)
			(xy 68.163263 -419.164165) (xy 68.182886 -419.149971) (xy 68.205939 -419.142549) (xy 68.21805 -419.142164)
			(xy 69.15785 -419.142164) (xy 69.169939 -419.14265) (xy 69.192942 -419.150096) (xy 69.212525 -419.164277)
			(xy 69.226777 -419.183808) (xy 69.234306 -419.206784) (xy 69.234812 -419.218872) (xy 69.234812 -420.760398)
			(xy 70.141084 -420.760398) (xy 70.141084 -418.218874) (xy 70.141438 -418.206745) (xy 70.148943 -418.183678)
			(xy 70.16321 -418.164059) (xy 70.182842 -418.14981) (xy 70.205917 -418.142327) (xy 70.218046 -418.141912)
			(xy 71.157846 -418.141912) (xy 71.16996 -418.142372) (xy 71.193001 -418.149869) (xy 71.212599 -418.164115)
			(xy 71.22684 -418.183717) (xy 71.234331 -418.20676) (xy 71.234808 -418.218874) (xy 71.234808 -418.3761)
			(xy 77.661008 -418.3761) (xy 77.661008 -417.5125) (xy 77.661494 -417.485231) (xy 77.669256 -417.431247)
			(xy 77.684621 -417.378917) (xy 77.707278 -417.329307) (xy 77.736764 -417.283426) (xy 77.772479 -417.242209)
			(xy 77.813696 -417.206494) (xy 77.859577 -417.177008) (xy 77.909187 -417.154351) (xy 77.961517 -417.138986)
			(xy 78.015501 -417.131224) (xy 78.070039 -417.131224) (xy 78.124023 -417.138986) (xy 78.176353 -417.154351)
			(xy 78.225963 -417.177008) (xy 78.271844 -417.206494) (xy 78.313061 -417.242209) (xy 78.348776 -417.283426)
			(xy 78.378262 -417.329307) (xy 78.400919 -417.378917) (xy 78.416284 -417.431247) (xy 78.424046 -417.485231)
			(xy 78.424532 -417.5125) (xy 78.424532 -418.3761) (xy 78.424046 -418.403369) (xy 78.416284 -418.457353)
			(xy 78.400919 -418.509683) (xy 78.378262 -418.559293) (xy 78.348776 -418.605174) (xy 78.313061 -418.646391)
			(xy 78.271844 -418.682106) (xy 78.225963 -418.711592) (xy 78.176353 -418.734249) (xy 78.124023 -418.749614)
			(xy 78.070039 -418.757376) (xy 78.015501 -418.757376) (xy 77.961517 -418.749614) (xy 77.909187 -418.734249)
			(xy 77.859577 -418.711592) (xy 77.813696 -418.682106) (xy 77.772479 -418.646391) (xy 77.736764 -418.605174)
			(xy 77.707278 -418.559293) (xy 77.684621 -418.509683) (xy 77.669256 -418.457353) (xy 77.661494 -418.403369)
			(xy 77.661008 -418.3761) (xy 71.234808 -418.3761) (xy 71.234808 -420.760398) (xy 71.234287 -420.772508)
			(xy 71.226806 -420.795543) (xy 71.212575 -420.815141) (xy 71.192986 -420.829384) (xy 71.169956 -420.83688)
			(xy 71.157846 -420.83736) (xy 70.218046 -420.83736) (xy 70.205925 -420.836901) (xy 70.182868 -420.829421)
			(xy 70.163252 -420.81518) (xy 70.148999 -420.795572) (xy 70.141506 -420.772518) (xy 70.141084 -420.760398)
			(xy 69.234812 -420.760398) (xy 69.234812 -421.760396) (xy 69.234381 -421.772503) (xy 69.226884 -421.795529)
			(xy 69.212626 -421.815101) (xy 69.193008 -421.829296) (xy 69.169959 -421.836719) (xy 69.15785 -421.837104)
			(xy 68.21805 -421.837104) (xy 68.205967 -421.836551) (xy 68.182976 -421.829113) (xy 68.163399 -421.814947)
			(xy 68.149145 -421.795434) (xy 68.141604 -421.772476) (xy 68.141088 -421.760396) (xy 63.207258 -421.760396)
			(xy 63.212645 -421.764306) (xy 63.226899 -421.783907) (xy 63.234398 -421.806953) (xy 63.234824 -421.81907)
			(xy 63.234824 -424.360594) (xy 63.234434 -424.37272) (xy 63.226939 -424.395785) (xy 63.212681 -424.415404)
			(xy 63.193057 -424.429654) (xy 63.169988 -424.437139) (xy 63.157862 -424.437556) (xy 62.218062 -424.437556)
			(xy 62.205945 -424.437121) (xy 62.182899 -424.429622) (xy 62.163298 -424.415371) (xy 62.149058 -424.395761)
			(xy 62.141572 -424.372711) (xy 62.1411 -424.360594) (xy 59.234832 -424.360594) (xy 59.234434 -424.372719)
			(xy 59.22694 -424.395783) (xy 59.212684 -424.415401) (xy 59.193062 -424.429651) (xy 59.169996 -424.437138)
			(xy 59.15787 -424.437556) (xy 58.21807 -424.437556) (xy 58.205953 -424.437114) (xy 58.182908 -424.429618)
			(xy 58.163306 -424.415368) (xy 58.149066 -424.39576) (xy 58.14158 -424.372711) (xy 58.141108 -424.360594)
			(xy 22.691108 -424.360594) (xy 22.697828 -424.383481) (xy 22.70559 -424.437465) (xy 22.706076 -424.464734)
			(xy 22.706076 -425.328334) (xy 22.70559 -425.355603) (xy 22.697828 -425.409587) (xy 22.682463 -425.461917)
			(xy 22.659806 -425.511527) (xy 22.63032 -425.557408) (xy 22.594605 -425.598625) (xy 22.553388 -425.63434)
			(xy 22.507507 -425.663826) (xy 22.457897 -425.686483) (xy 22.405567 -425.701848) (xy 22.351583 -425.70961)
			(xy 22.297045 -425.70961) (xy 22.243061 -425.701848) (xy 22.190731 -425.686483) (xy 22.141121 -425.663826)
			(xy 22.09524 -425.63434) (xy 22.054023 -425.598625) (xy 22.018308 -425.557408) (xy 21.988822 -425.511527)
			(xy 21.966165 -425.461917) (xy 21.9508 -425.409587) (xy 21.943038 -425.355603) (xy 21.942552 -425.328334)
			(xy 10.968228 -425.328334) (xy 10.968228 -425.887642) (xy 10.967742 -425.914911) (xy 10.964527 -425.937273)
			(xy 38.737196 -425.937273) (xy 38.737196 -425.882727) (xy 38.744959 -425.828736) (xy 38.760327 -425.776399)
			(xy 38.782988 -425.726782) (xy 38.81248 -425.680896) (xy 38.848202 -425.639674) (xy 38.889428 -425.603956)
			(xy 38.935317 -425.574469) (xy 38.984936 -425.551813) (xy 39.037275 -425.53645) (xy 39.091267 -425.528693)
			(xy 39.11854 -425.528232) (xy 39.98214 -425.528232) (xy 40.009407 -425.528733) (xy 40.063385 -425.536499)
			(xy 40.115709 -425.551868) (xy 40.165314 -425.574526) (xy 40.211189 -425.604012) (xy 40.252401 -425.639727)
			(xy 40.288112 -425.680943) (xy 40.317593 -425.726821) (xy 40.340246 -425.776428) (xy 40.355609 -425.828754)
			(xy 40.36337 -425.882733) (xy 40.36337 -425.937267) (xy 40.355609 -425.991246) (xy 40.340246 -426.043572)
			(xy 40.317593 -426.093179) (xy 40.288112 -426.139057) (xy 40.252401 -426.180273) (xy 40.211189 -426.215988)
			(xy 40.165314 -426.245474) (xy 40.115709 -426.268132) (xy 40.063385 -426.283501) (xy 40.009407 -426.291267)
			(xy 39.98214 -426.291756) (xy 39.11854 -426.291756) (xy 39.091267 -426.291307) (xy 39.037275 -426.28355)
			(xy 38.984936 -426.268187) (xy 38.935317 -426.245531) (xy 38.889428 -426.216044) (xy 38.848202 -426.180326)
			(xy 38.81248 -426.139104) (xy 38.782988 -426.093218) (xy 38.760327 -426.043601) (xy 38.744959 -425.991264)
			(xy 38.737196 -425.937273) (xy 10.964527 -425.937273) (xy 10.95998 -425.968895) (xy 10.944615 -426.021225)
			(xy 10.921958 -426.070835) (xy 10.892472 -426.116716) (xy 10.856757 -426.157933) (xy 10.81554 -426.193648)
			(xy 10.769659 -426.223134) (xy 10.720049 -426.245791) (xy 10.667719 -426.261156) (xy 10.613735 -426.268918)
			(xy 10.559197 -426.268918) (xy 10.505213 -426.261156) (xy 10.452883 -426.245791) (xy 10.403273 -426.223134)
			(xy 10.357392 -426.193648) (xy 10.316175 -426.157933) (xy 10.28046 -426.116716) (xy 10.250974 -426.070835)
			(xy 10.228317 -426.021225) (xy 10.212952 -425.968895) (xy 10.20519 -425.914911) (xy 10.204704 -425.887642)
			(xy 7.00913 -425.887642) (xy 7.00913 -426.333158) (xy 41.613836 -426.333158) (xy 41.613836 -425.469558)
			(xy 41.614322 -425.442307) (xy 41.622078 -425.388359) (xy 41.637433 -425.336064) (xy 41.660075 -425.286487)
			(xy 41.689541 -425.240637) (xy 41.725232 -425.199446) (xy 41.766423 -425.163755) (xy 41.812273 -425.134289)
			(xy 41.86185 -425.111647) (xy 41.914145 -425.096292) (xy 41.968093 -425.088536) (xy 42.022595 -425.088536)
			(xy 42.076543 -425.096292) (xy 42.128838 -425.111647) (xy 42.178415 -425.134289) (xy 42.224265 -425.163755)
			(xy 42.265456 -425.199446) (xy 42.301147 -425.240637) (xy 42.330613 -425.286487) (xy 42.353255 -425.336064)
			(xy 42.36861 -425.388359) (xy 42.376366 -425.442307) (xy 42.376852 -425.469558) (xy 42.376852 -426.333158)
			(xy 42.376366 -426.360409) (xy 42.36861 -426.414357) (xy 42.353255 -426.466652) (xy 42.330613 -426.516229)
			(xy 42.301147 -426.562079) (xy 42.265456 -426.60327) (xy 42.224265 -426.638961) (xy 42.178415 -426.668427)
			(xy 42.128838 -426.691069) (xy 42.076543 -426.706424) (xy 42.022595 -426.71418) (xy 41.968093 -426.71418)
			(xy 41.914145 -426.706424) (xy 41.86185 -426.691069) (xy 41.812273 -426.668427) (xy 41.766423 -426.638961)
			(xy 41.725232 -426.60327) (xy 41.689541 -426.562079) (xy 41.660075 -426.516229) (xy 41.637433 -426.466652)
			(xy 41.622078 -426.414357) (xy 41.614322 -426.360409) (xy 41.613836 -426.333158) (xy 7.00913 -426.333158)
			(xy 7.00913 -428.615602) (xy 25.13076 -428.615602) (xy 25.13076 -427.752002) (xy 25.131246 -427.724733)
			(xy 25.139008 -427.670749) (xy 25.154373 -427.618419) (xy 25.17703 -427.568809) (xy 25.206516 -427.522928)
			(xy 25.242231 -427.481711) (xy 25.283448 -427.445996) (xy 25.329329 -427.41651) (xy 25.378939 -427.393853)
			(xy 25.431269 -427.378488) (xy 25.485253 -427.370726) (xy 25.539791 -427.370726) (xy 25.593775 -427.378488)
			(xy 25.646105 -427.393853) (xy 25.695715 -427.41651) (xy 25.741596 -427.445996) (xy 25.782813 -427.481711)
			(xy 25.818528 -427.522928) (xy 25.848014 -427.568809) (xy 25.870671 -427.618419) (xy 25.886036 -427.670749)
			(xy 25.893798 -427.724733) (xy 25.894284 -427.752002) (xy 25.894284 -428.211072) (xy 26.941204 -428.211072)
			(xy 26.941204 -428.156528) (xy 26.948966 -428.102539) (xy 26.964334 -428.050205) (xy 26.986993 -428.00059)
			(xy 27.016483 -427.954705) (xy 27.052203 -427.913485) (xy 27.093426 -427.877767) (xy 27.139313 -427.848281)
			(xy 27.188929 -427.825625) (xy 27.241265 -427.810261) (xy 27.295254 -427.802502) (xy 27.322526 -427.80204)
			(xy 28.186126 -427.80204) (xy 28.213394 -427.802524) (xy 28.267375 -427.810289) (xy 28.319702 -427.825657)
			(xy 28.369309 -427.848314) (xy 28.415187 -427.877801) (xy 28.456402 -427.913517) (xy 28.492114 -427.954734)
			(xy 28.495843 -427.960536) (xy 58.141108 -427.960536) (xy 58.141108 -427.233588) (xy 58.14139 -427.224753)
			(xy 58.145504 -427.207565) (xy 58.149236 -427.199552) (xy 58.382662 -426.723302) (xy 58.387347 -426.712779)
			(xy 58.390839 -426.690025) (xy 58.387362 -426.667269) (xy 58.382662 -426.656754) (xy 58.149236 -426.180504)
			(xy 58.145483 -426.172497) (xy 58.141364 -426.155306) (xy 58.141108 -426.146468) (xy 58.141108 -425.419012)
			(xy 58.141527 -425.406903) (xy 58.149024 -425.383875) (xy 58.163285 -425.364301) (xy 58.182906 -425.350106)
			(xy 58.20596 -425.342687) (xy 58.21807 -425.342304) (xy 59.15787 -425.342304) (xy 59.169954 -425.342832)
			(xy 59.192948 -425.350276) (xy 59.212525 -425.364448) (xy 59.226778 -425.383967) (xy 59.234317 -425.40693)
			(xy 59.234832 -425.419012) (xy 59.234832 -427.960536) (xy 59.234415 -427.972644) (xy 59.226909 -427.995667)
			(xy 59.212647 -428.015236) (xy 59.193028 -428.029431) (xy 59.169979 -428.036856) (xy 59.15787 -428.037244)
			(xy 58.21807 -428.037244) (xy 58.205977 -428.036818) (xy 58.182973 -428.029351) (xy 58.163392 -428.015154)
			(xy 58.149143 -427.995612) (xy 58.141615 -427.972627) (xy 58.141108 -427.960536) (xy 28.495843 -427.960536)
			(xy 28.521598 -428.000614) (xy 28.544253 -428.050222) (xy 28.559617 -428.10255) (xy 28.567378 -428.156532)
			(xy 28.567378 -428.211068) (xy 28.559617 -428.26505) (xy 28.544253 -428.317378) (xy 28.521598 -428.366986)
			(xy 28.492114 -428.412866) (xy 28.456402 -428.454083) (xy 28.415187 -428.489799) (xy 28.369309 -428.519286)
			(xy 28.319702 -428.541943) (xy 28.267375 -428.557311) (xy 28.213394 -428.565076) (xy 28.186126 -428.565564)
			(xy 27.322526 -428.565564) (xy 27.295254 -428.565098) (xy 27.241265 -428.557339) (xy 27.188929 -428.541975)
			(xy 27.139313 -428.519319) (xy 27.093426 -428.489833) (xy 27.052203 -428.454115) (xy 27.016483 -428.412895)
			(xy 26.986993 -428.36701) (xy 26.964334 -428.317395) (xy 26.948966 -428.265061) (xy 26.941204 -428.211072)
			(xy 25.894284 -428.211072) (xy 25.894284 -428.615602) (xy 25.893798 -428.642871) (xy 25.886036 -428.696855)
			(xy 25.870671 -428.749185) (xy 25.848014 -428.798795) (xy 25.818528 -428.844676) (xy 25.782813 -428.885893)
			(xy 25.741596 -428.921608) (xy 25.695715 -428.951094) (xy 25.646105 -428.973751) (xy 25.593775 -428.989116)
			(xy 25.539791 -428.996878) (xy 25.485253 -428.996878) (xy 25.431269 -428.989116) (xy 25.378939 -428.973751)
			(xy 25.329329 -428.951094) (xy 25.283448 -428.921608) (xy 25.242231 -428.885893) (xy 25.206516 -428.844676)
			(xy 25.17703 -428.798795) (xy 25.154373 -428.749185) (xy 25.139008 -428.696855) (xy 25.131246 -428.642871)
			(xy 25.13076 -428.615602) (xy 7.00913 -428.615602) (xy 7.00913 -431.560478) (xy 58.141108 -431.560478)
			(xy 58.141108 -429.018954) (xy 58.141572 -429.00684) (xy 58.149068 -428.9838) (xy 58.163313 -428.964202)
			(xy 58.182915 -428.949961) (xy 58.205956 -428.94247) (xy 58.21807 -428.941992) (xy 59.15787 -428.941992)
			(xy 59.169978 -428.942537) (xy 59.193013 -428.95001) (xy 59.207512 -428.960534) (xy 60.141104 -428.960534)
			(xy 60.141104 -428.233586) (xy 60.141385 -428.224751) (xy 60.1455 -428.207563) (xy 60.149232 -428.19955)
			(xy 60.382658 -427.7233) (xy 60.387344 -427.712778) (xy 60.390836 -427.690023) (xy 60.387359 -427.667267)
			(xy 60.382658 -427.656752) (xy 60.149232 -427.180502) (xy 60.145478 -427.172496) (xy 60.14136 -427.155304)
			(xy 60.141104 -427.146466) (xy 60.141104 -426.41901) (xy 60.14162 -426.406899) (xy 60.1491 -426.383862)
			(xy 60.163332 -426.364263) (xy 60.182923 -426.35002) (xy 60.205956 -426.342527) (xy 60.218066 -426.342048)
			(xy 61.157866 -426.342048) (xy 61.169988 -426.342489) (xy 61.193047 -426.349973) (xy 61.212664 -426.364219)
			(xy 61.226916 -426.383831) (xy 61.234407 -426.406888) (xy 61.234828 -426.41901) (xy 61.234828 -427.960536)
			(xy 62.1411 -427.960536) (xy 62.1411 -427.233588) (xy 62.141382 -427.224753) (xy 62.145496 -427.207565)
			(xy 62.149228 -427.199552) (xy 62.382654 -426.723302) (xy 62.387339 -426.71278) (xy 62.390832 -426.690025)
			(xy 62.387354 -426.667269) (xy 62.382654 -426.656754) (xy 62.149228 -426.180504) (xy 62.145474 -426.172498)
			(xy 62.141356 -426.155306) (xy 62.1411 -426.146468) (xy 62.1411 -425.419012) (xy 62.141527 -425.406904)
			(xy 62.149023 -425.383877) (xy 62.163282 -425.364304) (xy 62.182901 -425.350109) (xy 62.205952 -425.342688)
			(xy 62.218062 -425.342304) (xy 63.157862 -425.342304) (xy 63.169946 -425.342839) (xy 63.192939 -425.350281)
			(xy 63.207185 -425.360592) (xy 64.141096 -425.360592) (xy 64.141096 -422.819068) (xy 64.141489 -422.806958)
			(xy 64.148997 -422.78393) (xy 64.163265 -422.764358) (xy 64.18289 -422.750164) (xy 64.205946 -422.742744)
			(xy 64.218058 -422.74236) (xy 65.157858 -422.74236) (xy 65.169947 -422.742843) (xy 65.19295 -422.750291)
			(xy 65.212532 -422.764473) (xy 65.226784 -422.784004) (xy 65.234313 -422.80698) (xy 65.23482 -422.819068)
			(xy 65.23482 -425.360592) (xy 65.234377 -425.372698) (xy 65.226883 -425.395722) (xy 65.212627 -425.415294)
			(xy 65.193012 -425.429489) (xy 65.169966 -425.436914) (xy 65.157858 -425.4373) (xy 64.218058 -425.4373)
			(xy 64.20597 -425.436829) (xy 64.182975 -425.429366) (xy 64.163399 -425.415179) (xy 64.149149 -425.395649)
			(xy 64.141611 -425.372678) (xy 64.141096 -425.360592) (xy 63.207185 -425.360592) (xy 63.212517 -425.364451)
			(xy 63.22677 -425.383968) (xy 63.234309 -425.40693) (xy 63.234824 -425.419012) (xy 63.234824 -427.960536)
			(xy 63.234415 -427.972644) (xy 63.226908 -427.995669) (xy 63.212644 -428.015239) (xy 63.193023 -428.029433)
			(xy 63.169972 -428.036857) (xy 63.157862 -428.037244) (xy 62.218062 -428.037244) (xy 62.205969 -428.036825)
			(xy 62.182964 -428.029356) (xy 62.163384 -428.015157) (xy 62.149135 -427.995613) (xy 62.141607 -427.972628)
			(xy 62.1411 -427.960536) (xy 61.234828 -427.960536) (xy 61.234828 -428.960534) (xy 61.234417 -428.972654)
			(xy 61.226916 -428.995704) (xy 61.21266 -429.015308) (xy 61.193043 -429.029547) (xy 61.169986 -429.037027)
			(xy 61.157866 -429.037496) (xy 60.218066 -429.037496) (xy 60.205953 -429.037018) (xy 60.182914 -429.029525)
			(xy 60.163316 -429.015284) (xy 60.149075 -428.995686) (xy 60.141582 -428.972647) (xy 60.141104 -428.960534)
			(xy 59.207512 -428.960534) (xy 59.212611 -428.964235) (xy 59.226855 -428.983819) (xy 59.234351 -429.006846)
			(xy 59.234832 -429.018954) (xy 59.234832 -431.560478) (xy 59.234421 -431.572603) (xy 59.226931 -431.595666)
			(xy 59.212678 -431.615284) (xy 59.193059 -431.629535) (xy 59.169995 -431.637022) (xy 59.15787 -431.63744)
			(xy 58.21807 -431.63744) (xy 58.205952 -431.637014) (xy 58.182904 -431.629515) (xy 58.163301 -431.615262)
			(xy 58.149061 -431.59565) (xy 58.141578 -431.572597) (xy 58.141108 -431.560478) (xy 7.00913 -431.560478)
			(xy 7.00913 -435.160674) (xy 58.141108 -435.160674) (xy 58.141108 -432.61915) (xy 58.141569 -432.607036)
			(xy 58.149066 -432.583996) (xy 58.163312 -432.564398) (xy 58.182914 -432.550157) (xy 58.205956 -432.542666)
			(xy 58.21807 -432.542188) (xy 59.15787 -432.542188) (xy 59.169978 -432.542737) (xy 59.193012 -432.550209)
			(xy 59.207158 -432.560476) (xy 60.141104 -432.560476) (xy 60.141104 -430.018952) (xy 60.141476 -430.00684)
			(xy 60.148989 -429.983811) (xy 60.163262 -429.964238) (xy 60.182893 -429.950045) (xy 60.205953 -429.942626)
			(xy 60.218066 -429.942244) (xy 61.157866 -429.942244) (xy 61.169954 -429.942736) (xy 61.192954 -429.950184)
			(xy 61.212535 -429.964364) (xy 61.226787 -429.983893) (xy 61.234319 -430.006866) (xy 61.234828 -430.018952)
			(xy 61.234828 -431.560478) (xy 62.1411 -431.560478) (xy 62.1411 -429.018954) (xy 62.141572 -429.006841)
			(xy 62.149067 -428.983803) (xy 62.163311 -428.964205) (xy 62.18291 -428.949964) (xy 62.205949 -428.942471)
			(xy 62.218062 -428.941992) (xy 63.157862 -428.941992) (xy 63.16997 -428.942543) (xy 63.193004 -428.950015)
			(xy 63.207499 -428.960534) (xy 64.141096 -428.960534) (xy 64.141096 -428.233586) (xy 64.141378 -428.224751)
			(xy 64.145492 -428.207563) (xy 64.149224 -428.19955) (xy 64.38265 -427.7233) (xy 64.387337 -427.712778)
			(xy 64.390829 -427.690023) (xy 64.387351 -427.667267) (xy 64.38265 -427.656752) (xy 64.149224 -427.180502)
			(xy 64.145469 -427.172496) (xy 64.141352 -427.155304) (xy 64.141096 -427.146466) (xy 64.141096 -426.41901)
			(xy 64.14162 -426.4069) (xy 64.149099 -426.383864) (xy 64.163329 -426.364266) (xy 64.182918 -426.350023)
			(xy 64.205948 -426.342528) (xy 64.218058 -426.342048) (xy 65.157858 -426.342048) (xy 65.16998 -426.342496)
			(xy 65.193039 -426.349978) (xy 65.212655 -426.364222) (xy 65.226908 -426.383833) (xy 65.234399 -426.406889)
			(xy 65.23482 -426.41901) (xy 65.23482 -427.960536) (xy 66.141092 -427.960536) (xy 66.141092 -427.233588)
			(xy 66.141375 -427.224753) (xy 66.145488 -427.207566) (xy 66.14922 -427.199552) (xy 66.382646 -426.723302)
			(xy 66.387332 -426.71278) (xy 66.390825 -426.690025) (xy 66.387347 -426.667269) (xy 66.382646 -426.656754)
			(xy 66.14922 -426.180504) (xy 66.145466 -426.172498) (xy 66.141348 -426.155306) (xy 66.141092 -426.146468)
			(xy 66.141092 -425.419012) (xy 66.141527 -425.406905) (xy 66.149022 -425.383879) (xy 66.163279 -425.364307)
			(xy 66.182896 -425.350111) (xy 66.205945 -425.342689) (xy 66.218054 -425.342304) (xy 67.157854 -425.342304)
			(xy 67.169938 -425.342846) (xy 67.192931 -425.350286) (xy 67.207172 -425.360592) (xy 68.141088 -425.360592)
			(xy 68.141088 -422.819068) (xy 68.141489 -422.806959) (xy 68.148996 -422.783932) (xy 68.163262 -422.764361)
			(xy 68.182885 -422.750167) (xy 68.205939 -422.742745) (xy 68.21805 -422.74236) (xy 69.15785 -422.74236)
			(xy 69.169939 -422.74285) (xy 69.192941 -422.750296) (xy 69.212524 -422.764475) (xy 69.226775 -422.784006)
			(xy 69.234305 -422.806981) (xy 69.234812 -422.819068) (xy 69.234812 -424.360594) (xy 70.141084 -424.360594)
			(xy 70.141084 -421.81907) (xy 70.141435 -421.806941) (xy 70.148941 -421.783873) (xy 70.163209 -421.764255)
			(xy 70.182842 -421.750006) (xy 70.205917 -421.742523) (xy 70.218046 -421.742108) (xy 71.157846 -421.742108)
			(xy 71.16996 -421.742572) (xy 71.193 -421.750068) (xy 71.207209 -421.760396) (xy 72.14108 -421.760396)
			(xy 72.14108 -419.218872) (xy 72.141492 -419.206764) (xy 72.148997 -419.183739) (xy 72.16326 -419.164168)
			(xy 72.182881 -419.149974) (xy 72.205932 -419.14255) (xy 72.218042 -419.142164) (xy 73.157842 -419.142164)
			(xy 73.169936 -419.142572) (xy 73.192942 -419.150043) (xy 73.212524 -419.164244) (xy 73.226772 -419.183791)
			(xy 73.234298 -419.206779) (xy 73.234804 -419.218872) (xy 73.234804 -420.921688) (xy 75.13828 -420.921688)
			(xy 75.13828 -420.058088) (xy 75.138766 -420.030819) (xy 75.146528 -419.976835) (xy 75.161893 -419.924505)
			(xy 75.18455 -419.874895) (xy 75.214036 -419.829014) (xy 75.249751 -419.787797) (xy 75.290968 -419.752082)
			(xy 75.336849 -419.722596) (xy 75.386459 -419.699939) (xy 75.438789 -419.684574) (xy 75.492773 -419.676812)
			(xy 75.547311 -419.676812) (xy 75.601295 -419.684574) (xy 75.653625 -419.699939) (xy 75.703235 -419.722596)
			(xy 75.749116 -419.752082) (xy 75.790333 -419.787797) (xy 75.826048 -419.829014) (xy 75.855534 -419.874895)
			(xy 75.878191 -419.924505) (xy 75.893556 -419.976835) (xy 75.901318 -420.030819) (xy 75.901804 -420.058088)
			(xy 75.901804 -420.921688) (xy 75.901318 -420.948957) (xy 75.893556 -421.002941) (xy 75.878191 -421.055271)
			(xy 75.855534 -421.104881) (xy 75.844472 -421.122094) (xy 97.149412 -421.122094) (xy 97.149412 -414.328102)
			(xy 97.149934 -414.317948) (xy 97.157703 -414.299183) (xy 97.17206 -414.284819) (xy 97.19082 -414.27704)
			(xy 97.200974 -414.27654) (xy 102.099618 -414.27654) (xy 102.109777 -414.277018) (xy 102.128547 -414.284799)
			(xy 102.142912 -414.29917) (xy 102.150685 -414.317943) (xy 102.15118 -414.328102) (xy 102.15118 -420.700708)
			(xy 194.5894 -420.700708) (xy 194.5894 -413.816038) (xy 194.589861 -413.791087) (xy 194.597682 -413.741803)
			(xy 194.613107 -413.694345) (xy 194.635757 -413.649879) (xy 194.665075 -413.609499) (xy 194.682364 -413.591502)
			(xy 195.567554 -412.706312) (xy 195.585523 -412.688994) (xy 195.625906 -412.659673) (xy 195.670378 -412.63703)
			(xy 195.717845 -412.621623) (xy 195.767138 -412.61383) (xy 195.79209 -412.613348) (xy 226.774756 -412.613348)
			(xy 226.784825 -412.612913) (xy 226.803423 -412.605201) (xy 226.810824 -412.598362) (xy 229.321106 -410.08808)
			(xy 229.339091 -410.070779) (xy 229.37947 -410.041457) (xy 229.423939 -410.018812) (xy 229.471402 -410.0034)
			(xy 229.520691 -409.995602) (xy 229.545642 -409.995116) (xy 234.562904 -409.995116) (xy 234.572976 -409.994715)
			(xy 234.591575 -409.98698) (xy 234.598972 -409.98013) (xy 238.550196 -406.028906) (xy 238.557025 -406.021497)
			(xy 238.564751 -406.002905) (xy 238.565182 -405.992838) (xy 238.565182 -397.97228) (xy 238.565675 -397.947331)
			(xy 238.573489 -397.898048) (xy 238.588907 -397.85059) (xy 238.611549 -397.806124) (xy 238.640861 -397.765742)
			(xy 238.658146 -397.747744) (xy 239.164876 -397.241014) (xy 239.18288 -397.223733) (xy 239.223253 -397.194408)
			(xy 239.267717 -397.171758) (xy 239.315176 -397.156341) (xy 239.364462 -397.148538) (xy 239.389412 -397.14805)
			(xy 279.416002 -397.14805) (xy 279.44095 -397.148563) (xy 279.490232 -397.156374) (xy 279.491975 -397.15694)
			(xy 303.485804 -397.15694) (xy 303.485804 -397.156432) (xy 303.486268 -397.132439) (xy 303.49377 -397.085044)
			(xy 303.508595 -397.039405) (xy 303.530377 -396.996648) (xy 303.558581 -396.957826) (xy 303.592511 -396.923894)
			(xy 303.631331 -396.895688) (xy 303.674087 -396.873903) (xy 303.719724 -396.859075) (xy 303.767119 -396.851569)
			(xy 303.791112 -396.851124) (xy 303.815047 -396.851594) (xy 303.862333 -396.859047) (xy 303.907877 -396.873786)
			(xy 303.950565 -396.895448) (xy 303.989351 -396.923504) (xy 304.023286 -396.957267) (xy 304.051539 -396.99591)
			(xy 304.062892 -397.016986) (xy 304.0634 -397.018002) (xy 304.143706 -397.15694) (xy 304.6857 -397.15694)
			(xy 304.6857 -397.156432) (xy 304.686168 -397.132439) (xy 304.69367 -397.085044) (xy 304.708495 -397.039406)
			(xy 304.730277 -396.99665) (xy 304.75848 -396.957827) (xy 304.792409 -396.923895) (xy 304.831229 -396.895689)
			(xy 304.873984 -396.873904) (xy 304.919621 -396.859076) (xy 304.967015 -396.85157) (xy 304.991008 -396.851124)
			(xy 305.014943 -396.851597) (xy 305.062229 -396.85905) (xy 305.107773 -396.873788) (xy 305.150461 -396.89545)
			(xy 305.189247 -396.923505) (xy 305.223182 -396.957268) (xy 305.251435 -396.99591) (xy 305.262788 -397.016986)
			(xy 305.263296 -397.018002) (xy 305.343602 -397.15694) (xy 305.885596 -397.15694) (xy 305.885596 -397.156432)
			(xy 305.886068 -397.13244) (xy 305.89357 -397.085045) (xy 305.908394 -397.039407) (xy 305.930176 -396.996651)
			(xy 305.958378 -396.957829) (xy 305.992307 -396.923897) (xy 306.031127 -396.895691) (xy 306.073881 -396.873905)
			(xy 306.119517 -396.859076) (xy 306.166912 -396.85157) (xy 306.190904 -396.851124) (xy 306.214839 -396.8516)
			(xy 306.262124 -396.859053) (xy 306.307668 -396.87379) (xy 306.350356 -396.895451) (xy 306.389142 -396.923506)
			(xy 306.423077 -396.957268) (xy 306.451331 -396.99591) (xy 306.462684 -397.016986) (xy 306.463192 -397.018002)
			(xy 306.543498 -397.15694) (xy 307.085492 -397.15694) (xy 307.085492 -397.156432) (xy 307.085969 -397.132427)
			(xy 307.093478 -397.085008) (xy 307.108318 -397.039349) (xy 307.130122 -396.996576) (xy 307.158352 -396.957743)
			(xy 307.192312 -396.923807) (xy 307.231166 -396.895605) (xy 307.273955 -396.873833) (xy 307.319624 -396.859027)
			(xy 307.367049 -396.851551) (xy 307.391054 -396.851124) (xy 307.41499 -396.85156) (xy 307.462278 -396.85902)
			(xy 307.507823 -396.873764) (xy 307.550511 -396.895432) (xy 307.589296 -396.923493) (xy 307.62323 -396.957261)
			(xy 307.651481 -396.995908) (xy 307.662834 -397.016986) (xy 307.663342 -397.018002) (xy 307.743648 -397.15694)
			(xy 308.285388 -397.15694) (xy 308.285388 -397.156432) (xy 308.285869 -397.132427) (xy 308.293378 -397.085009)
			(xy 308.308218 -397.03935) (xy 308.330021 -396.996577) (xy 308.35825 -396.957744) (xy 308.39221 -396.923809)
			(xy 308.431063 -396.895607) (xy 308.473852 -396.873834) (xy 308.519521 -396.859027) (xy 308.566945 -396.851552)
			(xy 308.59095 -396.851124) (xy 308.614886 -396.851563) (xy 308.662173 -396.859022) (xy 308.707718 -396.873766)
			(xy 308.750406 -396.895434) (xy 308.789192 -396.923494) (xy 308.823126 -396.957262) (xy 308.851377 -396.995908)
			(xy 308.86273 -397.016986) (xy 308.863238 -397.018002) (xy 308.943544 -397.15694) (xy 309.485792 -397.15694)
			(xy 309.485792 -397.156432) (xy 309.486268 -397.13244) (xy 309.49377 -397.085045) (xy 309.508594 -397.039408)
			(xy 309.530375 -396.996652) (xy 309.558577 -396.95783) (xy 309.592506 -396.923898) (xy 309.631325 -396.895692)
			(xy 309.674079 -396.873906) (xy 309.719714 -396.859077) (xy 309.767108 -396.85157) (xy 309.7911 -396.851124)
			(xy 309.815035 -396.851603) (xy 309.86232 -396.859055) (xy 309.907864 -396.873792) (xy 309.950552 -396.895453)
			(xy 309.989338 -396.923507) (xy 310.023273 -396.957269) (xy 310.051526 -396.995911) (xy 310.06288 -397.016986)
			(xy 310.063388 -397.018002) (xy 310.143694 -397.15694) (xy 310.685688 -397.15694) (xy 310.685688 -397.156432)
			(xy 310.686168 -397.13244) (xy 310.69367 -397.085046) (xy 310.708493 -397.039409) (xy 310.730274 -396.996653)
			(xy 310.758476 -396.957831) (xy 310.792404 -396.9239) (xy 310.831223 -396.895693) (xy 310.873976 -396.873907)
			(xy 310.919611 -396.859078) (xy 310.967004 -396.851571) (xy 310.990996 -396.851124) (xy 311.014933 -396.851526)
			(xy 311.062223 -396.858992) (xy 311.107768 -396.873742) (xy 311.150456 -396.895416) (xy 311.189241 -396.923483)
			(xy 311.223174 -396.957255) (xy 311.251424 -396.995906) (xy 311.262776 -397.016986) (xy 311.263284 -397.018002)
			(xy 311.34359 -397.15694) (xy 311.885584 -397.15694) (xy 311.885584 -397.156432) (xy 311.886068 -397.13244)
			(xy 311.893569 -397.085046) (xy 311.908393 -397.03941) (xy 311.930174 -396.996654) (xy 311.958375 -396.957833)
			(xy 311.992302 -396.923901) (xy 312.03112 -396.895695) (xy 312.073873 -396.873908) (xy 312.119508 -396.859079)
			(xy 312.1669 -396.851571) (xy 312.190892 -396.851124) (xy 312.214829 -396.851529) (xy 312.262118 -396.858995)
			(xy 312.307664 -396.873745) (xy 312.350352 -396.895418) (xy 312.389137 -396.923484) (xy 312.42307 -396.957256)
			(xy 312.45132 -396.995906) (xy 312.462672 -397.016986) (xy 312.46318 -397.018002) (xy 312.543486 -397.15694)
			(xy 313.08548 -397.15694) (xy 313.08548 -397.156432) (xy 313.085969 -397.132428) (xy 313.093478 -397.08501)
			(xy 313.108317 -397.039352) (xy 313.130119 -396.99658) (xy 313.158348 -396.957747) (xy 313.192307 -396.923811)
			(xy 313.231159 -396.89561) (xy 313.273946 -396.873836) (xy 313.319614 -396.859029) (xy 313.367037 -396.851552)
			(xy 313.391042 -396.851124) (xy 313.414978 -396.851569) (xy 313.462265 -396.859028) (xy 313.50781 -396.87377)
			(xy 313.550497 -396.895437) (xy 313.589283 -396.923496) (xy 313.623217 -396.957263) (xy 313.651469 -396.995909)
			(xy 313.662822 -397.016986) (xy 313.66333 -397.018002) (xy 313.743636 -397.15694) (xy 314.285376 -397.15694)
			(xy 314.285376 -397.156432) (xy 314.285869 -397.132428) (xy 314.293378 -397.085011) (xy 314.308217 -397.039353)
			(xy 314.330019 -396.996581) (xy 314.358247 -396.957748) (xy 314.392205 -396.923813) (xy 314.431057 -396.895611)
			(xy 314.473844 -396.873838) (xy 314.519511 -396.85903) (xy 314.566934 -396.851552) (xy 314.590938 -396.851124)
			(xy 314.614874 -396.851573) (xy 314.662161 -396.85903) (xy 314.707705 -396.873772) (xy 314.750393 -396.895438)
			(xy 314.789179 -396.923498) (xy 314.823113 -396.957263) (xy 314.851365 -396.995909) (xy 314.862718 -397.016986)
			(xy 314.863226 -397.018002) (xy 314.943532 -397.15694) (xy 315.48578 -397.15694) (xy 315.48578 -397.156432)
			(xy 315.486268 -397.13244) (xy 315.493769 -397.085047) (xy 315.508593 -397.039411) (xy 315.530373 -396.996656)
			(xy 315.558574 -396.957834) (xy 315.592501 -396.923902) (xy 315.631318 -396.895696) (xy 315.67407 -396.87391)
			(xy 315.719704 -396.85908) (xy 315.767096 -396.851571) (xy 315.791088 -396.851124) (xy 315.815025 -396.851532)
			(xy 315.862314 -396.858997) (xy 315.90786 -396.873747) (xy 315.950547 -396.895419) (xy 315.989333 -396.923485)
			(xy 316.023266 -396.957256) (xy 316.051516 -396.995907) (xy 316.062868 -397.016986) (xy 316.063376 -397.018002)
			(xy 316.143682 -397.15694) (xy 316.685676 -397.15694) (xy 316.685676 -397.156432) (xy 316.686168 -397.132441)
			(xy 316.693669 -397.085048) (xy 316.708492 -397.039412) (xy 316.730272 -396.996657) (xy 316.758473 -396.957836)
			(xy 316.792399 -396.923904) (xy 316.831216 -396.895697) (xy 316.873967 -396.873911) (xy 316.919601 -396.85908)
			(xy 316.966993 -396.851571) (xy 316.990984 -396.851124) (xy 317.014921 -396.851535) (xy 317.06221 -396.859)
			(xy 317.107755 -396.873749) (xy 317.150443 -396.895421) (xy 317.189228 -396.923486) (xy 317.223161 -396.957257)
			(xy 317.251412 -396.995907) (xy 317.262764 -397.016986) (xy 317.263272 -397.018002) (xy 317.343578 -397.15694)
			(xy 317.885572 -397.15694) (xy 317.885572 -397.156432) (xy 317.886068 -397.132441) (xy 317.893569 -397.085048)
			(xy 317.908392 -397.039413) (xy 317.930172 -396.996658) (xy 317.958371 -396.957837) (xy 317.992297 -396.923905)
			(xy 318.031114 -396.895699) (xy 318.073865 -396.873912) (xy 318.119498 -396.859081) (xy 318.166889 -396.851572)
			(xy 318.19088 -396.851124) (xy 318.214817 -396.851539) (xy 318.262105 -396.859002) (xy 318.307651 -396.873751)
			(xy 318.350339 -396.895422) (xy 318.389124 -396.923487) (xy 318.423057 -396.957257) (xy 318.451308 -396.995907)
			(xy 318.46266 -397.016986) (xy 318.463168 -397.018002) (xy 318.543474 -397.15694) (xy 319.085468 -397.15694)
			(xy 319.085468 -397.156432) (xy 319.085969 -397.132428) (xy 319.093478 -397.085012) (xy 319.108316 -397.039355)
			(xy 319.130117 -396.996583) (xy 319.158345 -396.957751) (xy 319.192302 -396.923816) (xy 319.231152 -396.895614)
			(xy 319.273938 -396.87384) (xy 319.319605 -396.859031) (xy 319.367026 -396.851553) (xy 319.39103 -396.851124)
			(xy 319.414965 -396.851579) (xy 319.462252 -396.859035) (xy 319.507797 -396.873776) (xy 319.550484 -396.895441)
			(xy 319.58927 -396.9235) (xy 319.623205 -396.957264) (xy 319.651457 -396.995909) (xy 319.66281 -397.016986)
			(xy 319.663318 -397.018002) (xy 319.743624 -397.15694) (xy 320.285364 -397.15694) (xy 320.285364 -397.156432)
			(xy 320.285869 -397.132428) (xy 320.293378 -397.085012) (xy 320.308215 -397.039356) (xy 320.330017 -396.996584)
			(xy 320.358243 -396.957753) (xy 320.3922 -396.923817) (xy 320.43105 -396.895615) (xy 320.473835 -396.873841)
			(xy 320.519501 -396.859032) (xy 320.566922 -396.851553) (xy 320.590926 -396.851124) (xy 320.614861 -396.851582)
			(xy 320.662148 -396.859038) (xy 320.707692 -396.873778) (xy 320.75038 -396.895443) (xy 320.789166 -396.923501)
			(xy 320.823101 -396.957265) (xy 320.851353 -396.995909) (xy 320.862706 -397.016986) (xy 320.863214 -397.018002)
			(xy 320.94352 -397.15694) (xy 321.485768 -397.15694) (xy 321.485768 -397.156432) (xy 321.486268 -397.132441)
			(xy 321.493769 -397.085049) (xy 321.508592 -397.039414) (xy 321.530371 -396.996659) (xy 321.55857 -396.957838)
			(xy 321.592496 -396.923907) (xy 321.631311 -396.8957) (xy 321.674062 -396.873913) (xy 321.719694 -396.859082)
			(xy 321.767085 -396.851572) (xy 321.791076 -396.851124) (xy 321.815013 -396.851542) (xy 321.862301 -396.859005)
			(xy 321.907847 -396.873753) (xy 321.950534 -396.895424) (xy 321.98932 -396.923488) (xy 322.023253 -396.957258)
			(xy 322.051504 -396.995907) (xy 322.062856 -397.016986) (xy 322.063364 -397.018002) (xy 322.129999 -397.133287)
			(xy 336.013603 -397.133287) (xy 336.020935 -397.085732) (xy 336.035629 -397.039915) (xy 336.057324 -396.996967)
			(xy 336.085482 -396.95795) (xy 336.119407 -396.923829) (xy 336.15826 -396.895446) (xy 336.201082 -396.873504)
			(xy 336.246814 -396.858545) (xy 336.294325 -396.850939) (xy 336.342442 -396.850873) (xy 336.389974 -396.85835)
			(xy 336.435746 -396.873184) (xy 336.478628 -396.895009) (xy 336.517559 -396.923285) (xy 336.551577 -396.957314)
			(xy 336.579841 -396.996254) (xy 336.591148 -397.017494) (xy 336.591656 -397.018764) (xy 336.657839 -397.133287)
			(xy 337.213506 -397.133287) (xy 337.220838 -397.085733) (xy 337.235533 -397.039916) (xy 337.257227 -396.996969)
			(xy 337.285384 -396.957952) (xy 337.319309 -396.923831) (xy 337.358162 -396.895449) (xy 337.400983 -396.873508)
			(xy 337.446714 -396.858549) (xy 337.494225 -396.850942) (xy 337.54234 -396.850877) (xy 337.589872 -396.858353)
			(xy 337.635644 -396.873187) (xy 337.678525 -396.895011) (xy 337.717455 -396.923287) (xy 337.751473 -396.957315)
			(xy 337.779737 -396.996254) (xy 337.791044 -397.017494) (xy 337.791552 -397.018764) (xy 337.857735 -397.133286)
			(xy 338.41341 -397.133286) (xy 338.420742 -397.085733) (xy 338.435436 -397.039917) (xy 338.45713 -396.996971)
			(xy 338.485287 -396.957955) (xy 338.519211 -396.923834) (xy 338.558063 -396.895453) (xy 338.600884 -396.873511)
			(xy 338.646615 -396.858552) (xy 338.694124 -396.850946) (xy 338.742239 -396.85088) (xy 338.78977 -396.858356)
			(xy 338.835541 -396.87319) (xy 338.878422 -396.895014) (xy 338.917352 -396.923289) (xy 338.951369 -396.957316)
			(xy 338.979633 -396.996254) (xy 338.99094 -397.017494) (xy 338.991448 -397.018764) (xy 339.057629 -397.133284)
			(xy 339.613655 -397.133284) (xy 339.620986 -397.08574) (xy 339.635678 -397.039932) (xy 339.657368 -396.996993)
			(xy 339.68552 -396.957985) (xy 339.719438 -396.92387) (xy 339.758283 -396.895493) (xy 339.801095 -396.873555)
			(xy 339.846817 -396.858598) (xy 339.894318 -396.850991) (xy 339.942424 -396.850924) (xy 339.989947 -396.858397)
			(xy 340.03571 -396.873225) (xy 340.078584 -396.895043) (xy 340.117509 -396.923311) (xy 340.151522 -396.95733)
			(xy 340.179784 -396.996259) (xy 340.19109 -397.017494) (xy 340.191598 -397.018764) (xy 340.257779 -397.133284)
			(xy 340.813558 -397.133284) (xy 340.82089 -397.08574) (xy 340.835582 -397.039933) (xy 340.857271 -396.996995)
			(xy 340.885423 -396.957987) (xy 340.91934 -396.923873) (xy 340.958184 -396.895496) (xy 341.000996 -396.873558)
			(xy 341.046717 -396.858601) (xy 341.094218 -396.850995) (xy 341.142323 -396.850927) (xy 341.189845 -396.8584)
			(xy 341.235608 -396.873228) (xy 341.278481 -396.895045) (xy 341.317406 -396.923312) (xy 341.351419 -396.957331)
			(xy 341.37968 -396.996259) (xy 341.390986 -397.017494) (xy 341.391494 -397.018764) (xy 341.457677 -397.133286)
			(xy 342.013613 -397.133286) (xy 342.020945 -397.085734) (xy 342.03564 -397.039918) (xy 342.057333 -396.996972)
			(xy 342.08549 -396.957957) (xy 342.119413 -396.923837) (xy 342.158265 -396.895456) (xy 342.201085 -396.873515)
			(xy 342.246815 -396.858556) (xy 342.294324 -396.85095) (xy 342.342438 -396.850884) (xy 342.389968 -396.858359)
			(xy 342.435739 -396.873192) (xy 342.478619 -396.895016) (xy 342.517549 -396.92329) (xy 342.551566 -396.957317)
			(xy 342.579829 -396.996255) (xy 342.591136 -397.017494) (xy 342.591644 -397.018764) (xy 342.657827 -397.133286)
			(xy 343.213517 -397.133286) (xy 343.220849 -397.085734) (xy 343.235543 -397.03992) (xy 343.257236 -396.996974)
			(xy 343.285392 -396.95796) (xy 343.319315 -396.92384) (xy 343.358166 -396.895459) (xy 343.400986 -396.873518)
			(xy 343.446715 -396.85856) (xy 343.494223 -396.850953) (xy 343.542337 -396.850887) (xy 343.589866 -396.858363)
			(xy 343.635636 -396.873195) (xy 343.678516 -396.895018) (xy 343.717445 -396.923292) (xy 343.751462 -396.957318)
			(xy 343.779725 -396.996255) (xy 343.791032 -397.017494) (xy 343.79154 -397.018764) (xy 343.857723 -397.133286)
			(xy 344.413421 -397.133286) (xy 344.420752 -397.085735) (xy 344.435446 -397.039921) (xy 344.457139 -396.996976)
			(xy 344.485295 -396.957962) (xy 344.519217 -396.923843) (xy 344.558068 -396.895462) (xy 344.600887 -396.873522)
			(xy 344.646615 -396.858563) (xy 344.694123 -396.850957) (xy 344.742236 -396.850891) (xy 344.789764 -396.858366)
			(xy 344.835534 -396.873198) (xy 344.878413 -396.895021) (xy 344.917342 -396.923294) (xy 344.951358 -396.957319)
			(xy 344.979621 -396.996256) (xy 344.990928 -397.017494) (xy 344.991436 -397.018764) (xy 345.057617 -397.133284)
			(xy 345.613665 -397.133284) (xy 345.620997 -397.085741) (xy 345.635688 -397.039936) (xy 345.657377 -396.996999)
			(xy 345.685528 -396.957992) (xy 345.719444 -396.923879) (xy 345.758287 -396.895503) (xy 345.801098 -396.873565)
			(xy 345.846818 -396.858609) (xy 345.894317 -396.851002) (xy 345.942421 -396.850934) (xy 345.989941 -396.858406)
			(xy 346.035703 -396.873234) (xy 346.078575 -396.89505) (xy 346.117499 -396.923316) (xy 346.151511 -396.957333)
			(xy 346.179772 -396.99626) (xy 346.191078 -397.017494) (xy 346.191586 -397.018764) (xy 346.284753 -397.179979)
			(xy 346.813611 -397.179979) (xy 346.813859 -397.129044) (xy 346.822553 -397.078855) (xy 346.83945 -397.030804)
			(xy 346.864083 -396.986221) (xy 346.89577 -396.946341) (xy 346.933633 -396.912269) (xy 346.976622 -396.884949)
			(xy 347.023547 -396.865138) (xy 347.073108 -396.853385) (xy 347.123932 -396.850014) (xy 347.174611 -396.85512)
			(xy 347.223742 -396.868562) (xy 347.269962 -396.889966) (xy 347.311992 -396.918739) (xy 347.348668 -396.954086)
			(xy 347.378973 -396.995025) (xy 347.390974 -397.017494) (xy 347.391482 -397.018764) (xy 347.457665 -397.133286)
			(xy 348.013624 -397.133286) (xy 348.020956 -397.085735) (xy 348.03565 -397.039922) (xy 348.057342 -396.996978)
			(xy 348.085497 -396.957964) (xy 348.119419 -396.923846) (xy 348.15827 -396.895466) (xy 348.201088 -396.873525)
			(xy 348.246815 -396.858567) (xy 348.294322 -396.850961) (xy 348.342434 -396.850894) (xy 348.389962 -396.858369)
			(xy 348.435731 -396.873201) (xy 348.47861 -396.895023) (xy 348.517538 -396.923296) (xy 348.551554 -396.95732)
			(xy 348.579817 -396.996256) (xy 348.591124 -397.017494) (xy 348.591632 -397.018764) (xy 348.657814 -397.133285)
			(xy 349.213528 -397.133285) (xy 349.220859 -397.085736) (xy 349.235553 -397.039923) (xy 349.257245 -396.99698)
			(xy 349.2854 -396.957967) (xy 349.319322 -396.923849) (xy 349.358171 -396.895469) (xy 349.400989 -396.873529)
			(xy 349.446716 -396.858571) (xy 349.494222 -396.850964) (xy 349.542333 -396.850898) (xy 349.58986 -396.858372)
			(xy 349.635629 -396.873204) (xy 349.678507 -396.895025) (xy 349.717435 -396.923297) (xy 349.751451 -396.957321)
			(xy 349.779713 -396.996256) (xy 349.79102 -397.017494) (xy 349.791528 -397.018764) (xy 349.85771 -397.133285)
			(xy 350.413431 -397.133285) (xy 350.420763 -397.085737) (xy 350.435456 -397.039924) (xy 350.457148 -396.996982)
			(xy 350.485303 -396.957969) (xy 350.519224 -396.923851) (xy 350.558073 -396.895472) (xy 350.60089 -396.873532)
			(xy 350.646616 -396.858574) (xy 350.694121 -396.850968) (xy 350.742232 -396.850901) (xy 350.789759 -396.858376)
			(xy 350.835526 -396.873207) (xy 350.878404 -396.895028) (xy 350.917331 -396.923299) (xy 350.951347 -396.957323)
			(xy 350.979609 -396.996257) (xy 350.990916 -397.017494) (xy 350.991424 -397.018764) (xy 351.084589 -397.179977)
			(xy 351.613718 -397.179977) (xy 351.613966 -397.129044) (xy 351.62266 -397.078857) (xy 351.639557 -397.030807)
			(xy 351.664189 -396.986225) (xy 351.695875 -396.946346) (xy 351.733736 -396.912275) (xy 351.776724 -396.884956)
			(xy 351.823648 -396.865145) (xy 351.873208 -396.853392) (xy 351.92403 -396.850021) (xy 351.974708 -396.855127)
			(xy 352.023837 -396.868568) (xy 352.070056 -396.88997) (xy 352.112086 -396.918743) (xy 352.14876 -396.954088)
			(xy 352.179065 -396.995026) (xy 352.191066 -397.017494) (xy 352.191574 -397.018764) (xy 352.284739 -397.179976)
			(xy 352.813621 -397.179976) (xy 352.81387 -397.129044) (xy 352.822563 -397.078857) (xy 352.83946 -397.030808)
			(xy 352.864092 -396.986227) (xy 352.895778 -396.946349) (xy 352.933638 -396.912278) (xy 352.976626 -396.88496)
			(xy 353.023549 -396.865149) (xy 353.073108 -396.853396) (xy 353.123929 -396.850025) (xy 353.174606 -396.85513)
			(xy 353.223735 -396.86857) (xy 353.269953 -396.889973) (xy 353.311982 -396.918745) (xy 353.348657 -396.954089)
			(xy 353.378961 -396.995027) (xy 353.390962 -397.017494) (xy 353.39147 -397.018764) (xy 353.457652 -397.133285)
			(xy 354.013635 -397.133285) (xy 354.020967 -397.085737) (xy 354.03566 -397.039926) (xy 354.057351 -396.996983)
			(xy 354.085505 -396.957971) (xy 354.119426 -396.923854) (xy 354.158274 -396.895475) (xy 354.20109 -396.873536)
			(xy 354.246816 -396.858578) (xy 354.294321 -396.850971) (xy 354.342431 -396.850905) (xy 354.389957 -396.858379)
			(xy 354.435724 -396.873209) (xy 354.478601 -396.89503) (xy 354.517528 -396.923301) (xy 354.551543 -396.957324)
			(xy 354.579805 -396.996257) (xy 354.591112 -397.017494) (xy 354.59162 -397.018764) (xy 354.657801 -397.133284)
			(xy 370.586149 -397.133284) (xy 370.593481 -397.085739) (xy 370.608173 -397.03993) (xy 370.629864 -396.996991)
			(xy 370.658016 -396.957981) (xy 370.691934 -396.923866) (xy 370.73078 -396.895488) (xy 370.773594 -396.87355)
			(xy 370.819317 -396.858592) (xy 370.866819 -396.850986) (xy 370.914926 -396.850918) (xy 370.962449 -396.858392)
			(xy 371.008214 -396.873221) (xy 371.051089 -396.895039) (xy 371.090014 -396.923308) (xy 371.124028 -396.957328)
			(xy 371.15229 -396.996259) (xy 371.163596 -397.017494) (xy 371.164104 -397.018764) (xy 371.230285 -397.133284)
			(xy 371.786053 -397.133284) (xy 371.793384 -397.08574) (xy 371.808077 -397.039932) (xy 371.829767 -396.996992)
			(xy 371.857919 -396.957983) (xy 371.891837 -396.923869) (xy 371.930682 -396.895491) (xy 371.973495 -396.873553)
			(xy 372.019217 -396.858596) (xy 372.066718 -396.850989) (xy 372.114825 -396.850922) (xy 372.162347 -396.858395)
			(xy 372.208111 -396.873224) (xy 372.250986 -396.895042) (xy 372.289911 -396.92331) (xy 372.323924 -396.957329)
			(xy 372.352186 -396.996259) (xy 372.363492 -397.017494) (xy 372.364 -397.018764) (xy 372.430181 -397.133284)
			(xy 372.985956 -397.133284) (xy 372.993288 -397.08574) (xy 373.00798 -397.039933) (xy 373.02967 -396.996994)
			(xy 373.057821 -396.957986) (xy 373.091739 -396.923872) (xy 373.130584 -396.895495) (xy 373.173396 -396.873557)
			(xy 373.219117 -396.858599) (xy 373.266618 -396.850993) (xy 373.314724 -396.850925) (xy 373.362246 -396.858398)
			(xy 373.408009 -396.873226) (xy 373.450883 -396.895044) (xy 373.489807 -396.923311) (xy 373.523821 -396.95733)
			(xy 373.552082 -396.996259) (xy 373.563388 -397.017494) (xy 373.563896 -397.018764) (xy 373.630079 -397.133286)
			(xy 374.186012 -397.133286) (xy 374.193344 -397.085734) (xy 374.208038 -397.039918) (xy 374.229732 -396.996971)
			(xy 374.257888 -396.957956) (xy 374.291812 -396.923836) (xy 374.330664 -396.895454) (xy 374.373485 -396.873513)
			(xy 374.419215 -396.858554) (xy 374.466724 -396.850948) (xy 374.514839 -396.850882) (xy 374.562369 -396.858358)
			(xy 374.60814 -396.873191) (xy 374.65102 -396.895015) (xy 374.68995 -396.92329) (xy 374.723968 -396.957317)
			(xy 374.752231 -396.996255) (xy 374.763538 -397.017494) (xy 374.764046 -397.018764) (xy 374.830229 -397.133286)
			(xy 375.385915 -397.133286) (xy 375.393247 -397.085734) (xy 375.407941 -397.039919) (xy 375.429635 -396.996973)
			(xy 375.457791 -396.957958) (xy 375.491714 -396.923839) (xy 375.530566 -396.895457) (xy 375.573385 -396.873516)
			(xy 375.619115 -396.858558) (xy 375.666624 -396.850952) (xy 375.714737 -396.850885) (xy 375.762267 -396.858361)
			(xy 375.808037 -396.873194) (xy 375.850917 -396.895017) (xy 375.889847 -396.923291) (xy 375.923864 -396.957318)
			(xy 375.952127 -396.996255) (xy 375.963434 -397.017494) (xy 375.963942 -397.018764) (xy 376.030123 -397.133284)
			(xy 376.58616 -397.133284) (xy 376.593491 -397.085741) (xy 376.608183 -397.039934) (xy 376.629873 -396.996996)
			(xy 376.658024 -396.957988) (xy 376.691941 -396.923874) (xy 376.730785 -396.895498) (xy 376.773597 -396.87356)
			(xy 376.819317 -396.858603) (xy 376.866817 -396.850997) (xy 376.914922 -396.850929) (xy 376.962444 -396.858401)
			(xy 377.008207 -396.873229) (xy 377.05108 -396.895046) (xy 377.090004 -396.923313) (xy 377.124017 -396.957331)
			(xy 377.152278 -396.99626) (xy 377.163584 -397.017494) (xy 377.164092 -397.018764) (xy 377.230273 -397.133284)
			(xy 377.786064 -397.133284) (xy 377.793395 -397.085741) (xy 377.808087 -397.039935) (xy 377.829776 -396.996998)
			(xy 377.857927 -396.957991) (xy 377.891843 -396.923877) (xy 377.930687 -396.895501) (xy 377.973498 -396.873564)
			(xy 378.019218 -396.858607) (xy 378.066717 -396.851) (xy 378.114821 -396.850932) (xy 378.162342 -396.858405)
			(xy 378.208104 -396.873232) (xy 378.250977 -396.895049) (xy 378.2899 -396.923315) (xy 378.323913 -396.957332)
			(xy 378.352174 -396.99626) (xy 378.36348 -397.017494) (xy 378.363988 -397.018764) (xy 378.430169 -397.133284)
			(xy 378.985967 -397.133284) (xy 378.993298 -397.085742) (xy 379.00799 -397.039936) (xy 379.029679 -396.997)
			(xy 379.057829 -396.957993) (xy 379.091745 -396.92388) (xy 379.130588 -396.895504) (xy 379.173398 -396.873567)
			(xy 379.219118 -396.85861) (xy 379.266616 -396.851004) (xy 379.31472 -396.850936) (xy 379.36224 -396.858408)
			(xy 379.408002 -396.873235) (xy 379.450874 -396.895051) (xy 379.489797 -396.923317) (xy 379.523809 -396.957333)
			(xy 379.55207 -396.99626) (xy 379.563376 -397.017494) (xy 379.563884 -397.018764) (xy 379.630067 -397.133286)
			(xy 380.186022 -397.133286) (xy 380.193354 -397.085735) (xy 380.208048 -397.039921) (xy 380.229741 -396.996977)
			(xy 380.257896 -396.957963) (xy 380.291818 -396.923844) (xy 380.330669 -396.895464) (xy 380.373487 -396.873523)
			(xy 380.419215 -396.858565) (xy 380.466723 -396.850959) (xy 380.514835 -396.850892) (xy 380.562363 -396.858368)
			(xy 380.608132 -396.8732) (xy 380.651011 -396.895022) (xy 380.68994 -396.923295) (xy 380.723956 -396.95732)
			(xy 380.752219 -396.996256) (xy 380.763526 -397.017494) (xy 380.764034 -397.018764) (xy 380.830217 -397.133286)
			(xy 381.385926 -397.133286) (xy 381.393258 -397.085736) (xy 381.407951 -397.039923) (xy 381.429644 -396.996979)
			(xy 381.457799 -396.957966) (xy 381.49172 -396.923847) (xy 381.53057 -396.895467) (xy 381.573388 -396.873527)
			(xy 381.619116 -396.858569) (xy 381.666622 -396.850962) (xy 381.714734 -396.850896) (xy 381.762261 -396.858371)
			(xy 381.80803 -396.873202) (xy 381.850908 -396.895024) (xy 381.889837 -396.923297) (xy 381.923853 -396.957321)
			(xy 381.952115 -396.996256) (xy 381.963422 -397.017494) (xy 381.96393 -397.018764) (xy 382.057097 -397.179979)
			(xy 382.586212 -397.179979) (xy 382.586461 -397.129044) (xy 382.595154 -397.078856) (xy 382.612052 -397.030805)
			(xy 382.636685 -396.986222) (xy 382.668371 -396.946342) (xy 382.706233 -396.912271) (xy 382.749222 -396.884951)
			(xy 382.796147 -396.86514) (xy 382.845708 -396.853387) (xy 382.896532 -396.850016) (xy 382.947211 -396.855122)
			(xy 382.996341 -396.868563) (xy 383.042561 -396.889967) (xy 383.084591 -396.91874) (xy 383.121266 -396.954086)
			(xy 383.151571 -396.995026) (xy 383.163572 -397.017494) (xy 383.16408 -397.018764) (xy 383.257246 -397.179978)
			(xy 383.786116 -397.179978) (xy 383.786365 -397.129044) (xy 383.795058 -397.078856) (xy 383.811955 -397.030806)
			(xy 383.836588 -396.986224) (xy 383.868274 -396.946345) (xy 383.906135 -396.912274) (xy 383.949124 -396.884955)
			(xy 383.996048 -396.865144) (xy 384.045608 -396.85339) (xy 384.096431 -396.85002) (xy 384.147109 -396.855125)
			(xy 384.196238 -396.868566) (xy 384.242458 -396.889969) (xy 384.284487 -396.918742) (xy 384.321162 -396.954087)
			(xy 384.351467 -396.995026) (xy 384.363468 -397.017494) (xy 384.363976 -397.018764) (xy 384.457141 -397.179977)
			(xy 384.986019 -397.179977) (xy 384.986268 -397.129044) (xy 384.994961 -397.078857) (xy 385.011858 -397.030807)
			(xy 385.036491 -396.986226) (xy 385.068176 -396.946348) (xy 385.106037 -396.912277) (xy 385.149025 -396.884958)
			(xy 385.195948 -396.865147) (xy 385.245508 -396.853394) (xy 385.29633 -396.850023) (xy 385.347007 -396.855129)
			(xy 385.396136 -396.868569) (xy 385.442355 -396.889972) (xy 385.484384 -396.918744) (xy 385.521058 -396.954088)
			(xy 385.551363 -396.995026) (xy 385.563364 -397.017494) (xy 385.563872 -397.018764) (xy 385.630054 -397.133285)
			(xy 386.186033 -397.133285) (xy 386.193365 -397.085737) (xy 386.208058 -397.039925) (xy 386.22975 -396.996982)
			(xy 386.257904 -396.95797) (xy 386.291825 -396.923853) (xy 386.330673 -396.895474) (xy 386.37349 -396.873534)
			(xy 386.419216 -396.858576) (xy 386.466721 -396.85097) (xy 386.514831 -396.850903) (xy 386.562358 -396.858377)
			(xy 386.608125 -396.873208) (xy 386.651002 -396.895029) (xy 386.68993 -396.9233) (xy 386.723945 -396.957323)
			(xy 386.752207 -396.996257) (xy 386.763514 -397.017494) (xy 386.764022 -397.018764) (xy 386.830204 -397.133285)
			(xy 387.385937 -397.133285) (xy 387.393268 -397.085737) (xy 387.407961 -397.039926) (xy 387.429653 -396.996984)
			(xy 387.457807 -396.957973) (xy 387.491727 -396.923856) (xy 387.530575 -396.895477) (xy 387.573391 -396.873537)
			(xy 387.619116 -396.85858) (xy 387.666621 -396.850973) (xy 387.71473 -396.850906) (xy 387.762256 -396.85838)
			(xy 387.808023 -396.873211) (xy 387.850899 -396.895031) (xy 387.889826 -396.923302) (xy 387.923841 -396.957324)
			(xy 387.952103 -396.996257) (xy 387.96341 -397.017494) (xy 387.963918 -397.018764) (xy 388.057083 -397.179976)
			(xy 388.586223 -397.179976) (xy 388.586472 -397.129043) (xy 388.595165 -397.078858) (xy 388.612062 -397.030809)
			(xy 388.636694 -396.986228) (xy 388.668379 -396.94635) (xy 388.706239 -396.91228) (xy 388.749226 -396.884961)
			(xy 388.796149 -396.865151) (xy 388.845707 -396.853397) (xy 388.896529 -396.850027) (xy 388.947206 -396.855132)
			(xy 388.996334 -396.868572) (xy 389.042552 -396.889974) (xy 389.08458 -396.918746) (xy 389.121255 -396.95409)
			(xy 389.151559 -396.995027) (xy 389.16356 -397.017494) (xy 389.164068 -397.018764) (xy 389.24392 -397.15694)
			(xy 403.113748 -397.15694) (xy 403.113748 -397.156432) (xy 403.114292 -397.132444) (xy 403.121792 -397.085057)
			(xy 403.136612 -397.039428) (xy 403.158388 -396.996678) (xy 403.186583 -396.957861) (xy 403.220503 -396.923933)
			(xy 403.259313 -396.895728) (xy 403.302057 -396.873941) (xy 403.347683 -396.85911) (xy 403.395068 -396.851598)
			(xy 403.419056 -396.851124) (xy 403.442992 -396.851558) (xy 403.49028 -396.859018) (xy 403.535825 -396.873763)
			(xy 403.578513 -396.895431) (xy 403.617298 -396.923493) (xy 403.651232 -396.957261) (xy 403.679483 -396.995908)
			(xy 403.690836 -397.016986) (xy 403.691344 -397.018002) (xy 403.77165 -397.15694) (xy 404.313644 -397.15694)
			(xy 404.313644 -397.156432) (xy 404.314192 -397.132444) (xy 404.321692 -397.085058) (xy 404.336512 -397.039429)
			(xy 404.358287 -396.996679) (xy 404.386482 -396.957862) (xy 404.420401 -396.923934) (xy 404.459211 -396.895729)
			(xy 404.501955 -396.873943) (xy 404.54758 -396.859111) (xy 404.594964 -396.851598) (xy 404.618952 -396.851124)
			(xy 404.642888 -396.851561) (xy 404.690176 -396.859021) (xy 404.735721 -396.873765) (xy 404.778408 -396.895433)
			(xy 404.817194 -396.923494) (xy 404.851128 -396.957261) (xy 404.879379 -396.995908) (xy 404.890732 -397.016986)
			(xy 404.89124 -397.018002) (xy 404.971546 -397.15694) (xy 405.51354 -397.15694) (xy 405.51354 -397.156432)
			(xy 405.513968 -397.132437) (xy 405.521471 -397.085038) (xy 405.536298 -397.039397) (xy 405.558084 -396.996638)
			(xy 405.586291 -396.957814) (xy 405.620226 -396.923881) (xy 405.659051 -396.895676) (xy 405.701812 -396.873892)
			(xy 405.747454 -396.859068) (xy 405.794853 -396.851567) (xy 405.818848 -396.851124) (xy 405.842784 -396.851565)
			(xy 405.890071 -396.859024) (xy 405.935616 -396.873767) (xy 405.978304 -396.895434) (xy 406.01709 -396.923495)
			(xy 406.051024 -396.957262) (xy 406.079275 -396.995908) (xy 406.090628 -397.016986) (xy 406.091136 -397.018002)
			(xy 406.171442 -397.15694) (xy 406.713436 -397.15694) (xy 406.713436 -397.156432) (xy 406.713869 -397.132425)
			(xy 406.72138 -397.085002) (xy 406.736222 -397.039339) (xy 406.75803 -396.996563) (xy 406.786264 -396.957728)
			(xy 406.82023 -396.923791) (xy 406.85909 -396.89559) (xy 406.901885 -396.87382) (xy 406.947561 -396.859018)
			(xy 406.99499 -396.851548) (xy 407.018998 -396.851124) (xy 407.042935 -396.851524) (xy 407.090225 -396.858991)
			(xy 407.135771 -396.873741) (xy 407.178458 -396.895415) (xy 407.217243 -396.923482) (xy 407.251176 -396.957255)
			(xy 407.279426 -396.995906) (xy 407.290778 -397.016986) (xy 407.291286 -397.018002) (xy 407.371592 -397.15694)
			(xy 407.913332 -397.15694) (xy 407.913332 -397.156432) (xy 407.913769 -397.132425) (xy 407.92128 -397.085002)
			(xy 407.936122 -397.03934) (xy 407.957929 -396.996564) (xy 407.986163 -396.957729) (xy 408.020129 -396.923793)
			(xy 408.058988 -396.895592) (xy 408.101783 -396.873822) (xy 408.147458 -396.859019) (xy 408.194887 -396.851548)
			(xy 408.218894 -396.851124) (xy 408.242831 -396.851527) (xy 408.29012 -396.858993) (xy 408.335666 -396.873744)
			(xy 408.378354 -396.895417) (xy 408.417139 -396.923483) (xy 408.451072 -396.957255) (xy 408.479322 -396.995906)
			(xy 408.490674 -397.016986) (xy 408.491182 -397.018002) (xy 408.571488 -397.15694) (xy 409.113736 -397.15694)
			(xy 409.113736 -397.156432) (xy 409.114168 -397.132438) (xy 409.121671 -397.085039) (xy 409.136498 -397.039398)
			(xy 409.158283 -396.996639) (xy 409.18649 -396.957815) (xy 409.220424 -396.923882) (xy 409.259249 -396.895677)
			(xy 409.302009 -396.873893) (xy 409.347651 -396.859068) (xy 409.39505 -396.851567) (xy 409.419044 -396.851124)
			(xy 409.44298 -396.851568) (xy 409.490267 -396.859026) (xy 409.535812 -396.873769) (xy 409.5785 -396.895436)
			(xy 409.617285 -396.923496) (xy 409.651219 -396.957262) (xy 409.679471 -396.995909) (xy 409.690824 -397.016986)
			(xy 409.691332 -397.018002) (xy 409.771638 -397.15694) (xy 410.313632 -397.15694) (xy 410.313632 -397.156432)
			(xy 410.314068 -397.132438) (xy 410.321571 -397.085039) (xy 410.336398 -397.039399) (xy 410.358183 -396.99664)
			(xy 410.386389 -396.957816) (xy 410.420322 -396.923884) (xy 410.459147 -396.895678) (xy 410.501906 -396.873895)
			(xy 410.547547 -396.859069) (xy 410.594946 -396.851567) (xy 410.61894 -396.851124) (xy 410.642876 -396.851571)
			(xy 410.690163 -396.859029) (xy 410.735708 -396.873771) (xy 410.778395 -396.895437) (xy 410.817181 -396.923497)
			(xy 410.851115 -396.957263) (xy 410.879367 -396.995909) (xy 410.89072 -397.016986) (xy 410.891228 -397.018002)
			(xy 410.971534 -397.15694) (xy 411.513528 -397.15694) (xy 411.513528 -397.156432) (xy 411.513968 -397.132438)
			(xy 411.521471 -397.08504) (xy 411.536297 -397.0394) (xy 411.558082 -396.996641) (xy 411.586288 -396.957818)
			(xy 411.620221 -396.923885) (xy 411.659045 -396.89568) (xy 411.701804 -396.873896) (xy 411.747444 -396.85907)
			(xy 411.794842 -396.851568) (xy 411.818836 -396.851124) (xy 411.842772 -396.851574) (xy 411.890058 -396.859031)
			(xy 411.935603 -396.873773) (xy 411.978291 -396.895439) (xy 412.017077 -396.923498) (xy 412.051011 -396.957264)
			(xy 412.079263 -396.995909) (xy 412.090616 -397.016986) (xy 412.091124 -397.018002) (xy 412.17143 -397.15694)
			(xy 412.713424 -397.15694) (xy 412.713424 -397.156432) (xy 412.713869 -397.132425) (xy 412.72138 -397.085004)
			(xy 412.736221 -397.039342) (xy 412.758027 -396.996567) (xy 412.786261 -396.957732) (xy 412.820225 -396.923796)
			(xy 412.859083 -396.895595) (xy 412.901877 -396.873824) (xy 412.947551 -396.85902) (xy 412.994979 -396.851549)
			(xy 413.018986 -396.851124) (xy 413.042923 -396.851534) (xy 413.090212 -396.858998) (xy 413.135757 -396.873748)
			(xy 413.178445 -396.89542) (xy 413.21723 -396.923485) (xy 413.251164 -396.957256) (xy 413.279414 -396.995907)
			(xy 413.290766 -397.016986) (xy 413.291274 -397.018002) (xy 413.37158 -397.15694) (xy 413.91332 -397.15694)
			(xy 413.91332 -397.156432) (xy 413.913769 -397.132426) (xy 413.921279 -397.085004) (xy 413.936121 -397.039343)
			(xy 413.957927 -396.996568) (xy 413.98616 -396.957733) (xy 414.020124 -396.923797) (xy 414.058981 -396.895596)
			(xy 414.101774 -396.873825) (xy 414.147448 -396.859021) (xy 414.194875 -396.851549) (xy 414.218882 -396.851124)
			(xy 414.242819 -396.851537) (xy 414.290108 -396.859001) (xy 414.335653 -396.87375) (xy 414.378341 -396.895422)
			(xy 414.417126 -396.923486) (xy 414.451059 -396.957257) (xy 414.47931 -396.995907) (xy 414.490662 -397.016986)
			(xy 414.49117 -397.018002) (xy 414.571476 -397.15694) (xy 415.113724 -397.15694) (xy 415.113724 -397.156432)
			(xy 415.114168 -397.132438) (xy 415.121671 -397.085041) (xy 415.136497 -397.039401) (xy 415.158281 -396.996643)
			(xy 415.186487 -396.957819) (xy 415.220419 -396.923887) (xy 415.259243 -396.895681) (xy 415.302001 -396.873897)
			(xy 415.347641 -396.859071) (xy 415.395038 -396.851568) (xy 415.419032 -396.851124) (xy 415.442968 -396.851578)
			(xy 415.490254 -396.859034) (xy 415.535799 -396.873775) (xy 415.578487 -396.89544) (xy 415.617272 -396.923499)
			(xy 415.651207 -396.957264) (xy 415.679459 -396.995909) (xy 415.690812 -397.016986) (xy 415.69132 -397.018002)
			(xy 415.771626 -397.15694) (xy 416.31362 -397.15694) (xy 416.31362 -397.156432) (xy 416.314068 -397.132438)
			(xy 416.321571 -397.085041) (xy 416.336397 -397.039402) (xy 416.35818 -396.996644) (xy 416.386386 -396.95782)
			(xy 416.420317 -396.923888) (xy 416.45914 -396.895682) (xy 416.501898 -396.873898) (xy 416.547537 -396.859072)
			(xy 416.594934 -396.851568) (xy 416.618928 -396.851124) (xy 416.642863 -396.851581) (xy 416.69015 -396.859037)
			(xy 416.735695 -396.873777) (xy 416.778382 -396.895442) (xy 416.817168 -396.9235) (xy 416.851103 -396.957265)
			(xy 416.879355 -396.995909) (xy 416.890708 -397.016986) (xy 416.891216 -397.018002) (xy 416.971522 -397.15694)
			(xy 417.513516 -397.15694) (xy 417.513516 -397.156432) (xy 417.513968 -397.132439) (xy 417.521471 -397.085042)
			(xy 417.536296 -397.039403) (xy 417.55808 -396.996645) (xy 417.586284 -396.957822) (xy 417.620216 -396.92389)
			(xy 417.659038 -396.895684) (xy 417.701795 -396.873899) (xy 417.747434 -396.859072) (xy 417.794831 -396.851568)
			(xy 417.818824 -396.851124) (xy 417.842759 -396.851584) (xy 417.890046 -396.859039) (xy 417.93559 -396.873779)
			(xy 417.978278 -396.895444) (xy 418.017064 -396.923501) (xy 418.050998 -396.957265) (xy 418.079251 -396.99591)
			(xy 418.090604 -397.016986) (xy 418.091112 -397.018002) (xy 418.171418 -397.15694) (xy 418.713412 -397.15694)
			(xy 418.713412 -397.156432) (xy 418.713869 -397.132426) (xy 418.721379 -397.085005) (xy 418.73622 -397.039345)
			(xy 418.758025 -396.99657) (xy 418.786257 -396.957736) (xy 418.82022 -396.9238) (xy 418.859077 -396.895599)
			(xy 418.901869 -396.873827) (xy 418.947541 -396.859023) (xy 418.994968 -396.85155) (xy 419.018974 -396.851124)
			(xy 419.042911 -396.851543) (xy 419.090199 -396.859006) (xy 419.135744 -396.873754) (xy 419.178432 -396.895425)
			(xy 419.217218 -396.923488) (xy 419.251151 -396.957258) (xy 419.279402 -396.995907) (xy 419.290754 -397.016986)
			(xy 419.291262 -397.018002) (xy 419.371568 -397.15694) (xy 419.913308 -397.15694) (xy 419.913308 -397.156432)
			(xy 419.913769 -397.132426) (xy 419.921279 -397.085006) (xy 419.93612 -397.039346) (xy 419.957925 -396.996571)
			(xy 419.986156 -396.957737) (xy 420.020119 -396.923801) (xy 420.058975 -396.8956) (xy 420.101766 -396.873828)
			(xy 420.147438 -396.859023) (xy 420.194864 -396.85155) (xy 420.21887 -396.851124) (xy 420.242807 -396.851547)
			(xy 420.290095 -396.859009) (xy 420.33564 -396.873756) (xy 420.378328 -396.895426) (xy 420.417113 -396.923489)
			(xy 420.451047 -396.957259) (xy 420.479298 -396.995907) (xy 420.49065 -397.016986) (xy 420.491158 -397.018002)
			(xy 420.571464 -397.15694) (xy 421.113712 -397.15694) (xy 421.113712 -397.156432) (xy 421.114168 -397.132439)
			(xy 421.12167 -397.085042) (xy 421.136496 -397.039404) (xy 421.158279 -396.996646) (xy 421.186483 -396.957823)
			(xy 421.220414 -396.923891) (xy 421.259236 -396.895685) (xy 421.301992 -396.8739) (xy 421.347631 -396.859073)
			(xy 421.395027 -396.851569) (xy 421.41902 -396.851124) (xy 421.442955 -396.851587) (xy 421.490241 -396.859042)
			(xy 421.535786 -396.873782) (xy 421.578474 -396.895445) (xy 421.61726 -396.923502) (xy 421.651194 -396.957266)
			(xy 421.679447 -396.99591) (xy 421.6908 -397.016986) (xy 421.691308 -397.018002) (xy 422.083738 -397.696944)
			(xy 422.096544 -397.720286) (xy 422.114771 -397.770304) (xy 422.124039 -397.822727) (xy 422.124632 -397.849344)
			(xy 422.124202 -397.87335) (xy 422.116681 -397.920769) (xy 422.101833 -397.966427) (xy 422.080022 -398.009199)
			(xy 422.051786 -398.04803) (xy 422.017821 -398.081964) (xy 421.978965 -398.110165) (xy 421.936173 -398.131938)
			(xy 421.890502 -398.146745) (xy 421.843076 -398.154223) (xy 421.81907 -398.154652) (xy 421.795497 -398.154255)
			(xy 421.74891 -398.14701) (xy 421.703993 -398.132683) (xy 421.661815 -398.111614) (xy 421.623383 -398.084306)
			(xy 421.58961 -398.051409) (xy 421.561302 -398.013706) (xy 421.54983 -397.993108) (xy 421.549322 -397.992346)
			(xy 421.151558 -397.304006) (xy 421.139682 -397.281329) (xy 421.122831 -397.232996) (xy 421.114258 -397.182533)
			(xy 421.113712 -397.15694) (xy 420.571464 -397.15694) (xy 420.883588 -397.696944) (xy 420.896319 -397.72031)
			(xy 420.914436 -397.770338) (xy 420.923646 -397.822741) (xy 420.924228 -397.849344) (xy 420.923778 -397.873335)
			(xy 420.916266 -397.920727) (xy 420.901434 -397.96636) (xy 420.879647 -398.009111) (xy 420.851441 -398.047928)
			(xy 420.81751 -398.081856) (xy 420.778691 -398.110059) (xy 420.735937 -398.131843) (xy 420.690303 -398.146672)
			(xy 420.642911 -398.15418) (xy 420.61892 -398.154652) (xy 420.595348 -398.154215) (xy 420.548763 -398.146978)
			(xy 420.503847 -398.132658) (xy 420.46167 -398.111595) (xy 420.423236 -398.084293) (xy 420.389462 -398.051402)
			(xy 420.361153 -398.013704) (xy 420.34968 -397.993108) (xy 420.349172 -397.992346) (xy 419.951408 -397.304006)
			(xy 419.939493 -397.281337) (xy 419.922555 -397.233012) (xy 419.913896 -397.182542) (xy 419.913308 -397.15694)
			(xy 419.371568 -397.15694) (xy 419.683692 -397.696944) (xy 419.696424 -397.72031) (xy 419.71454 -397.770338)
			(xy 419.72375 -397.822741) (xy 419.724332 -397.849344) (xy 419.723878 -397.873335) (xy 419.716366 -397.920726)
			(xy 419.701534 -397.966359) (xy 419.679747 -398.00911) (xy 419.651542 -398.047927) (xy 419.617612 -398.081855)
			(xy 419.578793 -398.110058) (xy 419.53604 -398.131842) (xy 419.490407 -398.146671) (xy 419.443015 -398.15418)
			(xy 419.419024 -398.154652) (xy 419.395452 -398.154211) (xy 419.348867 -398.146975) (xy 419.303951 -398.132656)
			(xy 419.261774 -398.111594) (xy 419.223341 -398.084292) (xy 419.189567 -398.051401) (xy 419.161257 -398.013704)
			(xy 419.149784 -397.993108) (xy 419.149276 -397.992346) (xy 418.751512 -397.304006) (xy 418.739598 -397.281337)
			(xy 418.72266 -397.233012) (xy 418.714 -397.182542) (xy 418.713412 -397.15694) (xy 418.171418 -397.15694)
			(xy 418.483542 -397.696944) (xy 418.496349 -397.720286) (xy 418.514576 -397.770304) (xy 418.523843 -397.822727)
			(xy 418.524436 -397.849344) (xy 418.524002 -397.87335) (xy 418.516481 -397.920768) (xy 418.501633 -397.966426)
			(xy 418.479822 -398.009197) (xy 418.451587 -398.048029) (xy 418.417623 -398.081963) (xy 418.378767 -398.110164)
			(xy 418.335976 -398.131936) (xy 418.290305 -398.146744) (xy 418.24288 -398.154223) (xy 418.218874 -398.154652)
			(xy 418.195301 -398.154252) (xy 418.148714 -398.147008) (xy 418.103797 -398.132681) (xy 418.06162 -398.111613)
			(xy 418.023187 -398.084305) (xy 417.989414 -398.051408) (xy 417.961106 -398.013706) (xy 417.949634 -397.993108)
			(xy 417.949126 -397.992346) (xy 417.551362 -397.304006) (xy 417.539486 -397.281329) (xy 417.522635 -397.232996)
			(xy 417.514062 -397.182533) (xy 417.513516 -397.15694) (xy 416.971522 -397.15694) (xy 417.283646 -397.696944)
			(xy 417.296453 -397.720286) (xy 417.31468 -397.770304) (xy 417.323947 -397.822727) (xy 417.32454 -397.849344)
			(xy 417.324102 -397.873349) (xy 417.316581 -397.920768) (xy 417.301733 -397.966425) (xy 417.279923 -398.009196)
			(xy 417.251688 -398.048027) (xy 417.217725 -398.081961) (xy 417.178869 -398.110162) (xy 417.136079 -398.131935)
			(xy 417.090409 -398.146744) (xy 417.042984 -398.154222) (xy 417.018978 -398.154652) (xy 416.995405 -398.154249)
			(xy 416.948818 -398.147005) (xy 416.903901 -398.132679) (xy 416.861724 -398.111611) (xy 416.823291 -398.084304)
			(xy 416.789518 -398.051408) (xy 416.76121 -398.013706) (xy 416.749738 -397.993108) (xy 416.74923 -397.992346)
			(xy 416.351466 -397.304006) (xy 416.339591 -397.281329) (xy 416.322739 -397.232996) (xy 416.314166 -397.182533)
			(xy 416.31362 -397.15694) (xy 415.771626 -397.15694) (xy 416.08375 -397.696944) (xy 416.096557 -397.720285)
			(xy 416.114784 -397.770304) (xy 416.124051 -397.822726) (xy 416.124644 -397.849344) (xy 416.124202 -397.873349)
			(xy 416.116682 -397.920767) (xy 416.101834 -397.966424) (xy 416.080024 -398.009195) (xy 416.05179 -398.048026)
			(xy 416.017826 -398.08196) (xy 415.978971 -398.110161) (xy 415.936182 -398.131934) (xy 415.890512 -398.146743)
			(xy 415.843088 -398.154222) (xy 415.819082 -398.154652) (xy 415.795509 -398.154245) (xy 415.748922 -398.147003)
			(xy 415.704006 -398.132677) (xy 415.661828 -398.11161) (xy 415.623395 -398.084303) (xy 415.589623 -398.051407)
			(xy 415.561314 -398.013706) (xy 415.549842 -397.993108) (xy 415.549334 -397.992346) (xy 415.15157 -397.304006)
			(xy 415.139695 -397.281329) (xy 415.122843 -397.232996) (xy 415.11427 -397.182533) (xy 415.113724 -397.15694)
			(xy 414.571476 -397.15694) (xy 414.8836 -397.696944) (xy 414.896332 -397.72031) (xy 414.914448 -397.770338)
			(xy 414.923658 -397.822741) (xy 414.92424 -397.849344) (xy 414.923778 -397.873335) (xy 414.916266 -397.920725)
			(xy 414.901435 -397.966357) (xy 414.879649 -398.009107) (xy 414.851444 -398.047924) (xy 414.817515 -398.081852)
			(xy 414.778697 -398.110055) (xy 414.735946 -398.13184) (xy 414.690313 -398.146669) (xy 414.642923 -398.154179)
			(xy 414.618932 -398.154652) (xy 414.59536 -398.154205) (xy 414.548776 -398.14697) (xy 414.50386 -398.132651)
			(xy 414.461683 -398.111591) (xy 414.423249 -398.08429) (xy 414.389475 -398.0514) (xy 414.361165 -398.013703)
			(xy 414.349692 -397.993108) (xy 414.349184 -397.992346) (xy 413.95142 -397.304006) (xy 413.939506 -397.281337)
			(xy 413.922568 -397.233012) (xy 413.913908 -397.182542) (xy 413.91332 -397.15694) (xy 413.37158 -397.15694)
			(xy 413.683704 -397.696944) (xy 413.696437 -397.72031) (xy 413.714552 -397.770337) (xy 413.723762 -397.822741)
			(xy 413.724344 -397.849344) (xy 413.723878 -397.873335) (xy 413.716367 -397.920724) (xy 413.701535 -397.966356)
			(xy 413.679749 -398.009106) (xy 413.651545 -398.047923) (xy 413.617617 -398.08185) (xy 413.578799 -398.110054)
			(xy 413.536049 -398.131838) (xy 413.490417 -398.146668) (xy 413.443027 -398.154179) (xy 413.419036 -398.154652)
			(xy 413.395464 -398.154202) (xy 413.34888 -398.146967) (xy 413.303964 -398.132649) (xy 413.261787 -398.111589)
			(xy 413.223353 -398.084289) (xy 413.189579 -398.051399) (xy 413.161269 -398.013703) (xy 413.149796 -397.993108)
			(xy 413.149288 -397.992346) (xy 412.751524 -397.304006) (xy 412.739611 -397.281337) (xy 412.722672 -397.233012)
			(xy 412.714012 -397.182542) (xy 412.713424 -397.15694) (xy 412.17143 -397.15694) (xy 412.483554 -397.696944)
			(xy 412.496362 -397.720285) (xy 412.514588 -397.770304) (xy 412.523855 -397.822726) (xy 412.524448 -397.849344)
			(xy 412.524002 -397.873349) (xy 412.516482 -397.920767) (xy 412.501634 -397.966423) (xy 412.479825 -398.009194)
			(xy 412.451591 -398.048025) (xy 412.417628 -398.081959) (xy 412.378773 -398.11016) (xy 412.335984 -398.131933)
			(xy 412.290315 -398.146742) (xy 412.242891 -398.154222) (xy 412.218886 -398.154652) (xy 412.195313 -398.154242)
			(xy 412.148727 -398.147) (xy 412.10381 -398.132675) (xy 412.061633 -398.111608) (xy 412.0232 -398.084302)
			(xy 411.989427 -398.051406) (xy 411.961119 -398.013705) (xy 411.949646 -397.993108) (xy 411.949138 -397.992346)
			(xy 411.551374 -397.304006) (xy 411.539499 -397.281329) (xy 411.522648 -397.232996) (xy 411.514074 -397.182533)
			(xy 411.513528 -397.15694) (xy 410.971534 -397.15694) (xy 411.283658 -397.696944) (xy 411.296466 -397.720285)
			(xy 411.314692 -397.770304) (xy 411.323959 -397.822726) (xy 411.324552 -397.849344) (xy 411.324102 -397.873349)
			(xy 411.316582 -397.920766) (xy 411.301734 -397.966422) (xy 411.279925 -398.009193) (xy 411.251692 -398.048023)
			(xy 411.21773 -398.081957) (xy 411.178876 -398.110158) (xy 411.136087 -398.131932) (xy 411.090419 -398.146741)
			(xy 411.042995 -398.154222) (xy 411.01899 -398.154652) (xy 410.995417 -398.154239) (xy 410.948831 -398.146997)
			(xy 410.903914 -398.132673) (xy 410.861737 -398.111607) (xy 410.823304 -398.084301) (xy 410.789531 -398.051406)
			(xy 410.761223 -398.013705) (xy 410.74975 -397.993108) (xy 410.749242 -397.992346) (xy 410.351478 -397.304006)
			(xy 410.339603 -397.281328) (xy 410.322752 -397.232996) (xy 410.314178 -397.182533) (xy 410.313632 -397.15694)
			(xy 409.771638 -397.15694) (xy 410.083762 -397.696944) (xy 410.09657 -397.720285) (xy 410.114796 -397.770304)
			(xy 410.124063 -397.822726) (xy 410.124656 -397.849344) (xy 410.124202 -397.873349) (xy 410.116682 -397.920765)
			(xy 410.101835 -397.966421) (xy 410.080026 -398.009191) (xy 410.051793 -398.048022) (xy 410.017831 -398.081956)
			(xy 409.978978 -398.110157) (xy 409.93619 -398.131931) (xy 409.890522 -398.14674) (xy 409.843099 -398.154221)
			(xy 409.819094 -398.154652) (xy 409.795521 -398.154236) (xy 409.748935 -398.146995) (xy 409.704019 -398.132671)
			(xy 409.661841 -398.111605) (xy 409.623408 -398.0843) (xy 409.589635 -398.051405) (xy 409.561327 -398.013705)
			(xy 409.549854 -397.993108) (xy 409.549346 -397.992346) (xy 409.151582 -397.304006) (xy 409.139708 -397.281328)
			(xy 409.122856 -397.232996) (xy 409.114282 -397.182533) (xy 409.113736 -397.15694) (xy 408.571488 -397.15694)
			(xy 408.883612 -397.696944) (xy 408.896345 -397.720309) (xy 408.91446 -397.770337) (xy 408.92367 -397.822741)
			(xy 408.924252 -397.849344) (xy 408.923778 -397.873334) (xy 408.916267 -397.920723) (xy 408.901436 -397.966354)
			(xy 408.879651 -398.009104) (xy 408.851448 -398.04792) (xy 408.81752 -398.081848) (xy 408.778704 -398.110051)
			(xy 408.735954 -398.131836) (xy 408.690323 -398.146667) (xy 408.642934 -398.154178) (xy 408.618944 -398.154652)
			(xy 408.595373 -398.154195) (xy 408.548789 -398.146962) (xy 408.503873 -398.132645) (xy 408.461696 -398.111586)
			(xy 408.423262 -398.084287) (xy 408.389488 -398.051398) (xy 408.361178 -398.013703) (xy 408.349704 -397.993108)
			(xy 408.349196 -397.992346) (xy 407.951432 -397.304006) (xy 407.939519 -397.281336) (xy 407.92258 -397.233012)
			(xy 407.91392 -397.182542) (xy 407.913332 -397.15694) (xy 407.371592 -397.15694) (xy 407.683716 -397.696944)
			(xy 407.69645 -397.720309) (xy 407.714565 -397.770337) (xy 407.723774 -397.822741) (xy 407.724356 -397.849344)
			(xy 407.723878 -397.873334) (xy 407.716367 -397.920723) (xy 407.701536 -397.966353) (xy 407.679752 -398.009103)
			(xy 407.651549 -398.047919) (xy 407.617622 -398.081846) (xy 407.578806 -398.11005) (xy 407.536057 -398.131835)
			(xy 407.490427 -398.146666) (xy 407.443038 -398.154178) (xy 407.419048 -398.154652) (xy 407.395477 -398.154192)
			(xy 407.348893 -398.146959) (xy 407.303977 -398.132643) (xy 407.2618 -398.111585) (xy 407.223366 -398.084286)
			(xy 407.189592 -398.051398) (xy 407.161282 -398.013703) (xy 407.149808 -397.993108) (xy 407.1493 -397.992346)
			(xy 406.751536 -397.304006) (xy 406.739623 -397.281336) (xy 406.722684 -397.233012) (xy 406.714024 -397.182542)
			(xy 406.713436 -397.15694) (xy 406.171442 -397.15694) (xy 406.483566 -397.696944) (xy 406.496375 -397.720285)
			(xy 406.5146 -397.770303) (xy 406.523867 -397.822726) (xy 406.52446 -397.849344) (xy 406.524101 -397.873353)
			(xy 406.516579 -397.92078) (xy 406.501726 -397.966444) (xy 406.479909 -398.00922) (xy 406.451665 -398.048055)
			(xy 406.417691 -398.08199) (xy 406.378825 -398.11019) (xy 406.336023 -398.131958) (xy 406.290342 -398.146759)
			(xy 406.242908 -398.154228) (xy 406.218898 -398.154652) (xy 406.195325 -398.154232) (xy 406.14874 -398.146992)
			(xy 406.103823 -398.132669) (xy 406.061646 -398.111604) (xy 406.023213 -398.084299) (xy 405.989439 -398.051405)
			(xy 405.961131 -398.013705) (xy 405.949658 -397.993108) (xy 405.94915 -397.992346) (xy 405.551386 -397.304006)
			(xy 405.539512 -397.281328) (xy 405.52266 -397.232996) (xy 405.514086 -397.182533) (xy 405.51354 -397.15694)
			(xy 404.971546 -397.15694) (xy 405.28367 -397.696944) (xy 405.296479 -397.720285) (xy 405.314704 -397.770303)
			(xy 405.323971 -397.822726) (xy 405.324564 -397.849344) (xy 405.324201 -397.873353) (xy 405.316679 -397.920779)
			(xy 405.301826 -397.966443) (xy 405.280009 -398.009219) (xy 405.251766 -398.048053) (xy 405.217793 -398.081989)
			(xy 405.178927 -398.110188) (xy 405.136126 -398.131957) (xy 405.090446 -398.146759) (xy 405.043012 -398.154228)
			(xy 405.019002 -398.154652) (xy 404.995429 -398.154229) (xy 404.948844 -398.14699) (xy 404.903927 -398.132667)
			(xy 404.86175 -398.111602) (xy 404.823317 -398.084298) (xy 404.789544 -398.051404) (xy 404.761235 -398.013705)
			(xy 404.749762 -397.993108) (xy 404.749254 -397.992346) (xy 404.35149 -397.304006) (xy 404.339616 -397.281328)
			(xy 404.322764 -397.232995) (xy 404.31419 -397.182533) (xy 404.313644 -397.15694) (xy 403.77165 -397.15694)
			(xy 404.083774 -397.696944) (xy 404.096583 -397.720284) (xy 404.114808 -397.770303) (xy 404.124075 -397.822726)
			(xy 404.124668 -397.849344) (xy 404.124301 -397.873353) (xy 404.116779 -397.920778) (xy 404.101926 -397.966442)
			(xy 404.08011 -398.009218) (xy 404.051867 -398.048052) (xy 404.017895 -398.081987) (xy 403.979029 -398.110187)
			(xy 403.936229 -398.131956) (xy 403.890549 -398.146758) (xy 403.843116 -398.154228) (xy 403.819106 -398.154652)
			(xy 403.795534 -398.154226) (xy 403.748948 -398.146987) (xy 403.704032 -398.132665) (xy 403.661854 -398.111601)
			(xy 403.623421 -398.084297) (xy 403.589648 -398.051404) (xy 403.561339 -398.013705) (xy 403.549866 -397.993108)
			(xy 403.549358 -397.992346) (xy 403.151594 -397.304006) (xy 403.139721 -397.281328) (xy 403.122868 -397.232995)
			(xy 403.114294 -397.182532) (xy 403.113748 -397.15694) (xy 389.24392 -397.15694) (xy 389.55599 -397.696944)
			(xy 389.556244 -397.697452) (xy 389.556498 -397.697452) (xy 389.557768 -397.699992) (xy 389.570036 -397.722909)
			(xy 389.587445 -397.771886) (xy 389.59632 -397.823102) (xy 389.596884 -397.84909) (xy 389.596884 -397.849344)
			(xy 389.596501 -397.873352) (xy 389.588979 -397.920776) (xy 389.574128 -397.966438) (xy 389.552313 -398.009213)
			(xy 389.524072 -398.048046) (xy 389.490101 -398.081981) (xy 389.451238 -398.110181) (xy 389.40844 -398.131951)
			(xy 389.362762 -398.146755) (xy 389.315331 -398.154227) (xy 389.291322 -398.154652) (xy 389.267658 -398.154195)
			(xy 389.220898 -398.146888) (xy 389.175823 -398.13246) (xy 389.133511 -398.111257) (xy 389.094972 -398.083784)
			(xy 389.061129 -398.0507) (xy 389.032791 -398.012795) (xy 389.02132 -397.992092) (xy 389.021066 -397.99133)
			(xy 388.62381 -397.304006) (xy 388.611629 -397.280791) (xy 388.594516 -397.231239) (xy 388.589774 -397.205454)
			(xy 388.589774 -397.2052) (xy 388.586223 -397.179976) (xy 388.057083 -397.179976) (xy 388.35584 -397.696944)
			(xy 388.356094 -397.697452) (xy 388.356348 -397.697452) (xy 388.357618 -397.699992) (xy 388.369851 -397.722916)
			(xy 388.387171 -397.771902) (xy 388.395958 -397.823111) (xy 388.39648 -397.84909) (xy 388.39648 -397.849344)
			(xy 388.396078 -397.873338) (xy 388.388564 -397.920734) (xy 388.373729 -397.966371) (xy 388.351938 -398.009125)
			(xy 388.323726 -398.047945) (xy 388.28979 -398.081873) (xy 388.250964 -398.110075) (xy 388.208204 -398.131857)
			(xy 388.162564 -398.146681) (xy 388.115166 -398.154184) (xy 388.091172 -398.154652) (xy 388.06751 -398.154155)
			(xy 388.020751 -398.146855) (xy 387.975677 -398.132434) (xy 387.933365 -398.111238) (xy 387.894826 -398.083772)
			(xy 387.860982 -398.050693) (xy 387.832641 -398.012793) (xy 387.82117 -397.992092) (xy 387.820916 -397.99133)
			(xy 387.42366 -397.304006) (xy 387.411482 -397.280789) (xy 387.394366 -397.231239) (xy 387.389624 -397.205454)
			(xy 387.389624 -397.2052) (xy 387.386148 -397.181394) (xy 387.385937 -397.133285) (xy 386.830204 -397.133285)
			(xy 387.155944 -397.696944) (xy 387.156198 -397.697452) (xy 387.156452 -397.697452) (xy 387.157722 -397.699992)
			(xy 387.169955 -397.722916) (xy 387.187275 -397.771902) (xy 387.196062 -397.823111) (xy 387.196584 -397.84909)
			(xy 387.196584 -397.849344) (xy 387.196178 -397.873338) (xy 387.188664 -397.920733) (xy 387.17383 -397.96637)
			(xy 387.152038 -398.009124) (xy 387.123828 -398.047943) (xy 387.089892 -398.081872) (xy 387.051066 -398.110074)
			(xy 387.008307 -398.131856) (xy 386.962667 -398.14668) (xy 386.91527 -398.154183) (xy 386.891276 -398.154652)
			(xy 386.867611 -398.154232) (xy 386.820849 -398.146918) (xy 386.775773 -398.132483) (xy 386.733461 -398.111274)
			(xy 386.694923 -398.083796) (xy 386.661081 -398.050707) (xy 386.632744 -398.012797) (xy 386.621274 -397.992092)
			(xy 386.62102 -397.99133) (xy 386.223764 -397.304006) (xy 386.211586 -397.280789) (xy 386.19447 -397.231239)
			(xy 386.189728 -397.205454) (xy 386.189728 -397.2052) (xy 386.186245 -397.181395) (xy 386.186033 -397.133285)
			(xy 385.630054 -397.133285) (xy 385.955794 -397.696944) (xy 385.956048 -397.697452) (xy 385.956302 -397.697452)
			(xy 385.957572 -397.699992) (xy 385.969841 -397.722909) (xy 385.987249 -397.771886) (xy 385.996124 -397.823102)
			(xy 385.996688 -397.84909) (xy 385.996688 -397.849344) (xy 385.996301 -397.873352) (xy 385.98878 -397.920775)
			(xy 385.973928 -397.966437) (xy 385.952114 -398.009212) (xy 385.923873 -398.048045) (xy 385.889903 -398.08198)
			(xy 385.85104 -398.11018) (xy 385.808243 -398.13195) (xy 385.762566 -398.146754) (xy 385.715134 -398.154226)
			(xy 385.691126 -398.154652) (xy 385.667462 -398.154192) (xy 385.620702 -398.146885) (xy 385.575627 -398.132458)
			(xy 385.533315 -398.111255) (xy 385.494777 -398.083783) (xy 385.460934 -398.0507) (xy 385.432595 -398.012795)
			(xy 385.421124 -397.992092) (xy 385.42087 -397.99133) (xy 385.023614 -397.304006) (xy 385.011433 -397.28079)
			(xy 384.99432 -397.231239) (xy 384.989578 -397.205454) (xy 384.989578 -397.2052) (xy 384.986019 -397.179977)
			(xy 384.457141 -397.179977) (xy 384.755898 -397.696944) (xy 384.756152 -397.697452) (xy 384.756406 -397.697452)
			(xy 384.757676 -397.699992) (xy 384.769945 -397.722909) (xy 384.787353 -397.771886) (xy 384.796228 -397.823102)
			(xy 384.796792 -397.84909) (xy 384.796792 -397.849344) (xy 384.796401 -397.873352) (xy 384.78888 -397.920775)
			(xy 384.774029 -397.966436) (xy 384.752214 -398.009211) (xy 384.723974 -398.048044) (xy 384.690005 -398.081979)
			(xy 384.651142 -398.110179) (xy 384.608346 -398.131949) (xy 384.562669 -398.146753) (xy 384.515238 -398.154226)
			(xy 384.49123 -398.154652) (xy 384.467566 -398.154188) (xy 384.420807 -398.146882) (xy 384.375732 -398.132456)
			(xy 384.333419 -398.111254) (xy 384.294881 -398.083782) (xy 384.261038 -398.050699) (xy 384.232699 -398.012794)
			(xy 384.221228 -397.992092) (xy 384.220974 -397.99133) (xy 383.823718 -397.304006) (xy 383.811537 -397.28079)
			(xy 383.794424 -397.231239) (xy 383.789682 -397.205454) (xy 383.789682 -397.2052) (xy 383.786116 -397.179978)
			(xy 383.257246 -397.179978) (xy 383.556002 -397.696944) (xy 383.556256 -397.697452) (xy 383.55651 -397.697452)
			(xy 383.55778 -397.699992) (xy 383.570049 -397.722909) (xy 383.587457 -397.771886) (xy 383.596332 -397.823102)
			(xy 383.596896 -397.84909) (xy 383.596896 -397.849344) (xy 383.596501 -397.873352) (xy 383.58898 -397.920774)
			(xy 383.574129 -397.966435) (xy 383.552315 -398.009209) (xy 383.524075 -398.048042) (xy 383.490106 -398.081977)
			(xy 383.451245 -398.110177) (xy 383.408448 -398.131948) (xy 383.362772 -398.146752) (xy 383.315342 -398.154226)
			(xy 383.291334 -398.154652) (xy 383.267671 -398.154185) (xy 383.220911 -398.14688) (xy 383.175836 -398.132454)
			(xy 383.133524 -398.111252) (xy 383.094985 -398.083781) (xy 383.061142 -398.050699) (xy 383.032803 -398.012794)
			(xy 383.021332 -397.992092) (xy 383.021078 -397.99133) (xy 382.623822 -397.304006) (xy 382.611641 -397.28079)
			(xy 382.594528 -397.231239) (xy 382.589786 -397.205454) (xy 382.589786 -397.2052) (xy 382.586212 -397.179979)
			(xy 382.057097 -397.179979) (xy 382.355852 -397.696944) (xy 382.356106 -397.697452) (xy 382.35636 -397.697452)
			(xy 382.35763 -397.699992) (xy 382.369864 -397.722916) (xy 382.387183 -397.771902) (xy 382.395971 -397.823111)
			(xy 382.396492 -397.84909) (xy 382.396492 -397.849344) (xy 382.396078 -397.873337) (xy 382.388565 -397.920732)
			(xy 382.37373 -397.966368) (xy 382.35194 -398.009122) (xy 382.32373 -398.047941) (xy 382.289795 -398.081869)
			(xy 382.250971 -398.110071) (xy 382.208212 -398.131853) (xy 382.162574 -398.146679) (xy 382.115177 -398.154183)
			(xy 382.091184 -398.154652) (xy 382.067519 -398.154226) (xy 382.020757 -398.146913) (xy 381.975682 -398.132479)
			(xy 381.933369 -398.111271) (xy 381.894832 -398.083794) (xy 381.860989 -398.050706) (xy 381.832652 -398.012796)
			(xy 381.821182 -397.992092) (xy 381.820928 -397.99133) (xy 381.423672 -397.304006) (xy 381.411495 -397.280788)
			(xy 381.394379 -397.231238) (xy 381.389636 -397.205454) (xy 381.389636 -397.2052) (xy 381.386138 -397.181397)
			(xy 381.385926 -397.133286) (xy 380.830217 -397.133286) (xy 381.155956 -397.696944) (xy 381.15621 -397.697452)
			(xy 381.156464 -397.697452) (xy 381.157734 -397.699992) (xy 381.169968 -397.722915) (xy 381.187288 -397.771902)
			(xy 381.196075 -397.823111) (xy 381.196596 -397.84909) (xy 381.196596 -397.849344) (xy 381.196178 -397.873337)
			(xy 381.188665 -397.920731) (xy 381.173831 -397.966367) (xy 381.152041 -398.009121) (xy 381.123831 -398.047939)
			(xy 381.089897 -398.081868) (xy 381.051073 -398.11007) (xy 381.008315 -398.131852) (xy 380.962677 -398.146678)
			(xy 380.915281 -398.154182) (xy 380.891288 -398.154652) (xy 380.867623 -398.154222) (xy 380.820862 -398.14691)
			(xy 380.775786 -398.132477) (xy 380.733474 -398.111269) (xy 380.694936 -398.083793) (xy 380.661094 -398.050705)
			(xy 380.632756 -398.012796) (xy 380.621286 -397.992092) (xy 380.621032 -397.99133) (xy 380.223776 -397.304006)
			(xy 380.211599 -397.280788) (xy 380.194483 -397.231238) (xy 380.18974 -397.205454) (xy 380.18974 -397.2052)
			(xy 380.186234 -397.181398) (xy 380.186022 -397.133286) (xy 379.630067 -397.133286) (xy 379.955806 -397.696944)
			(xy 379.95606 -397.697452) (xy 379.956314 -397.697452) (xy 379.957584 -397.699992) (xy 379.969854 -397.722909)
			(xy 379.987261 -397.771886) (xy 379.996136 -397.823101) (xy 379.9967 -397.84909) (xy 379.9967 -397.849344)
			(xy 379.996301 -397.873351) (xy 379.98878 -397.920774) (xy 379.97393 -397.966434) (xy 379.952116 -398.009208)
			(xy 379.923877 -398.048041) (xy 379.889908 -398.081976) (xy 379.851047 -398.110176) (xy 379.808251 -398.131947)
			(xy 379.762576 -398.146752) (xy 379.715146 -398.154225) (xy 379.691138 -398.154652) (xy 379.667475 -398.154182)
			(xy 379.620715 -398.146877) (xy 379.57564 -398.132452) (xy 379.533328 -398.111251) (xy 379.494789 -398.08378)
			(xy 379.460946 -398.050698) (xy 379.432607 -398.012794) (xy 379.421136 -397.992092) (xy 379.420882 -397.99133)
			(xy 379.023626 -397.304006) (xy 379.011446 -397.28079) (xy 378.994332 -397.231239) (xy 378.98959 -397.205454)
			(xy 378.98959 -397.2052) (xy 378.986178 -397.181387) (xy 378.985967 -397.133284) (xy 378.430169 -397.133284)
			(xy 378.75591 -397.696944) (xy 378.756164 -397.697452) (xy 378.756418 -397.697452) (xy 378.757688 -397.699992)
			(xy 378.769958 -397.722908) (xy 378.787365 -397.771886) (xy 378.79624 -397.823101) (xy 378.796804 -397.84909)
			(xy 378.796804 -397.849344) (xy 378.796401 -397.873351) (xy 378.78888 -397.920773) (xy 378.77403 -397.966433)
			(xy 378.752217 -398.009207) (xy 378.723978 -398.04804) (xy 378.69001 -398.081974) (xy 378.651149 -398.110175)
			(xy 378.608354 -398.131946) (xy 378.562679 -398.146751) (xy 378.51525 -398.154225) (xy 378.491242 -398.154652)
			(xy 378.467579 -398.154179) (xy 378.420819 -398.146875) (xy 378.375745 -398.13245) (xy 378.333432 -398.111249)
			(xy 378.294894 -398.083779) (xy 378.26105 -398.050697) (xy 378.232711 -398.012794) (xy 378.22124 -397.992092)
			(xy 378.220986 -397.99133) (xy 377.82373 -397.304006) (xy 377.81155 -397.28079) (xy 377.794436 -397.231239)
			(xy 377.789694 -397.205454) (xy 377.789694 -397.2052) (xy 377.786274 -397.181388) (xy 377.786064 -397.133284)
			(xy 377.230273 -397.133284) (xy 377.556014 -397.696944) (xy 377.556268 -397.697452) (xy 377.556522 -397.697452)
			(xy 377.557792 -397.699992) (xy 377.570062 -397.722908) (xy 377.587469 -397.771886) (xy 377.596344 -397.823101)
			(xy 377.596908 -397.84909) (xy 377.596908 -397.849344) (xy 377.596501 -397.873351) (xy 377.58898 -397.920772)
			(xy 377.57413 -397.966432) (xy 377.552317 -398.009206) (xy 377.524079 -398.048038) (xy 377.490111 -398.081973)
			(xy 377.451251 -398.110173) (xy 377.408457 -398.131944) (xy 377.362782 -398.14675) (xy 377.315353 -398.154225)
			(xy 377.291346 -398.154652) (xy 377.267683 -398.154176) (xy 377.220924 -398.146872) (xy 377.175849 -398.132448)
			(xy 377.133537 -398.111248) (xy 377.094998 -398.083778) (xy 377.061154 -398.050697) (xy 377.032815 -398.012794)
			(xy 377.021344 -397.992092) (xy 377.02109 -397.99133) (xy 376.623834 -397.304006) (xy 376.611654 -397.28079)
			(xy 376.59454 -397.231239) (xy 376.589798 -397.205454) (xy 376.589798 -397.2052) (xy 376.586371 -397.181389)
			(xy 376.58616 -397.133284) (xy 376.030123 -397.133284) (xy 376.355864 -397.696944) (xy 376.356118 -397.697452)
			(xy 376.356372 -397.697452) (xy 376.357642 -397.699992) (xy 376.369877 -397.722915) (xy 376.387196 -397.771902)
			(xy 376.395983 -397.823111) (xy 376.396504 -397.84909) (xy 376.396504 -397.849344) (xy 376.396078 -397.873337)
			(xy 376.388565 -397.92073) (xy 376.373731 -397.966365) (xy 376.351942 -398.009118) (xy 376.323733 -398.047937)
			(xy 376.2898 -398.081865) (xy 376.250977 -398.110067) (xy 376.208221 -398.13185) (xy 376.162583 -398.146676)
			(xy 376.115189 -398.154182) (xy 376.091196 -398.154652) (xy 376.067531 -398.154216) (xy 376.02077 -398.146905)
			(xy 375.975695 -398.132473) (xy 375.933382 -398.111266) (xy 375.894844 -398.083791) (xy 375.861002 -398.050704)
			(xy 375.832664 -398.012796) (xy 375.821194 -397.992092) (xy 375.82094 -397.99133) (xy 375.423684 -397.304006)
			(xy 375.411508 -397.280788) (xy 375.394391 -397.231238) (xy 375.389648 -397.205454) (xy 375.389648 -397.2052)
			(xy 375.386127 -397.181399) (xy 375.385915 -397.133286) (xy 374.830229 -397.133286) (xy 375.155968 -397.696944)
			(xy 375.156222 -397.697452) (xy 375.156476 -397.697452) (xy 375.157746 -397.699992) (xy 375.169981 -397.722915)
			(xy 375.1873 -397.771902) (xy 375.196087 -397.823111) (xy 375.196608 -397.84909) (xy 375.196608 -397.849344)
			(xy 375.196178 -397.873336) (xy 375.188665 -397.92073) (xy 375.173832 -397.966364) (xy 375.152043 -398.009117)
			(xy 375.123835 -398.047935) (xy 375.089902 -398.081863) (xy 375.051079 -398.110066) (xy 375.008324 -398.131849)
			(xy 374.962687 -398.146676) (xy 374.915292 -398.154181) (xy 374.8913 -398.154652) (xy 374.867636 -398.154213)
			(xy 374.820875 -398.146902) (xy 374.775799 -398.132471) (xy 374.733487 -398.111265) (xy 374.694949 -398.08379)
			(xy 374.661106 -398.050703) (xy 374.632768 -398.012796) (xy 374.621298 -397.992092) (xy 374.621044 -397.99133)
			(xy 374.223788 -397.304006) (xy 374.211612 -397.280788) (xy 374.194495 -397.231238) (xy 374.189752 -397.205454)
			(xy 374.189752 -397.2052) (xy 374.186223 -397.1814) (xy 374.186012 -397.133286) (xy 373.630079 -397.133286)
			(xy 373.955818 -397.696944) (xy 373.956072 -397.697452) (xy 373.956326 -397.697452) (xy 373.957596 -397.699992)
			(xy 373.969867 -397.722908) (xy 373.987274 -397.771886) (xy 373.996148 -397.823101) (xy 373.996712 -397.84909)
			(xy 373.996712 -397.849344) (xy 373.996302 -397.873351) (xy 373.98878 -397.920772) (xy 373.973931 -397.966432)
			(xy 373.952118 -398.009205) (xy 373.92388 -398.048037) (xy 373.889913 -398.081971) (xy 373.851053 -398.110172)
			(xy 373.808259 -398.131943) (xy 373.762586 -398.146749) (xy 373.715157 -398.154225) (xy 373.69115 -398.154652)
			(xy 373.667487 -398.154172) (xy 373.620728 -398.146869) (xy 373.575653 -398.132446) (xy 373.533341 -398.111246)
			(xy 373.494802 -398.083777) (xy 373.460959 -398.050696) (xy 373.432619 -398.012793) (xy 373.421148 -397.992092)
			(xy 373.420894 -397.99133) (xy 373.023638 -397.304006) (xy 373.011458 -397.28079) (xy 372.994344 -397.231239)
			(xy 372.989602 -397.205454) (xy 372.989602 -397.2052) (xy 372.986167 -397.181389) (xy 372.985956 -397.133284)
			(xy 372.430181 -397.133284) (xy 372.755922 -397.696944) (xy 372.756176 -397.697452) (xy 372.75643 -397.697452)
			(xy 372.7577 -397.699992) (xy 372.769971 -397.722908) (xy 372.787378 -397.771886) (xy 372.796252 -397.823101)
			(xy 372.796816 -397.84909) (xy 372.796816 -397.849344) (xy 372.796402 -397.873351) (xy 372.788881 -397.920771)
			(xy 372.774031 -397.966431) (xy 372.752219 -398.009203) (xy 372.723981 -398.048036) (xy 372.690015 -398.08197)
			(xy 372.651156 -398.110171) (xy 372.608362 -398.131942) (xy 372.562689 -398.146748) (xy 372.515261 -398.154224)
			(xy 372.491254 -398.154652) (xy 372.467591 -398.154169) (xy 372.420832 -398.146867) (xy 372.375758 -398.132444)
			(xy 372.333445 -398.111245) (xy 372.294907 -398.083776) (xy 372.261063 -398.050696) (xy 372.232723 -398.012793)
			(xy 372.221252 -397.992092) (xy 372.220998 -397.99133) (xy 371.823742 -397.304006) (xy 371.811563 -397.280789)
			(xy 371.794448 -397.231239) (xy 371.789706 -397.205454) (xy 371.789706 -397.2052) (xy 371.786264 -397.18139)
			(xy 371.786053 -397.133284) (xy 371.230285 -397.133284) (xy 371.556026 -397.696944) (xy 371.55628 -397.697452)
			(xy 371.556534 -397.697452) (xy 371.557804 -397.699992) (xy 371.570075 -397.722908) (xy 371.587482 -397.771886)
			(xy 371.596356 -397.823101) (xy 371.59692 -397.84909) (xy 371.59692 -397.849344) (xy 371.596502 -397.87335)
			(xy 371.588981 -397.920771) (xy 371.574131 -397.96643) (xy 371.552319 -398.009202) (xy 371.524082 -398.048034)
			(xy 371.490116 -398.081969) (xy 371.451258 -398.110169) (xy 371.408465 -398.131941) (xy 371.362792 -398.146748)
			(xy 371.315365 -398.154224) (xy 371.291358 -398.154652) (xy 371.267695 -398.154166) (xy 371.220936 -398.146864)
			(xy 371.175862 -398.132442) (xy 371.13355 -398.111243) (xy 371.095011 -398.083775) (xy 371.061167 -398.050695)
			(xy 371.032827 -398.012793) (xy 371.021356 -397.992092) (xy 371.021102 -397.99133) (xy 370.623846 -397.304006)
			(xy 370.611667 -397.280789) (xy 370.594552 -397.231239) (xy 370.58981 -397.205454) (xy 370.58981 -397.2052)
			(xy 370.58636 -397.181391) (xy 370.586149 -397.133284) (xy 354.657801 -397.133284) (xy 354.983542 -397.696944)
			(xy 354.983796 -397.697452) (xy 354.98405 -397.697452) (xy 354.98532 -397.699992) (xy 354.997593 -397.722907)
			(xy 355.014998 -397.771885) (xy 355.023872 -397.823101) (xy 355.024436 -397.84909) (xy 355.024436 -397.849344)
			(xy 355.024002 -397.87335) (xy 355.016481 -397.920768) (xy 355.001633 -397.966426) (xy 354.979822 -398.009197)
			(xy 354.951587 -398.048029) (xy 354.917623 -398.081963) (xy 354.878767 -398.110164) (xy 354.835976 -398.131936)
			(xy 354.790305 -398.146744) (xy 354.74288 -398.154223) (xy 354.718874 -398.154652) (xy 354.695212 -398.154153)
			(xy 354.648453 -398.146854) (xy 354.603379 -398.132433) (xy 354.561067 -398.111237) (xy 354.522528 -398.083771)
			(xy 354.488684 -398.050693) (xy 354.460343 -398.012792) (xy 354.448872 -397.992092) (xy 354.448618 -397.99133)
			(xy 354.051362 -397.304006) (xy 354.039184 -397.280789) (xy 354.022068 -397.231239) (xy 354.017326 -397.205454)
			(xy 354.017326 -397.2052) (xy 354.013846 -397.181395) (xy 354.013635 -397.133285) (xy 353.457652 -397.133285)
			(xy 353.783392 -397.696944) (xy 353.783646 -397.697452) (xy 353.7839 -397.697452) (xy 353.78517 -397.699992)
			(xy 353.797399 -397.722918) (xy 353.814722 -397.771903) (xy 353.82351 -397.823111) (xy 353.824032 -397.84909)
			(xy 353.824032 -397.849344) (xy 353.823578 -397.873335) (xy 353.816066 -397.920726) (xy 353.801234 -397.966359)
			(xy 353.779447 -398.00911) (xy 353.751242 -398.047927) (xy 353.717312 -398.081855) (xy 353.678493 -398.110058)
			(xy 353.63574 -398.131842) (xy 353.590107 -398.146671) (xy 353.542715 -398.15418) (xy 353.518724 -398.154652)
			(xy 353.49506 -398.154193) (xy 353.4483 -398.146886) (xy 353.403225 -398.132459) (xy 353.360913 -398.111256)
			(xy 353.322374 -398.083784) (xy 353.288531 -398.0507) (xy 353.260193 -398.012795) (xy 353.248722 -397.992092)
			(xy 353.248468 -397.99133) (xy 352.851212 -397.304006) (xy 352.839031 -397.28079) (xy 352.821918 -397.231239)
			(xy 352.817176 -397.205454) (xy 352.817176 -397.2052) (xy 352.813621 -397.179976) (xy 352.284739 -397.179976)
			(xy 352.583496 -397.696944) (xy 352.58375 -397.697452) (xy 352.584004 -397.697452) (xy 352.585274 -397.699992)
			(xy 352.597504 -397.722918) (xy 352.614826 -397.771903) (xy 352.623614 -397.823111) (xy 352.624136 -397.84909)
			(xy 352.624136 -397.849344) (xy 352.623678 -397.873335) (xy 352.616166 -397.920726) (xy 352.601335 -397.966358)
			(xy 352.579548 -398.009109) (xy 352.551343 -398.047926) (xy 352.517413 -398.081853) (xy 352.478595 -398.110056)
			(xy 352.435843 -398.131841) (xy 352.39021 -398.14667) (xy 352.342819 -398.154179) (xy 352.318828 -398.154652)
			(xy 352.295164 -398.15419) (xy 352.248404 -398.146884) (xy 352.203329 -398.132457) (xy 352.161017 -398.111254)
			(xy 352.122479 -398.083783) (xy 352.088636 -398.050699) (xy 352.060297 -398.012794) (xy 352.048826 -397.992092)
			(xy 352.048572 -397.99133) (xy 351.651316 -397.304006) (xy 351.639135 -397.28079) (xy 351.622022 -397.231239)
			(xy 351.61728 -397.205454) (xy 351.61728 -397.2052) (xy 351.613718 -397.179977) (xy 351.084589 -397.179977)
			(xy 351.383346 -397.696944) (xy 351.3836 -397.697452) (xy 351.383854 -397.697452) (xy 351.385124 -397.699992)
			(xy 351.397397 -397.722907) (xy 351.414802 -397.771885) (xy 351.423676 -397.823101) (xy 351.42424 -397.84909)
			(xy 351.42424 -397.849344) (xy 351.423802 -397.873349) (xy 351.416281 -397.920768) (xy 351.401433 -397.966425)
			(xy 351.379623 -398.009196) (xy 351.351388 -398.048027) (xy 351.317425 -398.081961) (xy 351.278569 -398.110162)
			(xy 351.235779 -398.131935) (xy 351.190109 -398.146744) (xy 351.142684 -398.154222) (xy 351.118678 -398.154652)
			(xy 351.095013 -398.15423) (xy 351.048251 -398.146916) (xy 351.003175 -398.132482) (xy 350.960863 -398.111273)
			(xy 350.922325 -398.083796) (xy 350.888483 -398.050707) (xy 350.860146 -398.012797) (xy 350.848676 -397.992092)
			(xy 350.848422 -397.99133) (xy 350.451166 -397.304006) (xy 350.438988 -397.280789) (xy 350.421872 -397.231239)
			(xy 350.41713 -397.205454) (xy 350.41713 -397.2052) (xy 350.413643 -397.181396) (xy 350.413431 -397.133285)
			(xy 349.85771 -397.133285) (xy 350.18345 -397.696944) (xy 350.183704 -397.697452) (xy 350.183958 -397.697452)
			(xy 350.185228 -397.699992) (xy 350.197501 -397.722907) (xy 350.214906 -397.771885) (xy 350.22378 -397.823101)
			(xy 350.224344 -397.84909) (xy 350.224344 -397.849344) (xy 350.223902 -397.873349) (xy 350.216382 -397.920767)
			(xy 350.201534 -397.966424) (xy 350.179724 -398.009195) (xy 350.15149 -398.048026) (xy 350.117526 -398.08196)
			(xy 350.078671 -398.110161) (xy 350.035882 -398.131934) (xy 349.990212 -398.146743) (xy 349.942788 -398.154222)
			(xy 349.918782 -398.154652) (xy 349.895117 -398.154227) (xy 349.848355 -398.146914) (xy 349.80328 -398.13248)
			(xy 349.760967 -398.111272) (xy 349.722429 -398.083795) (xy 349.688587 -398.050706) (xy 349.66025 -398.012797)
			(xy 349.64878 -397.992092) (xy 349.648526 -397.99133) (xy 349.25127 -397.304006) (xy 349.239093 -397.280789)
			(xy 349.221977 -397.231238) (xy 349.217234 -397.205454) (xy 349.217234 -397.2052) (xy 349.213739 -397.181396)
			(xy 349.213528 -397.133285) (xy 348.657814 -397.133285) (xy 348.983554 -397.696944) (xy 348.983808 -397.697452)
			(xy 348.984062 -397.697452) (xy 348.985332 -397.699992) (xy 348.997606 -397.722907) (xy 349.015011 -397.771885)
			(xy 349.023884 -397.823101) (xy 349.024448 -397.84909) (xy 349.024448 -397.849344) (xy 349.024002 -397.873349)
			(xy 349.016482 -397.920767) (xy 349.001634 -397.966423) (xy 348.979825 -398.009194) (xy 348.951591 -398.048025)
			(xy 348.917628 -398.081959) (xy 348.878773 -398.11016) (xy 348.835984 -398.131933) (xy 348.790315 -398.146742)
			(xy 348.742891 -398.154222) (xy 348.718886 -398.154652) (xy 348.695221 -398.154224) (xy 348.64846 -398.146911)
			(xy 348.603384 -398.132478) (xy 348.561072 -398.11127) (xy 348.522534 -398.083794) (xy 348.488692 -398.050705)
			(xy 348.460354 -398.012796) (xy 348.448884 -397.992092) (xy 348.44863 -397.99133) (xy 348.051374 -397.304006)
			(xy 348.039197 -397.280788) (xy 348.022081 -397.231238) (xy 348.017338 -397.205454) (xy 348.017338 -397.2052)
			(xy 348.013836 -397.181397) (xy 348.013624 -397.133286) (xy 347.457665 -397.133286) (xy 347.783404 -397.696944)
			(xy 347.783658 -397.697452) (xy 347.783912 -397.697452) (xy 347.785182 -397.699992) (xy 347.797412 -397.722918)
			(xy 347.814734 -397.771903) (xy 347.823522 -397.823111) (xy 347.824044 -397.84909) (xy 347.824044 -397.849344)
			(xy 347.823578 -397.873335) (xy 347.816067 -397.920724) (xy 347.801235 -397.966356) (xy 347.779449 -398.009106)
			(xy 347.751245 -398.047923) (xy 347.717317 -398.08185) (xy 347.678499 -398.110054) (xy 347.635749 -398.131838)
			(xy 347.590117 -398.146668) (xy 347.542727 -398.154179) (xy 347.518736 -398.154652) (xy 347.495073 -398.154184)
			(xy 347.448313 -398.146878) (xy 347.403238 -398.132453) (xy 347.360926 -398.111251) (xy 347.322387 -398.083781)
			(xy 347.288544 -398.050698) (xy 347.260205 -398.012794) (xy 347.248734 -397.992092) (xy 347.24848 -397.99133)
			(xy 346.851224 -397.304006) (xy 346.839044 -397.28079) (xy 346.82193 -397.231239) (xy 346.817188 -397.205454)
			(xy 346.817188 -397.2052) (xy 346.813611 -397.179979) (xy 346.284753 -397.179979) (xy 346.583508 -397.696944)
			(xy 346.583762 -397.697452) (xy 346.584016 -397.697452) (xy 346.585286 -397.699992) (xy 346.597517 -397.722917)
			(xy 346.614838 -397.771902) (xy 346.623626 -397.823111) (xy 346.624148 -397.84909) (xy 346.624148 -397.849344)
			(xy 346.623678 -397.873334) (xy 346.616167 -397.920724) (xy 346.601336 -397.966355) (xy 346.57955 -398.009105)
			(xy 346.551346 -398.047922) (xy 346.517418 -398.081849) (xy 346.478602 -398.110052) (xy 346.435851 -398.131837)
			(xy 346.39022 -398.146668) (xy 346.34283 -398.154178) (xy 346.31884 -398.154652) (xy 346.295177 -398.15418)
			(xy 346.248417 -398.146876) (xy 346.203342 -398.132451) (xy 346.16103 -398.11125) (xy 346.122492 -398.08378)
			(xy 346.088648 -398.050698) (xy 346.060309 -398.012794) (xy 346.048838 -397.992092) (xy 346.048584 -397.99133)
			(xy 345.651328 -397.304006) (xy 345.639148 -397.28079) (xy 345.622034 -397.231239) (xy 345.617292 -397.205454)
			(xy 345.617292 -397.2052) (xy 345.613876 -397.181387) (xy 345.613665 -397.133284) (xy 345.057617 -397.133284)
			(xy 345.383358 -397.696944) (xy 345.383612 -397.697452) (xy 345.383866 -397.697452) (xy 345.385136 -397.699992)
			(xy 345.39741 -397.722906) (xy 345.414815 -397.771885) (xy 345.423688 -397.823101) (xy 345.424252 -397.84909)
			(xy 345.424252 -397.849344) (xy 345.423802 -397.873349) (xy 345.416282 -397.920766) (xy 345.401434 -397.966422)
			(xy 345.379625 -398.009193) (xy 345.351392 -398.048023) (xy 345.31743 -398.081957) (xy 345.278576 -398.110158)
			(xy 345.235787 -398.131932) (xy 345.190119 -398.146741) (xy 345.142695 -398.154222) (xy 345.11869 -398.154652)
			(xy 345.095025 -398.154221) (xy 345.048264 -398.146909) (xy 345.003188 -398.132476) (xy 344.960876 -398.111269)
			(xy 344.922338 -398.083793) (xy 344.888496 -398.050705) (xy 344.860158 -398.012796) (xy 344.848688 -397.992092)
			(xy 344.848434 -397.99133) (xy 344.451178 -397.304006) (xy 344.439001 -397.280788) (xy 344.421885 -397.231238)
			(xy 344.417142 -397.205454) (xy 344.417142 -397.2052) (xy 344.413632 -397.181398) (xy 344.413421 -397.133286)
			(xy 343.857723 -397.133286) (xy 344.183462 -397.696944) (xy 344.183716 -397.697452) (xy 344.18397 -397.697452)
			(xy 344.18524 -397.699992) (xy 344.197514 -397.722906) (xy 344.214919 -397.771885) (xy 344.223792 -397.823101)
			(xy 344.224356 -397.84909) (xy 344.224356 -397.849344) (xy 344.223902 -397.873349) (xy 344.216382 -397.920765)
			(xy 344.201535 -397.966421) (xy 344.179726 -398.009191) (xy 344.151493 -398.048022) (xy 344.117531 -398.081956)
			(xy 344.078678 -398.110157) (xy 344.03589 -398.131931) (xy 343.990222 -398.14674) (xy 343.942799 -398.154221)
			(xy 343.918794 -398.154652) (xy 343.895129 -398.154217) (xy 343.848368 -398.146906) (xy 343.803293 -398.132474)
			(xy 343.76098 -398.111267) (xy 343.722442 -398.083792) (xy 343.6886 -398.050704) (xy 343.660262 -398.012796)
			(xy 343.648792 -397.992092) (xy 343.648538 -397.99133) (xy 343.251282 -397.304006) (xy 343.239105 -397.280788)
			(xy 343.221989 -397.231238) (xy 343.217246 -397.205454) (xy 343.217246 -397.2052) (xy 343.213729 -397.181399)
			(xy 343.213517 -397.133286) (xy 342.657827 -397.133286) (xy 342.983566 -397.696944) (xy 342.98382 -397.697452)
			(xy 342.984074 -397.697452) (xy 342.985344 -397.699992) (xy 342.997619 -397.722906) (xy 343.015023 -397.771885)
			(xy 343.023896 -397.823101) (xy 343.02446 -397.84909) (xy 343.02446 -397.849344) (xy 343.024101 -397.873353)
			(xy 343.016579 -397.92078) (xy 343.001726 -397.966444) (xy 342.979909 -398.00922) (xy 342.951665 -398.048055)
			(xy 342.917691 -398.08199) (xy 342.878825 -398.11019) (xy 342.836023 -398.131958) (xy 342.790342 -398.146759)
			(xy 342.742908 -398.154228) (xy 342.718898 -398.154652) (xy 342.695234 -398.154214) (xy 342.648472 -398.146903)
			(xy 342.603397 -398.132472) (xy 342.561085 -398.111266) (xy 342.522547 -398.083791) (xy 342.488704 -398.050704)
			(xy 342.460366 -398.012796) (xy 342.448896 -397.992092) (xy 342.448642 -397.99133) (xy 342.051386 -397.304006)
			(xy 342.03921 -397.280788) (xy 342.022093 -397.231238) (xy 342.01735 -397.205454) (xy 342.01735 -397.2052)
			(xy 342.013825 -397.1814) (xy 342.013613 -397.133286) (xy 341.457677 -397.133286) (xy 341.783416 -397.696944)
			(xy 341.78367 -397.697452) (xy 341.783924 -397.697452) (xy 341.785194 -397.699992) (xy 341.797425 -397.722917)
			(xy 341.814746 -397.771902) (xy 341.823534 -397.823111) (xy 341.824056 -397.84909) (xy 341.824056 -397.849344)
			(xy 341.823578 -397.873334) (xy 341.816067 -397.920723) (xy 341.801236 -397.966353) (xy 341.779452 -398.009103)
			(xy 341.751249 -398.047919) (xy 341.717322 -398.081846) (xy 341.678506 -398.11005) (xy 341.635757 -398.131835)
			(xy 341.590127 -398.146666) (xy 341.542738 -398.154178) (xy 341.518748 -398.154652) (xy 341.495085 -398.154174)
			(xy 341.448326 -398.146871) (xy 341.403251 -398.132447) (xy 341.360939 -398.111247) (xy 341.3224 -398.083778)
			(xy 341.288557 -398.050697) (xy 341.260217 -398.012794) (xy 341.248746 -397.992092) (xy 341.248492 -397.99133)
			(xy 340.851236 -397.304006) (xy 340.839056 -397.28079) (xy 340.821942 -397.231239) (xy 340.8172 -397.205454)
			(xy 340.8172 -397.2052) (xy 340.813769 -397.181389) (xy 340.813558 -397.133284) (xy 340.257779 -397.133284)
			(xy 340.58352 -397.696944) (xy 340.583774 -397.697452) (xy 340.584028 -397.697452) (xy 340.585298 -397.699992)
			(xy 340.597529 -397.722917) (xy 340.61485 -397.771902) (xy 340.623638 -397.823111) (xy 340.62416 -397.84909)
			(xy 340.62416 -397.849344) (xy 340.623802 -397.873341) (xy 340.616287 -397.920742) (xy 340.60145 -397.966385)
			(xy 340.579655 -398.009144) (xy 340.551439 -398.047968) (xy 340.517498 -398.081899) (xy 340.478666 -398.110103)
			(xy 340.4359 -398.131885) (xy 340.390253 -398.146709) (xy 340.342849 -398.154209) (xy 340.318852 -398.154652)
			(xy 340.295189 -398.154171) (xy 340.24843 -398.146868) (xy 340.203356 -398.132445) (xy 340.161043 -398.111245)
			(xy 340.122505 -398.083777) (xy 340.088661 -398.050696) (xy 340.060321 -398.012793) (xy 340.04885 -397.992092)
			(xy 340.048596 -397.99133) (xy 339.65134 -397.304006) (xy 339.639161 -397.28079) (xy 339.622046 -397.231239)
			(xy 339.617304 -397.205454) (xy 339.617304 -397.2052) (xy 339.613866 -397.18139) (xy 339.613655 -397.133284)
			(xy 339.057629 -397.133284) (xy 339.38337 -397.696944) (xy 339.383624 -397.697452) (xy 339.383878 -397.697452)
			(xy 339.385148 -397.699992) (xy 339.397423 -397.722906) (xy 339.414827 -397.771885) (xy 339.4237 -397.823101)
			(xy 339.424264 -397.84909) (xy 339.424264 -397.849344) (xy 339.423901 -397.873353) (xy 339.416379 -397.920779)
			(xy 339.401526 -397.966443) (xy 339.379709 -398.009219) (xy 339.351466 -398.048053) (xy 339.317493 -398.081989)
			(xy 339.278627 -398.110188) (xy 339.235826 -398.131957) (xy 339.190146 -398.146759) (xy 339.142712 -398.154228)
			(xy 339.118702 -398.154652) (xy 339.095038 -398.154211) (xy 339.048277 -398.146901) (xy 339.003201 -398.13247)
			(xy 338.960889 -398.111264) (xy 338.922351 -398.08379) (xy 338.888508 -398.050703) (xy 338.86017 -398.012796)
			(xy 338.8487 -397.992092) (xy 338.848446 -397.99133) (xy 338.45119 -397.304006) (xy 338.439014 -397.280788)
			(xy 338.421897 -397.231238) (xy 338.417154 -397.205454) (xy 338.417154 -397.2052) (xy 338.413622 -397.181401)
			(xy 338.41341 -397.133286) (xy 337.857735 -397.133286) (xy 338.183474 -397.696944) (xy 338.183728 -397.697452)
			(xy 338.183982 -397.697452) (xy 338.185252 -397.699992) (xy 338.197527 -397.722906) (xy 338.214931 -397.771885)
			(xy 338.223804 -397.823101) (xy 338.224368 -397.84909) (xy 338.224368 -397.849344) (xy 338.224001 -397.873353)
			(xy 338.216479 -397.920778) (xy 338.201626 -397.966442) (xy 338.17981 -398.009218) (xy 338.151567 -398.048052)
			(xy 338.117595 -398.081987) (xy 338.078729 -398.110187) (xy 338.035929 -398.131956) (xy 337.990249 -398.146758)
			(xy 337.942816 -398.154228) (xy 337.918806 -398.154652) (xy 337.895142 -398.154208) (xy 337.848381 -398.146898)
			(xy 337.803306 -398.132468) (xy 337.760993 -398.111263) (xy 337.722455 -398.083789) (xy 337.688613 -398.050703)
			(xy 337.660274 -398.012795) (xy 337.648804 -397.992092) (xy 337.64855 -397.99133) (xy 337.251294 -397.304006)
			(xy 337.239112 -397.280791) (xy 337.221999 -397.231239) (xy 337.217258 -397.205454) (xy 337.217258 -397.2052)
			(xy 337.213718 -397.181402) (xy 337.213506 -397.133287) (xy 336.657839 -397.133287) (xy 336.983578 -397.696944)
			(xy 336.983832 -397.697452) (xy 336.984086 -397.697452) (xy 336.985356 -397.699992) (xy 336.997631 -397.722906)
			(xy 337.015035 -397.771885) (xy 337.023908 -397.823101) (xy 337.024472 -397.84909) (xy 337.024472 -397.849344)
			(xy 337.024101 -397.873353) (xy 337.016579 -397.920778) (xy 337.001727 -397.966441) (xy 336.979911 -398.009217)
			(xy 336.951668 -398.048051) (xy 336.917696 -398.081986) (xy 336.878831 -398.110185) (xy 336.836032 -398.131955)
			(xy 336.790352 -398.146757) (xy 336.742919 -398.154228) (xy 336.71891 -398.154652) (xy 336.695246 -398.154205)
			(xy 336.648485 -398.146896) (xy 336.60341 -398.132466) (xy 336.561098 -398.111261) (xy 336.522559 -398.083788)
			(xy 336.488717 -398.050702) (xy 336.460378 -398.012795) (xy 336.448908 -397.992092) (xy 336.448654 -397.99133)
			(xy 336.051398 -397.304006) (xy 336.039216 -397.280791) (xy 336.022103 -397.231239) (xy 336.017362 -397.205454)
			(xy 336.017362 -397.2052) (xy 336.013815 -397.181402) (xy 336.013603 -397.133287) (xy 322.129999 -397.133287)
			(xy 322.455794 -397.696944) (xy 322.468605 -397.720283) (xy 322.486829 -397.770303) (xy 322.496095 -397.822726)
			(xy 322.496688 -397.849344) (xy 322.496301 -397.873352) (xy 322.48878 -397.920775) (xy 322.473928 -397.966437)
			(xy 322.452114 -398.009212) (xy 322.423873 -398.048045) (xy 322.389903 -398.08198) (xy 322.35104 -398.11018)
			(xy 322.308243 -398.13195) (xy 322.262566 -398.146754) (xy 322.215134 -398.154226) (xy 322.191126 -398.154652)
			(xy 322.167554 -398.15421) (xy 322.120969 -398.146974) (xy 322.076053 -398.132654) (xy 322.033876 -398.111593)
			(xy 321.995443 -398.084292) (xy 321.961669 -398.051401) (xy 321.933359 -398.013704) (xy 321.921886 -397.993108)
			(xy 321.921378 -397.992346) (xy 321.523614 -397.304006) (xy 321.511735 -397.281331) (xy 321.494886 -397.232997)
			(xy 321.486314 -397.182533) (xy 321.485768 -397.15694) (xy 320.94352 -397.15694) (xy 321.255644 -397.696944)
			(xy 321.26838 -397.720308) (xy 321.286493 -397.770337) (xy 321.295702 -397.822741) (xy 321.296284 -397.849344)
			(xy 321.295878 -397.873338) (xy 321.288364 -397.920733) (xy 321.27353 -397.96637) (xy 321.251738 -398.009124)
			(xy 321.223528 -398.047943) (xy 321.189592 -398.081872) (xy 321.150766 -398.110074) (xy 321.108007 -398.131856)
			(xy 321.062367 -398.14668) (xy 321.01497 -398.154183) (xy 320.990976 -398.154652) (xy 320.967403 -398.15425)
			(xy 320.920816 -398.147007) (xy 320.875899 -398.13268) (xy 320.833722 -398.111612) (xy 320.795289 -398.084305)
			(xy 320.761516 -398.051408) (xy 320.733208 -398.013706) (xy 320.721736 -397.993108) (xy 320.721228 -397.992346)
			(xy 320.323464 -397.304006) (xy 320.311554 -397.281335) (xy 320.294614 -397.233011) (xy 320.285952 -397.182542)
			(xy 320.285364 -397.15694) (xy 319.743624 -397.15694) (xy 320.055748 -397.696944) (xy 320.068484 -397.720308)
			(xy 320.086597 -397.770337) (xy 320.095806 -397.822741) (xy 320.096388 -397.849344) (xy 320.095978 -397.873337)
			(xy 320.088465 -397.920733) (xy 320.07363 -397.966369) (xy 320.051839 -398.009123) (xy 320.023629 -398.047942)
			(xy 319.989693 -398.08187) (xy 319.950868 -398.110073) (xy 319.90811 -398.131854) (xy 319.86247 -398.14668)
			(xy 319.815074 -398.154183) (xy 319.79108 -398.154652) (xy 319.767507 -398.154247) (xy 319.72092 -398.147004)
			(xy 319.676003 -398.132678) (xy 319.633826 -398.111611) (xy 319.595393 -398.084304) (xy 319.561621 -398.051407)
			(xy 319.533312 -398.013706) (xy 319.52184 -397.993108) (xy 319.521332 -397.992346) (xy 319.123568 -397.304006)
			(xy 319.111658 -397.281335) (xy 319.094718 -397.233011) (xy 319.086056 -397.182542) (xy 319.085468 -397.15694)
			(xy 318.543474 -397.15694) (xy 318.855598 -397.696944) (xy 318.868401 -397.720288) (xy 318.88663 -397.770305)
			(xy 318.895899 -397.822727) (xy 318.896492 -397.849344) (xy 318.896101 -397.873352) (xy 318.88858 -397.920775)
			(xy 318.873729 -397.966436) (xy 318.851914 -398.009211) (xy 318.823674 -398.048044) (xy 318.789705 -398.081979)
			(xy 318.750842 -398.110179) (xy 318.708046 -398.131949) (xy 318.662369 -398.146753) (xy 318.614938 -398.154226)
			(xy 318.59093 -398.154652) (xy 318.567358 -398.154207) (xy 318.520774 -398.146971) (xy 318.475858 -398.132652)
			(xy 318.43368 -398.111592) (xy 318.395247 -398.084291) (xy 318.361473 -398.0514) (xy 318.333163 -398.013704)
			(xy 318.32169 -397.993108) (xy 318.321182 -397.992346) (xy 317.923418 -397.304006) (xy 317.911539 -397.281331)
			(xy 317.89469 -397.232997) (xy 317.886118 -397.182533) (xy 317.885572 -397.15694) (xy 317.343578 -397.15694)
			(xy 317.655702 -397.696944) (xy 317.668505 -397.720288) (xy 317.686734 -397.770305) (xy 317.696003 -397.822727)
			(xy 317.696596 -397.849344) (xy 317.696201 -397.873352) (xy 317.68868 -397.920774) (xy 317.673829 -397.966435)
			(xy 317.652015 -398.009209) (xy 317.623775 -398.048042) (xy 317.589806 -398.081977) (xy 317.550945 -398.110177)
			(xy 317.508148 -398.131948) (xy 317.462472 -398.146752) (xy 317.415042 -398.154226) (xy 317.391034 -398.154652)
			(xy 317.367462 -398.154203) (xy 317.320878 -398.146969) (xy 317.275962 -398.13265) (xy 317.233785 -398.11159)
			(xy 317.195351 -398.08429) (xy 317.161577 -398.0514) (xy 317.133267 -398.013703) (xy 317.121794 -397.993108)
			(xy 317.121286 -397.992346) (xy 316.723522 -397.304006) (xy 316.711643 -397.281331) (xy 316.694794 -397.232996)
			(xy 316.686222 -397.182533) (xy 316.685676 -397.15694) (xy 316.143682 -397.15694) (xy 316.455806 -397.696944)
			(xy 316.46861 -397.720287) (xy 316.486838 -397.770304) (xy 316.496107 -397.822727) (xy 316.4967 -397.849344)
			(xy 316.496301 -397.873351) (xy 316.48878 -397.920774) (xy 316.47393 -397.966434) (xy 316.452116 -398.009208)
			(xy 316.423877 -398.048041) (xy 316.389908 -398.081976) (xy 316.351047 -398.110176) (xy 316.308251 -398.131947)
			(xy 316.262576 -398.146752) (xy 316.215146 -398.154225) (xy 316.191138 -398.154652) (xy 316.167566 -398.1542)
			(xy 316.120982 -398.146966) (xy 316.076066 -398.132648) (xy 316.033889 -398.111589) (xy 315.995456 -398.084289)
			(xy 315.961681 -398.051399) (xy 315.933371 -398.013703) (xy 315.921898 -397.993108) (xy 315.92139 -397.992346)
			(xy 315.523626 -397.304006) (xy 315.511747 -397.28133) (xy 315.494898 -397.232996) (xy 315.486326 -397.182533)
			(xy 315.48578 -397.15694) (xy 314.943532 -397.15694) (xy 315.255656 -397.696944) (xy 315.268393 -397.720307)
			(xy 315.286506 -397.770337) (xy 315.295714 -397.822741) (xy 315.296296 -397.849344) (xy 315.295878 -397.873337)
			(xy 315.288365 -397.920731) (xy 315.273531 -397.966367) (xy 315.251741 -398.009121) (xy 315.223531 -398.047939)
			(xy 315.189597 -398.081868) (xy 315.150773 -398.11007) (xy 315.108015 -398.131852) (xy 315.062377 -398.146678)
			(xy 315.014981 -398.154182) (xy 314.990988 -398.154652) (xy 314.967415 -398.154241) (xy 314.920829 -398.146999)
			(xy 314.875912 -398.132674) (xy 314.833735 -398.111608) (xy 314.795302 -398.084301) (xy 314.761529 -398.051406)
			(xy 314.733221 -398.013705) (xy 314.721748 -397.993108) (xy 314.72124 -397.992346) (xy 314.323476 -397.304006)
			(xy 314.311559 -397.281339) (xy 314.294623 -397.233013) (xy 314.285963 -397.182542) (xy 314.285376 -397.15694)
			(xy 313.743636 -397.15694) (xy 314.05576 -397.696944) (xy 314.068497 -397.720307) (xy 314.08661 -397.770337)
			(xy 314.095818 -397.822741) (xy 314.0964 -397.849344) (xy 314.095978 -397.873337) (xy 314.088465 -397.920731)
			(xy 314.073631 -397.966366) (xy 314.051841 -398.009119) (xy 314.023632 -398.047938) (xy 313.989698 -398.081866)
			(xy 313.950875 -398.110069) (xy 313.908118 -398.131851) (xy 313.86248 -398.146677) (xy 313.815085 -398.154182)
			(xy 313.791092 -398.154652) (xy 313.767519 -398.154237) (xy 313.720933 -398.146996) (xy 313.676016 -398.132672)
			(xy 313.633839 -398.111606) (xy 313.595406 -398.0843) (xy 313.561633 -398.051406) (xy 313.533325 -398.013705)
			(xy 313.521852 -397.993108) (xy 313.521344 -397.992346) (xy 313.12358 -397.304006) (xy 313.111663 -397.281339)
			(xy 313.094727 -397.233013) (xy 313.086067 -397.182542) (xy 313.08548 -397.15694) (xy 312.543486 -397.15694)
			(xy 312.85561 -397.696944) (xy 312.868414 -397.720287) (xy 312.886643 -397.770304) (xy 312.895911 -397.822727)
			(xy 312.896504 -397.849344) (xy 312.896101 -397.873351) (xy 312.88858 -397.920773) (xy 312.87373 -397.966433)
			(xy 312.851917 -398.009207) (xy 312.823678 -398.04804) (xy 312.78971 -398.081974) (xy 312.750849 -398.110175)
			(xy 312.708054 -398.131946) (xy 312.662379 -398.146751) (xy 312.61495 -398.154225) (xy 312.590942 -398.154652)
			(xy 312.567371 -398.154197) (xy 312.520786 -398.146963) (xy 312.475871 -398.132646) (xy 312.433693 -398.111587)
			(xy 312.39526 -398.084288) (xy 312.361486 -398.051398) (xy 312.333176 -398.013703) (xy 312.321702 -397.993108)
			(xy 312.321194 -397.992346) (xy 311.92343 -397.304006) (xy 311.911552 -397.28133) (xy 311.894702 -397.232996)
			(xy 311.88613 -397.182533) (xy 311.885584 -397.15694) (xy 311.34359 -397.15694) (xy 311.655714 -397.696944)
			(xy 311.668518 -397.720287) (xy 311.686747 -397.770304) (xy 311.696015 -397.822727) (xy 311.696608 -397.849344)
			(xy 311.696201 -397.873351) (xy 311.68868 -397.920772) (xy 311.67383 -397.966432) (xy 311.652017 -398.009206)
			(xy 311.623779 -398.048038) (xy 311.589811 -398.081973) (xy 311.550951 -398.110173) (xy 311.508157 -398.131944)
			(xy 311.462482 -398.14675) (xy 311.415053 -398.154225) (xy 311.391046 -398.154652) (xy 311.367475 -398.154194)
			(xy 311.320891 -398.146961) (xy 311.275975 -398.132644) (xy 311.233798 -398.111586) (xy 311.195364 -398.084287)
			(xy 311.16159 -398.051398) (xy 311.13328 -398.013703) (xy 311.121806 -397.993108) (xy 311.121298 -397.992346)
			(xy 310.723534 -397.304006) (xy 310.711656 -397.28133) (xy 310.694806 -397.232996) (xy 310.686234 -397.182533)
			(xy 310.685688 -397.15694) (xy 310.143694 -397.15694) (xy 310.455818 -397.696944) (xy 310.468623 -397.720287)
			(xy 310.486851 -397.770304) (xy 310.496119 -397.822727) (xy 310.496712 -397.849344) (xy 310.496302 -397.873351)
			(xy 310.48878 -397.920772) (xy 310.473931 -397.966432) (xy 310.452118 -398.009205) (xy 310.42388 -398.048037)
			(xy 310.389913 -398.081971) (xy 310.351053 -398.110172) (xy 310.308259 -398.131943) (xy 310.262586 -398.146749)
			(xy 310.215157 -398.154225) (xy 310.19115 -398.154652) (xy 310.167579 -398.154191) (xy 310.120995 -398.146958)
			(xy 310.076079 -398.132642) (xy 310.033902 -398.111584) (xy 309.995468 -398.084286) (xy 309.961694 -398.051397)
			(xy 309.933384 -398.013703) (xy 309.92191 -397.993108) (xy 309.921402 -397.992346) (xy 309.523638 -397.304006)
			(xy 309.51176 -397.28133) (xy 309.494911 -397.232996) (xy 309.486338 -397.182533) (xy 309.485792 -397.15694)
			(xy 308.943544 -397.15694) (xy 309.255668 -397.696944) (xy 309.268406 -397.720307) (xy 309.286518 -397.770336)
			(xy 309.295726 -397.822741) (xy 309.296308 -397.849344) (xy 309.295878 -397.873336) (xy 309.288365 -397.92073)
			(xy 309.273532 -397.966364) (xy 309.251743 -398.009117) (xy 309.223535 -398.047935) (xy 309.189602 -398.081863)
			(xy 309.150779 -398.110066) (xy 309.108024 -398.131849) (xy 309.062387 -398.146676) (xy 309.014992 -398.154181)
			(xy 308.991 -398.154652) (xy 308.967427 -398.154231) (xy 308.920842 -398.146991) (xy 308.875925 -398.132668)
			(xy 308.833748 -398.111603) (xy 308.795315 -398.084298) (xy 308.761542 -398.051404) (xy 308.733233 -398.013705)
			(xy 308.72176 -397.993108) (xy 308.721252 -397.992346) (xy 308.323488 -397.304006) (xy 308.311572 -397.281338)
			(xy 308.294635 -397.233013) (xy 308.285975 -397.182542) (xy 308.285388 -397.15694) (xy 307.743648 -397.15694)
			(xy 308.055772 -397.696944) (xy 308.06851 -397.720307) (xy 308.086622 -397.770336) (xy 308.09583 -397.822741)
			(xy 308.096412 -397.849344) (xy 308.095978 -397.873336) (xy 308.088465 -397.920729) (xy 308.073632 -397.966363)
			(xy 308.051844 -398.009116) (xy 308.023636 -398.047934) (xy 307.989703 -398.081862) (xy 307.950882 -398.110065)
			(xy 307.908126 -398.131848) (xy 307.86249 -398.146675) (xy 307.815096 -398.154181) (xy 307.791104 -398.154652)
			(xy 307.767532 -398.154228) (xy 307.720946 -398.146988) (xy 307.676029 -398.132666) (xy 307.633852 -398.111602)
			(xy 307.595419 -398.084297) (xy 307.561646 -398.051404) (xy 307.533337 -398.013705) (xy 307.521864 -397.993108)
			(xy 307.521356 -397.992346) (xy 307.123592 -397.304006) (xy 307.111676 -397.281338) (xy 307.094739 -397.233012)
			(xy 307.086079 -397.182542) (xy 307.085492 -397.15694) (xy 306.543498 -397.15694) (xy 306.855622 -397.696944)
			(xy 306.868427 -397.720287) (xy 306.886655 -397.770304) (xy 306.895923 -397.822727) (xy 306.896516 -397.849344)
			(xy 306.896102 -397.873351) (xy 306.888581 -397.920771) (xy 306.873731 -397.966431) (xy 306.851919 -398.009203)
			(xy 306.823681 -398.048036) (xy 306.789715 -398.08197) (xy 306.750856 -398.110171) (xy 306.708062 -398.131942)
			(xy 306.662389 -398.146748) (xy 306.614961 -398.154224) (xy 306.590954 -398.154652) (xy 306.567383 -398.154187)
			(xy 306.520799 -398.146955) (xy 306.475884 -398.13264) (xy 306.433706 -398.111583) (xy 306.395273 -398.084285)
			(xy 306.361498 -398.051397) (xy 306.333188 -398.013702) (xy 306.321714 -397.993108) (xy 306.321206 -397.992346)
			(xy 305.923442 -397.304006) (xy 305.911565 -397.28133) (xy 305.894715 -397.232996) (xy 305.886142 -397.182533)
			(xy 305.885596 -397.15694) (xy 305.343602 -397.15694) (xy 305.655726 -397.696944) (xy 305.668531 -397.720286)
			(xy 305.686759 -397.770304) (xy 305.696027 -397.822727) (xy 305.69662 -397.849344) (xy 305.696202 -397.87335)
			(xy 305.688681 -397.920771) (xy 305.673831 -397.96643) (xy 305.652019 -398.009202) (xy 305.623782 -398.048034)
			(xy 305.589816 -398.081969) (xy 305.550958 -398.110169) (xy 305.508165 -398.131941) (xy 305.462492 -398.146748)
			(xy 305.415065 -398.154224) (xy 305.391058 -398.154652) (xy 305.367487 -398.154184) (xy 305.320904 -398.146953)
			(xy 305.275988 -398.132638) (xy 305.233811 -398.111581) (xy 305.195377 -398.084284) (xy 305.161602 -398.051396)
			(xy 305.133292 -398.013702) (xy 305.121818 -397.993108) (xy 305.12131 -397.992346) (xy 304.723546 -397.304006)
			(xy 304.711669 -397.28133) (xy 304.694819 -397.232996) (xy 304.686246 -397.182533) (xy 304.6857 -397.15694)
			(xy 304.143706 -397.15694) (xy 304.45583 -397.696944) (xy 304.468636 -397.720286) (xy 304.486863 -397.770304)
			(xy 304.496131 -397.822727) (xy 304.496724 -397.849344) (xy 304.496302 -397.87335) (xy 304.488781 -397.92077)
			(xy 304.473932 -397.966429) (xy 304.45212 -398.009201) (xy 304.423884 -398.048033) (xy 304.389918 -398.081967)
			(xy 304.35106 -398.110168) (xy 304.308268 -398.13194) (xy 304.262595 -398.146747) (xy 304.215169 -398.154224)
			(xy 304.191162 -398.154652) (xy 304.167591 -398.154181) (xy 304.121008 -398.14695) (xy 304.076092 -398.132636)
			(xy 304.033915 -398.11158) (xy 303.995481 -398.084283) (xy 303.961707 -398.051396) (xy 303.933396 -398.013702)
			(xy 303.921922 -397.993108) (xy 303.921414 -397.992346) (xy 303.52365 -397.304006) (xy 303.511773 -397.281329)
			(xy 303.494923 -397.232996) (xy 303.48635 -397.182533) (xy 303.485804 -397.15694) (xy 279.491975 -397.15694)
			(xy 279.537689 -397.171787) (xy 279.582155 -397.194425) (xy 279.622539 -397.223731) (xy 279.640538 -397.241014)
			(xy 280.592276 -398.192752) (xy 280.609591 -398.210724) (xy 280.638913 -398.251106) (xy 280.661557 -398.295577)
			(xy 280.676965 -398.343044) (xy 280.684758 -398.392336) (xy 280.68524 -398.417288) (xy 280.68524 -401.674838)
			(xy 303.434496 -401.674838) (xy 303.434496 -400.811238) (xy 303.434982 -400.783969) (xy 303.442744 -400.729985)
			(xy 303.458109 -400.677655) (xy 303.480766 -400.628045) (xy 303.510252 -400.582164) (xy 303.545967 -400.540947)
			(xy 303.587184 -400.505232) (xy 303.633065 -400.475746) (xy 303.682675 -400.453089) (xy 303.735005 -400.437724)
			(xy 303.788989 -400.429962) (xy 303.843527 -400.429962) (xy 303.897511 -400.437724) (xy 303.949841 -400.453089)
			(xy 303.999451 -400.475746) (xy 304.045332 -400.505232) (xy 304.086549 -400.540947) (xy 304.122264 -400.582164)
			(xy 304.15175 -400.628045) (xy 304.174407 -400.677655) (xy 304.189772 -400.729985) (xy 304.197534 -400.783969)
			(xy 304.19802 -400.811238) (xy 304.19802 -401.674838) (xy 304.634392 -401.674838) (xy 304.634392 -400.811238)
			(xy 304.634878 -400.783969) (xy 304.64264 -400.729985) (xy 304.658005 -400.677655) (xy 304.680662 -400.628045)
			(xy 304.710148 -400.582164) (xy 304.745863 -400.540947) (xy 304.78708 -400.505232) (xy 304.832961 -400.475746)
			(xy 304.882571 -400.453089) (xy 304.934901 -400.437724) (xy 304.988885 -400.429962) (xy 305.043423 -400.429962)
			(xy 305.097407 -400.437724) (xy 305.149737 -400.453089) (xy 305.199347 -400.475746) (xy 305.245228 -400.505232)
			(xy 305.286445 -400.540947) (xy 305.32216 -400.582164) (xy 305.351646 -400.628045) (xy 305.374303 -400.677655)
			(xy 305.389668 -400.729985) (xy 305.39743 -400.783969) (xy 305.397916 -400.811238) (xy 305.397916 -401.674838)
			(xy 305.834796 -401.674838) (xy 305.834796 -400.811238) (xy 305.835282 -400.783987) (xy 305.843038 -400.730039)
			(xy 305.858393 -400.677744) (xy 305.881035 -400.628167) (xy 305.910501 -400.582317) (xy 305.946192 -400.541126)
			(xy 305.987383 -400.505435) (xy 306.033233 -400.475969) (xy 306.08281 -400.453327) (xy 306.135105 -400.437972)
			(xy 306.189053 -400.430216) (xy 306.243555 -400.430216) (xy 306.297503 -400.437972) (xy 306.349798 -400.453327)
			(xy 306.399375 -400.475969) (xy 306.445225 -400.505435) (xy 306.486416 -400.541126) (xy 306.522107 -400.582317)
			(xy 306.551573 -400.628167) (xy 306.574215 -400.677744) (xy 306.58957 -400.730039) (xy 306.597326 -400.783987)
			(xy 306.597812 -400.811238) (xy 306.597812 -401.674838) (xy 307.034692 -401.674838) (xy 307.034692 -400.811238)
			(xy 307.035178 -400.783987) (xy 307.042934 -400.730039) (xy 307.058289 -400.677744) (xy 307.080931 -400.628167)
			(xy 307.110397 -400.582317) (xy 307.146088 -400.541126) (xy 307.187279 -400.505435) (xy 307.233129 -400.475969)
			(xy 307.282706 -400.453327) (xy 307.335001 -400.437972) (xy 307.388949 -400.430216) (xy 307.443451 -400.430216)
			(xy 307.497399 -400.437972) (xy 307.549694 -400.453327) (xy 307.599271 -400.475969) (xy 307.645121 -400.505435)
			(xy 307.686312 -400.541126) (xy 307.722003 -400.582317) (xy 307.751469 -400.628167) (xy 307.774111 -400.677744)
			(xy 307.789466 -400.730039) (xy 307.797222 -400.783987) (xy 307.797708 -400.811238) (xy 307.797708 -401.674838)
			(xy 308.234588 -401.674838) (xy 308.234588 -400.811238) (xy 308.235074 -400.783969) (xy 308.242836 -400.729985)
			(xy 308.258201 -400.677655) (xy 308.280858 -400.628045) (xy 308.310344 -400.582164) (xy 308.346059 -400.540947)
			(xy 308.387276 -400.505232) (xy 308.433157 -400.475746) (xy 308.482767 -400.453089) (xy 308.535097 -400.437724)
			(xy 308.589081 -400.429962) (xy 308.643619 -400.429962) (xy 308.697603 -400.437724) (xy 308.749933 -400.453089)
			(xy 308.799543 -400.475746) (xy 308.845424 -400.505232) (xy 308.886641 -400.540947) (xy 308.922356 -400.582164)
			(xy 308.951842 -400.628045) (xy 308.974499 -400.677655) (xy 308.989864 -400.729985) (xy 308.997626 -400.783969)
			(xy 308.998112 -400.811238) (xy 308.998112 -401.674838) (xy 309.434484 -401.674838) (xy 309.434484 -400.811238)
			(xy 309.43497 -400.783969) (xy 309.442732 -400.729985) (xy 309.458097 -400.677655) (xy 309.480754 -400.628045)
			(xy 309.51024 -400.582164) (xy 309.545955 -400.540947) (xy 309.587172 -400.505232) (xy 309.633053 -400.475746)
			(xy 309.682663 -400.453089) (xy 309.734993 -400.437724) (xy 309.788977 -400.429962) (xy 309.843515 -400.429962)
			(xy 309.897499 -400.437724) (xy 309.949829 -400.453089) (xy 309.999439 -400.475746) (xy 310.04532 -400.505232)
			(xy 310.086537 -400.540947) (xy 310.122252 -400.582164) (xy 310.151738 -400.628045) (xy 310.174395 -400.677655)
			(xy 310.18976 -400.729985) (xy 310.197522 -400.783969) (xy 310.198008 -400.811238) (xy 310.198008 -401.674838)
			(xy 310.634888 -401.674838) (xy 310.634888 -400.811238) (xy 310.635374 -400.783987) (xy 310.64313 -400.730039)
			(xy 310.658485 -400.677744) (xy 310.681127 -400.628167) (xy 310.710593 -400.582317) (xy 310.746284 -400.541126)
			(xy 310.787475 -400.505435) (xy 310.833325 -400.475969) (xy 310.882902 -400.453327) (xy 310.935197 -400.437972)
			(xy 310.989145 -400.430216) (xy 311.043647 -400.430216) (xy 311.097595 -400.437972) (xy 311.14989 -400.453327)
			(xy 311.199467 -400.475969) (xy 311.245317 -400.505435) (xy 311.286508 -400.541126) (xy 311.322199 -400.582317)
			(xy 311.351665 -400.628167) (xy 311.374307 -400.677744) (xy 311.389662 -400.730039) (xy 311.397418 -400.783987)
			(xy 311.397904 -400.811238) (xy 311.397904 -401.674838) (xy 311.834784 -401.674838) (xy 311.834784 -400.811238)
			(xy 311.83527 -400.783987) (xy 311.843026 -400.730039) (xy 311.858381 -400.677744) (xy 311.881023 -400.628167)
			(xy 311.910489 -400.582317) (xy 311.94618 -400.541126) (xy 311.987371 -400.505435) (xy 312.033221 -400.475969)
			(xy 312.082798 -400.453327) (xy 312.135093 -400.437972) (xy 312.189041 -400.430216) (xy 312.243543 -400.430216)
			(xy 312.297491 -400.437972) (xy 312.349786 -400.453327) (xy 312.399363 -400.475969) (xy 312.445213 -400.505435)
			(xy 312.486404 -400.541126) (xy 312.522095 -400.582317) (xy 312.551561 -400.628167) (xy 312.574203 -400.677744)
			(xy 312.589558 -400.730039) (xy 312.597314 -400.783987) (xy 312.5978 -400.811238) (xy 312.5978 -401.674838)
			(xy 313.03468 -401.674838) (xy 313.03468 -400.811238) (xy 313.035166 -400.783969) (xy 313.042928 -400.729985)
			(xy 313.058293 -400.677655) (xy 313.08095 -400.628045) (xy 313.110436 -400.582164) (xy 313.146151 -400.540947)
			(xy 313.187368 -400.505232) (xy 313.233249 -400.475746) (xy 313.282859 -400.453089) (xy 313.335189 -400.437724)
			(xy 313.389173 -400.429962) (xy 313.443711 -400.429962) (xy 313.497695 -400.437724) (xy 313.550025 -400.453089)
			(xy 313.599635 -400.475746) (xy 313.645516 -400.505232) (xy 313.686733 -400.540947) (xy 313.722448 -400.582164)
			(xy 313.751934 -400.628045) (xy 313.774591 -400.677655) (xy 313.789956 -400.729985) (xy 313.797718 -400.783969)
			(xy 313.798204 -400.811238) (xy 313.798204 -401.674838) (xy 314.234576 -401.674838) (xy 314.234576 -400.811238)
			(xy 314.235062 -400.783969) (xy 314.242824 -400.729985) (xy 314.258189 -400.677655) (xy 314.280846 -400.628045)
			(xy 314.310332 -400.582164) (xy 314.346047 -400.540947) (xy 314.387264 -400.505232) (xy 314.433145 -400.475746)
			(xy 314.482755 -400.453089) (xy 314.535085 -400.437724) (xy 314.589069 -400.429962) (xy 314.643607 -400.429962)
			(xy 314.697591 -400.437724) (xy 314.749921 -400.453089) (xy 314.799531 -400.475746) (xy 314.845412 -400.505232)
			(xy 314.886629 -400.540947) (xy 314.922344 -400.582164) (xy 314.95183 -400.628045) (xy 314.974487 -400.677655)
			(xy 314.989852 -400.729985) (xy 314.997614 -400.783969) (xy 314.9981 -400.811238) (xy 314.9981 -401.674838)
			(xy 315.43498 -401.674838) (xy 315.43498 -400.811238) (xy 315.435466 -400.783987) (xy 315.443222 -400.730039)
			(xy 315.458577 -400.677744) (xy 315.481219 -400.628167) (xy 315.510685 -400.582317) (xy 315.546376 -400.541126)
			(xy 315.587567 -400.505435) (xy 315.633417 -400.475969) (xy 315.682994 -400.453327) (xy 315.735289 -400.437972)
			(xy 315.789237 -400.430216) (xy 315.843739 -400.430216) (xy 315.897687 -400.437972) (xy 315.949982 -400.453327)
			(xy 315.999559 -400.475969) (xy 316.045409 -400.505435) (xy 316.0866 -400.541126) (xy 316.122291 -400.582317)
			(xy 316.151757 -400.628167) (xy 316.174399 -400.677744) (xy 316.189754 -400.730039) (xy 316.19751 -400.783987)
			(xy 316.197996 -400.811238) (xy 316.197996 -401.674838) (xy 316.634876 -401.674838) (xy 316.634876 -400.811238)
			(xy 316.635362 -400.783987) (xy 316.643118 -400.730039) (xy 316.658473 -400.677744) (xy 316.681115 -400.628167)
			(xy 316.710581 -400.582317) (xy 316.746272 -400.541126) (xy 316.787463 -400.505435) (xy 316.833313 -400.475969)
			(xy 316.88289 -400.453327) (xy 316.935185 -400.437972) (xy 316.989133 -400.430216) (xy 317.043635 -400.430216)
			(xy 317.097583 -400.437972) (xy 317.149878 -400.453327) (xy 317.199455 -400.475969) (xy 317.245305 -400.505435)
			(xy 317.286496 -400.541126) (xy 317.322187 -400.582317) (xy 317.351653 -400.628167) (xy 317.374295 -400.677744)
			(xy 317.38965 -400.730039) (xy 317.397406 -400.783987) (xy 317.397892 -400.811238) (xy 317.397892 -401.674838)
			(xy 317.834772 -401.674838) (xy 317.834772 -400.811238) (xy 317.835258 -400.783987) (xy 317.843014 -400.730039)
			(xy 317.858369 -400.677744) (xy 317.881011 -400.628167) (xy 317.910477 -400.582317) (xy 317.946168 -400.541126)
			(xy 317.987359 -400.505435) (xy 318.033209 -400.475969) (xy 318.082786 -400.453327) (xy 318.135081 -400.437972)
			(xy 318.189029 -400.430216) (xy 318.243531 -400.430216) (xy 318.297479 -400.437972) (xy 318.349774 -400.453327)
			(xy 318.399351 -400.475969) (xy 318.445201 -400.505435) (xy 318.486392 -400.541126) (xy 318.522083 -400.582317)
			(xy 318.551549 -400.628167) (xy 318.574191 -400.677744) (xy 318.589546 -400.730039) (xy 318.597302 -400.783987)
			(xy 318.597788 -400.811238) (xy 318.597788 -401.674838) (xy 319.034668 -401.674838) (xy 319.034668 -400.811238)
			(xy 319.035154 -400.783987) (xy 319.04291 -400.730039) (xy 319.058265 -400.677744) (xy 319.080907 -400.628167)
			(xy 319.110373 -400.582317) (xy 319.146064 -400.541126) (xy 319.187255 -400.505435) (xy 319.233105 -400.475969)
			(xy 319.282682 -400.453327) (xy 319.334977 -400.437972) (xy 319.388925 -400.430216) (xy 319.443427 -400.430216)
			(xy 319.497375 -400.437972) (xy 319.54967 -400.453327) (xy 319.599247 -400.475969) (xy 319.645097 -400.505435)
			(xy 319.686288 -400.541126) (xy 319.721979 -400.582317) (xy 319.751445 -400.628167) (xy 319.774087 -400.677744)
			(xy 319.789442 -400.730039) (xy 319.797198 -400.783987) (xy 319.797684 -400.811238) (xy 319.797684 -401.674838)
			(xy 320.234564 -401.674838) (xy 320.234564 -400.811238) (xy 320.23505 -400.783969) (xy 320.242812 -400.729985)
			(xy 320.258177 -400.677655) (xy 320.280834 -400.628045) (xy 320.31032 -400.582164) (xy 320.346035 -400.540947)
			(xy 320.387252 -400.505232) (xy 320.433133 -400.475746) (xy 320.482743 -400.453089) (xy 320.535073 -400.437724)
			(xy 320.589057 -400.429962) (xy 320.643595 -400.429962) (xy 320.697579 -400.437724) (xy 320.749909 -400.453089)
			(xy 320.799519 -400.475746) (xy 320.8454 -400.505232) (xy 320.886617 -400.540947) (xy 320.922332 -400.582164)
			(xy 320.951818 -400.628045) (xy 320.974475 -400.677655) (xy 320.98984 -400.729985) (xy 320.997602 -400.783969)
			(xy 320.998088 -400.811238) (xy 320.998088 -401.674838) (xy 321.43446 -401.674838) (xy 321.43446 -400.811238)
			(xy 321.434946 -400.783969) (xy 321.442708 -400.729985) (xy 321.458073 -400.677655) (xy 321.48073 -400.628045)
			(xy 321.510216 -400.582164) (xy 321.545931 -400.540947) (xy 321.587148 -400.505232) (xy 321.633029 -400.475746)
			(xy 321.682639 -400.453089) (xy 321.734969 -400.437724) (xy 321.788953 -400.429962) (xy 321.843491 -400.429962)
			(xy 321.897475 -400.437724) (xy 321.949805 -400.453089) (xy 321.999415 -400.475746) (xy 322.045296 -400.505232)
			(xy 322.086513 -400.540947) (xy 322.122228 -400.582164) (xy 322.151714 -400.628045) (xy 322.174371 -400.677655)
			(xy 322.189736 -400.729985) (xy 322.197498 -400.783969) (xy 322.197984 -400.811238) (xy 322.197984 -401.674838)
			(xy 335.962244 -401.674838) (xy 335.962244 -400.811238) (xy 335.96273 -400.783969) (xy 335.970492 -400.729985)
			(xy 335.985857 -400.677655) (xy 336.008514 -400.628045) (xy 336.038 -400.582164) (xy 336.073715 -400.540947)
			(xy 336.114932 -400.505232) (xy 336.160813 -400.475746) (xy 336.210423 -400.453089) (xy 336.262753 -400.437724)
			(xy 336.316737 -400.429962) (xy 336.371275 -400.429962) (xy 336.425259 -400.437724) (xy 336.477589 -400.453089)
			(xy 336.527199 -400.475746) (xy 336.57308 -400.505232) (xy 336.614297 -400.540947) (xy 336.650012 -400.582164)
			(xy 336.679498 -400.628045) (xy 336.702155 -400.677655) (xy 336.71752 -400.729985) (xy 336.725282 -400.783969)
			(xy 336.725768 -400.811238) (xy 336.725768 -401.674838) (xy 337.16214 -401.674838) (xy 337.16214 -400.811238)
			(xy 337.162626 -400.783969) (xy 337.170388 -400.729985) (xy 337.185753 -400.677655) (xy 337.20841 -400.628045)
			(xy 337.237896 -400.582164) (xy 337.273611 -400.540947) (xy 337.314828 -400.505232) (xy 337.360709 -400.475746)
			(xy 337.410319 -400.453089) (xy 337.462649 -400.437724) (xy 337.516633 -400.429962) (xy 337.571171 -400.429962)
			(xy 337.625155 -400.437724) (xy 337.677485 -400.453089) (xy 337.727095 -400.475746) (xy 337.772976 -400.505232)
			(xy 337.814193 -400.540947) (xy 337.849908 -400.582164) (xy 337.879394 -400.628045) (xy 337.902051 -400.677655)
			(xy 337.917416 -400.729985) (xy 337.925178 -400.783969) (xy 337.925664 -400.811238) (xy 337.925664 -401.674838)
			(xy 338.362544 -401.674838) (xy 338.362544 -400.811238) (xy 338.36303 -400.783987) (xy 338.370786 -400.730039)
			(xy 338.386141 -400.677744) (xy 338.408783 -400.628167) (xy 338.438249 -400.582317) (xy 338.47394 -400.541126)
			(xy 338.515131 -400.505435) (xy 338.560981 -400.475969) (xy 338.610558 -400.453327) (xy 338.662853 -400.437972)
			(xy 338.716801 -400.430216) (xy 338.771303 -400.430216) (xy 338.825251 -400.437972) (xy 338.877546 -400.453327)
			(xy 338.927123 -400.475969) (xy 338.972973 -400.505435) (xy 339.014164 -400.541126) (xy 339.049855 -400.582317)
			(xy 339.079321 -400.628167) (xy 339.101963 -400.677744) (xy 339.117318 -400.730039) (xy 339.125074 -400.783987)
			(xy 339.12556 -400.811238) (xy 339.12556 -401.674838) (xy 339.56244 -401.674838) (xy 339.56244 -400.811238)
			(xy 339.562926 -400.783987) (xy 339.570682 -400.730039) (xy 339.586037 -400.677744) (xy 339.608679 -400.628167)
			(xy 339.638145 -400.582317) (xy 339.673836 -400.541126) (xy 339.715027 -400.505435) (xy 339.760877 -400.475969)
			(xy 339.810454 -400.453327) (xy 339.862749 -400.437972) (xy 339.916697 -400.430216) (xy 339.971199 -400.430216)
			(xy 340.025147 -400.437972) (xy 340.077442 -400.453327) (xy 340.127019 -400.475969) (xy 340.172869 -400.505435)
			(xy 340.21406 -400.541126) (xy 340.249751 -400.582317) (xy 340.279217 -400.628167) (xy 340.301859 -400.677744)
			(xy 340.317214 -400.730039) (xy 340.32497 -400.783987) (xy 340.325456 -400.811238) (xy 340.325456 -401.674838)
			(xy 340.762336 -401.674838) (xy 340.762336 -400.811238) (xy 340.762822 -400.783969) (xy 340.770584 -400.729985)
			(xy 340.785949 -400.677655) (xy 340.808606 -400.628045) (xy 340.838092 -400.582164) (xy 340.873807 -400.540947)
			(xy 340.915024 -400.505232) (xy 340.960905 -400.475746) (xy 341.010515 -400.453089) (xy 341.062845 -400.437724)
			(xy 341.116829 -400.429962) (xy 341.171367 -400.429962) (xy 341.225351 -400.437724) (xy 341.277681 -400.453089)
			(xy 341.327291 -400.475746) (xy 341.373172 -400.505232) (xy 341.414389 -400.540947) (xy 341.450104 -400.582164)
			(xy 341.47959 -400.628045) (xy 341.502247 -400.677655) (xy 341.517612 -400.729985) (xy 341.525374 -400.783969)
			(xy 341.52586 -400.811238) (xy 341.52586 -401.674838) (xy 341.962232 -401.674838) (xy 341.962232 -400.811238)
			(xy 341.962718 -400.783969) (xy 341.97048 -400.729985) (xy 341.985845 -400.677655) (xy 342.008502 -400.628045)
			(xy 342.037988 -400.582164) (xy 342.073703 -400.540947) (xy 342.11492 -400.505232) (xy 342.160801 -400.475746)
			(xy 342.210411 -400.453089) (xy 342.262741 -400.437724) (xy 342.316725 -400.429962) (xy 342.371263 -400.429962)
			(xy 342.425247 -400.437724) (xy 342.477577 -400.453089) (xy 342.527187 -400.475746) (xy 342.573068 -400.505232)
			(xy 342.614285 -400.540947) (xy 342.65 -400.582164) (xy 342.679486 -400.628045) (xy 342.702143 -400.677655)
			(xy 342.717508 -400.729985) (xy 342.72527 -400.783969) (xy 342.725756 -400.811238) (xy 342.725756 -401.674838)
			(xy 343.162636 -401.674838) (xy 343.162636 -400.811238) (xy 343.163122 -400.783987) (xy 343.170878 -400.730039)
			(xy 343.186233 -400.677744) (xy 343.208875 -400.628167) (xy 343.238341 -400.582317) (xy 343.274032 -400.541126)
			(xy 343.315223 -400.505435) (xy 343.361073 -400.475969) (xy 343.41065 -400.453327) (xy 343.462945 -400.437972)
			(xy 343.516893 -400.430216) (xy 343.571395 -400.430216) (xy 343.625343 -400.437972) (xy 343.677638 -400.453327)
			(xy 343.727215 -400.475969) (xy 343.773065 -400.505435) (xy 343.814256 -400.541126) (xy 343.849947 -400.582317)
			(xy 343.879413 -400.628167) (xy 343.902055 -400.677744) (xy 343.91741 -400.730039) (xy 343.925166 -400.783987)
			(xy 343.925652 -400.811238) (xy 343.925652 -401.674838) (xy 344.362532 -401.674838) (xy 344.362532 -400.811238)
			(xy 344.363018 -400.783987) (xy 344.370774 -400.730039) (xy 344.386129 -400.677744) (xy 344.408771 -400.628167)
			(xy 344.438237 -400.582317) (xy 344.473928 -400.541126) (xy 344.515119 -400.505435) (xy 344.560969 -400.475969)
			(xy 344.610546 -400.453327) (xy 344.662841 -400.437972) (xy 344.716789 -400.430216) (xy 344.771291 -400.430216)
			(xy 344.825239 -400.437972) (xy 344.877534 -400.453327) (xy 344.927111 -400.475969) (xy 344.972961 -400.505435)
			(xy 345.014152 -400.541126) (xy 345.049843 -400.582317) (xy 345.079309 -400.628167) (xy 345.101951 -400.677744)
			(xy 345.117306 -400.730039) (xy 345.125062 -400.783987) (xy 345.125548 -400.811238) (xy 345.125548 -401.674838)
			(xy 345.562428 -401.674838) (xy 345.562428 -400.811238) (xy 345.562914 -400.783969) (xy 345.570676 -400.729985)
			(xy 345.586041 -400.677655) (xy 345.608698 -400.628045) (xy 345.638184 -400.582164) (xy 345.673899 -400.540947)
			(xy 345.715116 -400.505232) (xy 345.760997 -400.475746) (xy 345.810607 -400.453089) (xy 345.862937 -400.437724)
			(xy 345.916921 -400.429962) (xy 345.971459 -400.429962) (xy 346.025443 -400.437724) (xy 346.077773 -400.453089)
			(xy 346.127383 -400.475746) (xy 346.173264 -400.505232) (xy 346.214481 -400.540947) (xy 346.250196 -400.582164)
			(xy 346.279682 -400.628045) (xy 346.302339 -400.677655) (xy 346.317704 -400.729985) (xy 346.325466 -400.783969)
			(xy 346.325952 -400.811238) (xy 346.325952 -401.674838) (xy 346.762324 -401.674838) (xy 346.762324 -400.811238)
			(xy 346.76281 -400.783969) (xy 346.770572 -400.729985) (xy 346.785937 -400.677655) (xy 346.808594 -400.628045)
			(xy 346.83808 -400.582164) (xy 346.873795 -400.540947) (xy 346.915012 -400.505232) (xy 346.960893 -400.475746)
			(xy 347.010503 -400.453089) (xy 347.062833 -400.437724) (xy 347.116817 -400.429962) (xy 347.171355 -400.429962)
			(xy 347.225339 -400.437724) (xy 347.277669 -400.453089) (xy 347.327279 -400.475746) (xy 347.37316 -400.505232)
			(xy 347.414377 -400.540947) (xy 347.450092 -400.582164) (xy 347.479578 -400.628045) (xy 347.502235 -400.677655)
			(xy 347.5176 -400.729985) (xy 347.525362 -400.783969) (xy 347.525848 -400.811238) (xy 347.525848 -401.674838)
			(xy 347.962728 -401.674838) (xy 347.962728 -400.811238) (xy 347.963214 -400.783987) (xy 347.97097 -400.730039)
			(xy 347.986325 -400.677744) (xy 348.008967 -400.628167) (xy 348.038433 -400.582317) (xy 348.074124 -400.541126)
			(xy 348.115315 -400.505435) (xy 348.161165 -400.475969) (xy 348.210742 -400.453327) (xy 348.263037 -400.437972)
			(xy 348.316985 -400.430216) (xy 348.371487 -400.430216) (xy 348.425435 -400.437972) (xy 348.47773 -400.453327)
			(xy 348.527307 -400.475969) (xy 348.573157 -400.505435) (xy 348.614348 -400.541126) (xy 348.650039 -400.582317)
			(xy 348.679505 -400.628167) (xy 348.702147 -400.677744) (xy 348.717502 -400.730039) (xy 348.725258 -400.783987)
			(xy 348.725744 -400.811238) (xy 348.725744 -401.674838) (xy 349.162624 -401.674838) (xy 349.162624 -400.811238)
			(xy 349.16311 -400.783987) (xy 349.170866 -400.730039) (xy 349.186221 -400.677744) (xy 349.208863 -400.628167)
			(xy 349.238329 -400.582317) (xy 349.27402 -400.541126) (xy 349.315211 -400.505435) (xy 349.361061 -400.475969)
			(xy 349.410638 -400.453327) (xy 349.462933 -400.437972) (xy 349.516881 -400.430216) (xy 349.571383 -400.430216)
			(xy 349.625331 -400.437972) (xy 349.677626 -400.453327) (xy 349.727203 -400.475969) (xy 349.773053 -400.505435)
			(xy 349.814244 -400.541126) (xy 349.849935 -400.582317) (xy 349.879401 -400.628167) (xy 349.902043 -400.677744)
			(xy 349.917398 -400.730039) (xy 349.925154 -400.783987) (xy 349.92564 -400.811238) (xy 349.92564 -401.674838)
			(xy 350.36252 -401.674838) (xy 350.36252 -400.811238) (xy 350.363006 -400.783987) (xy 350.370762 -400.730039)
			(xy 350.386117 -400.677744) (xy 350.408759 -400.628167) (xy 350.438225 -400.582317) (xy 350.473916 -400.541126)
			(xy 350.515107 -400.505435) (xy 350.560957 -400.475969) (xy 350.610534 -400.453327) (xy 350.662829 -400.437972)
			(xy 350.716777 -400.430216) (xy 350.771279 -400.430216) (xy 350.825227 -400.437972) (xy 350.877522 -400.453327)
			(xy 350.927099 -400.475969) (xy 350.972949 -400.505435) (xy 351.01414 -400.541126) (xy 351.049831 -400.582317)
			(xy 351.079297 -400.628167) (xy 351.101939 -400.677744) (xy 351.117294 -400.730039) (xy 351.12505 -400.783987)
			(xy 351.125536 -400.811238) (xy 351.125536 -401.674838) (xy 351.562416 -401.674838) (xy 351.562416 -400.811238)
			(xy 351.562902 -400.783987) (xy 351.570658 -400.730039) (xy 351.586013 -400.677744) (xy 351.608655 -400.628167)
			(xy 351.638121 -400.582317) (xy 351.673812 -400.541126) (xy 351.715003 -400.505435) (xy 351.760853 -400.475969)
			(xy 351.81043 -400.453327) (xy 351.862725 -400.437972) (xy 351.916673 -400.430216) (xy 351.971175 -400.430216)
			(xy 352.025123 -400.437972) (xy 352.077418 -400.453327) (xy 352.126995 -400.475969) (xy 352.172845 -400.505435)
			(xy 352.214036 -400.541126) (xy 352.249727 -400.582317) (xy 352.279193 -400.628167) (xy 352.301835 -400.677744)
			(xy 352.31719 -400.730039) (xy 352.324946 -400.783987) (xy 352.325432 -400.811238) (xy 352.325432 -401.674838)
			(xy 352.762312 -401.674838) (xy 352.762312 -400.811238) (xy 352.762798 -400.783969) (xy 352.77056 -400.729985)
			(xy 352.785925 -400.677655) (xy 352.808582 -400.628045) (xy 352.838068 -400.582164) (xy 352.873783 -400.540947)
			(xy 352.915 -400.505232) (xy 352.960881 -400.475746) (xy 353.010491 -400.453089) (xy 353.062821 -400.437724)
			(xy 353.116805 -400.429962) (xy 353.171343 -400.429962) (xy 353.225327 -400.437724) (xy 353.277657 -400.453089)
			(xy 353.327267 -400.475746) (xy 353.373148 -400.505232) (xy 353.414365 -400.540947) (xy 353.45008 -400.582164)
			(xy 353.479566 -400.628045) (xy 353.502223 -400.677655) (xy 353.517588 -400.729985) (xy 353.52535 -400.783969)
			(xy 353.525836 -400.811238) (xy 353.525836 -401.674838) (xy 353.962208 -401.674838) (xy 353.962208 -400.811238)
			(xy 353.962694 -400.783969) (xy 353.970456 -400.729985) (xy 353.985821 -400.677655) (xy 354.008478 -400.628045)
			(xy 354.037964 -400.582164) (xy 354.073679 -400.540947) (xy 354.114896 -400.505232) (xy 354.160777 -400.475746)
			(xy 354.210387 -400.453089) (xy 354.262717 -400.437724) (xy 354.316701 -400.429962) (xy 354.371239 -400.429962)
			(xy 354.425223 -400.437724) (xy 354.477553 -400.453089) (xy 354.527163 -400.475746) (xy 354.573044 -400.505232)
			(xy 354.614261 -400.540947) (xy 354.649976 -400.582164) (xy 354.679462 -400.628045) (xy 354.702119 -400.677655)
			(xy 354.717484 -400.729985) (xy 354.725246 -400.783969) (xy 354.725732 -400.811238) (xy 354.725732 -401.674838)
			(xy 370.534692 -401.674838) (xy 370.534692 -400.811238) (xy 370.535178 -400.783969) (xy 370.54294 -400.729985)
			(xy 370.558305 -400.677655) (xy 370.580962 -400.628045) (xy 370.610448 -400.582164) (xy 370.646163 -400.540947)
			(xy 370.68738 -400.505232) (xy 370.733261 -400.475746) (xy 370.782871 -400.453089) (xy 370.835201 -400.437724)
			(xy 370.889185 -400.429962) (xy 370.943723 -400.429962) (xy 370.997707 -400.437724) (xy 371.050037 -400.453089)
			(xy 371.099647 -400.475746) (xy 371.145528 -400.505232) (xy 371.186745 -400.540947) (xy 371.22246 -400.582164)
			(xy 371.251946 -400.628045) (xy 371.274603 -400.677655) (xy 371.289968 -400.729985) (xy 371.29773 -400.783969)
			(xy 371.298216 -400.811238) (xy 371.298216 -401.674838) (xy 371.734588 -401.674838) (xy 371.734588 -400.811238)
			(xy 371.735074 -400.783969) (xy 371.742836 -400.729985) (xy 371.758201 -400.677655) (xy 371.780858 -400.628045)
			(xy 371.810344 -400.582164) (xy 371.846059 -400.540947) (xy 371.887276 -400.505232) (xy 371.933157 -400.475746)
			(xy 371.982767 -400.453089) (xy 372.035097 -400.437724) (xy 372.089081 -400.429962) (xy 372.143619 -400.429962)
			(xy 372.197603 -400.437724) (xy 372.249933 -400.453089) (xy 372.299543 -400.475746) (xy 372.345424 -400.505232)
			(xy 372.386641 -400.540947) (xy 372.422356 -400.582164) (xy 372.451842 -400.628045) (xy 372.474499 -400.677655)
			(xy 372.489864 -400.729985) (xy 372.497626 -400.783969) (xy 372.498112 -400.811238) (xy 372.498112 -401.674838)
			(xy 372.934992 -401.674838) (xy 372.934992 -400.811238) (xy 372.935478 -400.783987) (xy 372.943234 -400.730039)
			(xy 372.958589 -400.677744) (xy 372.981231 -400.628167) (xy 373.010697 -400.582317) (xy 373.046388 -400.541126)
			(xy 373.087579 -400.505435) (xy 373.133429 -400.475969) (xy 373.183006 -400.453327) (xy 373.235301 -400.437972)
			(xy 373.289249 -400.430216) (xy 373.343751 -400.430216) (xy 373.397699 -400.437972) (xy 373.449994 -400.453327)
			(xy 373.499571 -400.475969) (xy 373.545421 -400.505435) (xy 373.586612 -400.541126) (xy 373.622303 -400.582317)
			(xy 373.651769 -400.628167) (xy 373.674411 -400.677744) (xy 373.689766 -400.730039) (xy 373.697522 -400.783987)
			(xy 373.698008 -400.811238) (xy 373.698008 -401.674838) (xy 374.134888 -401.674838) (xy 374.134888 -400.811238)
			(xy 374.135374 -400.783987) (xy 374.14313 -400.730039) (xy 374.158485 -400.677744) (xy 374.181127 -400.628167)
			(xy 374.210593 -400.582317) (xy 374.246284 -400.541126) (xy 374.287475 -400.505435) (xy 374.333325 -400.475969)
			(xy 374.382902 -400.453327) (xy 374.435197 -400.437972) (xy 374.489145 -400.430216) (xy 374.543647 -400.430216)
			(xy 374.597595 -400.437972) (xy 374.64989 -400.453327) (xy 374.699467 -400.475969) (xy 374.745317 -400.505435)
			(xy 374.786508 -400.541126) (xy 374.822199 -400.582317) (xy 374.851665 -400.628167) (xy 374.874307 -400.677744)
			(xy 374.889662 -400.730039) (xy 374.897418 -400.783987) (xy 374.897904 -400.811238) (xy 374.897904 -401.674838)
			(xy 375.334784 -401.674838) (xy 375.334784 -400.811238) (xy 375.33527 -400.783969) (xy 375.343032 -400.729985)
			(xy 375.358397 -400.677655) (xy 375.381054 -400.628045) (xy 375.41054 -400.582164) (xy 375.446255 -400.540947)
			(xy 375.487472 -400.505232) (xy 375.533353 -400.475746) (xy 375.582963 -400.453089) (xy 375.635293 -400.437724)
			(xy 375.689277 -400.429962) (xy 375.743815 -400.429962) (xy 375.797799 -400.437724) (xy 375.850129 -400.453089)
			(xy 375.899739 -400.475746) (xy 375.94562 -400.505232) (xy 375.986837 -400.540947) (xy 376.022552 -400.582164)
			(xy 376.052038 -400.628045) (xy 376.074695 -400.677655) (xy 376.09006 -400.729985) (xy 376.097822 -400.783969)
			(xy 376.098308 -400.811238) (xy 376.098308 -401.674838) (xy 376.53468 -401.674838) (xy 376.53468 -400.811238)
			(xy 376.535166 -400.783969) (xy 376.542928 -400.729985) (xy 376.558293 -400.677655) (xy 376.58095 -400.628045)
			(xy 376.610436 -400.582164) (xy 376.646151 -400.540947) (xy 376.687368 -400.505232) (xy 376.733249 -400.475746)
			(xy 376.782859 -400.453089) (xy 376.835189 -400.437724) (xy 376.889173 -400.429962) (xy 376.943711 -400.429962)
			(xy 376.997695 -400.437724) (xy 377.050025 -400.453089) (xy 377.099635 -400.475746) (xy 377.145516 -400.505232)
			(xy 377.186733 -400.540947) (xy 377.222448 -400.582164) (xy 377.251934 -400.628045) (xy 377.274591 -400.677655)
			(xy 377.289956 -400.729985) (xy 377.297718 -400.783969) (xy 377.298204 -400.811238) (xy 377.298204 -401.674838)
			(xy 377.735084 -401.674838) (xy 377.735084 -400.811238) (xy 377.73557 -400.783987) (xy 377.743326 -400.730039)
			(xy 377.758681 -400.677744) (xy 377.781323 -400.628167) (xy 377.810789 -400.582317) (xy 377.84648 -400.541126)
			(xy 377.887671 -400.505435) (xy 377.933521 -400.475969) (xy 377.983098 -400.453327) (xy 378.035393 -400.437972)
			(xy 378.089341 -400.430216) (xy 378.143843 -400.430216) (xy 378.197791 -400.437972) (xy 378.250086 -400.453327)
			(xy 378.299663 -400.475969) (xy 378.345513 -400.505435) (xy 378.386704 -400.541126) (xy 378.422395 -400.582317)
			(xy 378.451861 -400.628167) (xy 378.474503 -400.677744) (xy 378.489858 -400.730039) (xy 378.497614 -400.783987)
			(xy 378.4981 -400.811238) (xy 378.4981 -401.674838) (xy 378.93498 -401.674838) (xy 378.93498 -400.811238)
			(xy 378.935466 -400.783987) (xy 378.943222 -400.730039) (xy 378.958577 -400.677744) (xy 378.981219 -400.628167)
			(xy 379.010685 -400.582317) (xy 379.046376 -400.541126) (xy 379.087567 -400.505435) (xy 379.133417 -400.475969)
			(xy 379.182994 -400.453327) (xy 379.235289 -400.437972) (xy 379.289237 -400.430216) (xy 379.343739 -400.430216)
			(xy 379.397687 -400.437972) (xy 379.449982 -400.453327) (xy 379.499559 -400.475969) (xy 379.545409 -400.505435)
			(xy 379.5866 -400.541126) (xy 379.622291 -400.582317) (xy 379.651757 -400.628167) (xy 379.674399 -400.677744)
			(xy 379.689754 -400.730039) (xy 379.69751 -400.783987) (xy 379.697996 -400.811238) (xy 379.697996 -401.674838)
			(xy 380.134876 -401.674838) (xy 380.134876 -400.811238) (xy 380.135362 -400.783969) (xy 380.143124 -400.729985)
			(xy 380.158489 -400.677655) (xy 380.181146 -400.628045) (xy 380.210632 -400.582164) (xy 380.246347 -400.540947)
			(xy 380.287564 -400.505232) (xy 380.333445 -400.475746) (xy 380.383055 -400.453089) (xy 380.435385 -400.437724)
			(xy 380.489369 -400.429962) (xy 380.543907 -400.429962) (xy 380.597891 -400.437724) (xy 380.650221 -400.453089)
			(xy 380.699831 -400.475746) (xy 380.745712 -400.505232) (xy 380.786929 -400.540947) (xy 380.822644 -400.582164)
			(xy 380.85213 -400.628045) (xy 380.874787 -400.677655) (xy 380.890152 -400.729985) (xy 380.897914 -400.783969)
			(xy 380.8984 -400.811238) (xy 380.8984 -401.674838) (xy 381.334772 -401.674838) (xy 381.334772 -400.811238)
			(xy 381.335258 -400.783969) (xy 381.34302 -400.729985) (xy 381.358385 -400.677655) (xy 381.381042 -400.628045)
			(xy 381.410528 -400.582164) (xy 381.446243 -400.540947) (xy 381.48746 -400.505232) (xy 381.533341 -400.475746)
			(xy 381.582951 -400.453089) (xy 381.635281 -400.437724) (xy 381.689265 -400.429962) (xy 381.743803 -400.429962)
			(xy 381.797787 -400.437724) (xy 381.850117 -400.453089) (xy 381.899727 -400.475746) (xy 381.945608 -400.505232)
			(xy 381.986825 -400.540947) (xy 382.02254 -400.582164) (xy 382.052026 -400.628045) (xy 382.074683 -400.677655)
			(xy 382.090048 -400.729985) (xy 382.09781 -400.783969) (xy 382.098296 -400.811238) (xy 382.098296 -401.674838)
			(xy 382.535176 -401.674838) (xy 382.535176 -400.811238) (xy 382.535662 -400.783987) (xy 382.543418 -400.730039)
			(xy 382.558773 -400.677744) (xy 382.581415 -400.628167) (xy 382.610881 -400.582317) (xy 382.646572 -400.541126)
			(xy 382.687763 -400.505435) (xy 382.733613 -400.475969) (xy 382.78319 -400.453327) (xy 382.835485 -400.437972)
			(xy 382.889433 -400.430216) (xy 382.943935 -400.430216) (xy 382.997883 -400.437972) (xy 383.050178 -400.453327)
			(xy 383.099755 -400.475969) (xy 383.145605 -400.505435) (xy 383.186796 -400.541126) (xy 383.222487 -400.582317)
			(xy 383.251953 -400.628167) (xy 383.274595 -400.677744) (xy 383.28995 -400.730039) (xy 383.297706 -400.783987)
			(xy 383.298192 -400.811238) (xy 383.298192 -401.674838) (xy 383.735072 -401.674838) (xy 383.735072 -400.811238)
			(xy 383.735558 -400.783987) (xy 383.743314 -400.730039) (xy 383.758669 -400.677744) (xy 383.781311 -400.628167)
			(xy 383.810777 -400.582317) (xy 383.846468 -400.541126) (xy 383.887659 -400.505435) (xy 383.933509 -400.475969)
			(xy 383.983086 -400.453327) (xy 384.035381 -400.437972) (xy 384.089329 -400.430216) (xy 384.143831 -400.430216)
			(xy 384.197779 -400.437972) (xy 384.250074 -400.453327) (xy 384.299651 -400.475969) (xy 384.345501 -400.505435)
			(xy 384.386692 -400.541126) (xy 384.422383 -400.582317) (xy 384.451849 -400.628167) (xy 384.474491 -400.677744)
			(xy 384.489846 -400.730039) (xy 384.497602 -400.783987) (xy 384.498088 -400.811238) (xy 384.498088 -401.674838)
			(xy 384.934968 -401.674838) (xy 384.934968 -400.811238) (xy 384.935454 -400.783987) (xy 384.94321 -400.730039)
			(xy 384.958565 -400.677744) (xy 384.981207 -400.628167) (xy 385.010673 -400.582317) (xy 385.046364 -400.541126)
			(xy 385.087555 -400.505435) (xy 385.133405 -400.475969) (xy 385.182982 -400.453327) (xy 385.235277 -400.437972)
			(xy 385.289225 -400.430216) (xy 385.343727 -400.430216) (xy 385.397675 -400.437972) (xy 385.44997 -400.453327)
			(xy 385.499547 -400.475969) (xy 385.545397 -400.505435) (xy 385.586588 -400.541126) (xy 385.622279 -400.582317)
			(xy 385.651745 -400.628167) (xy 385.674387 -400.677744) (xy 385.689742 -400.730039) (xy 385.697498 -400.783987)
			(xy 385.697984 -400.811238) (xy 385.697984 -401.674838) (xy 386.134864 -401.674838) (xy 386.134864 -400.811238)
			(xy 386.13535 -400.783987) (xy 386.143106 -400.730039) (xy 386.158461 -400.677744) (xy 386.181103 -400.628167)
			(xy 386.210569 -400.582317) (xy 386.24626 -400.541126) (xy 386.287451 -400.505435) (xy 386.333301 -400.475969)
			(xy 386.382878 -400.453327) (xy 386.435173 -400.437972) (xy 386.489121 -400.430216) (xy 386.543623 -400.430216)
			(xy 386.597571 -400.437972) (xy 386.649866 -400.453327) (xy 386.699443 -400.475969) (xy 386.745293 -400.505435)
			(xy 386.786484 -400.541126) (xy 386.822175 -400.582317) (xy 386.851641 -400.628167) (xy 386.874283 -400.677744)
			(xy 386.889638 -400.730039) (xy 386.897394 -400.783987) (xy 386.89788 -400.811238) (xy 386.89788 -401.674838)
			(xy 387.33476 -401.674838) (xy 387.33476 -400.811238) (xy 387.335246 -400.783969) (xy 387.343008 -400.729985)
			(xy 387.358373 -400.677655) (xy 387.38103 -400.628045) (xy 387.410516 -400.582164) (xy 387.446231 -400.540947)
			(xy 387.487448 -400.505232) (xy 387.533329 -400.475746) (xy 387.582939 -400.453089) (xy 387.635269 -400.437724)
			(xy 387.689253 -400.429962) (xy 387.743791 -400.429962) (xy 387.797775 -400.437724) (xy 387.850105 -400.453089)
			(xy 387.899715 -400.475746) (xy 387.945596 -400.505232) (xy 387.986813 -400.540947) (xy 388.022528 -400.582164)
			(xy 388.052014 -400.628045) (xy 388.074671 -400.677655) (xy 388.090036 -400.729985) (xy 388.097798 -400.783969)
			(xy 388.098284 -400.811238) (xy 388.098284 -401.674838) (xy 388.534656 -401.674838) (xy 388.534656 -400.811238)
			(xy 388.535142 -400.783969) (xy 388.542904 -400.729985) (xy 388.558269 -400.677655) (xy 388.580926 -400.628045)
			(xy 388.610412 -400.582164) (xy 388.646127 -400.540947) (xy 388.687344 -400.505232) (xy 388.733225 -400.475746)
			(xy 388.782835 -400.453089) (xy 388.835165 -400.437724) (xy 388.889149 -400.429962) (xy 388.943687 -400.429962)
			(xy 388.997671 -400.437724) (xy 389.050001 -400.453089) (xy 389.099611 -400.475746) (xy 389.145492 -400.505232)
			(xy 389.186709 -400.540947) (xy 389.222424 -400.582164) (xy 389.25191 -400.628045) (xy 389.274567 -400.677655)
			(xy 389.289932 -400.729985) (xy 389.297694 -400.783969) (xy 389.29818 -400.811238) (xy 389.29818 -401.674838)
			(xy 403.06244 -401.674838) (xy 403.06244 -400.811238) (xy 403.062926 -400.783969) (xy 403.070688 -400.729985)
			(xy 403.086053 -400.677655) (xy 403.10871 -400.628045) (xy 403.138196 -400.582164) (xy 403.173911 -400.540947)
			(xy 403.215128 -400.505232) (xy 403.261009 -400.475746) (xy 403.310619 -400.453089) (xy 403.362949 -400.437724)
			(xy 403.416933 -400.429962) (xy 403.471471 -400.429962) (xy 403.525455 -400.437724) (xy 403.577785 -400.453089)
			(xy 403.627395 -400.475746) (xy 403.673276 -400.505232) (xy 403.714493 -400.540947) (xy 403.750208 -400.582164)
			(xy 403.779694 -400.628045) (xy 403.802351 -400.677655) (xy 403.817716 -400.729985) (xy 403.825478 -400.783969)
			(xy 403.825964 -400.811238) (xy 403.825964 -401.674838) (xy 404.262336 -401.674838) (xy 404.262336 -400.811238)
			(xy 404.262822 -400.783969) (xy 404.270584 -400.729985) (xy 404.285949 -400.677655) (xy 404.308606 -400.628045)
			(xy 404.338092 -400.582164) (xy 404.373807 -400.540947) (xy 404.415024 -400.505232) (xy 404.460905 -400.475746)
			(xy 404.510515 -400.453089) (xy 404.562845 -400.437724) (xy 404.616829 -400.429962) (xy 404.671367 -400.429962)
			(xy 404.725351 -400.437724) (xy 404.777681 -400.453089) (xy 404.827291 -400.475746) (xy 404.873172 -400.505232)
			(xy 404.914389 -400.540947) (xy 404.950104 -400.582164) (xy 404.97959 -400.628045) (xy 405.002247 -400.677655)
			(xy 405.017612 -400.729985) (xy 405.025374 -400.783969) (xy 405.02586 -400.811238) (xy 405.02586 -401.674838)
			(xy 405.46274 -401.674838) (xy 405.46274 -400.811238) (xy 405.463226 -400.783987) (xy 405.470982 -400.730039)
			(xy 405.486337 -400.677744) (xy 405.508979 -400.628167) (xy 405.538445 -400.582317) (xy 405.574136 -400.541126)
			(xy 405.615327 -400.505435) (xy 405.661177 -400.475969) (xy 405.710754 -400.453327) (xy 405.763049 -400.437972)
			(xy 405.816997 -400.430216) (xy 405.871499 -400.430216) (xy 405.925447 -400.437972) (xy 405.977742 -400.453327)
			(xy 406.027319 -400.475969) (xy 406.073169 -400.505435) (xy 406.11436 -400.541126) (xy 406.150051 -400.582317)
			(xy 406.179517 -400.628167) (xy 406.202159 -400.677744) (xy 406.217514 -400.730039) (xy 406.22527 -400.783987)
			(xy 406.225756 -400.811238) (xy 406.225756 -401.674838) (xy 406.662636 -401.674838) (xy 406.662636 -400.811238)
			(xy 406.663122 -400.783987) (xy 406.670878 -400.730039) (xy 406.686233 -400.677744) (xy 406.708875 -400.628167)
			(xy 406.738341 -400.582317) (xy 406.774032 -400.541126) (xy 406.815223 -400.505435) (xy 406.861073 -400.475969)
			(xy 406.91065 -400.453327) (xy 406.962945 -400.437972) (xy 407.016893 -400.430216) (xy 407.071395 -400.430216)
			(xy 407.125343 -400.437972) (xy 407.177638 -400.453327) (xy 407.227215 -400.475969) (xy 407.273065 -400.505435)
			(xy 407.314256 -400.541126) (xy 407.349947 -400.582317) (xy 407.379413 -400.628167) (xy 407.402055 -400.677744)
			(xy 407.41741 -400.730039) (xy 407.425166 -400.783987) (xy 407.425652 -400.811238) (xy 407.425652 -401.674838)
			(xy 407.862532 -401.674838) (xy 407.862532 -400.811238) (xy 407.863018 -400.783969) (xy 407.87078 -400.729985)
			(xy 407.886145 -400.677655) (xy 407.908802 -400.628045) (xy 407.938288 -400.582164) (xy 407.974003 -400.540947)
			(xy 408.01522 -400.505232) (xy 408.061101 -400.475746) (xy 408.110711 -400.453089) (xy 408.163041 -400.437724)
			(xy 408.217025 -400.429962) (xy 408.271563 -400.429962) (xy 408.325547 -400.437724) (xy 408.377877 -400.453089)
			(xy 408.427487 -400.475746) (xy 408.473368 -400.505232) (xy 408.514585 -400.540947) (xy 408.5503 -400.582164)
			(xy 408.579786 -400.628045) (xy 408.602443 -400.677655) (xy 408.617808 -400.729985) (xy 408.62557 -400.783969)
			(xy 408.626056 -400.811238) (xy 408.626056 -401.674838) (xy 409.062428 -401.674838) (xy 409.062428 -400.811238)
			(xy 409.062914 -400.783969) (xy 409.070676 -400.729985) (xy 409.086041 -400.677655) (xy 409.108698 -400.628045)
			(xy 409.138184 -400.582164) (xy 409.173899 -400.540947) (xy 409.215116 -400.505232) (xy 409.260997 -400.475746)
			(xy 409.310607 -400.453089) (xy 409.362937 -400.437724) (xy 409.416921 -400.429962) (xy 409.471459 -400.429962)
			(xy 409.525443 -400.437724) (xy 409.577773 -400.453089) (xy 409.627383 -400.475746) (xy 409.673264 -400.505232)
			(xy 409.714481 -400.540947) (xy 409.750196 -400.582164) (xy 409.779682 -400.628045) (xy 409.802339 -400.677655)
			(xy 409.817704 -400.729985) (xy 409.825466 -400.783969) (xy 409.825952 -400.811238) (xy 409.825952 -401.674838)
			(xy 410.262832 -401.674838) (xy 410.262832 -400.811238) (xy 410.263318 -400.783987) (xy 410.271074 -400.730039)
			(xy 410.286429 -400.677744) (xy 410.309071 -400.628167) (xy 410.338537 -400.582317) (xy 410.374228 -400.541126)
			(xy 410.415419 -400.505435) (xy 410.461269 -400.475969) (xy 410.510846 -400.453327) (xy 410.563141 -400.437972)
			(xy 410.617089 -400.430216) (xy 410.671591 -400.430216) (xy 410.725539 -400.437972) (xy 410.777834 -400.453327)
			(xy 410.827411 -400.475969) (xy 410.873261 -400.505435) (xy 410.914452 -400.541126) (xy 410.950143 -400.582317)
			(xy 410.979609 -400.628167) (xy 411.002251 -400.677744) (xy 411.017606 -400.730039) (xy 411.025362 -400.783987)
			(xy 411.025848 -400.811238) (xy 411.025848 -401.674838) (xy 411.462728 -401.674838) (xy 411.462728 -400.811238)
			(xy 411.463214 -400.783987) (xy 411.47097 -400.730039) (xy 411.486325 -400.677744) (xy 411.508967 -400.628167)
			(xy 411.538433 -400.582317) (xy 411.574124 -400.541126) (xy 411.615315 -400.505435) (xy 411.661165 -400.475969)
			(xy 411.710742 -400.453327) (xy 411.763037 -400.437972) (xy 411.816985 -400.430216) (xy 411.871487 -400.430216)
			(xy 411.925435 -400.437972) (xy 411.97773 -400.453327) (xy 412.027307 -400.475969) (xy 412.073157 -400.505435)
			(xy 412.114348 -400.541126) (xy 412.150039 -400.582317) (xy 412.179505 -400.628167) (xy 412.202147 -400.677744)
			(xy 412.217502 -400.730039) (xy 412.225258 -400.783987) (xy 412.225744 -400.811238) (xy 412.225744 -401.674838)
			(xy 412.662624 -401.674838) (xy 412.662624 -400.811238) (xy 412.66311 -400.783969) (xy 412.670872 -400.729985)
			(xy 412.686237 -400.677655) (xy 412.708894 -400.628045) (xy 412.73838 -400.582164) (xy 412.774095 -400.540947)
			(xy 412.815312 -400.505232) (xy 412.861193 -400.475746) (xy 412.910803 -400.453089) (xy 412.963133 -400.437724)
			(xy 413.017117 -400.429962) (xy 413.071655 -400.429962) (xy 413.125639 -400.437724) (xy 413.177969 -400.453089)
			(xy 413.227579 -400.475746) (xy 413.27346 -400.505232) (xy 413.314677 -400.540947) (xy 413.350392 -400.582164)
			(xy 413.379878 -400.628045) (xy 413.402535 -400.677655) (xy 413.4179 -400.729985) (xy 413.425662 -400.783969)
			(xy 413.426148 -400.811238) (xy 413.426148 -401.674838) (xy 413.86252 -401.674838) (xy 413.86252 -400.811238)
			(xy 413.863006 -400.783969) (xy 413.870768 -400.729985) (xy 413.886133 -400.677655) (xy 413.90879 -400.628045)
			(xy 413.938276 -400.582164) (xy 413.973991 -400.540947) (xy 414.015208 -400.505232) (xy 414.061089 -400.475746)
			(xy 414.110699 -400.453089) (xy 414.163029 -400.437724) (xy 414.217013 -400.429962) (xy 414.271551 -400.429962)
			(xy 414.325535 -400.437724) (xy 414.377865 -400.453089) (xy 414.427475 -400.475746) (xy 414.473356 -400.505232)
			(xy 414.514573 -400.540947) (xy 414.550288 -400.582164) (xy 414.579774 -400.628045) (xy 414.602431 -400.677655)
			(xy 414.617796 -400.729985) (xy 414.625558 -400.783969) (xy 414.626044 -400.811238) (xy 414.626044 -401.674838)
			(xy 415.062924 -401.674838) (xy 415.062924 -400.811238) (xy 415.06341 -400.783987) (xy 415.071166 -400.730039)
			(xy 415.086521 -400.677744) (xy 415.109163 -400.628167) (xy 415.138629 -400.582317) (xy 415.17432 -400.541126)
			(xy 415.215511 -400.505435) (xy 415.261361 -400.475969) (xy 415.310938 -400.453327) (xy 415.363233 -400.437972)
			(xy 415.417181 -400.430216) (xy 415.471683 -400.430216) (xy 415.525631 -400.437972) (xy 415.577926 -400.453327)
			(xy 415.627503 -400.475969) (xy 415.673353 -400.505435) (xy 415.714544 -400.541126) (xy 415.750235 -400.582317)
			(xy 415.779701 -400.628167) (xy 415.802343 -400.677744) (xy 415.817698 -400.730039) (xy 415.825454 -400.783987)
			(xy 415.82594 -400.811238) (xy 415.82594 -401.674838) (xy 416.26282 -401.674838) (xy 416.26282 -400.811238)
			(xy 416.263306 -400.783987) (xy 416.271062 -400.730039) (xy 416.286417 -400.677744) (xy 416.309059 -400.628167)
			(xy 416.338525 -400.582317) (xy 416.374216 -400.541126) (xy 416.415407 -400.505435) (xy 416.461257 -400.475969)
			(xy 416.510834 -400.453327) (xy 416.563129 -400.437972) (xy 416.617077 -400.430216) (xy 416.671579 -400.430216)
			(xy 416.725527 -400.437972) (xy 416.777822 -400.453327) (xy 416.827399 -400.475969) (xy 416.873249 -400.505435)
			(xy 416.91444 -400.541126) (xy 416.950131 -400.582317) (xy 416.979597 -400.628167) (xy 417.002239 -400.677744)
			(xy 417.017594 -400.730039) (xy 417.02535 -400.783987) (xy 417.025836 -400.811238) (xy 417.025836 -401.674838)
			(xy 417.462716 -401.674838) (xy 417.462716 -400.811238) (xy 417.463202 -400.783987) (xy 417.470958 -400.730039)
			(xy 417.486313 -400.677744) (xy 417.508955 -400.628167) (xy 417.538421 -400.582317) (xy 417.574112 -400.541126)
			(xy 417.615303 -400.505435) (xy 417.661153 -400.475969) (xy 417.71073 -400.453327) (xy 417.763025 -400.437972)
			(xy 417.816973 -400.430216) (xy 417.871475 -400.430216) (xy 417.925423 -400.437972) (xy 417.977718 -400.453327)
			(xy 418.027295 -400.475969) (xy 418.073145 -400.505435) (xy 418.114336 -400.541126) (xy 418.150027 -400.582317)
			(xy 418.179493 -400.628167) (xy 418.202135 -400.677744) (xy 418.21749 -400.730039) (xy 418.225246 -400.783987)
			(xy 418.225732 -400.811238) (xy 418.225732 -401.674838) (xy 418.662612 -401.674838) (xy 418.662612 -400.811238)
			(xy 418.663098 -400.783987) (xy 418.670854 -400.730039) (xy 418.686209 -400.677744) (xy 418.708851 -400.628167)
			(xy 418.738317 -400.582317) (xy 418.774008 -400.541126) (xy 418.815199 -400.505435) (xy 418.861049 -400.475969)
			(xy 418.910626 -400.453327) (xy 418.962921 -400.437972) (xy 419.016869 -400.430216) (xy 419.071371 -400.430216)
			(xy 419.125319 -400.437972) (xy 419.177614 -400.453327) (xy 419.227191 -400.475969) (xy 419.273041 -400.505435)
			(xy 419.314232 -400.541126) (xy 419.349923 -400.582317) (xy 419.379389 -400.628167) (xy 419.402031 -400.677744)
			(xy 419.417386 -400.730039) (xy 419.425142 -400.783987) (xy 419.425628 -400.811238) (xy 419.425628 -401.674838)
			(xy 419.862508 -401.674838) (xy 419.862508 -400.811238) (xy 419.862994 -400.783969) (xy 419.870756 -400.729985)
			(xy 419.886121 -400.677655) (xy 419.908778 -400.628045) (xy 419.938264 -400.582164) (xy 419.973979 -400.540947)
			(xy 420.015196 -400.505232) (xy 420.061077 -400.475746) (xy 420.110687 -400.453089) (xy 420.163017 -400.437724)
			(xy 420.217001 -400.429962) (xy 420.271539 -400.429962) (xy 420.325523 -400.437724) (xy 420.377853 -400.453089)
			(xy 420.427463 -400.475746) (xy 420.473344 -400.505232) (xy 420.514561 -400.540947) (xy 420.550276 -400.582164)
			(xy 420.579762 -400.628045) (xy 420.602419 -400.677655) (xy 420.617784 -400.729985) (xy 420.625546 -400.783969)
			(xy 420.626032 -400.811238) (xy 420.626032 -401.674838) (xy 421.062404 -401.674838) (xy 421.062404 -400.811238)
			(xy 421.06289 -400.783969) (xy 421.070652 -400.729985) (xy 421.086017 -400.677655) (xy 421.108674 -400.628045)
			(xy 421.13816 -400.582164) (xy 421.173875 -400.540947) (xy 421.215092 -400.505232) (xy 421.260973 -400.475746)
			(xy 421.310583 -400.453089) (xy 421.362913 -400.437724) (xy 421.416897 -400.429962) (xy 421.471435 -400.429962)
			(xy 421.525419 -400.437724) (xy 421.577749 -400.453089) (xy 421.627359 -400.475746) (xy 421.67324 -400.505232)
			(xy 421.714457 -400.540947) (xy 421.750172 -400.582164) (xy 421.779658 -400.628045) (xy 421.802315 -400.677655)
			(xy 421.81768 -400.729985) (xy 421.825442 -400.783969) (xy 421.825928 -400.811238) (xy 421.825928 -401.674838)
			(xy 421.825442 -401.702107) (xy 421.81768 -401.756091) (xy 421.802315 -401.808421) (xy 421.779658 -401.858031)
			(xy 421.750172 -401.903912) (xy 421.714457 -401.945129) (xy 421.67324 -401.980844) (xy 421.627359 -402.01033)
			(xy 421.577749 -402.032987) (xy 421.525419 -402.048352) (xy 421.471435 -402.056114) (xy 421.416897 -402.056114)
			(xy 421.362913 -402.048352) (xy 421.310583 -402.032987) (xy 421.260973 -402.01033) (xy 421.215092 -401.980844)
			(xy 421.173875 -401.945129) (xy 421.13816 -401.903912) (xy 421.108674 -401.858031) (xy 421.086017 -401.808421)
			(xy 421.070652 -401.756091) (xy 421.06289 -401.702107) (xy 421.062404 -401.674838) (xy 420.626032 -401.674838)
			(xy 420.625546 -401.702107) (xy 420.617784 -401.756091) (xy 420.602419 -401.808421) (xy 420.579762 -401.858031)
			(xy 420.550276 -401.903912) (xy 420.514561 -401.945129) (xy 420.473344 -401.980844) (xy 420.427463 -402.01033)
			(xy 420.377853 -402.032987) (xy 420.325523 -402.048352) (xy 420.271539 -402.056114) (xy 420.217001 -402.056114)
			(xy 420.163017 -402.048352) (xy 420.110687 -402.032987) (xy 420.061077 -402.01033) (xy 420.015196 -401.980844)
			(xy 419.973979 -401.945129) (xy 419.938264 -401.903912) (xy 419.908778 -401.858031) (xy 419.886121 -401.808421)
			(xy 419.870756 -401.756091) (xy 419.862994 -401.702107) (xy 419.862508 -401.674838) (xy 419.425628 -401.674838)
			(xy 419.425142 -401.702089) (xy 419.417386 -401.756037) (xy 419.402031 -401.808332) (xy 419.379389 -401.857909)
			(xy 419.349923 -401.903759) (xy 419.314232 -401.94495) (xy 419.273041 -401.980641) (xy 419.227191 -402.010107)
			(xy 419.177614 -402.032749) (xy 419.125319 -402.048104) (xy 419.071371 -402.05586) (xy 419.016869 -402.05586)
			(xy 418.962921 -402.048104) (xy 418.910626 -402.032749) (xy 418.861049 -402.010107) (xy 418.815199 -401.980641)
			(xy 418.774008 -401.94495) (xy 418.738317 -401.903759) (xy 418.708851 -401.857909) (xy 418.686209 -401.808332)
			(xy 418.670854 -401.756037) (xy 418.663098 -401.702089) (xy 418.662612 -401.674838) (xy 418.225732 -401.674838)
			(xy 418.225246 -401.702089) (xy 418.21749 -401.756037) (xy 418.202135 -401.808332) (xy 418.179493 -401.857909)
			(xy 418.150027 -401.903759) (xy 418.114336 -401.94495) (xy 418.073145 -401.980641) (xy 418.027295 -402.010107)
			(xy 417.977718 -402.032749) (xy 417.925423 -402.048104) (xy 417.871475 -402.05586) (xy 417.816973 -402.05586)
			(xy 417.763025 -402.048104) (xy 417.71073 -402.032749) (xy 417.661153 -402.010107) (xy 417.615303 -401.980641)
			(xy 417.574112 -401.94495) (xy 417.538421 -401.903759) (xy 417.508955 -401.857909) (xy 417.486313 -401.808332)
			(xy 417.470958 -401.756037) (xy 417.463202 -401.702089) (xy 417.462716 -401.674838) (xy 417.025836 -401.674838)
			(xy 417.02535 -401.702089) (xy 417.017594 -401.756037) (xy 417.002239 -401.808332) (xy 416.979597 -401.857909)
			(xy 416.950131 -401.903759) (xy 416.91444 -401.94495) (xy 416.873249 -401.980641) (xy 416.827399 -402.010107)
			(xy 416.777822 -402.032749) (xy 416.725527 -402.048104) (xy 416.671579 -402.05586) (xy 416.617077 -402.05586)
			(xy 416.563129 -402.048104) (xy 416.510834 -402.032749) (xy 416.461257 -402.010107) (xy 416.415407 -401.980641)
			(xy 416.374216 -401.94495) (xy 416.338525 -401.903759) (xy 416.309059 -401.857909) (xy 416.286417 -401.808332)
			(xy 416.271062 -401.756037) (xy 416.263306 -401.702089) (xy 416.26282 -401.674838) (xy 415.82594 -401.674838)
			(xy 415.825454 -401.702089) (xy 415.817698 -401.756037) (xy 415.802343 -401.808332) (xy 415.779701 -401.857909)
			(xy 415.750235 -401.903759) (xy 415.714544 -401.94495) (xy 415.673353 -401.980641) (xy 415.627503 -402.010107)
			(xy 415.577926 -402.032749) (xy 415.525631 -402.048104) (xy 415.471683 -402.05586) (xy 415.417181 -402.05586)
			(xy 415.363233 -402.048104) (xy 415.310938 -402.032749) (xy 415.261361 -402.010107) (xy 415.215511 -401.980641)
			(xy 415.17432 -401.94495) (xy 415.138629 -401.903759) (xy 415.109163 -401.857909) (xy 415.086521 -401.808332)
			(xy 415.071166 -401.756037) (xy 415.06341 -401.702089) (xy 415.062924 -401.674838) (xy 414.626044 -401.674838)
			(xy 414.625558 -401.702107) (xy 414.617796 -401.756091) (xy 414.602431 -401.808421) (xy 414.579774 -401.858031)
			(xy 414.550288 -401.903912) (xy 414.514573 -401.945129) (xy 414.473356 -401.980844) (xy 414.427475 -402.01033)
			(xy 414.377865 -402.032987) (xy 414.325535 -402.048352) (xy 414.271551 -402.056114) (xy 414.217013 -402.056114)
			(xy 414.163029 -402.048352) (xy 414.110699 -402.032987) (xy 414.061089 -402.01033) (xy 414.015208 -401.980844)
			(xy 413.973991 -401.945129) (xy 413.938276 -401.903912) (xy 413.90879 -401.858031) (xy 413.886133 -401.808421)
			(xy 413.870768 -401.756091) (xy 413.863006 -401.702107) (xy 413.86252 -401.674838) (xy 413.426148 -401.674838)
			(xy 413.425662 -401.702107) (xy 413.4179 -401.756091) (xy 413.402535 -401.808421) (xy 413.379878 -401.858031)
			(xy 413.350392 -401.903912) (xy 413.314677 -401.945129) (xy 413.27346 -401.980844) (xy 413.227579 -402.01033)
			(xy 413.177969 -402.032987) (xy 413.125639 -402.048352) (xy 413.071655 -402.056114) (xy 413.017117 -402.056114)
			(xy 412.963133 -402.048352) (xy 412.910803 -402.032987) (xy 412.861193 -402.01033) (xy 412.815312 -401.980844)
			(xy 412.774095 -401.945129) (xy 412.73838 -401.903912) (xy 412.708894 -401.858031) (xy 412.686237 -401.808421)
			(xy 412.670872 -401.756091) (xy 412.66311 -401.702107) (xy 412.662624 -401.674838) (xy 412.225744 -401.674838)
			(xy 412.225258 -401.702089) (xy 412.217502 -401.756037) (xy 412.202147 -401.808332) (xy 412.179505 -401.857909)
			(xy 412.150039 -401.903759) (xy 412.114348 -401.94495) (xy 412.073157 -401.980641) (xy 412.027307 -402.010107)
			(xy 411.97773 -402.032749) (xy 411.925435 -402.048104) (xy 411.871487 -402.05586) (xy 411.816985 -402.05586)
			(xy 411.763037 -402.048104) (xy 411.710742 -402.032749) (xy 411.661165 -402.010107) (xy 411.615315 -401.980641)
			(xy 411.574124 -401.94495) (xy 411.538433 -401.903759) (xy 411.508967 -401.857909) (xy 411.486325 -401.808332)
			(xy 411.47097 -401.756037) (xy 411.463214 -401.702089) (xy 411.462728 -401.674838) (xy 411.025848 -401.674838)
			(xy 411.025362 -401.702089) (xy 411.017606 -401.756037) (xy 411.002251 -401.808332) (xy 410.979609 -401.857909)
			(xy 410.950143 -401.903759) (xy 410.914452 -401.94495) (xy 410.873261 -401.980641) (xy 410.827411 -402.010107)
			(xy 410.777834 -402.032749) (xy 410.725539 -402.048104) (xy 410.671591 -402.05586) (xy 410.617089 -402.05586)
			(xy 410.563141 -402.048104) (xy 410.510846 -402.032749) (xy 410.461269 -402.010107) (xy 410.415419 -401.980641)
			(xy 410.374228 -401.94495) (xy 410.338537 -401.903759) (xy 410.309071 -401.857909) (xy 410.286429 -401.808332)
			(xy 410.271074 -401.756037) (xy 410.263318 -401.702089) (xy 410.262832 -401.674838) (xy 409.825952 -401.674838)
			(xy 409.825466 -401.702107) (xy 409.817704 -401.756091) (xy 409.802339 -401.808421) (xy 409.779682 -401.858031)
			(xy 409.750196 -401.903912) (xy 409.714481 -401.945129) (xy 409.673264 -401.980844) (xy 409.627383 -402.01033)
			(xy 409.577773 -402.032987) (xy 409.525443 -402.048352) (xy 409.471459 -402.056114) (xy 409.416921 -402.056114)
			(xy 409.362937 -402.048352) (xy 409.310607 -402.032987) (xy 409.260997 -402.01033) (xy 409.215116 -401.980844)
			(xy 409.173899 -401.945129) (xy 409.138184 -401.903912) (xy 409.108698 -401.858031) (xy 409.086041 -401.808421)
			(xy 409.070676 -401.756091) (xy 409.062914 -401.702107) (xy 409.062428 -401.674838) (xy 408.626056 -401.674838)
			(xy 408.62557 -401.702107) (xy 408.617808 -401.756091) (xy 408.602443 -401.808421) (xy 408.579786 -401.858031)
			(xy 408.5503 -401.903912) (xy 408.514585 -401.945129) (xy 408.473368 -401.980844) (xy 408.427487 -402.01033)
			(xy 408.377877 -402.032987) (xy 408.325547 -402.048352) (xy 408.271563 -402.056114) (xy 408.217025 -402.056114)
			(xy 408.163041 -402.048352) (xy 408.110711 -402.032987) (xy 408.061101 -402.01033) (xy 408.01522 -401.980844)
			(xy 407.974003 -401.945129) (xy 407.938288 -401.903912) (xy 407.908802 -401.858031) (xy 407.886145 -401.808421)
			(xy 407.87078 -401.756091) (xy 407.863018 -401.702107) (xy 407.862532 -401.674838) (xy 407.425652 -401.674838)
			(xy 407.425166 -401.702089) (xy 407.41741 -401.756037) (xy 407.402055 -401.808332) (xy 407.379413 -401.857909)
			(xy 407.349947 -401.903759) (xy 407.314256 -401.94495) (xy 407.273065 -401.980641) (xy 407.227215 -402.010107)
			(xy 407.177638 -402.032749) (xy 407.125343 -402.048104) (xy 407.071395 -402.05586) (xy 407.016893 -402.05586)
			(xy 406.962945 -402.048104) (xy 406.91065 -402.032749) (xy 406.861073 -402.010107) (xy 406.815223 -401.980641)
			(xy 406.774032 -401.94495) (xy 406.738341 -401.903759) (xy 406.708875 -401.857909) (xy 406.686233 -401.808332)
			(xy 406.670878 -401.756037) (xy 406.663122 -401.702089) (xy 406.662636 -401.674838) (xy 406.225756 -401.674838)
			(xy 406.22527 -401.702089) (xy 406.217514 -401.756037) (xy 406.202159 -401.808332) (xy 406.179517 -401.857909)
			(xy 406.150051 -401.903759) (xy 406.11436 -401.94495) (xy 406.073169 -401.980641) (xy 406.027319 -402.010107)
			(xy 405.977742 -402.032749) (xy 405.925447 -402.048104) (xy 405.871499 -402.05586) (xy 405.816997 -402.05586)
			(xy 405.763049 -402.048104) (xy 405.710754 -402.032749) (xy 405.661177 -402.010107) (xy 405.615327 -401.980641)
			(xy 405.574136 -401.94495) (xy 405.538445 -401.903759) (xy 405.508979 -401.857909) (xy 405.486337 -401.808332)
			(xy 405.470982 -401.756037) (xy 405.463226 -401.702089) (xy 405.46274 -401.674838) (xy 405.02586 -401.674838)
			(xy 405.025374 -401.702107) (xy 405.017612 -401.756091) (xy 405.002247 -401.808421) (xy 404.97959 -401.858031)
			(xy 404.950104 -401.903912) (xy 404.914389 -401.945129) (xy 404.873172 -401.980844) (xy 404.827291 -402.01033)
			(xy 404.777681 -402.032987) (xy 404.725351 -402.048352) (xy 404.671367 -402.056114) (xy 404.616829 -402.056114)
			(xy 404.562845 -402.048352) (xy 404.510515 -402.032987) (xy 404.460905 -402.01033) (xy 404.415024 -401.980844)
			(xy 404.373807 -401.945129) (xy 404.338092 -401.903912) (xy 404.308606 -401.858031) (xy 404.285949 -401.808421)
			(xy 404.270584 -401.756091) (xy 404.262822 -401.702107) (xy 404.262336 -401.674838) (xy 403.825964 -401.674838)
			(xy 403.825478 -401.702107) (xy 403.817716 -401.756091) (xy 403.802351 -401.808421) (xy 403.779694 -401.858031)
			(xy 403.750208 -401.903912) (xy 403.714493 -401.945129) (xy 403.673276 -401.980844) (xy 403.627395 -402.01033)
			(xy 403.577785 -402.032987) (xy 403.525455 -402.048352) (xy 403.471471 -402.056114) (xy 403.416933 -402.056114)
			(xy 403.362949 -402.048352) (xy 403.310619 -402.032987) (xy 403.261009 -402.01033) (xy 403.215128 -401.980844)
			(xy 403.173911 -401.945129) (xy 403.138196 -401.903912) (xy 403.10871 -401.858031) (xy 403.086053 -401.808421)
			(xy 403.070688 -401.756091) (xy 403.062926 -401.702107) (xy 403.06244 -401.674838) (xy 389.29818 -401.674838)
			(xy 389.297694 -401.702107) (xy 389.289932 -401.756091) (xy 389.274567 -401.808421) (xy 389.25191 -401.858031)
			(xy 389.222424 -401.903912) (xy 389.186709 -401.945129) (xy 389.145492 -401.980844) (xy 389.099611 -402.01033)
			(xy 389.050001 -402.032987) (xy 388.997671 -402.048352) (xy 388.943687 -402.056114) (xy 388.889149 -402.056114)
			(xy 388.835165 -402.048352) (xy 388.782835 -402.032987) (xy 388.733225 -402.01033) (xy 388.687344 -401.980844)
			(xy 388.646127 -401.945129) (xy 388.610412 -401.903912) (xy 388.580926 -401.858031) (xy 388.558269 -401.808421)
			(xy 388.542904 -401.756091) (xy 388.535142 -401.702107) (xy 388.534656 -401.674838) (xy 388.098284 -401.674838)
			(xy 388.097798 -401.702107) (xy 388.090036 -401.756091) (xy 388.074671 -401.808421) (xy 388.052014 -401.858031)
			(xy 388.022528 -401.903912) (xy 387.986813 -401.945129) (xy 387.945596 -401.980844) (xy 387.899715 -402.01033)
			(xy 387.850105 -402.032987) (xy 387.797775 -402.048352) (xy 387.743791 -402.056114) (xy 387.689253 -402.056114)
			(xy 387.635269 -402.048352) (xy 387.582939 -402.032987) (xy 387.533329 -402.01033) (xy 387.487448 -401.980844)
			(xy 387.446231 -401.945129) (xy 387.410516 -401.903912) (xy 387.38103 -401.858031) (xy 387.358373 -401.808421)
			(xy 387.343008 -401.756091) (xy 387.335246 -401.702107) (xy 387.33476 -401.674838) (xy 386.89788 -401.674838)
			(xy 386.897394 -401.702089) (xy 386.889638 -401.756037) (xy 386.874283 -401.808332) (xy 386.851641 -401.857909)
			(xy 386.822175 -401.903759) (xy 386.786484 -401.94495) (xy 386.745293 -401.980641) (xy 386.699443 -402.010107)
			(xy 386.649866 -402.032749) (xy 386.597571 -402.048104) (xy 386.543623 -402.05586) (xy 386.489121 -402.05586)
			(xy 386.435173 -402.048104) (xy 386.382878 -402.032749) (xy 386.333301 -402.010107) (xy 386.287451 -401.980641)
			(xy 386.24626 -401.94495) (xy 386.210569 -401.903759) (xy 386.181103 -401.857909) (xy 386.158461 -401.808332)
			(xy 386.143106 -401.756037) (xy 386.13535 -401.702089) (xy 386.134864 -401.674838) (xy 385.697984 -401.674838)
			(xy 385.697498 -401.702089) (xy 385.689742 -401.756037) (xy 385.674387 -401.808332) (xy 385.651745 -401.857909)
			(xy 385.622279 -401.903759) (xy 385.586588 -401.94495) (xy 385.545397 -401.980641) (xy 385.499547 -402.010107)
			(xy 385.44997 -402.032749) (xy 385.397675 -402.048104) (xy 385.343727 -402.05586) (xy 385.289225 -402.05586)
			(xy 385.235277 -402.048104) (xy 385.182982 -402.032749) (xy 385.133405 -402.010107) (xy 385.087555 -401.980641)
			(xy 385.046364 -401.94495) (xy 385.010673 -401.903759) (xy 384.981207 -401.857909) (xy 384.958565 -401.808332)
			(xy 384.94321 -401.756037) (xy 384.935454 -401.702089) (xy 384.934968 -401.674838) (xy 384.498088 -401.674838)
			(xy 384.497602 -401.702089) (xy 384.489846 -401.756037) (xy 384.474491 -401.808332) (xy 384.451849 -401.857909)
			(xy 384.422383 -401.903759) (xy 384.386692 -401.94495) (xy 384.345501 -401.980641) (xy 384.299651 -402.010107)
			(xy 384.250074 -402.032749) (xy 384.197779 -402.048104) (xy 384.143831 -402.05586) (xy 384.089329 -402.05586)
			(xy 384.035381 -402.048104) (xy 383.983086 -402.032749) (xy 383.933509 -402.010107) (xy 383.887659 -401.980641)
			(xy 383.846468 -401.94495) (xy 383.810777 -401.903759) (xy 383.781311 -401.857909) (xy 383.758669 -401.808332)
			(xy 383.743314 -401.756037) (xy 383.735558 -401.702089) (xy 383.735072 -401.674838) (xy 383.298192 -401.674838)
			(xy 383.297706 -401.702089) (xy 383.28995 -401.756037) (xy 383.274595 -401.808332) (xy 383.251953 -401.857909)
			(xy 383.222487 -401.903759) (xy 383.186796 -401.94495) (xy 383.145605 -401.980641) (xy 383.099755 -402.010107)
			(xy 383.050178 -402.032749) (xy 382.997883 -402.048104) (xy 382.943935 -402.05586) (xy 382.889433 -402.05586)
			(xy 382.835485 -402.048104) (xy 382.78319 -402.032749) (xy 382.733613 -402.010107) (xy 382.687763 -401.980641)
			(xy 382.646572 -401.94495) (xy 382.610881 -401.903759) (xy 382.581415 -401.857909) (xy 382.558773 -401.808332)
			(xy 382.543418 -401.756037) (xy 382.535662 -401.702089) (xy 382.535176 -401.674838) (xy 382.098296 -401.674838)
			(xy 382.09781 -401.702107) (xy 382.090048 -401.756091) (xy 382.074683 -401.808421) (xy 382.052026 -401.858031)
			(xy 382.02254 -401.903912) (xy 381.986825 -401.945129) (xy 381.945608 -401.980844) (xy 381.899727 -402.01033)
			(xy 381.850117 -402.032987) (xy 381.797787 -402.048352) (xy 381.743803 -402.056114) (xy 381.689265 -402.056114)
			(xy 381.635281 -402.048352) (xy 381.582951 -402.032987) (xy 381.533341 -402.01033) (xy 381.48746 -401.980844)
			(xy 381.446243 -401.945129) (xy 381.410528 -401.903912) (xy 381.381042 -401.858031) (xy 381.358385 -401.808421)
			(xy 381.34302 -401.756091) (xy 381.335258 -401.702107) (xy 381.334772 -401.674838) (xy 380.8984 -401.674838)
			(xy 380.897914 -401.702107) (xy 380.890152 -401.756091) (xy 380.874787 -401.808421) (xy 380.85213 -401.858031)
			(xy 380.822644 -401.903912) (xy 380.786929 -401.945129) (xy 380.745712 -401.980844) (xy 380.699831 -402.01033)
			(xy 380.650221 -402.032987) (xy 380.597891 -402.048352) (xy 380.543907 -402.056114) (xy 380.489369 -402.056114)
			(xy 380.435385 -402.048352) (xy 380.383055 -402.032987) (xy 380.333445 -402.01033) (xy 380.287564 -401.980844)
			(xy 380.246347 -401.945129) (xy 380.210632 -401.903912) (xy 380.181146 -401.858031) (xy 380.158489 -401.808421)
			(xy 380.143124 -401.756091) (xy 380.135362 -401.702107) (xy 380.134876 -401.674838) (xy 379.697996 -401.674838)
			(xy 379.69751 -401.702089) (xy 379.689754 -401.756037) (xy 379.674399 -401.808332) (xy 379.651757 -401.857909)
			(xy 379.622291 -401.903759) (xy 379.5866 -401.94495) (xy 379.545409 -401.980641) (xy 379.499559 -402.010107)
			(xy 379.449982 -402.032749) (xy 379.397687 -402.048104) (xy 379.343739 -402.05586) (xy 379.289237 -402.05586)
			(xy 379.235289 -402.048104) (xy 379.182994 -402.032749) (xy 379.133417 -402.010107) (xy 379.087567 -401.980641)
			(xy 379.046376 -401.94495) (xy 379.010685 -401.903759) (xy 378.981219 -401.857909) (xy 378.958577 -401.808332)
			(xy 378.943222 -401.756037) (xy 378.935466 -401.702089) (xy 378.93498 -401.674838) (xy 378.4981 -401.674838)
			(xy 378.497614 -401.702089) (xy 378.489858 -401.756037) (xy 378.474503 -401.808332) (xy 378.451861 -401.857909)
			(xy 378.422395 -401.903759) (xy 378.386704 -401.94495) (xy 378.345513 -401.980641) (xy 378.299663 -402.010107)
			(xy 378.250086 -402.032749) (xy 378.197791 -402.048104) (xy 378.143843 -402.05586) (xy 378.089341 -402.05586)
			(xy 378.035393 -402.048104) (xy 377.983098 -402.032749) (xy 377.933521 -402.010107) (xy 377.887671 -401.980641)
			(xy 377.84648 -401.94495) (xy 377.810789 -401.903759) (xy 377.781323 -401.857909) (xy 377.758681 -401.808332)
			(xy 377.743326 -401.756037) (xy 377.73557 -401.702089) (xy 377.735084 -401.674838) (xy 377.298204 -401.674838)
			(xy 377.297718 -401.702107) (xy 377.289956 -401.756091) (xy 377.274591 -401.808421) (xy 377.251934 -401.858031)
			(xy 377.222448 -401.903912) (xy 377.186733 -401.945129) (xy 377.145516 -401.980844) (xy 377.099635 -402.01033)
			(xy 377.050025 -402.032987) (xy 376.997695 -402.048352) (xy 376.943711 -402.056114) (xy 376.889173 -402.056114)
			(xy 376.835189 -402.048352) (xy 376.782859 -402.032987) (xy 376.733249 -402.01033) (xy 376.687368 -401.980844)
			(xy 376.646151 -401.945129) (xy 376.610436 -401.903912) (xy 376.58095 -401.858031) (xy 376.558293 -401.808421)
			(xy 376.542928 -401.756091) (xy 376.535166 -401.702107) (xy 376.53468 -401.674838) (xy 376.098308 -401.674838)
			(xy 376.097822 -401.702107) (xy 376.09006 -401.756091) (xy 376.074695 -401.808421) (xy 376.052038 -401.858031)
			(xy 376.022552 -401.903912) (xy 375.986837 -401.945129) (xy 375.94562 -401.980844) (xy 375.899739 -402.01033)
			(xy 375.850129 -402.032987) (xy 375.797799 -402.048352) (xy 375.743815 -402.056114) (xy 375.689277 -402.056114)
			(xy 375.635293 -402.048352) (xy 375.582963 -402.032987) (xy 375.533353 -402.01033) (xy 375.487472 -401.980844)
			(xy 375.446255 -401.945129) (xy 375.41054 -401.903912) (xy 375.381054 -401.858031) (xy 375.358397 -401.808421)
			(xy 375.343032 -401.756091) (xy 375.33527 -401.702107) (xy 375.334784 -401.674838) (xy 374.897904 -401.674838)
			(xy 374.897418 -401.702089) (xy 374.889662 -401.756037) (xy 374.874307 -401.808332) (xy 374.851665 -401.857909)
			(xy 374.822199 -401.903759) (xy 374.786508 -401.94495) (xy 374.745317 -401.980641) (xy 374.699467 -402.010107)
			(xy 374.64989 -402.032749) (xy 374.597595 -402.048104) (xy 374.543647 -402.05586) (xy 374.489145 -402.05586)
			(xy 374.435197 -402.048104) (xy 374.382902 -402.032749) (xy 374.333325 -402.010107) (xy 374.287475 -401.980641)
			(xy 374.246284 -401.94495) (xy 374.210593 -401.903759) (xy 374.181127 -401.857909) (xy 374.158485 -401.808332)
			(xy 374.14313 -401.756037) (xy 374.135374 -401.702089) (xy 374.134888 -401.674838) (xy 373.698008 -401.674838)
			(xy 373.697522 -401.702089) (xy 373.689766 -401.756037) (xy 373.674411 -401.808332) (xy 373.651769 -401.857909)
			(xy 373.622303 -401.903759) (xy 373.586612 -401.94495) (xy 373.545421 -401.980641) (xy 373.499571 -402.010107)
			(xy 373.449994 -402.032749) (xy 373.397699 -402.048104) (xy 373.343751 -402.05586) (xy 373.289249 -402.05586)
			(xy 373.235301 -402.048104) (xy 373.183006 -402.032749) (xy 373.133429 -402.010107) (xy 373.087579 -401.980641)
			(xy 373.046388 -401.94495) (xy 373.010697 -401.903759) (xy 372.981231 -401.857909) (xy 372.958589 -401.808332)
			(xy 372.943234 -401.756037) (xy 372.935478 -401.702089) (xy 372.934992 -401.674838) (xy 372.498112 -401.674838)
			(xy 372.497626 -401.702107) (xy 372.489864 -401.756091) (xy 372.474499 -401.808421) (xy 372.451842 -401.858031)
			(xy 372.422356 -401.903912) (xy 372.386641 -401.945129) (xy 372.345424 -401.980844) (xy 372.299543 -402.01033)
			(xy 372.249933 -402.032987) (xy 372.197603 -402.048352) (xy 372.143619 -402.056114) (xy 372.089081 -402.056114)
			(xy 372.035097 -402.048352) (xy 371.982767 -402.032987) (xy 371.933157 -402.01033) (xy 371.887276 -401.980844)
			(xy 371.846059 -401.945129) (xy 371.810344 -401.903912) (xy 371.780858 -401.858031) (xy 371.758201 -401.808421)
			(xy 371.742836 -401.756091) (xy 371.735074 -401.702107) (xy 371.734588 -401.674838) (xy 371.298216 -401.674838)
			(xy 371.29773 -401.702107) (xy 371.289968 -401.756091) (xy 371.274603 -401.808421) (xy 371.251946 -401.858031)
			(xy 371.22246 -401.903912) (xy 371.186745 -401.945129) (xy 371.145528 -401.980844) (xy 371.099647 -402.01033)
			(xy 371.050037 -402.032987) (xy 370.997707 -402.048352) (xy 370.943723 -402.056114) (xy 370.889185 -402.056114)
			(xy 370.835201 -402.048352) (xy 370.782871 -402.032987) (xy 370.733261 -402.01033) (xy 370.68738 -401.980844)
			(xy 370.646163 -401.945129) (xy 370.610448 -401.903912) (xy 370.580962 -401.858031) (xy 370.558305 -401.808421)
			(xy 370.54294 -401.756091) (xy 370.535178 -401.702107) (xy 370.534692 -401.674838) (xy 354.725732 -401.674838)
			(xy 354.725246 -401.702107) (xy 354.717484 -401.756091) (xy 354.702119 -401.808421) (xy 354.679462 -401.858031)
			(xy 354.649976 -401.903912) (xy 354.614261 -401.945129) (xy 354.573044 -401.980844) (xy 354.527163 -402.01033)
			(xy 354.477553 -402.032987) (xy 354.425223 -402.048352) (xy 354.371239 -402.056114) (xy 354.316701 -402.056114)
			(xy 354.262717 -402.048352) (xy 354.210387 -402.032987) (xy 354.160777 -402.01033) (xy 354.114896 -401.980844)
			(xy 354.073679 -401.945129) (xy 354.037964 -401.903912) (xy 354.008478 -401.858031) (xy 353.985821 -401.808421)
			(xy 353.970456 -401.756091) (xy 353.962694 -401.702107) (xy 353.962208 -401.674838) (xy 353.525836 -401.674838)
			(xy 353.52535 -401.702107) (xy 353.517588 -401.756091) (xy 353.502223 -401.808421) (xy 353.479566 -401.858031)
			(xy 353.45008 -401.903912) (xy 353.414365 -401.945129) (xy 353.373148 -401.980844) (xy 353.327267 -402.01033)
			(xy 353.277657 -402.032987) (xy 353.225327 -402.048352) (xy 353.171343 -402.056114) (xy 353.116805 -402.056114)
			(xy 353.062821 -402.048352) (xy 353.010491 -402.032987) (xy 352.960881 -402.01033) (xy 352.915 -401.980844)
			(xy 352.873783 -401.945129) (xy 352.838068 -401.903912) (xy 352.808582 -401.858031) (xy 352.785925 -401.808421)
			(xy 352.77056 -401.756091) (xy 352.762798 -401.702107) (xy 352.762312 -401.674838) (xy 352.325432 -401.674838)
			(xy 352.324946 -401.702089) (xy 352.31719 -401.756037) (xy 352.301835 -401.808332) (xy 352.279193 -401.857909)
			(xy 352.249727 -401.903759) (xy 352.214036 -401.94495) (xy 352.172845 -401.980641) (xy 352.126995 -402.010107)
			(xy 352.077418 -402.032749) (xy 352.025123 -402.048104) (xy 351.971175 -402.05586) (xy 351.916673 -402.05586)
			(xy 351.862725 -402.048104) (xy 351.81043 -402.032749) (xy 351.760853 -402.010107) (xy 351.715003 -401.980641)
			(xy 351.673812 -401.94495) (xy 351.638121 -401.903759) (xy 351.608655 -401.857909) (xy 351.586013 -401.808332)
			(xy 351.570658 -401.756037) (xy 351.562902 -401.702089) (xy 351.562416 -401.674838) (xy 351.125536 -401.674838)
			(xy 351.12505 -401.702089) (xy 351.117294 -401.756037) (xy 351.101939 -401.808332) (xy 351.079297 -401.857909)
			(xy 351.049831 -401.903759) (xy 351.01414 -401.94495) (xy 350.972949 -401.980641) (xy 350.927099 -402.010107)
			(xy 350.877522 -402.032749) (xy 350.825227 -402.048104) (xy 350.771279 -402.05586) (xy 350.716777 -402.05586)
			(xy 350.662829 -402.048104) (xy 350.610534 -402.032749) (xy 350.560957 -402.010107) (xy 350.515107 -401.980641)
			(xy 350.473916 -401.94495) (xy 350.438225 -401.903759) (xy 350.408759 -401.857909) (xy 350.386117 -401.808332)
			(xy 350.370762 -401.756037) (xy 350.363006 -401.702089) (xy 350.36252 -401.674838) (xy 349.92564 -401.674838)
			(xy 349.925154 -401.702089) (xy 349.917398 -401.756037) (xy 349.902043 -401.808332) (xy 349.879401 -401.857909)
			(xy 349.849935 -401.903759) (xy 349.814244 -401.94495) (xy 349.773053 -401.980641) (xy 349.727203 -402.010107)
			(xy 349.677626 -402.032749) (xy 349.625331 -402.048104) (xy 349.571383 -402.05586) (xy 349.516881 -402.05586)
			(xy 349.462933 -402.048104) (xy 349.410638 -402.032749) (xy 349.361061 -402.010107) (xy 349.315211 -401.980641)
			(xy 349.27402 -401.94495) (xy 349.238329 -401.903759) (xy 349.208863 -401.857909) (xy 349.186221 -401.808332)
			(xy 349.170866 -401.756037) (xy 349.16311 -401.702089) (xy 349.162624 -401.674838) (xy 348.725744 -401.674838)
			(xy 348.725258 -401.702089) (xy 348.717502 -401.756037) (xy 348.702147 -401.808332) (xy 348.679505 -401.857909)
			(xy 348.650039 -401.903759) (xy 348.614348 -401.94495) (xy 348.573157 -401.980641) (xy 348.527307 -402.010107)
			(xy 348.47773 -402.032749) (xy 348.425435 -402.048104) (xy 348.371487 -402.05586) (xy 348.316985 -402.05586)
			(xy 348.263037 -402.048104) (xy 348.210742 -402.032749) (xy 348.161165 -402.010107) (xy 348.115315 -401.980641)
			(xy 348.074124 -401.94495) (xy 348.038433 -401.903759) (xy 348.008967 -401.857909) (xy 347.986325 -401.808332)
			(xy 347.97097 -401.756037) (xy 347.963214 -401.702089) (xy 347.962728 -401.674838) (xy 347.525848 -401.674838)
			(xy 347.525362 -401.702107) (xy 347.5176 -401.756091) (xy 347.502235 -401.808421) (xy 347.479578 -401.858031)
			(xy 347.450092 -401.903912) (xy 347.414377 -401.945129) (xy 347.37316 -401.980844) (xy 347.327279 -402.01033)
			(xy 347.277669 -402.032987) (xy 347.225339 -402.048352) (xy 347.171355 -402.056114) (xy 347.116817 -402.056114)
			(xy 347.062833 -402.048352) (xy 347.010503 -402.032987) (xy 346.960893 -402.01033) (xy 346.915012 -401.980844)
			(xy 346.873795 -401.945129) (xy 346.83808 -401.903912) (xy 346.808594 -401.858031) (xy 346.785937 -401.808421)
			(xy 346.770572 -401.756091) (xy 346.76281 -401.702107) (xy 346.762324 -401.674838) (xy 346.325952 -401.674838)
			(xy 346.325466 -401.702107) (xy 346.317704 -401.756091) (xy 346.302339 -401.808421) (xy 346.279682 -401.858031)
			(xy 346.250196 -401.903912) (xy 346.214481 -401.945129) (xy 346.173264 -401.980844) (xy 346.127383 -402.01033)
			(xy 346.077773 -402.032987) (xy 346.025443 -402.048352) (xy 345.971459 -402.056114) (xy 345.916921 -402.056114)
			(xy 345.862937 -402.048352) (xy 345.810607 -402.032987) (xy 345.760997 -402.01033) (xy 345.715116 -401.980844)
			(xy 345.673899 -401.945129) (xy 345.638184 -401.903912) (xy 345.608698 -401.858031) (xy 345.586041 -401.808421)
			(xy 345.570676 -401.756091) (xy 345.562914 -401.702107) (xy 345.562428 -401.674838) (xy 345.125548 -401.674838)
			(xy 345.125062 -401.702089) (xy 345.117306 -401.756037) (xy 345.101951 -401.808332) (xy 345.079309 -401.857909)
			(xy 345.049843 -401.903759) (xy 345.014152 -401.94495) (xy 344.972961 -401.980641) (xy 344.927111 -402.010107)
			(xy 344.877534 -402.032749) (xy 344.825239 -402.048104) (xy 344.771291 -402.05586) (xy 344.716789 -402.05586)
			(xy 344.662841 -402.048104) (xy 344.610546 -402.032749) (xy 344.560969 -402.010107) (xy 344.515119 -401.980641)
			(xy 344.473928 -401.94495) (xy 344.438237 -401.903759) (xy 344.408771 -401.857909) (xy 344.386129 -401.808332)
			(xy 344.370774 -401.756037) (xy 344.363018 -401.702089) (xy 344.362532 -401.674838) (xy 343.925652 -401.674838)
			(xy 343.925166 -401.702089) (xy 343.91741 -401.756037) (xy 343.902055 -401.808332) (xy 343.879413 -401.857909)
			(xy 343.849947 -401.903759) (xy 343.814256 -401.94495) (xy 343.773065 -401.980641) (xy 343.727215 -402.010107)
			(xy 343.677638 -402.032749) (xy 343.625343 -402.048104) (xy 343.571395 -402.05586) (xy 343.516893 -402.05586)
			(xy 343.462945 -402.048104) (xy 343.41065 -402.032749) (xy 343.361073 -402.010107) (xy 343.315223 -401.980641)
			(xy 343.274032 -401.94495) (xy 343.238341 -401.903759) (xy 343.208875 -401.857909) (xy 343.186233 -401.808332)
			(xy 343.170878 -401.756037) (xy 343.163122 -401.702089) (xy 343.162636 -401.674838) (xy 342.725756 -401.674838)
			(xy 342.72527 -401.702107) (xy 342.717508 -401.756091) (xy 342.702143 -401.808421) (xy 342.679486 -401.858031)
			(xy 342.65 -401.903912) (xy 342.614285 -401.945129) (xy 342.573068 -401.980844) (xy 342.527187 -402.01033)
			(xy 342.477577 -402.032987) (xy 342.425247 -402.048352) (xy 342.371263 -402.056114) (xy 342.316725 -402.056114)
			(xy 342.262741 -402.048352) (xy 342.210411 -402.032987) (xy 342.160801 -402.01033) (xy 342.11492 -401.980844)
			(xy 342.073703 -401.945129) (xy 342.037988 -401.903912) (xy 342.008502 -401.858031) (xy 341.985845 -401.808421)
			(xy 341.97048 -401.756091) (xy 341.962718 -401.702107) (xy 341.962232 -401.674838) (xy 341.52586 -401.674838)
			(xy 341.525374 -401.702107) (xy 341.517612 -401.756091) (xy 341.502247 -401.808421) (xy 341.47959 -401.858031)
			(xy 341.450104 -401.903912) (xy 341.414389 -401.945129) (xy 341.373172 -401.980844) (xy 341.327291 -402.01033)
			(xy 341.277681 -402.032987) (xy 341.225351 -402.048352) (xy 341.171367 -402.056114) (xy 341.116829 -402.056114)
			(xy 341.062845 -402.048352) (xy 341.010515 -402.032987) (xy 340.960905 -402.01033) (xy 340.915024 -401.980844)
			(xy 340.873807 -401.945129) (xy 340.838092 -401.903912) (xy 340.808606 -401.858031) (xy 340.785949 -401.808421)
			(xy 340.770584 -401.756091) (xy 340.762822 -401.702107) (xy 340.762336 -401.674838) (xy 340.325456 -401.674838)
			(xy 340.32497 -401.702089) (xy 340.317214 -401.756037) (xy 340.301859 -401.808332) (xy 340.279217 -401.857909)
			(xy 340.249751 -401.903759) (xy 340.21406 -401.94495) (xy 340.172869 -401.980641) (xy 340.127019 -402.010107)
			(xy 340.077442 -402.032749) (xy 340.025147 -402.048104) (xy 339.971199 -402.05586) (xy 339.916697 -402.05586)
			(xy 339.862749 -402.048104) (xy 339.810454 -402.032749) (xy 339.760877 -402.010107) (xy 339.715027 -401.980641)
			(xy 339.673836 -401.94495) (xy 339.638145 -401.903759) (xy 339.608679 -401.857909) (xy 339.586037 -401.808332)
			(xy 339.570682 -401.756037) (xy 339.562926 -401.702089) (xy 339.56244 -401.674838) (xy 339.12556 -401.674838)
			(xy 339.125074 -401.702089) (xy 339.117318 -401.756037) (xy 339.101963 -401.808332) (xy 339.079321 -401.857909)
			(xy 339.049855 -401.903759) (xy 339.014164 -401.94495) (xy 338.972973 -401.980641) (xy 338.927123 -402.010107)
			(xy 338.877546 -402.032749) (xy 338.825251 -402.048104) (xy 338.771303 -402.05586) (xy 338.716801 -402.05586)
			(xy 338.662853 -402.048104) (xy 338.610558 -402.032749) (xy 338.560981 -402.010107) (xy 338.515131 -401.980641)
			(xy 338.47394 -401.94495) (xy 338.438249 -401.903759) (xy 338.408783 -401.857909) (xy 338.386141 -401.808332)
			(xy 338.370786 -401.756037) (xy 338.36303 -401.702089) (xy 338.362544 -401.674838) (xy 337.925664 -401.674838)
			(xy 337.925178 -401.702107) (xy 337.917416 -401.756091) (xy 337.902051 -401.808421) (xy 337.879394 -401.858031)
			(xy 337.849908 -401.903912) (xy 337.814193 -401.945129) (xy 337.772976 -401.980844) (xy 337.727095 -402.01033)
			(xy 337.677485 -402.032987) (xy 337.625155 -402.048352) (xy 337.571171 -402.056114) (xy 337.516633 -402.056114)
			(xy 337.462649 -402.048352) (xy 337.410319 -402.032987) (xy 337.360709 -402.01033) (xy 337.314828 -401.980844)
			(xy 337.273611 -401.945129) (xy 337.237896 -401.903912) (xy 337.20841 -401.858031) (xy 337.185753 -401.808421)
			(xy 337.170388 -401.756091) (xy 337.162626 -401.702107) (xy 337.16214 -401.674838) (xy 336.725768 -401.674838)
			(xy 336.725282 -401.702107) (xy 336.71752 -401.756091) (xy 336.702155 -401.808421) (xy 336.679498 -401.858031)
			(xy 336.650012 -401.903912) (xy 336.614297 -401.945129) (xy 336.57308 -401.980844) (xy 336.527199 -402.01033)
			(xy 336.477589 -402.032987) (xy 336.425259 -402.048352) (xy 336.371275 -402.056114) (xy 336.316737 -402.056114)
			(xy 336.262753 -402.048352) (xy 336.210423 -402.032987) (xy 336.160813 -402.01033) (xy 336.114932 -401.980844)
			(xy 336.073715 -401.945129) (xy 336.038 -401.903912) (xy 336.008514 -401.858031) (xy 335.985857 -401.808421)
			(xy 335.970492 -401.756091) (xy 335.96273 -401.702107) (xy 335.962244 -401.674838) (xy 322.197984 -401.674838)
			(xy 322.197498 -401.702107) (xy 322.189736 -401.756091) (xy 322.174371 -401.808421) (xy 322.151714 -401.858031)
			(xy 322.122228 -401.903912) (xy 322.086513 -401.945129) (xy 322.045296 -401.980844) (xy 321.999415 -402.01033)
			(xy 321.949805 -402.032987) (xy 321.897475 -402.048352) (xy 321.843491 -402.056114) (xy 321.788953 -402.056114)
			(xy 321.734969 -402.048352) (xy 321.682639 -402.032987) (xy 321.633029 -402.01033) (xy 321.587148 -401.980844)
			(xy 321.545931 -401.945129) (xy 321.510216 -401.903912) (xy 321.48073 -401.858031) (xy 321.458073 -401.808421)
			(xy 321.442708 -401.756091) (xy 321.434946 -401.702107) (xy 321.43446 -401.674838) (xy 320.998088 -401.674838)
			(xy 320.997602 -401.702107) (xy 320.98984 -401.756091) (xy 320.974475 -401.808421) (xy 320.951818 -401.858031)
			(xy 320.922332 -401.903912) (xy 320.886617 -401.945129) (xy 320.8454 -401.980844) (xy 320.799519 -402.01033)
			(xy 320.749909 -402.032987) (xy 320.697579 -402.048352) (xy 320.643595 -402.056114) (xy 320.589057 -402.056114)
			(xy 320.535073 -402.048352) (xy 320.482743 -402.032987) (xy 320.433133 -402.01033) (xy 320.387252 -401.980844)
			(xy 320.346035 -401.945129) (xy 320.31032 -401.903912) (xy 320.280834 -401.858031) (xy 320.258177 -401.808421)
			(xy 320.242812 -401.756091) (xy 320.23505 -401.702107) (xy 320.234564 -401.674838) (xy 319.797684 -401.674838)
			(xy 319.797198 -401.702089) (xy 319.789442 -401.756037) (xy 319.774087 -401.808332) (xy 319.751445 -401.857909)
			(xy 319.721979 -401.903759) (xy 319.686288 -401.94495) (xy 319.645097 -401.980641) (xy 319.599247 -402.010107)
			(xy 319.54967 -402.032749) (xy 319.497375 -402.048104) (xy 319.443427 -402.05586) (xy 319.388925 -402.05586)
			(xy 319.334977 -402.048104) (xy 319.282682 -402.032749) (xy 319.233105 -402.010107) (xy 319.187255 -401.980641)
			(xy 319.146064 -401.94495) (xy 319.110373 -401.903759) (xy 319.080907 -401.857909) (xy 319.058265 -401.808332)
			(xy 319.04291 -401.756037) (xy 319.035154 -401.702089) (xy 319.034668 -401.674838) (xy 318.597788 -401.674838)
			(xy 318.597302 -401.702089) (xy 318.589546 -401.756037) (xy 318.574191 -401.808332) (xy 318.551549 -401.857909)
			(xy 318.522083 -401.903759) (xy 318.486392 -401.94495) (xy 318.445201 -401.980641) (xy 318.399351 -402.010107)
			(xy 318.349774 -402.032749) (xy 318.297479 -402.048104) (xy 318.243531 -402.05586) (xy 318.189029 -402.05586)
			(xy 318.135081 -402.048104) (xy 318.082786 -402.032749) (xy 318.033209 -402.010107) (xy 317.987359 -401.980641)
			(xy 317.946168 -401.94495) (xy 317.910477 -401.903759) (xy 317.881011 -401.857909) (xy 317.858369 -401.808332)
			(xy 317.843014 -401.756037) (xy 317.835258 -401.702089) (xy 317.834772 -401.674838) (xy 317.397892 -401.674838)
			(xy 317.397406 -401.702089) (xy 317.38965 -401.756037) (xy 317.374295 -401.808332) (xy 317.351653 -401.857909)
			(xy 317.322187 -401.903759) (xy 317.286496 -401.94495) (xy 317.245305 -401.980641) (xy 317.199455 -402.010107)
			(xy 317.149878 -402.032749) (xy 317.097583 -402.048104) (xy 317.043635 -402.05586) (xy 316.989133 -402.05586)
			(xy 316.935185 -402.048104) (xy 316.88289 -402.032749) (xy 316.833313 -402.010107) (xy 316.787463 -401.980641)
			(xy 316.746272 -401.94495) (xy 316.710581 -401.903759) (xy 316.681115 -401.857909) (xy 316.658473 -401.808332)
			(xy 316.643118 -401.756037) (xy 316.635362 -401.702089) (xy 316.634876 -401.674838) (xy 316.197996 -401.674838)
			(xy 316.19751 -401.702089) (xy 316.189754 -401.756037) (xy 316.174399 -401.808332) (xy 316.151757 -401.857909)
			(xy 316.122291 -401.903759) (xy 316.0866 -401.94495) (xy 316.045409 -401.980641) (xy 315.999559 -402.010107)
			(xy 315.949982 -402.032749) (xy 315.897687 -402.048104) (xy 315.843739 -402.05586) (xy 315.789237 -402.05586)
			(xy 315.735289 -402.048104) (xy 315.682994 -402.032749) (xy 315.633417 -402.010107) (xy 315.587567 -401.980641)
			(xy 315.546376 -401.94495) (xy 315.510685 -401.903759) (xy 315.481219 -401.857909) (xy 315.458577 -401.808332)
			(xy 315.443222 -401.756037) (xy 315.435466 -401.702089) (xy 315.43498 -401.674838) (xy 314.9981 -401.674838)
			(xy 314.997614 -401.702107) (xy 314.989852 -401.756091) (xy 314.974487 -401.808421) (xy 314.95183 -401.858031)
			(xy 314.922344 -401.903912) (xy 314.886629 -401.945129) (xy 314.845412 -401.980844) (xy 314.799531 -402.01033)
			(xy 314.749921 -402.032987) (xy 314.697591 -402.048352) (xy 314.643607 -402.056114) (xy 314.589069 -402.056114)
			(xy 314.535085 -402.048352) (xy 314.482755 -402.032987) (xy 314.433145 -402.01033) (xy 314.387264 -401.980844)
			(xy 314.346047 -401.945129) (xy 314.310332 -401.903912) (xy 314.280846 -401.858031) (xy 314.258189 -401.808421)
			(xy 314.242824 -401.756091) (xy 314.235062 -401.702107) (xy 314.234576 -401.674838) (xy 313.798204 -401.674838)
			(xy 313.797718 -401.702107) (xy 313.789956 -401.756091) (xy 313.774591 -401.808421) (xy 313.751934 -401.858031)
			(xy 313.722448 -401.903912) (xy 313.686733 -401.945129) (xy 313.645516 -401.980844) (xy 313.599635 -402.01033)
			(xy 313.550025 -402.032987) (xy 313.497695 -402.048352) (xy 313.443711 -402.056114) (xy 313.389173 -402.056114)
			(xy 313.335189 -402.048352) (xy 313.282859 -402.032987) (xy 313.233249 -402.01033) (xy 313.187368 -401.980844)
			(xy 313.146151 -401.945129) (xy 313.110436 -401.903912) (xy 313.08095 -401.858031) (xy 313.058293 -401.808421)
			(xy 313.042928 -401.756091) (xy 313.035166 -401.702107) (xy 313.03468 -401.674838) (xy 312.5978 -401.674838)
			(xy 312.597314 -401.702089) (xy 312.589558 -401.756037) (xy 312.574203 -401.808332) (xy 312.551561 -401.857909)
			(xy 312.522095 -401.903759) (xy 312.486404 -401.94495) (xy 312.445213 -401.980641) (xy 312.399363 -402.010107)
			(xy 312.349786 -402.032749) (xy 312.297491 -402.048104) (xy 312.243543 -402.05586) (xy 312.189041 -402.05586)
			(xy 312.135093 -402.048104) (xy 312.082798 -402.032749) (xy 312.033221 -402.010107) (xy 311.987371 -401.980641)
			(xy 311.94618 -401.94495) (xy 311.910489 -401.903759) (xy 311.881023 -401.857909) (xy 311.858381 -401.808332)
			(xy 311.843026 -401.756037) (xy 311.83527 -401.702089) (xy 311.834784 -401.674838) (xy 311.397904 -401.674838)
			(xy 311.397418 -401.702089) (xy 311.389662 -401.756037) (xy 311.374307 -401.808332) (xy 311.351665 -401.857909)
			(xy 311.322199 -401.903759) (xy 311.286508 -401.94495) (xy 311.245317 -401.980641) (xy 311.199467 -402.010107)
			(xy 311.14989 -402.032749) (xy 311.097595 -402.048104) (xy 311.043647 -402.05586) (xy 310.989145 -402.05586)
			(xy 310.935197 -402.048104) (xy 310.882902 -402.032749) (xy 310.833325 -402.010107) (xy 310.787475 -401.980641)
			(xy 310.746284 -401.94495) (xy 310.710593 -401.903759) (xy 310.681127 -401.857909) (xy 310.658485 -401.808332)
			(xy 310.64313 -401.756037) (xy 310.635374 -401.702089) (xy 310.634888 -401.674838) (xy 310.198008 -401.674838)
			(xy 310.197522 -401.702107) (xy 310.18976 -401.756091) (xy 310.174395 -401.808421) (xy 310.151738 -401.858031)
			(xy 310.122252 -401.903912) (xy 310.086537 -401.945129) (xy 310.04532 -401.980844) (xy 309.999439 -402.01033)
			(xy 309.949829 -402.032987) (xy 309.897499 -402.048352) (xy 309.843515 -402.056114) (xy 309.788977 -402.056114)
			(xy 309.734993 -402.048352) (xy 309.682663 -402.032987) (xy 309.633053 -402.01033) (xy 309.587172 -401.980844)
			(xy 309.545955 -401.945129) (xy 309.51024 -401.903912) (xy 309.480754 -401.858031) (xy 309.458097 -401.808421)
			(xy 309.442732 -401.756091) (xy 309.43497 -401.702107) (xy 309.434484 -401.674838) (xy 308.998112 -401.674838)
			(xy 308.997626 -401.702107) (xy 308.989864 -401.756091) (xy 308.974499 -401.808421) (xy 308.951842 -401.858031)
			(xy 308.922356 -401.903912) (xy 308.886641 -401.945129) (xy 308.845424 -401.980844) (xy 308.799543 -402.01033)
			(xy 308.749933 -402.032987) (xy 308.697603 -402.048352) (xy 308.643619 -402.056114) (xy 308.589081 -402.056114)
			(xy 308.535097 -402.048352) (xy 308.482767 -402.032987) (xy 308.433157 -402.01033) (xy 308.387276 -401.980844)
			(xy 308.346059 -401.945129) (xy 308.310344 -401.903912) (xy 308.280858 -401.858031) (xy 308.258201 -401.808421)
			(xy 308.242836 -401.756091) (xy 308.235074 -401.702107) (xy 308.234588 -401.674838) (xy 307.797708 -401.674838)
			(xy 307.797222 -401.702089) (xy 307.789466 -401.756037) (xy 307.774111 -401.808332) (xy 307.751469 -401.857909)
			(xy 307.722003 -401.903759) (xy 307.686312 -401.94495) (xy 307.645121 -401.980641) (xy 307.599271 -402.010107)
			(xy 307.549694 -402.032749) (xy 307.497399 -402.048104) (xy 307.443451 -402.05586) (xy 307.388949 -402.05586)
			(xy 307.335001 -402.048104) (xy 307.282706 -402.032749) (xy 307.233129 -402.010107) (xy 307.187279 -401.980641)
			(xy 307.146088 -401.94495) (xy 307.110397 -401.903759) (xy 307.080931 -401.857909) (xy 307.058289 -401.808332)
			(xy 307.042934 -401.756037) (xy 307.035178 -401.702089) (xy 307.034692 -401.674838) (xy 306.597812 -401.674838)
			(xy 306.597326 -401.702089) (xy 306.58957 -401.756037) (xy 306.574215 -401.808332) (xy 306.551573 -401.857909)
			(xy 306.522107 -401.903759) (xy 306.486416 -401.94495) (xy 306.445225 -401.980641) (xy 306.399375 -402.010107)
			(xy 306.349798 -402.032749) (xy 306.297503 -402.048104) (xy 306.243555 -402.05586) (xy 306.189053 -402.05586)
			(xy 306.135105 -402.048104) (xy 306.08281 -402.032749) (xy 306.033233 -402.010107) (xy 305.987383 -401.980641)
			(xy 305.946192 -401.94495) (xy 305.910501 -401.903759) (xy 305.881035 -401.857909) (xy 305.858393 -401.808332)
			(xy 305.843038 -401.756037) (xy 305.835282 -401.702089) (xy 305.834796 -401.674838) (xy 305.397916 -401.674838)
			(xy 305.39743 -401.702107) (xy 305.389668 -401.756091) (xy 305.374303 -401.808421) (xy 305.351646 -401.858031)
			(xy 305.32216 -401.903912) (xy 305.286445 -401.945129) (xy 305.245228 -401.980844) (xy 305.199347 -402.01033)
			(xy 305.149737 -402.032987) (xy 305.097407 -402.048352) (xy 305.043423 -402.056114) (xy 304.988885 -402.056114)
			(xy 304.934901 -402.048352) (xy 304.882571 -402.032987) (xy 304.832961 -402.01033) (xy 304.78708 -401.980844)
			(xy 304.745863 -401.945129) (xy 304.710148 -401.903912) (xy 304.680662 -401.858031) (xy 304.658005 -401.808421)
			(xy 304.64264 -401.756091) (xy 304.634878 -401.702107) (xy 304.634392 -401.674838) (xy 304.19802 -401.674838)
			(xy 304.197534 -401.702107) (xy 304.189772 -401.756091) (xy 304.174407 -401.808421) (xy 304.15175 -401.858031)
			(xy 304.122264 -401.903912) (xy 304.086549 -401.945129) (xy 304.045332 -401.980844) (xy 303.999451 -402.01033)
			(xy 303.949841 -402.032987) (xy 303.897511 -402.048352) (xy 303.843527 -402.056114) (xy 303.788989 -402.056114)
			(xy 303.735005 -402.048352) (xy 303.682675 -402.032987) (xy 303.633065 -402.01033) (xy 303.587184 -401.980844)
			(xy 303.545967 -401.945129) (xy 303.510252 -401.903912) (xy 303.480766 -401.858031) (xy 303.458109 -401.808421)
			(xy 303.442744 -401.756091) (xy 303.434982 -401.702107) (xy 303.434496 -401.674838) (xy 280.68524 -401.674838)
			(xy 280.68524 -404.215092) (xy 283.62402 -404.215092) (xy 283.62402 -403.351492) (xy 283.624506 -403.324223)
			(xy 283.632268 -403.270239) (xy 283.647633 -403.217909) (xy 283.67029 -403.168299) (xy 283.699776 -403.122418)
			(xy 283.735491 -403.081201) (xy 283.776708 -403.045486) (xy 283.822589 -403.016) (xy 283.872199 -402.993343)
			(xy 283.924529 -402.977978) (xy 283.978513 -402.970216) (xy 284.033051 -402.970216) (xy 284.087035 -402.977978)
			(xy 284.139365 -402.993343) (xy 284.188975 -403.016) (xy 284.203533 -403.025356) (xy 289.919156 -403.025356)
			(xy 289.919156 -402.161756) (xy 289.919642 -402.134487) (xy 289.927404 -402.080503) (xy 289.942769 -402.028173)
			(xy 289.965426 -401.978563) (xy 289.994912 -401.932682) (xy 290.030627 -401.891465) (xy 290.071844 -401.85575)
			(xy 290.117725 -401.826264) (xy 290.167335 -401.803607) (xy 290.219665 -401.788242) (xy 290.273649 -401.78048)
			(xy 290.328187 -401.78048) (xy 290.382171 -401.788242) (xy 290.434501 -401.803607) (xy 290.484111 -401.826264)
			(xy 290.529992 -401.85575) (xy 290.571209 -401.891465) (xy 290.606924 -401.932682) (xy 290.63641 -401.978563)
			(xy 290.659067 -402.028173) (xy 290.674432 -402.080503) (xy 290.682194 -402.134487) (xy 290.68268 -402.161756)
			(xy 290.68268 -403.025356) (xy 290.682194 -403.052625) (xy 290.674432 -403.106609) (xy 290.659067 -403.158939)
			(xy 290.63641 -403.208549) (xy 290.606924 -403.25443) (xy 290.571209 -403.295647) (xy 290.529992 -403.331362)
			(xy 290.484111 -403.360848) (xy 290.434501 -403.383505) (xy 290.382171 -403.39887) (xy 290.328187 -403.406632)
			(xy 290.273649 -403.406632) (xy 290.219665 -403.39887) (xy 290.167335 -403.383505) (xy 290.117725 -403.360848)
			(xy 290.071844 -403.331362) (xy 290.030627 -403.295647) (xy 289.994912 -403.25443) (xy 289.965426 -403.208549)
			(xy 289.942769 -403.158939) (xy 289.927404 -403.106609) (xy 289.919642 -403.052625) (xy 289.919156 -403.025356)
			(xy 284.203533 -403.025356) (xy 284.234856 -403.045486) (xy 284.276073 -403.081201) (xy 284.311788 -403.122418)
			(xy 284.341274 -403.168299) (xy 284.363931 -403.217909) (xy 284.379296 -403.270239) (xy 284.387058 -403.324223)
			(xy 284.387544 -403.351492) (xy 284.387544 -404.215092) (xy 284.387058 -404.242361) (xy 284.379296 -404.296345)
			(xy 284.363931 -404.348675) (xy 284.341274 -404.398285) (xy 284.311788 -404.444166) (xy 284.276073 -404.485383)
			(xy 284.234856 -404.521098) (xy 284.188975 -404.550584) (xy 284.139365 -404.573241) (xy 284.087035 -404.588606)
			(xy 284.033051 -404.596368) (xy 283.978513 -404.596368) (xy 283.924529 -404.588606) (xy 283.872199 -404.573241)
			(xy 283.822589 -404.550584) (xy 283.776708 -404.521098) (xy 283.735491 -404.485383) (xy 283.699776 -404.444166)
			(xy 283.67029 -404.398285) (xy 283.647633 -404.348675) (xy 283.632268 -404.296345) (xy 283.624506 -404.242361)
			(xy 283.62402 -404.215092) (xy 280.68524 -404.215092) (xy 280.68524 -407.583953) (xy 282.536071 -407.583953)
			(xy 282.536071 -407.529447) (xy 282.543829 -407.475495) (xy 282.559186 -407.423196) (xy 282.581831 -407.373615)
			(xy 282.611301 -407.327762) (xy 282.646997 -407.28657) (xy 282.688193 -407.250878) (xy 282.734049 -407.221412)
			(xy 282.783632 -407.198773) (xy 282.835932 -407.183421) (xy 282.889885 -407.175669) (xy 282.917138 -407.175208)
			(xy 283.780738 -407.175208) (xy 283.807989 -407.175664) (xy 283.861934 -407.183426) (xy 283.914227 -407.198785)
			(xy 283.963801 -407.221429) (xy 284.009649 -407.250898) (xy 284.050836 -407.286591) (xy 284.086525 -407.327782)
			(xy 284.115989 -407.373632) (xy 284.134525 -407.414222) (xy 287.101788 -407.414222) (xy 287.101788 -406.550622)
			(xy 287.102274 -406.523371) (xy 287.11003 -406.469423) (xy 287.125385 -406.417128) (xy 287.148027 -406.367551)
			(xy 287.177493 -406.321701) (xy 287.213184 -406.28051) (xy 287.254375 -406.244819) (xy 287.300225 -406.215353)
			(xy 287.349802 -406.192711) (xy 287.402097 -406.177356) (xy 287.456045 -406.1696) (xy 287.510547 -406.1696)
			(xy 287.564495 -406.177356) (xy 287.61679 -406.192711) (xy 287.666367 -406.215353) (xy 287.712217 -406.244819)
			(xy 287.753408 -406.28051) (xy 287.789099 -406.321701) (xy 287.818565 -406.367551) (xy 287.841207 -406.417128)
			(xy 287.856562 -406.469423) (xy 287.864318 -406.523371) (xy 287.864804 -406.550622) (xy 287.864804 -407.414222)
			(xy 287.864318 -407.441473) (xy 287.856562 -407.495421) (xy 287.841207 -407.547716) (xy 287.818565 -407.597293)
			(xy 287.789099 -407.643143) (xy 287.753408 -407.684334) (xy 287.712217 -407.720025) (xy 287.666367 -407.749491)
			(xy 287.61679 -407.772133) (xy 287.564495 -407.787488) (xy 287.510547 -407.795244) (xy 287.456045 -407.795244)
			(xy 287.402097 -407.787488) (xy 287.349802 -407.772133) (xy 287.300225 -407.749491) (xy 287.254375 -407.720025)
			(xy 287.213184 -407.684334) (xy 287.177493 -407.643143) (xy 287.148027 -407.597293) (xy 287.125385 -407.547716)
			(xy 287.11003 -407.495421) (xy 287.102274 -407.441473) (xy 287.101788 -407.414222) (xy 284.134525 -407.414222)
			(xy 284.138629 -407.423209) (xy 284.153982 -407.475503) (xy 284.161738 -407.529449) (xy 284.161738 -407.583951)
			(xy 284.153982 -407.637897) (xy 284.138629 -407.690191) (xy 284.115989 -407.739768) (xy 284.086525 -407.785619)
			(xy 284.050836 -407.826809) (xy 284.009649 -407.862502) (xy 283.963801 -407.891971) (xy 283.914227 -407.914615)
			(xy 283.861934 -407.929974) (xy 283.807989 -407.937736) (xy 283.780738 -407.938224) (xy 282.917138 -407.938224)
			(xy 282.889885 -407.937731) (xy 282.835932 -407.929979) (xy 282.783632 -407.914627) (xy 282.734049 -407.891988)
			(xy 282.688193 -407.862522) (xy 282.646997 -407.82683) (xy 282.611301 -407.785638) (xy 282.581831 -407.739785)
			(xy 282.559186 -407.690204) (xy 282.543829 -407.637905) (xy 282.536071 -407.583953) (xy 280.68524 -407.583953)
			(xy 280.68524 -409.10256) (xy 280.684766 -409.12751) (xy 280.676946 -409.176794) (xy 280.661524 -409.224251)
			(xy 280.638877 -409.268716) (xy 280.609563 -409.309098) (xy 280.592276 -409.327096) (xy 276.749256 -413.170116)
			(xy 293.568894 -413.170116) (xy 293.572866 -412.991873) (xy 293.584774 -412.813984) (xy 293.604595 -412.636802)
			(xy 293.632289 -412.460678) (xy 293.667801 -412.285963) (xy 293.711061 -412.113004) (xy 293.761983 -411.942143)
			(xy 293.820466 -411.773721) (xy 293.886393 -411.608071) (xy 293.959634 -411.445522) (xy 294.040044 -411.286397)
			(xy 294.127462 -411.131012) (xy 294.221715 -410.979676) (xy 294.322616 -410.832688) (xy 294.429965 -410.690341)
			(xy 294.543548 -410.552918) (xy 294.663141 -410.420691) (xy 294.788505 -410.293922) (xy 294.919392 -410.172864)
			(xy 295.055541 -410.057757) (xy 295.196683 -409.948829) (xy 295.342538 -409.846297) (xy 295.492815 -409.750363)
			(xy 295.647216 -409.66122) (xy 295.805435 -409.579043) (xy 295.967158 -409.503995) (xy 296.132063 -409.436227)
			(xy 296.299824 -409.375871) (xy 296.470107 -409.323049) (xy 296.642574 -409.277865) (xy 296.816882 -409.240408)
			(xy 296.992686 -409.210754) (xy 297.169636 -409.188961) (xy 297.347382 -409.175071) (xy 297.525569 -409.169114)
			(xy 297.703846 -409.1711) (xy 297.881857 -409.181026) (xy 298.059249 -409.198872) (xy 298.235669 -409.224602)
			(xy 298.410769 -409.258166) (xy 298.5842 -409.299496) (xy 298.755617 -409.348512) (xy 298.92468 -409.405114)
			(xy 299.091055 -409.469192) (xy 299.254409 -409.540618) (xy 299.41442 -409.61925) (xy 299.570769 -409.704931)
			(xy 299.723146 -409.797493) (xy 299.871249 -409.89675) (xy 300.014783 -410.002507) (xy 300.153463 -410.114552)
			(xy 300.287014 -410.232664) (xy 300.415171 -410.356608) (xy 300.53768 -410.486138) (xy 300.654297 -410.620997)
			(xy 300.76479 -410.760917) (xy 300.868941 -410.90562) (xy 300.966543 -411.054819) (xy 301.057401 -411.208218)
			(xy 301.141335 -411.365512) (xy 301.21818 -411.526388) (xy 301.287781 -411.690529) (xy 301.350002 -411.857606)
			(xy 301.404718 -412.02729) (xy 301.45182 -412.199243) (xy 301.491216 -412.373123) (xy 301.522827 -412.548586)
			(xy 301.546591 -412.725282) (xy 301.559858 -412.873752) (xy 303.412875 -412.873752) (xy 303.412875 -412.819248)
			(xy 303.420632 -412.7653) (xy 303.435988 -412.713004) (xy 303.458629 -412.663426) (xy 303.488096 -412.617575)
			(xy 303.523789 -412.576384) (xy 303.56498 -412.540693) (xy 303.610831 -412.511226) (xy 303.66041 -412.488585)
			(xy 303.712706 -412.473231) (xy 303.766654 -412.465475) (xy 303.793906 -412.465012) (xy 304.657506 -412.465012)
			(xy 304.684758 -412.465458) (xy 304.738708 -412.473216) (xy 304.791005 -412.488572) (xy 304.840584 -412.511215)
			(xy 304.886436 -412.540683) (xy 304.927628 -412.576376) (xy 304.963321 -412.617569) (xy 304.992788 -412.663421)
			(xy 305.01543 -412.713001) (xy 305.030785 -412.765298) (xy 305.038542 -412.819248) (xy 305.038542 -412.873752)
			(xy 305.038542 -412.873754) (xy 306.476075 -412.873754) (xy 306.476075 -412.819246) (xy 306.483833 -412.765294)
			(xy 306.499191 -412.712996) (xy 306.521835 -412.663415) (xy 306.551306 -412.617562) (xy 306.587003 -412.57637)
			(xy 306.628199 -412.540679) (xy 306.674055 -412.511213) (xy 306.723639 -412.488575) (xy 306.775939 -412.473223)
			(xy 306.829892 -412.465472) (xy 306.857146 -412.465012) (xy 307.720746 -412.465012) (xy 307.747997 -412.465461)
			(xy 307.801942 -412.473223) (xy 307.854234 -412.488583) (xy 307.903808 -412.511228) (xy 307.949655 -412.540697)
			(xy 307.990842 -412.576391) (xy 308.02653 -412.617582) (xy 308.055994 -412.663432) (xy 308.078633 -412.713009)
			(xy 308.093987 -412.765303) (xy 308.101742 -412.819249) (xy 308.101742 -412.873749) (xy 309.539398 -412.873749)
			(xy 309.539398 -412.819251) (xy 309.547154 -412.765307) (xy 309.562508 -412.713016) (xy 309.585146 -412.663443)
			(xy 309.61461 -412.617596) (xy 309.650298 -412.576408) (xy 309.691484 -412.540718) (xy 309.73733 -412.511253)
			(xy 309.786903 -412.488612) (xy 309.839194 -412.473257) (xy 309.893137 -412.465499) (xy 309.920386 -412.465012)
			(xy 310.783986 -412.465012) (xy 310.811241 -412.465434) (xy 310.865196 -412.47319) (xy 310.917499 -412.488545)
			(xy 310.967083 -412.511188) (xy 311.012941 -412.540657) (xy 311.054137 -412.576353) (xy 311.089834 -412.617548)
			(xy 311.119305 -412.663405) (xy 311.14195 -412.712988) (xy 311.157307 -412.76529) (xy 311.165065 -412.819245)
			(xy 311.165065 -412.873753) (xy 312.602575 -412.873753) (xy 312.602575 -412.819247) (xy 312.610333 -412.765297)
			(xy 312.625689 -412.713) (xy 312.648332 -412.663421) (xy 312.677801 -412.617569) (xy 312.713496 -412.576377)
			(xy 312.754689 -412.540686) (xy 312.800543 -412.51122) (xy 312.850124 -412.48858) (xy 312.902422 -412.473227)
			(xy 312.956373 -412.465474) (xy 312.983626 -412.465012) (xy 313.847226 -412.465012) (xy 313.874477 -412.46546)
			(xy 313.928425 -412.47322) (xy 313.98072 -412.488578) (xy 314.030296 -412.511222) (xy 314.076146 -412.54069)
			(xy 314.117335 -412.576383) (xy 314.153026 -412.617575) (xy 314.182491 -412.663427) (xy 314.205131 -412.713005)
			(xy 314.220486 -412.7653) (xy 314.228242 -412.819249) (xy 314.228242 -412.873748) (xy 315.665898 -412.873748)
			(xy 315.665898 -412.819252) (xy 315.673653 -412.76531) (xy 315.689006 -412.713021) (xy 315.711643 -412.663448)
			(xy 315.741105 -412.617602) (xy 315.776791 -412.576415) (xy 315.817975 -412.540725) (xy 315.863818 -412.51126)
			(xy 315.913389 -412.488618) (xy 315.965677 -412.473261) (xy 316.019618 -412.465501) (xy 316.046866 -412.465012)
			(xy 316.910466 -412.465012) (xy 316.937722 -412.465433) (xy 316.991679 -412.473186) (xy 317.043984 -412.48854)
			(xy 317.093571 -412.511182) (xy 317.139431 -412.54065) (xy 317.18063 -412.576346) (xy 317.216329 -412.617542)
			(xy 317.245802 -412.663399) (xy 317.268448 -412.712984) (xy 317.283807 -412.765287) (xy 317.291565 -412.819244)
			(xy 317.291565 -412.873752) (xy 318.729075 -412.873752) (xy 318.729075 -412.819248) (xy 318.736832 -412.7653)
			(xy 318.752188 -412.713004) (xy 318.774829 -412.663426) (xy 318.804296 -412.617575) (xy 318.839989 -412.576384)
			(xy 318.88118 -412.540693) (xy 318.927031 -412.511226) (xy 318.97661 -412.488585) (xy 319.028906 -412.473231)
			(xy 319.082854 -412.465475) (xy 319.110106 -412.465012) (xy 319.973706 -412.465012) (xy 320.000958 -412.465458)
			(xy 320.054908 -412.473216) (xy 320.107205 -412.488572) (xy 320.156784 -412.511215) (xy 320.202636 -412.540683)
			(xy 320.243828 -412.576376) (xy 320.279521 -412.617569) (xy 320.308988 -412.663421) (xy 320.33163 -412.713001)
			(xy 320.346985 -412.765298) (xy 320.354742 -412.819248) (xy 320.354742 -412.873752) (xy 320.354742 -412.873754)
			(xy 321.792275 -412.873754) (xy 321.792275 -412.819246) (xy 321.800033 -412.765294) (xy 321.815391 -412.712996)
			(xy 321.838035 -412.663415) (xy 321.867506 -412.617562) (xy 321.903203 -412.57637) (xy 321.944399 -412.540679)
			(xy 321.990255 -412.511213) (xy 322.039839 -412.488575) (xy 322.092139 -412.473223) (xy 322.146092 -412.465472)
			(xy 322.173346 -412.465012) (xy 323.036946 -412.465012) (xy 323.064197 -412.465461) (xy 323.118142 -412.473223)
			(xy 323.170434 -412.488583) (xy 323.220008 -412.511228) (xy 323.265855 -412.540697) (xy 323.307042 -412.576391)
			(xy 323.34273 -412.617582) (xy 323.372194 -412.663432) (xy 323.394833 -412.713009) (xy 323.410187 -412.765303)
			(xy 323.417942 -412.819249) (xy 323.417942 -412.873749) (xy 324.855598 -412.873749) (xy 324.855598 -412.819251)
			(xy 324.863354 -412.765307) (xy 324.878708 -412.713016) (xy 324.901346 -412.663443) (xy 324.93081 -412.617596)
			(xy 324.966498 -412.576408) (xy 325.007684 -412.540718) (xy 325.05353 -412.511253) (xy 325.103103 -412.488612)
			(xy 325.155394 -412.473257) (xy 325.209337 -412.465499) (xy 325.236586 -412.465012) (xy 326.100186 -412.465012)
			(xy 326.127441 -412.465434) (xy 326.181396 -412.47319) (xy 326.233699 -412.488545) (xy 326.283283 -412.511188)
			(xy 326.329141 -412.540657) (xy 326.370337 -412.576353) (xy 326.406034 -412.617548) (xy 326.435505 -412.663405)
			(xy 326.45815 -412.712988) (xy 326.473507 -412.76529) (xy 326.481265 -412.819245) (xy 326.481265 -412.873753)
			(xy 327.918775 -412.873753) (xy 327.918775 -412.819247) (xy 327.926533 -412.765297) (xy 327.941889 -412.713)
			(xy 327.964532 -412.663421) (xy 327.994001 -412.617569) (xy 328.029696 -412.576377) (xy 328.070889 -412.540686)
			(xy 328.116743 -412.51122) (xy 328.166324 -412.48858) (xy 328.218622 -412.473227) (xy 328.272573 -412.465474)
			(xy 328.299826 -412.465012) (xy 329.163426 -412.465012) (xy 329.190677 -412.46546) (xy 329.244625 -412.47322)
			(xy 329.29692 -412.488578) (xy 329.346496 -412.511222) (xy 329.392346 -412.54069) (xy 329.433535 -412.576383)
			(xy 329.469226 -412.617575) (xy 329.498691 -412.663427) (xy 329.521331 -412.713005) (xy 329.536686 -412.7653)
			(xy 329.544442 -412.819249) (xy 329.544442 -412.873748) (xy 330.982098 -412.873748) (xy 330.982098 -412.819252)
			(xy 330.989853 -412.76531) (xy 331.005206 -412.713021) (xy 331.027843 -412.663448) (xy 331.057305 -412.617602)
			(xy 331.092991 -412.576415) (xy 331.134175 -412.540725) (xy 331.180018 -412.51126) (xy 331.229589 -412.488618)
			(xy 331.281877 -412.473261) (xy 331.335818 -412.465501) (xy 331.363066 -412.465012) (xy 332.226666 -412.465012)
			(xy 332.253922 -412.465433) (xy 332.307879 -412.473186) (xy 332.360184 -412.48854) (xy 332.409771 -412.511182)
			(xy 332.455631 -412.54065) (xy 332.49683 -412.576346) (xy 332.532529 -412.617542) (xy 332.562002 -412.663399)
			(xy 332.584648 -412.712984) (xy 332.600007 -412.765287) (xy 332.607765 -412.819244) (xy 332.607765 -412.873752)
			(xy 334.045275 -412.873752) (xy 334.045275 -412.819248) (xy 334.053032 -412.7653) (xy 334.068388 -412.713004)
			(xy 334.091029 -412.663426) (xy 334.120496 -412.617575) (xy 334.156189 -412.576384) (xy 334.19738 -412.540693)
			(xy 334.243231 -412.511226) (xy 334.29281 -412.488585) (xy 334.345106 -412.473231) (xy 334.399054 -412.465475)
			(xy 334.426306 -412.465012) (xy 335.289906 -412.465012) (xy 335.317158 -412.465458) (xy 335.371108 -412.473216)
			(xy 335.423405 -412.488572) (xy 335.472984 -412.511215) (xy 335.518836 -412.540683) (xy 335.560028 -412.576376)
			(xy 335.595721 -412.617569) (xy 335.625188 -412.663421) (xy 335.64783 -412.713001) (xy 335.663185 -412.765298)
			(xy 335.670942 -412.819248) (xy 335.670942 -412.873752) (xy 335.670942 -412.873754) (xy 337.108475 -412.873754)
			(xy 337.108475 -412.819246) (xy 337.116233 -412.765294) (xy 337.131591 -412.712996) (xy 337.154235 -412.663415)
			(xy 337.183706 -412.617562) (xy 337.219403 -412.57637) (xy 337.260599 -412.540679) (xy 337.306455 -412.511213)
			(xy 337.356039 -412.488575) (xy 337.408339 -412.473223) (xy 337.462292 -412.465472) (xy 337.489546 -412.465012)
			(xy 338.353146 -412.465012) (xy 338.380397 -412.465461) (xy 338.434342 -412.473223) (xy 338.486634 -412.488583)
			(xy 338.536208 -412.511228) (xy 338.582055 -412.540697) (xy 338.623242 -412.576391) (xy 338.65893 -412.617582)
			(xy 338.688394 -412.663432) (xy 338.711033 -412.713009) (xy 338.726387 -412.765303) (xy 338.734142 -412.819249)
			(xy 338.734142 -412.873749) (xy 340.171798 -412.873749) (xy 340.171798 -412.819251) (xy 340.179554 -412.765307)
			(xy 340.194908 -412.713016) (xy 340.217546 -412.663443) (xy 340.24701 -412.617596) (xy 340.282698 -412.576408)
			(xy 340.323884 -412.540718) (xy 340.36973 -412.511253) (xy 340.419303 -412.488612) (xy 340.471594 -412.473257)
			(xy 340.525537 -412.465499) (xy 340.552786 -412.465012) (xy 341.416386 -412.465012) (xy 341.443641 -412.465434)
			(xy 341.497596 -412.47319) (xy 341.549899 -412.488545) (xy 341.599483 -412.511188) (xy 341.645341 -412.540657)
			(xy 341.686537 -412.576353) (xy 341.722234 -412.617548) (xy 341.751705 -412.663405) (xy 341.77435 -412.712988)
			(xy 341.789707 -412.76529) (xy 341.797465 -412.819245) (xy 341.797465 -412.873753) (xy 343.234975 -412.873753)
			(xy 343.234975 -412.819247) (xy 343.242733 -412.765297) (xy 343.258089 -412.713) (xy 343.280732 -412.663421)
			(xy 343.310201 -412.617569) (xy 343.345896 -412.576377) (xy 343.387089 -412.540686) (xy 343.432943 -412.51122)
			(xy 343.482524 -412.48858) (xy 343.534822 -412.473227) (xy 343.588773 -412.465474) (xy 343.616026 -412.465012)
			(xy 344.479626 -412.465012) (xy 344.506877 -412.46546) (xy 344.560825 -412.47322) (xy 344.61312 -412.488578)
			(xy 344.662696 -412.511222) (xy 344.708546 -412.54069) (xy 344.749735 -412.576383) (xy 344.785426 -412.617575)
			(xy 344.814891 -412.663427) (xy 344.837531 -412.713005) (xy 344.852886 -412.7653) (xy 344.860642 -412.819249)
			(xy 344.860642 -412.873748) (xy 346.298298 -412.873748) (xy 346.298298 -412.819252) (xy 346.306053 -412.76531)
			(xy 346.321406 -412.713021) (xy 346.344043 -412.663448) (xy 346.373505 -412.617602) (xy 346.409191 -412.576415)
			(xy 346.450375 -412.540725) (xy 346.496218 -412.51126) (xy 346.545789 -412.488618) (xy 346.598077 -412.473261)
			(xy 346.652018 -412.465501) (xy 346.679266 -412.465012) (xy 347.542866 -412.465012) (xy 347.570122 -412.465433)
			(xy 347.624079 -412.473186) (xy 347.676384 -412.48854) (xy 347.725971 -412.511182) (xy 347.771831 -412.54065)
			(xy 347.81303 -412.576346) (xy 347.848729 -412.617542) (xy 347.878202 -412.663399) (xy 347.900848 -412.712984)
			(xy 347.916207 -412.765287) (xy 347.923965 -412.819244) (xy 347.923965 -412.873752) (xy 349.361475 -412.873752)
			(xy 349.361475 -412.819248) (xy 349.369232 -412.7653) (xy 349.384588 -412.713004) (xy 349.407229 -412.663426)
			(xy 349.436696 -412.617575) (xy 349.472389 -412.576384) (xy 349.51358 -412.540693) (xy 349.559431 -412.511226)
			(xy 349.60901 -412.488585) (xy 349.661306 -412.473231) (xy 349.715254 -412.465475) (xy 349.742506 -412.465012)
			(xy 350.606106 -412.465012) (xy 350.633358 -412.465458) (xy 350.687308 -412.473216) (xy 350.739605 -412.488572)
			(xy 350.789184 -412.511215) (xy 350.835036 -412.540683) (xy 350.876228 -412.576376) (xy 350.911921 -412.617569)
			(xy 350.941388 -412.663421) (xy 350.96403 -412.713001) (xy 350.979385 -412.765298) (xy 350.987142 -412.819248)
			(xy 350.987142 -412.873752) (xy 370.513075 -412.873752) (xy 370.513075 -412.819248) (xy 370.520832 -412.7653)
			(xy 370.536187 -412.713005) (xy 370.558829 -412.663427) (xy 370.588295 -412.617576) (xy 370.623987 -412.576386)
			(xy 370.665178 -412.540694) (xy 370.711029 -412.511228) (xy 370.760607 -412.488587) (xy 370.812902 -412.473231)
			(xy 370.86685 -412.465475) (xy 370.894102 -412.465012) (xy 371.757702 -412.465012) (xy 371.784955 -412.465458)
			(xy 371.838905 -412.473215) (xy 371.891202 -412.488571) (xy 371.940782 -412.511214) (xy 371.986634 -412.540682)
			(xy 372.027826 -412.576375) (xy 372.06352 -412.617567) (xy 372.092987 -412.66342) (xy 372.115629 -412.713)
			(xy 372.130985 -412.765297) (xy 372.138742 -412.819247) (xy 372.138742 -412.873753) (xy 373.576275 -412.873753)
			(xy 373.576275 -412.819247) (xy 373.584033 -412.765295) (xy 373.59939 -412.712996) (xy 373.622035 -412.663416)
			(xy 373.651505 -412.617563) (xy 373.687201 -412.576372) (xy 373.728397 -412.54068) (xy 373.774253 -412.511215)
			(xy 373.823836 -412.488576) (xy 373.876136 -412.473224) (xy 373.930089 -412.465472) (xy 373.957342 -412.465012)
			(xy 374.820942 -412.465012) (xy 374.848193 -412.465461) (xy 374.902139 -412.473222) (xy 374.954431 -412.488582)
			(xy 375.004006 -412.511227) (xy 375.049853 -412.540696) (xy 375.091041 -412.576389) (xy 375.126729 -412.61758)
			(xy 375.156193 -412.663431) (xy 375.178833 -412.713008) (xy 375.194186 -412.765302) (xy 375.201942 -412.819249)
			(xy 375.201942 -412.873749) (xy 376.639598 -412.873749) (xy 376.639598 -412.819251) (xy 376.647354 -412.765308)
			(xy 376.662707 -412.713017) (xy 376.685346 -412.663444) (xy 376.714809 -412.617597) (xy 376.750497 -412.576409)
			(xy 376.791682 -412.54072) (xy 376.837528 -412.511254) (xy 376.8871 -412.488613) (xy 376.93939 -412.473258)
			(xy 376.993333 -412.465499) (xy 377.020582 -412.465012) (xy 377.884182 -412.465012) (xy 377.911437 -412.465434)
			(xy 377.965393 -412.473189) (xy 378.017696 -412.488544) (xy 378.067281 -412.511187) (xy 378.113139 -412.540656)
			(xy 378.154336 -412.576352) (xy 378.190033 -412.617547) (xy 378.219504 -412.663403) (xy 378.242149 -412.712987)
			(xy 378.257507 -412.765289) (xy 378.265265 -412.819245) (xy 378.265265 -412.873752) (xy 379.702775 -412.873752)
			(xy 379.702775 -412.819248) (xy 379.710532 -412.765298) (xy 379.725889 -412.713001) (xy 379.748532 -412.663422)
			(xy 379.778 -412.61757) (xy 379.813694 -412.576379) (xy 379.854888 -412.540687) (xy 379.900741 -412.511221)
			(xy 379.950321 -412.488581) (xy 380.002619 -412.473228) (xy 380.05657 -412.465474) (xy 380.083822 -412.465012)
			(xy 380.947422 -412.465012) (xy 380.974674 -412.465459) (xy 381.028622 -412.473219) (xy 381.080917 -412.488577)
			(xy 381.130494 -412.51122) (xy 381.176344 -412.540689) (xy 381.217534 -412.576382) (xy 381.253225 -412.617574)
			(xy 381.28269 -412.663426) (xy 381.305331 -412.713004) (xy 381.320686 -412.7653) (xy 381.328442 -412.819248)
			(xy 381.328442 -412.873748) (xy 382.766098 -412.873748) (xy 382.766098 -412.819252) (xy 382.773853 -412.76531)
			(xy 382.789206 -412.713022) (xy 382.811843 -412.663449) (xy 382.841304 -412.617603) (xy 382.876989 -412.576416)
			(xy 382.918173 -412.540727) (xy 382.964016 -412.511261) (xy 383.013586 -412.488619) (xy 383.065873 -412.473261)
			(xy 383.119814 -412.465501) (xy 383.147062 -412.465012) (xy 384.010662 -412.465012) (xy 384.037918 -412.465432)
			(xy 384.091876 -412.473185) (xy 384.144181 -412.488539) (xy 384.193769 -412.51118) (xy 384.239629 -412.540649)
			(xy 384.280829 -412.576345) (xy 384.316528 -412.61754) (xy 384.346001 -412.663398) (xy 384.368648 -412.712983)
			(xy 384.384007 -412.765287) (xy 384.391765 -412.819244) (xy 384.391765 -412.873752) (xy 385.829275 -412.873752)
			(xy 385.829275 -412.819248) (xy 385.837032 -412.7653) (xy 385.852387 -412.713005) (xy 385.875029 -412.663427)
			(xy 385.904495 -412.617576) (xy 385.940187 -412.576386) (xy 385.981378 -412.540694) (xy 386.027229 -412.511228)
			(xy 386.076807 -412.488587) (xy 386.129102 -412.473231) (xy 386.18305 -412.465475) (xy 386.210302 -412.465012)
			(xy 387.073902 -412.465012) (xy 387.101155 -412.465458) (xy 387.155105 -412.473215) (xy 387.207402 -412.488571)
			(xy 387.256982 -412.511214) (xy 387.302834 -412.540682) (xy 387.344026 -412.576375) (xy 387.37972 -412.617567)
			(xy 387.409187 -412.66342) (xy 387.431829 -412.713) (xy 387.447185 -412.765297) (xy 387.454942 -412.819247)
			(xy 387.454942 -412.873753) (xy 388.892475 -412.873753) (xy 388.892475 -412.819247) (xy 388.900233 -412.765295)
			(xy 388.91559 -412.712996) (xy 388.938235 -412.663416) (xy 388.967705 -412.617563) (xy 389.003401 -412.576372)
			(xy 389.044597 -412.54068) (xy 389.090453 -412.511215) (xy 389.140036 -412.488576) (xy 389.192336 -412.473224)
			(xy 389.246289 -412.465472) (xy 389.273542 -412.465012) (xy 390.137142 -412.465012) (xy 390.164393 -412.465461)
			(xy 390.218339 -412.473222) (xy 390.270631 -412.488582) (xy 390.320206 -412.511227) (xy 390.366053 -412.540696)
			(xy 390.407241 -412.576389) (xy 390.442929 -412.61758) (xy 390.472393 -412.663431) (xy 390.495033 -412.713008)
			(xy 390.510386 -412.765302) (xy 390.518142 -412.819249) (xy 390.518142 -412.873749) (xy 391.955798 -412.873749)
			(xy 391.955798 -412.819251) (xy 391.963554 -412.765308) (xy 391.978907 -412.713017) (xy 392.001546 -412.663444)
			(xy 392.031009 -412.617597) (xy 392.066697 -412.576409) (xy 392.107882 -412.54072) (xy 392.153728 -412.511254)
			(xy 392.2033 -412.488613) (xy 392.25559 -412.473258) (xy 392.309533 -412.465499) (xy 392.336782 -412.465012)
			(xy 393.200382 -412.465012) (xy 393.227637 -412.465434) (xy 393.281593 -412.473189) (xy 393.333896 -412.488544)
			(xy 393.383481 -412.511187) (xy 393.429339 -412.540656) (xy 393.470536 -412.576352) (xy 393.506233 -412.617547)
			(xy 393.535704 -412.663403) (xy 393.558349 -412.712987) (xy 393.573707 -412.765289) (xy 393.581465 -412.819245)
			(xy 393.581465 -412.873752) (xy 395.018975 -412.873752) (xy 395.018975 -412.819248) (xy 395.026732 -412.765298)
			(xy 395.042089 -412.713001) (xy 395.064732 -412.663422) (xy 395.0942 -412.61757) (xy 395.129894 -412.576379)
			(xy 395.171088 -412.540687) (xy 395.216941 -412.511221) (xy 395.266521 -412.488581) (xy 395.318819 -412.473228)
			(xy 395.37277 -412.465474) (xy 395.400022 -412.465012) (xy 396.263622 -412.465012) (xy 396.290874 -412.465459)
			(xy 396.344822 -412.473219) (xy 396.397117 -412.488577) (xy 396.446694 -412.51122) (xy 396.492544 -412.540689)
			(xy 396.533734 -412.576382) (xy 396.569425 -412.617574) (xy 396.59889 -412.663426) (xy 396.621531 -412.713004)
			(xy 396.636886 -412.7653) (xy 396.644642 -412.819248) (xy 396.644642 -412.873748) (xy 398.082298 -412.873748)
			(xy 398.082298 -412.819252) (xy 398.090053 -412.76531) (xy 398.105406 -412.713022) (xy 398.128043 -412.663449)
			(xy 398.157504 -412.617603) (xy 398.193189 -412.576416) (xy 398.234373 -412.540727) (xy 398.280216 -412.511261)
			(xy 398.329786 -412.488619) (xy 398.382073 -412.473261) (xy 398.436014 -412.465501) (xy 398.463262 -412.465012)
			(xy 399.326862 -412.465012) (xy 399.354118 -412.465432) (xy 399.408076 -412.473185) (xy 399.460381 -412.488539)
			(xy 399.509969 -412.51118) (xy 399.555829 -412.540649) (xy 399.597029 -412.576345) (xy 399.632728 -412.61754)
			(xy 399.662201 -412.663398) (xy 399.684848 -412.712983) (xy 399.700207 -412.765287) (xy 399.707965 -412.819244)
			(xy 399.707965 -412.873752) (xy 401.145475 -412.873752) (xy 401.145475 -412.819248) (xy 401.153232 -412.7653)
			(xy 401.168587 -412.713005) (xy 401.191229 -412.663427) (xy 401.220695 -412.617576) (xy 401.256387 -412.576386)
			(xy 401.297578 -412.540694) (xy 401.343429 -412.511228) (xy 401.393007 -412.488587) (xy 401.445302 -412.473231)
			(xy 401.49925 -412.465475) (xy 401.526502 -412.465012) (xy 402.390102 -412.465012) (xy 402.417355 -412.465458)
			(xy 402.471305 -412.473215) (xy 402.523602 -412.488571) (xy 402.573182 -412.511214) (xy 402.619034 -412.540682)
			(xy 402.660226 -412.576375) (xy 402.69592 -412.617567) (xy 402.725387 -412.66342) (xy 402.748029 -412.713)
			(xy 402.763385 -412.765297) (xy 402.771142 -412.819247) (xy 402.771142 -412.873753) (xy 404.208675 -412.873753)
			(xy 404.208675 -412.819247) (xy 404.216433 -412.765295) (xy 404.23179 -412.712996) (xy 404.254435 -412.663416)
			(xy 404.283905 -412.617563) (xy 404.319601 -412.576372) (xy 404.360797 -412.54068) (xy 404.406653 -412.511215)
			(xy 404.456236 -412.488576) (xy 404.508536 -412.473224) (xy 404.562489 -412.465472) (xy 404.589742 -412.465012)
			(xy 405.453342 -412.465012) (xy 405.480593 -412.465461) (xy 405.534539 -412.473222) (xy 405.586831 -412.488582)
			(xy 405.636406 -412.511227) (xy 405.682253 -412.540696) (xy 405.723441 -412.576389) (xy 405.759129 -412.61758)
			(xy 405.788593 -412.663431) (xy 405.811233 -412.713008) (xy 405.826586 -412.765302) (xy 405.834342 -412.819249)
			(xy 405.834342 -412.873749) (xy 407.271998 -412.873749) (xy 407.271998 -412.819251) (xy 407.279754 -412.765308)
			(xy 407.295107 -412.713017) (xy 407.317746 -412.663444) (xy 407.347209 -412.617597) (xy 407.382897 -412.576409)
			(xy 407.424082 -412.54072) (xy 407.469928 -412.511254) (xy 407.5195 -412.488613) (xy 407.57179 -412.473258)
			(xy 407.625733 -412.465499) (xy 407.652982 -412.465012) (xy 408.516582 -412.465012) (xy 408.543837 -412.465434)
			(xy 408.597793 -412.473189) (xy 408.650096 -412.488544) (xy 408.699681 -412.511187) (xy 408.745539 -412.540656)
			(xy 408.786736 -412.576352) (xy 408.822433 -412.617547) (xy 408.851904 -412.663403) (xy 408.874549 -412.712987)
			(xy 408.889907 -412.765289) (xy 408.897665 -412.819245) (xy 408.897665 -412.873752) (xy 410.335175 -412.873752)
			(xy 410.335175 -412.819248) (xy 410.342932 -412.765298) (xy 410.358289 -412.713001) (xy 410.380932 -412.663422)
			(xy 410.4104 -412.61757) (xy 410.446094 -412.576379) (xy 410.487288 -412.540687) (xy 410.533141 -412.511221)
			(xy 410.582721 -412.488581) (xy 410.635019 -412.473228) (xy 410.68897 -412.465474) (xy 410.716222 -412.465012)
			(xy 411.579822 -412.465012) (xy 411.607074 -412.465459) (xy 411.661022 -412.473219) (xy 411.713317 -412.488577)
			(xy 411.762894 -412.51122) (xy 411.808744 -412.540689) (xy 411.849934 -412.576382) (xy 411.885625 -412.617574)
			(xy 411.91509 -412.663426) (xy 411.937731 -412.713004) (xy 411.953086 -412.7653) (xy 411.960842 -412.819248)
			(xy 411.960842 -412.873748) (xy 413.398498 -412.873748) (xy 413.398498 -412.819252) (xy 413.406253 -412.76531)
			(xy 413.421606 -412.713022) (xy 413.444243 -412.663449) (xy 413.473704 -412.617603) (xy 413.509389 -412.576416)
			(xy 413.550573 -412.540727) (xy 413.596416 -412.511261) (xy 413.645986 -412.488619) (xy 413.698273 -412.473261)
			(xy 413.752214 -412.465501) (xy 413.779462 -412.465012) (xy 414.643062 -412.465012) (xy 414.670318 -412.465432)
			(xy 414.724276 -412.473185) (xy 414.776581 -412.488539) (xy 414.826169 -412.51118) (xy 414.872029 -412.540649)
			(xy 414.913229 -412.576345) (xy 414.948928 -412.61754) (xy 414.978401 -412.663398) (xy 415.001048 -412.712983)
			(xy 415.016407 -412.765287) (xy 415.024165 -412.819244) (xy 415.024165 -412.873752) (xy 416.461675 -412.873752)
			(xy 416.461675 -412.819248) (xy 416.469432 -412.7653) (xy 416.484787 -412.713005) (xy 416.507429 -412.663427)
			(xy 416.536895 -412.617576) (xy 416.572587 -412.576386) (xy 416.613778 -412.540694) (xy 416.659629 -412.511228)
			(xy 416.709207 -412.488587) (xy 416.761502 -412.473231) (xy 416.81545 -412.465475) (xy 416.842702 -412.465012)
			(xy 417.706302 -412.465012) (xy 417.733555 -412.465458) (xy 417.787505 -412.473215) (xy 417.839802 -412.488571)
			(xy 417.889382 -412.511214) (xy 417.935234 -412.540682) (xy 417.976426 -412.576375) (xy 418.01212 -412.617567)
			(xy 418.041587 -412.66342) (xy 418.064229 -412.713) (xy 418.079585 -412.765297) (xy 418.087342 -412.819247)
			(xy 418.087342 -412.873753) (xy 418.079585 -412.927703) (xy 418.064229 -412.98) (xy 418.041587 -413.02958)
			(xy 418.01212 -413.075433) (xy 417.976426 -413.116625) (xy 417.935234 -413.152318) (xy 417.90754 -413.170116)
			(xy 422.998658 -413.170116) (xy 423.00263 -412.991873) (xy 423.014538 -412.813984) (xy 423.034359 -412.636802)
			(xy 423.062053 -412.460678) (xy 423.097565 -412.285963) (xy 423.140825 -412.113004) (xy 423.191747 -411.942143)
			(xy 423.25023 -411.773721) (xy 423.316157 -411.608071) (xy 423.389398 -411.445522) (xy 423.469808 -411.286397)
			(xy 423.557226 -411.131012) (xy 423.651479 -410.979676) (xy 423.75238 -410.832688) (xy 423.859729 -410.690341)
			(xy 423.973312 -410.552918) (xy 424.092905 -410.420691) (xy 424.218269 -410.293922) (xy 424.349156 -410.172864)
			(xy 424.485305 -410.057757) (xy 424.626447 -409.948829) (xy 424.772302 -409.846297) (xy 424.922579 -409.750363)
			(xy 425.07698 -409.66122) (xy 425.235199 -409.579043) (xy 425.396922 -409.503995) (xy 425.561827 -409.436227)
			(xy 425.729588 -409.375871) (xy 425.899871 -409.323049) (xy 426.072338 -409.277865) (xy 426.246646 -409.240408)
			(xy 426.42245 -409.210754) (xy 426.5994 -409.188961) (xy 426.777146 -409.175071) (xy 426.955333 -409.169114)
			(xy 427.13361 -409.1711) (xy 427.311621 -409.181026) (xy 427.489013 -409.198872) (xy 427.665433 -409.224602)
			(xy 427.840533 -409.258166) (xy 428.013964 -409.299496) (xy 428.185381 -409.348512) (xy 428.354444 -409.405114)
			(xy 428.520819 -409.469192) (xy 428.684173 -409.540618) (xy 428.844184 -409.61925) (xy 429.000533 -409.704931)
			(xy 429.15291 -409.797493) (xy 429.301013 -409.89675) (xy 429.444547 -410.002507) (xy 429.583227 -410.114552)
			(xy 429.716778 -410.232664) (xy 429.844935 -410.356608) (xy 429.967444 -410.486138) (xy 430.084061 -410.620997)
			(xy 430.194554 -410.760917) (xy 430.298705 -410.90562) (xy 430.396307 -411.054819) (xy 430.487165 -411.208218)
			(xy 430.571099 -411.365512) (xy 430.647944 -411.526388) (xy 430.717545 -411.690529) (xy 430.779766 -411.857606)
			(xy 430.834482 -412.02729) (xy 430.881584 -412.199243) (xy 430.92098 -412.373123) (xy 430.952591 -412.548586)
			(xy 430.976355 -412.725282) (xy 430.992223 -412.902862) (xy 431.000165 -413.080972) (xy 431.000662 -413.170116)
			(xy 431.000165 -413.25926) (xy 430.992223 -413.43737) (xy 430.976355 -413.61495) (xy 430.952591 -413.791646)
			(xy 430.92098 -413.967109) (xy 430.881584 -414.140989) (xy 430.834482 -414.312942) (xy 430.779766 -414.482626)
			(xy 430.717545 -414.649703) (xy 430.647944 -414.813844) (xy 430.571099 -414.97472) (xy 430.487165 -415.132014)
			(xy 430.396307 -415.285413) (xy 430.298705 -415.434612) (xy 430.194554 -415.579315) (xy 430.084061 -415.719235)
			(xy 429.967444 -415.854094) (xy 429.844935 -415.983624) (xy 429.716778 -416.107568) (xy 429.583227 -416.22568)
			(xy 429.444547 -416.337725) (xy 429.301013 -416.443482) (xy 429.15291 -416.542739) (xy 429.000533 -416.635301)
			(xy 428.844184 -416.720982) (xy 428.684173 -416.799614) (xy 428.520819 -416.87104) (xy 428.354444 -416.935118)
			(xy 428.185381 -416.99172) (xy 428.013964 -417.040736) (xy 427.840533 -417.082066) (xy 427.665433 -417.11563)
			(xy 427.489013 -417.14136) (xy 427.311621 -417.159206) (xy 427.13361 -417.169132) (xy 426.955333 -417.171118)
			(xy 426.777146 -417.165161) (xy 426.5994 -417.151271) (xy 426.42245 -417.129478) (xy 426.246646 -417.099824)
			(xy 426.072338 -417.062367) (xy 425.899871 -417.017183) (xy 425.729588 -416.964361) (xy 425.561827 -416.904005)
			(xy 425.396922 -416.836237) (xy 425.235199 -416.761189) (xy 425.07698 -416.679012) (xy 424.922579 -416.589869)
			(xy 424.772302 -416.493935) (xy 424.626447 -416.391403) (xy 424.485305 -416.282475) (xy 424.349156 -416.167368)
			(xy 424.218269 -416.04631) (xy 424.092905 -415.919541) (xy 423.973312 -415.787314) (xy 423.859729 -415.649891)
			(xy 423.75238 -415.507544) (xy 423.651479 -415.360556) (xy 423.557226 -415.20922) (xy 423.469808 -415.053835)
			(xy 423.389398 -414.89471) (xy 423.316157 -414.732161) (xy 423.25023 -414.566511) (xy 423.191747 -414.398089)
			(xy 423.140825 -414.227228) (xy 423.097565 -414.054269) (xy 423.062053 -413.879554) (xy 423.034359 -413.70343)
			(xy 423.014538 -413.526248) (xy 423.00263 -413.348359) (xy 422.998658 -413.170116) (xy 417.90754 -413.170116)
			(xy 417.889382 -413.181786) (xy 417.839802 -413.204429) (xy 417.787505 -413.219785) (xy 417.733555 -413.227542)
			(xy 417.706302 -413.228028) (xy 416.842702 -413.228028) (xy 416.81545 -413.227525) (xy 416.761502 -413.219769)
			(xy 416.709207 -413.204413) (xy 416.659629 -413.181772) (xy 416.613778 -413.152306) (xy 416.572587 -413.116614)
			(xy 416.536895 -413.075424) (xy 416.507429 -413.029573) (xy 416.484787 -412.979995) (xy 416.469432 -412.9277)
			(xy 416.461675 -412.873752) (xy 415.024165 -412.873752) (xy 415.024165 -412.873756) (xy 415.016407 -412.927713)
			(xy 415.001048 -412.980017) (xy 414.978401 -413.029602) (xy 414.948928 -413.07546) (xy 414.913229 -413.116655)
			(xy 414.872029 -413.152351) (xy 414.826169 -413.18182) (xy 414.776581 -413.204461) (xy 414.724276 -413.219815)
			(xy 414.670318 -413.227568) (xy 414.643062 -413.228028) (xy 413.779462 -413.228028) (xy 413.752214 -413.227499)
			(xy 413.698273 -413.219739) (xy 413.645986 -413.204381) (xy 413.596416 -413.181739) (xy 413.550573 -413.152273)
			(xy 413.509389 -413.116584) (xy 413.473704 -413.075397) (xy 413.444243 -413.029551) (xy 413.421606 -412.979978)
			(xy 413.406253 -412.92769) (xy 413.398498 -412.873748) (xy 411.960842 -412.873748) (xy 411.960842 -412.873752)
			(xy 411.953086 -412.9277) (xy 411.937731 -412.979996) (xy 411.91509 -413.029574) (xy 411.885625 -413.075426)
			(xy 411.849934 -413.116618) (xy 411.808744 -413.152311) (xy 411.762894 -413.18178) (xy 411.713317 -413.204423)
			(xy 411.661022 -413.219781) (xy 411.607074 -413.227541) (xy 411.579822 -413.228028) (xy 410.716222 -413.228028)
			(xy 410.68897 -413.227526) (xy 410.635019 -413.219772) (xy 410.582721 -413.204419) (xy 410.533141 -413.181779)
			(xy 410.487288 -413.152313) (xy 410.446094 -413.116621) (xy 410.4104 -413.07543) (xy 410.380932 -413.029578)
			(xy 410.358289 -412.979999) (xy 410.342932 -412.927702) (xy 410.335175 -412.873752) (xy 408.897665 -412.873752)
			(xy 408.897665 -412.873755) (xy 408.889907 -412.927711) (xy 408.874549 -412.980013) (xy 408.851904 -413.029597)
			(xy 408.822433 -413.075453) (xy 408.786736 -413.116648) (xy 408.745539 -413.152344) (xy 408.699681 -413.181813)
			(xy 408.650096 -413.204456) (xy 408.597793 -413.219811) (xy 408.543837 -413.227566) (xy 408.516582 -413.228028)
			(xy 407.652982 -413.228028) (xy 407.625733 -413.227501) (xy 407.57179 -413.219742) (xy 407.5195 -413.204387)
			(xy 407.469928 -413.181746) (xy 407.424082 -413.15228) (xy 407.382897 -413.116591) (xy 407.347209 -413.075403)
			(xy 407.317746 -413.029556) (xy 407.295107 -412.979983) (xy 407.279754 -412.927692) (xy 407.271998 -412.873749)
			(xy 405.834342 -412.873749) (xy 405.834342 -412.873751) (xy 405.826586 -412.927698) (xy 405.811233 -412.979992)
			(xy 405.788593 -413.029569) (xy 405.759129 -413.07542) (xy 405.723441 -413.116611) (xy 405.682253 -413.152304)
			(xy 405.636406 -413.181773) (xy 405.586831 -413.204418) (xy 405.534539 -413.219778) (xy 405.480593 -413.227539)
			(xy 405.453342 -413.228028) (xy 404.589742 -413.228028) (xy 404.562489 -413.227528) (xy 404.508536 -413.219776)
			(xy 404.456236 -413.204424) (xy 404.406653 -413.181785) (xy 404.360797 -413.15232) (xy 404.319601 -413.116628)
			(xy 404.283905 -413.075437) (xy 404.254435 -413.029584) (xy 404.23179 -412.980004) (xy 404.216433 -412.927705)
			(xy 404.208675 -412.873753) (xy 402.771142 -412.873753) (xy 402.763385 -412.927703) (xy 402.748029 -412.98)
			(xy 402.725387 -413.02958) (xy 402.69592 -413.075433) (xy 402.660226 -413.116625) (xy 402.619034 -413.152318)
			(xy 402.573182 -413.181786) (xy 402.523602 -413.204429) (xy 402.471305 -413.219785) (xy 402.417355 -413.227542)
			(xy 402.390102 -413.228028) (xy 401.526502 -413.228028) (xy 401.49925 -413.227525) (xy 401.445302 -413.219769)
			(xy 401.393007 -413.204413) (xy 401.343429 -413.181772) (xy 401.297578 -413.152306) (xy 401.256387 -413.116614)
			(xy 401.220695 -413.075424) (xy 401.191229 -413.029573) (xy 401.168587 -412.979995) (xy 401.153232 -412.9277)
			(xy 401.145475 -412.873752) (xy 399.707965 -412.873752) (xy 399.707965 -412.873756) (xy 399.700207 -412.927713)
			(xy 399.684848 -412.980017) (xy 399.662201 -413.029602) (xy 399.632728 -413.07546) (xy 399.597029 -413.116655)
			(xy 399.555829 -413.152351) (xy 399.509969 -413.18182) (xy 399.460381 -413.204461) (xy 399.408076 -413.219815)
			(xy 399.354118 -413.227568) (xy 399.326862 -413.228028) (xy 398.463262 -413.228028) (xy 398.436014 -413.227499)
			(xy 398.382073 -413.219739) (xy 398.329786 -413.204381) (xy 398.280216 -413.181739) (xy 398.234373 -413.152273)
			(xy 398.193189 -413.116584) (xy 398.157504 -413.075397) (xy 398.128043 -413.029551) (xy 398.105406 -412.979978)
			(xy 398.090053 -412.92769) (xy 398.082298 -412.873748) (xy 396.644642 -412.873748) (xy 396.644642 -412.873752)
			(xy 396.636886 -412.9277) (xy 396.621531 -412.979996) (xy 396.59889 -413.029574) (xy 396.569425 -413.075426)
			(xy 396.533734 -413.116618) (xy 396.492544 -413.152311) (xy 396.446694 -413.18178) (xy 396.397117 -413.204423)
			(xy 396.344822 -413.219781) (xy 396.290874 -413.227541) (xy 396.263622 -413.228028) (xy 395.400022 -413.228028)
			(xy 395.37277 -413.227526) (xy 395.318819 -413.219772) (xy 395.266521 -413.204419) (xy 395.216941 -413.181779)
			(xy 395.171088 -413.152313) (xy 395.129894 -413.116621) (xy 395.0942 -413.07543) (xy 395.064732 -413.029578)
			(xy 395.042089 -412.979999) (xy 395.026732 -412.927702) (xy 395.018975 -412.873752) (xy 393.581465 -412.873752)
			(xy 393.581465 -412.873755) (xy 393.573707 -412.927711) (xy 393.558349 -412.980013) (xy 393.535704 -413.029597)
			(xy 393.506233 -413.075453) (xy 393.470536 -413.116648) (xy 393.429339 -413.152344) (xy 393.383481 -413.181813)
			(xy 393.333896 -413.204456) (xy 393.281593 -413.219811) (xy 393.227637 -413.227566) (xy 393.200382 -413.228028)
			(xy 392.336782 -413.228028) (xy 392.309533 -413.227501) (xy 392.25559 -413.219742) (xy 392.2033 -413.204387)
			(xy 392.153728 -413.181746) (xy 392.107882 -413.15228) (xy 392.066697 -413.116591) (xy 392.031009 -413.075403)
			(xy 392.001546 -413.029556) (xy 391.978907 -412.979983) (xy 391.963554 -412.927692) (xy 391.955798 -412.873749)
			(xy 390.518142 -412.873749) (xy 390.518142 -412.873751) (xy 390.510386 -412.927698) (xy 390.495033 -412.979992)
			(xy 390.472393 -413.029569) (xy 390.442929 -413.07542) (xy 390.407241 -413.116611) (xy 390.366053 -413.152304)
			(xy 390.320206 -413.181773) (xy 390.270631 -413.204418) (xy 390.218339 -413.219778) (xy 390.164393 -413.227539)
			(xy 390.137142 -413.228028) (xy 389.273542 -413.228028) (xy 389.246289 -413.227528) (xy 389.192336 -413.219776)
			(xy 389.140036 -413.204424) (xy 389.090453 -413.181785) (xy 389.044597 -413.15232) (xy 389.003401 -413.116628)
			(xy 388.967705 -413.075437) (xy 388.938235 -413.029584) (xy 388.91559 -412.980004) (xy 388.900233 -412.927705)
			(xy 388.892475 -412.873753) (xy 387.454942 -412.873753) (xy 387.447185 -412.927703) (xy 387.431829 -412.98)
			(xy 387.409187 -413.02958) (xy 387.37972 -413.075433) (xy 387.344026 -413.116625) (xy 387.302834 -413.152318)
			(xy 387.256982 -413.181786) (xy 387.207402 -413.204429) (xy 387.155105 -413.219785) (xy 387.101155 -413.227542)
			(xy 387.073902 -413.228028) (xy 386.210302 -413.228028) (xy 386.18305 -413.227525) (xy 386.129102 -413.219769)
			(xy 386.076807 -413.204413) (xy 386.027229 -413.181772) (xy 385.981378 -413.152306) (xy 385.940187 -413.116614)
			(xy 385.904495 -413.075424) (xy 385.875029 -413.029573) (xy 385.852387 -412.979995) (xy 385.837032 -412.9277)
			(xy 385.829275 -412.873752) (xy 384.391765 -412.873752) (xy 384.391765 -412.873756) (xy 384.384007 -412.927713)
			(xy 384.368648 -412.980017) (xy 384.346001 -413.029602) (xy 384.316528 -413.07546) (xy 384.280829 -413.116655)
			(xy 384.239629 -413.152351) (xy 384.193769 -413.18182) (xy 384.144181 -413.204461) (xy 384.091876 -413.219815)
			(xy 384.037918 -413.227568) (xy 384.010662 -413.228028) (xy 383.147062 -413.228028) (xy 383.119814 -413.227499)
			(xy 383.065873 -413.219739) (xy 383.013586 -413.204381) (xy 382.964016 -413.181739) (xy 382.918173 -413.152273)
			(xy 382.876989 -413.116584) (xy 382.841304 -413.075397) (xy 382.811843 -413.029551) (xy 382.789206 -412.979978)
			(xy 382.773853 -412.92769) (xy 382.766098 -412.873748) (xy 381.328442 -412.873748) (xy 381.328442 -412.873752)
			(xy 381.320686 -412.9277) (xy 381.305331 -412.979996) (xy 381.28269 -413.029574) (xy 381.253225 -413.075426)
			(xy 381.217534 -413.116618) (xy 381.176344 -413.152311) (xy 381.130494 -413.18178) (xy 381.080917 -413.204423)
			(xy 381.028622 -413.219781) (xy 380.974674 -413.227541) (xy 380.947422 -413.228028) (xy 380.083822 -413.228028)
			(xy 380.05657 -413.227526) (xy 380.002619 -413.219772) (xy 379.950321 -413.204419) (xy 379.900741 -413.181779)
			(xy 379.854888 -413.152313) (xy 379.813694 -413.116621) (xy 379.778 -413.07543) (xy 379.748532 -413.029578)
			(xy 379.725889 -412.979999) (xy 379.710532 -412.927702) (xy 379.702775 -412.873752) (xy 378.265265 -412.873752)
			(xy 378.265265 -412.873755) (xy 378.257507 -412.927711) (xy 378.242149 -412.980013) (xy 378.219504 -413.029597)
			(xy 378.190033 -413.075453) (xy 378.154336 -413.116648) (xy 378.113139 -413.152344) (xy 378.067281 -413.181813)
			(xy 378.017696 -413.204456) (xy 377.965393 -413.219811) (xy 377.911437 -413.227566) (xy 377.884182 -413.228028)
			(xy 377.020582 -413.228028) (xy 376.993333 -413.227501) (xy 376.93939 -413.219742) (xy 376.8871 -413.204387)
			(xy 376.837528 -413.181746) (xy 376.791682 -413.15228) (xy 376.750497 -413.116591) (xy 376.714809 -413.075403)
			(xy 376.685346 -413.029556) (xy 376.662707 -412.979983) (xy 376.647354 -412.927692) (xy 376.639598 -412.873749)
			(xy 375.201942 -412.873749) (xy 375.201942 -412.873751) (xy 375.194186 -412.927698) (xy 375.178833 -412.979992)
			(xy 375.156193 -413.029569) (xy 375.126729 -413.07542) (xy 375.091041 -413.116611) (xy 375.049853 -413.152304)
			(xy 375.004006 -413.181773) (xy 374.954431 -413.204418) (xy 374.902139 -413.219778) (xy 374.848193 -413.227539)
			(xy 374.820942 -413.228028) (xy 373.957342 -413.228028) (xy 373.930089 -413.227528) (xy 373.876136 -413.219776)
			(xy 373.823836 -413.204424) (xy 373.774253 -413.181785) (xy 373.728397 -413.15232) (xy 373.687201 -413.116628)
			(xy 373.651505 -413.075437) (xy 373.622035 -413.029584) (xy 373.59939 -412.980004) (xy 373.584033 -412.927705)
			(xy 373.576275 -412.873753) (xy 372.138742 -412.873753) (xy 372.130985 -412.927703) (xy 372.115629 -412.98)
			(xy 372.092987 -413.02958) (xy 372.06352 -413.075433) (xy 372.027826 -413.116625) (xy 371.986634 -413.152318)
			(xy 371.940782 -413.181786) (xy 371.891202 -413.204429) (xy 371.838905 -413.219785) (xy 371.784955 -413.227542)
			(xy 371.757702 -413.228028) (xy 370.894102 -413.228028) (xy 370.86685 -413.227525) (xy 370.812902 -413.219769)
			(xy 370.760607 -413.204413) (xy 370.711029 -413.181772) (xy 370.665178 -413.152306) (xy 370.623987 -413.116614)
			(xy 370.588295 -413.075424) (xy 370.558829 -413.029573) (xy 370.536187 -412.979995) (xy 370.520832 -412.9277)
			(xy 370.513075 -412.873752) (xy 350.987142 -412.873752) (xy 350.979385 -412.927702) (xy 350.96403 -412.979999)
			(xy 350.941388 -413.029579) (xy 350.911921 -413.075431) (xy 350.876228 -413.116624) (xy 350.835036 -413.152317)
			(xy 350.789184 -413.181785) (xy 350.739605 -413.204428) (xy 350.687308 -413.219784) (xy 350.633358 -413.227542)
			(xy 350.606106 -413.228028) (xy 349.742506 -413.228028) (xy 349.715254 -413.227525) (xy 349.661306 -413.219769)
			(xy 349.60901 -413.204415) (xy 349.559431 -413.181774) (xy 349.51358 -413.152307) (xy 349.472389 -413.116616)
			(xy 349.436696 -413.075425) (xy 349.407229 -413.029574) (xy 349.384588 -412.979996) (xy 349.369232 -412.9277)
			(xy 349.361475 -412.873752) (xy 347.923965 -412.873752) (xy 347.923965 -412.873756) (xy 347.916207 -412.927713)
			(xy 347.900848 -412.980016) (xy 347.878202 -413.029601) (xy 347.848729 -413.075458) (xy 347.81303 -413.116654)
			(xy 347.771831 -413.15235) (xy 347.725971 -413.181818) (xy 347.676384 -413.20446) (xy 347.624079 -413.219814)
			(xy 347.570122 -413.227567) (xy 347.542866 -413.228028) (xy 346.679266 -413.228028) (xy 346.652018 -413.227499)
			(xy 346.598077 -413.219739) (xy 346.545789 -413.204382) (xy 346.496218 -413.18174) (xy 346.450375 -413.152275)
			(xy 346.409191 -413.116585) (xy 346.373505 -413.075398) (xy 346.344043 -413.029552) (xy 346.321406 -412.979979)
			(xy 346.306053 -412.92769) (xy 346.298298 -412.873748) (xy 344.860642 -412.873748) (xy 344.860642 -412.873751)
			(xy 344.852886 -412.9277) (xy 344.837531 -412.979995) (xy 344.814891 -413.029573) (xy 344.785426 -413.075425)
			(xy 344.749735 -413.116617) (xy 344.708546 -413.15231) (xy 344.662696 -413.181778) (xy 344.61312 -413.204422)
			(xy 344.560825 -413.21978) (xy 344.506877 -413.22754) (xy 344.479626 -413.228028) (xy 343.616026 -413.228028)
			(xy 343.588773 -413.227526) (xy 343.534822 -413.219773) (xy 343.482524 -413.20442) (xy 343.432943 -413.18178)
			(xy 343.387089 -413.152314) (xy 343.345896 -413.116623) (xy 343.310201 -413.075431) (xy 343.280732 -413.029579)
			(xy 343.258089 -412.98) (xy 343.242733 -412.927703) (xy 343.234975 -412.873753) (xy 341.797465 -412.873753)
			(xy 341.797465 -412.873755) (xy 341.789707 -412.92771) (xy 341.77435 -412.980012) (xy 341.751705 -413.029595)
			(xy 341.722234 -413.075452) (xy 341.686537 -413.116647) (xy 341.645341 -413.152343) (xy 341.599483 -413.181812)
			(xy 341.549899 -413.204455) (xy 341.497596 -413.21981) (xy 341.443641 -413.227566) (xy 341.416386 -413.228028)
			(xy 340.552786 -413.228028) (xy 340.525537 -413.227501) (xy 340.471594 -413.219743) (xy 340.419303 -413.204388)
			(xy 340.36973 -413.181747) (xy 340.323884 -413.152282) (xy 340.282698 -413.116592) (xy 340.24701 -413.075404)
			(xy 340.217546 -413.029557) (xy 340.194908 -412.979984) (xy 340.179554 -412.927693) (xy 340.171798 -412.873749)
			(xy 338.734142 -412.873749) (xy 338.734142 -412.873751) (xy 338.726387 -412.927697) (xy 338.711033 -412.979991)
			(xy 338.688394 -413.029568) (xy 338.65893 -413.075418) (xy 338.623242 -413.116609) (xy 338.582055 -413.152303)
			(xy 338.536208 -413.181772) (xy 338.486634 -413.204417) (xy 338.434342 -413.219777) (xy 338.380397 -413.227539)
			(xy 338.353146 -413.228028) (xy 337.489546 -413.228028) (xy 337.462292 -413.227528) (xy 337.408339 -413.219777)
			(xy 337.356039 -413.204425) (xy 337.306455 -413.181787) (xy 337.260599 -413.152321) (xy 337.219403 -413.11663)
			(xy 337.183706 -413.075438) (xy 337.154235 -413.029585) (xy 337.131591 -412.980004) (xy 337.116233 -412.927706)
			(xy 337.108475 -412.873754) (xy 335.670942 -412.873754) (xy 335.663185 -412.927702) (xy 335.64783 -412.979999)
			(xy 335.625188 -413.029579) (xy 335.595721 -413.075431) (xy 335.560028 -413.116624) (xy 335.518836 -413.152317)
			(xy 335.472984 -413.181785) (xy 335.423405 -413.204428) (xy 335.371108 -413.219784) (xy 335.317158 -413.227542)
			(xy 335.289906 -413.228028) (xy 334.426306 -413.228028) (xy 334.399054 -413.227525) (xy 334.345106 -413.219769)
			(xy 334.29281 -413.204415) (xy 334.243231 -413.181774) (xy 334.19738 -413.152307) (xy 334.156189 -413.116616)
			(xy 334.120496 -413.075425) (xy 334.091029 -413.029574) (xy 334.068388 -412.979996) (xy 334.053032 -412.9277)
			(xy 334.045275 -412.873752) (xy 332.607765 -412.873752) (xy 332.607765 -412.873756) (xy 332.600007 -412.927713)
			(xy 332.584648 -412.980016) (xy 332.562002 -413.029601) (xy 332.532529 -413.075458) (xy 332.49683 -413.116654)
			(xy 332.455631 -413.15235) (xy 332.409771 -413.181818) (xy 332.360184 -413.20446) (xy 332.307879 -413.219814)
			(xy 332.253922 -413.227567) (xy 332.226666 -413.228028) (xy 331.363066 -413.228028) (xy 331.335818 -413.227499)
			(xy 331.281877 -413.219739) (xy 331.229589 -413.204382) (xy 331.180018 -413.18174) (xy 331.134175 -413.152275)
			(xy 331.092991 -413.116585) (xy 331.057305 -413.075398) (xy 331.027843 -413.029552) (xy 331.005206 -412.979979)
			(xy 330.989853 -412.92769) (xy 330.982098 -412.873748) (xy 329.544442 -412.873748) (xy 329.544442 -412.873751)
			(xy 329.536686 -412.9277) (xy 329.521331 -412.979995) (xy 329.498691 -413.029573) (xy 329.469226 -413.075425)
			(xy 329.433535 -413.116617) (xy 329.392346 -413.15231) (xy 329.346496 -413.181778) (xy 329.29692 -413.204422)
			(xy 329.244625 -413.21978) (xy 329.190677 -413.22754) (xy 329.163426 -413.228028) (xy 328.299826 -413.228028)
			(xy 328.272573 -413.227526) (xy 328.218622 -413.219773) (xy 328.166324 -413.20442) (xy 328.116743 -413.18178)
			(xy 328.070889 -413.152314) (xy 328.029696 -413.116623) (xy 327.994001 -413.075431) (xy 327.964532 -413.029579)
			(xy 327.941889 -412.98) (xy 327.926533 -412.927703) (xy 327.918775 -412.873753) (xy 326.481265 -412.873753)
			(xy 326.481265 -412.873755) (xy 326.473507 -412.92771) (xy 326.45815 -412.980012) (xy 326.435505 -413.029595)
			(xy 326.406034 -413.075452) (xy 326.370337 -413.116647) (xy 326.329141 -413.152343) (xy 326.283283 -413.181812)
			(xy 326.233699 -413.204455) (xy 326.181396 -413.21981) (xy 326.127441 -413.227566) (xy 326.100186 -413.228028)
			(xy 325.236586 -413.228028) (xy 325.209337 -413.227501) (xy 325.155394 -413.219743) (xy 325.103103 -413.204388)
			(xy 325.05353 -413.181747) (xy 325.007684 -413.152282) (xy 324.966498 -413.116592) (xy 324.93081 -413.075404)
			(xy 324.901346 -413.029557) (xy 324.878708 -412.979984) (xy 324.863354 -412.927693) (xy 324.855598 -412.873749)
			(xy 323.417942 -412.873749) (xy 323.417942 -412.873751) (xy 323.410187 -412.927697) (xy 323.394833 -412.979991)
			(xy 323.372194 -413.029568) (xy 323.34273 -413.075418) (xy 323.307042 -413.116609) (xy 323.265855 -413.152303)
			(xy 323.220008 -413.181772) (xy 323.170434 -413.204417) (xy 323.118142 -413.219777) (xy 323.064197 -413.227539)
			(xy 323.036946 -413.228028) (xy 322.173346 -413.228028) (xy 322.146092 -413.227528) (xy 322.092139 -413.219777)
			(xy 322.039839 -413.204425) (xy 321.990255 -413.181787) (xy 321.944399 -413.152321) (xy 321.903203 -413.11663)
			(xy 321.867506 -413.075438) (xy 321.838035 -413.029585) (xy 321.815391 -412.980004) (xy 321.800033 -412.927706)
			(xy 321.792275 -412.873754) (xy 320.354742 -412.873754) (xy 320.346985 -412.927702) (xy 320.33163 -412.979999)
			(xy 320.308988 -413.029579) (xy 320.279521 -413.075431) (xy 320.243828 -413.116624) (xy 320.202636 -413.152317)
			(xy 320.156784 -413.181785) (xy 320.107205 -413.204428) (xy 320.054908 -413.219784) (xy 320.000958 -413.227542)
			(xy 319.973706 -413.228028) (xy 319.110106 -413.228028) (xy 319.082854 -413.227525) (xy 319.028906 -413.219769)
			(xy 318.97661 -413.204415) (xy 318.927031 -413.181774) (xy 318.88118 -413.152307) (xy 318.839989 -413.116616)
			(xy 318.804296 -413.075425) (xy 318.774829 -413.029574) (xy 318.752188 -412.979996) (xy 318.736832 -412.9277)
			(xy 318.729075 -412.873752) (xy 317.291565 -412.873752) (xy 317.291565 -412.873756) (xy 317.283807 -412.927713)
			(xy 317.268448 -412.980016) (xy 317.245802 -413.029601) (xy 317.216329 -413.075458) (xy 317.18063 -413.116654)
			(xy 317.139431 -413.15235) (xy 317.093571 -413.181818) (xy 317.043984 -413.20446) (xy 316.991679 -413.219814)
			(xy 316.937722 -413.227567) (xy 316.910466 -413.228028) (xy 316.046866 -413.228028) (xy 316.019618 -413.227499)
			(xy 315.965677 -413.219739) (xy 315.913389 -413.204382) (xy 315.863818 -413.18174) (xy 315.817975 -413.152275)
			(xy 315.776791 -413.116585) (xy 315.741105 -413.075398) (xy 315.711643 -413.029552) (xy 315.689006 -412.979979)
			(xy 315.673653 -412.92769) (xy 315.665898 -412.873748) (xy 314.228242 -412.873748) (xy 314.228242 -412.873751)
			(xy 314.220486 -412.9277) (xy 314.205131 -412.979995) (xy 314.182491 -413.029573) (xy 314.153026 -413.075425)
			(xy 314.117335 -413.116617) (xy 314.076146 -413.15231) (xy 314.030296 -413.181778) (xy 313.98072 -413.204422)
			(xy 313.928425 -413.21978) (xy 313.874477 -413.22754) (xy 313.847226 -413.228028) (xy 312.983626 -413.228028)
			(xy 312.956373 -413.227526) (xy 312.902422 -413.219773) (xy 312.850124 -413.20442) (xy 312.800543 -413.18178)
			(xy 312.754689 -413.152314) (xy 312.713496 -413.116623) (xy 312.677801 -413.075431) (xy 312.648332 -413.029579)
			(xy 312.625689 -412.98) (xy 312.610333 -412.927703) (xy 312.602575 -412.873753) (xy 311.165065 -412.873753)
			(xy 311.165065 -412.873755) (xy 311.157307 -412.92771) (xy 311.14195 -412.980012) (xy 311.119305 -413.029595)
			(xy 311.089834 -413.075452) (xy 311.054137 -413.116647) (xy 311.012941 -413.152343) (xy 310.967083 -413.181812)
			(xy 310.917499 -413.204455) (xy 310.865196 -413.21981) (xy 310.811241 -413.227566) (xy 310.783986 -413.228028)
			(xy 309.920386 -413.228028) (xy 309.893137 -413.227501) (xy 309.839194 -413.219743) (xy 309.786903 -413.204388)
			(xy 309.73733 -413.181747) (xy 309.691484 -413.152282) (xy 309.650298 -413.116592) (xy 309.61461 -413.075404)
			(xy 309.585146 -413.029557) (xy 309.562508 -412.979984) (xy 309.547154 -412.927693) (xy 309.539398 -412.873749)
			(xy 308.101742 -412.873749) (xy 308.101742 -412.873751) (xy 308.093987 -412.927697) (xy 308.078633 -412.979991)
			(xy 308.055994 -413.029568) (xy 308.02653 -413.075418) (xy 307.990842 -413.116609) (xy 307.949655 -413.152303)
			(xy 307.903808 -413.181772) (xy 307.854234 -413.204417) (xy 307.801942 -413.219777) (xy 307.747997 -413.227539)
			(xy 307.720746 -413.228028) (xy 306.857146 -413.228028) (xy 306.829892 -413.227528) (xy 306.775939 -413.219777)
			(xy 306.723639 -413.204425) (xy 306.674055 -413.181787) (xy 306.628199 -413.152321) (xy 306.587003 -413.11663)
			(xy 306.551306 -413.075438) (xy 306.521835 -413.029585) (xy 306.499191 -412.980004) (xy 306.483833 -412.927706)
			(xy 306.476075 -412.873754) (xy 305.038542 -412.873754) (xy 305.030785 -412.927702) (xy 305.01543 -412.979999)
			(xy 304.992788 -413.029579) (xy 304.963321 -413.075431) (xy 304.927628 -413.116624) (xy 304.886436 -413.152317)
			(xy 304.840584 -413.181785) (xy 304.791005 -413.204428) (xy 304.738708 -413.219784) (xy 304.684758 -413.227542)
			(xy 304.657506 -413.228028) (xy 303.793906 -413.228028) (xy 303.766654 -413.227525) (xy 303.712706 -413.219769)
			(xy 303.66041 -413.204415) (xy 303.610831 -413.181774) (xy 303.56498 -413.152307) (xy 303.523789 -413.116616)
			(xy 303.488096 -413.075425) (xy 303.458629 -413.029574) (xy 303.435988 -412.979996) (xy 303.420632 -412.9277)
			(xy 303.412875 -412.873752) (xy 301.559858 -412.873752) (xy 301.562459 -412.902862) (xy 301.570401 -413.080972)
			(xy 301.570898 -413.170116) (xy 301.570401 -413.25926) (xy 301.562459 -413.43737) (xy 301.546591 -413.61495)
			(xy 301.522827 -413.791646) (xy 301.491216 -413.967109) (xy 301.45182 -414.140989) (xy 301.404718 -414.312942)
			(xy 301.350002 -414.482626) (xy 301.287781 -414.649703) (xy 301.21818 -414.813844) (xy 301.141335 -414.97472)
			(xy 301.057401 -415.132014) (xy 300.966543 -415.285413) (xy 300.882586 -415.413753) (xy 304.944475 -415.413753)
			(xy 304.944475 -415.359247) (xy 304.952233 -415.305297) (xy 304.967589 -415.253) (xy 304.990232 -415.203421)
			(xy 305.019701 -415.157569) (xy 305.055396 -415.116377) (xy 305.096589 -415.080686) (xy 305.142443 -415.05122)
			(xy 305.192024 -415.02858) (xy 305.244322 -415.013227) (xy 305.298273 -415.005474) (xy 305.325526 -415.005012)
			(xy 306.189126 -415.005012) (xy 306.216377 -415.00546) (xy 306.270325 -415.01322) (xy 306.32262 -415.028578)
			(xy 306.372196 -415.051222) (xy 306.418046 -415.08069) (xy 306.459235 -415.116383) (xy 306.494926 -415.157575)
			(xy 306.524391 -415.203427) (xy 306.547031 -415.253005) (xy 306.562386 -415.3053) (xy 306.570142 -415.359249)
			(xy 306.570142 -415.413748) (xy 308.007798 -415.413748) (xy 308.007798 -415.359252) (xy 308.015553 -415.30531)
			(xy 308.030906 -415.253021) (xy 308.053543 -415.203448) (xy 308.083005 -415.157602) (xy 308.118691 -415.116415)
			(xy 308.159875 -415.080725) (xy 308.205718 -415.05126) (xy 308.255289 -415.028618) (xy 308.307577 -415.013261)
			(xy 308.361518 -415.005501) (xy 308.388766 -415.005012) (xy 309.252366 -415.005012) (xy 309.279622 -415.005433)
			(xy 309.333579 -415.013186) (xy 309.385884 -415.02854) (xy 309.435471 -415.051182) (xy 309.481331 -415.08065)
			(xy 309.52253 -415.116346) (xy 309.558229 -415.157542) (xy 309.587702 -415.203399) (xy 309.610348 -415.252984)
			(xy 309.625707 -415.305287) (xy 309.633465 -415.359244) (xy 309.633465 -415.413752) (xy 311.070975 -415.413752)
			(xy 311.070975 -415.359248) (xy 311.078732 -415.3053) (xy 311.094088 -415.253004) (xy 311.116729 -415.203426)
			(xy 311.146196 -415.157575) (xy 311.181889 -415.116384) (xy 311.22308 -415.080693) (xy 311.268931 -415.051226)
			(xy 311.31851 -415.028585) (xy 311.370806 -415.013231) (xy 311.424754 -415.005475) (xy 311.452006 -415.005012)
			(xy 312.315606 -415.005012) (xy 312.342858 -415.005458) (xy 312.396808 -415.013216) (xy 312.449105 -415.028572)
			(xy 312.498684 -415.051215) (xy 312.544536 -415.080683) (xy 312.585728 -415.116376) (xy 312.621421 -415.157569)
			(xy 312.650888 -415.203421) (xy 312.67353 -415.253001) (xy 312.688885 -415.305298) (xy 312.696642 -415.359248)
			(xy 312.696642 -415.413752) (xy 312.696642 -415.413754) (xy 314.134175 -415.413754) (xy 314.134175 -415.359246)
			(xy 314.141933 -415.305294) (xy 314.157291 -415.252996) (xy 314.179935 -415.203415) (xy 314.209406 -415.157562)
			(xy 314.245103 -415.11637) (xy 314.286299 -415.080679) (xy 314.332155 -415.051213) (xy 314.381739 -415.028575)
			(xy 314.434039 -415.013223) (xy 314.487992 -415.005472) (xy 314.515246 -415.005012) (xy 315.378846 -415.005012)
			(xy 315.406097 -415.005461) (xy 315.460042 -415.013223) (xy 315.512334 -415.028583) (xy 315.561908 -415.051228)
			(xy 315.607755 -415.080697) (xy 315.648942 -415.116391) (xy 315.68463 -415.157582) (xy 315.714094 -415.203432)
			(xy 315.736733 -415.253009) (xy 315.752087 -415.305303) (xy 315.759842 -415.359249) (xy 315.759842 -415.413749)
			(xy 317.197498 -415.413749) (xy 317.197498 -415.359251) (xy 317.205254 -415.305307) (xy 317.220608 -415.253016)
			(xy 317.243246 -415.203443) (xy 317.27271 -415.157596) (xy 317.308398 -415.116408) (xy 317.349584 -415.080718)
			(xy 317.39543 -415.051253) (xy 317.445003 -415.028612) (xy 317.497294 -415.013257) (xy 317.551237 -415.005499)
			(xy 317.578486 -415.005012) (xy 318.442086 -415.005012) (xy 318.469341 -415.005434) (xy 318.523296 -415.01319)
			(xy 318.575599 -415.028545) (xy 318.625183 -415.051188) (xy 318.671041 -415.080657) (xy 318.712237 -415.116353)
			(xy 318.747934 -415.157548) (xy 318.777405 -415.203405) (xy 318.80005 -415.252988) (xy 318.815407 -415.30529)
			(xy 318.823165 -415.359245) (xy 318.823165 -415.413753) (xy 320.260675 -415.413753) (xy 320.260675 -415.359247)
			(xy 320.268433 -415.305297) (xy 320.283789 -415.253) (xy 320.306432 -415.203421) (xy 320.335901 -415.157569)
			(xy 320.371596 -415.116377) (xy 320.412789 -415.080686) (xy 320.458643 -415.05122) (xy 320.508224 -415.02858)
			(xy 320.560522 -415.013227) (xy 320.614473 -415.005474) (xy 320.641726 -415.005012) (xy 321.505326 -415.005012)
			(xy 321.532577 -415.00546) (xy 321.586525 -415.01322) (xy 321.63882 -415.028578) (xy 321.688396 -415.051222)
			(xy 321.734246 -415.08069) (xy 321.775435 -415.116383) (xy 321.811126 -415.157575) (xy 321.840591 -415.203427)
			(xy 321.863231 -415.253005) (xy 321.878586 -415.3053) (xy 321.886342 -415.359249) (xy 321.886342 -415.413748)
			(xy 323.323998 -415.413748) (xy 323.323998 -415.359252) (xy 323.331753 -415.30531) (xy 323.347106 -415.253021)
			(xy 323.369743 -415.203448) (xy 323.399205 -415.157602) (xy 323.434891 -415.116415) (xy 323.476075 -415.080725)
			(xy 323.521918 -415.05126) (xy 323.571489 -415.028618) (xy 323.623777 -415.013261) (xy 323.677718 -415.005501)
			(xy 323.704966 -415.005012) (xy 324.568566 -415.005012) (xy 324.595822 -415.005433) (xy 324.649779 -415.013186)
			(xy 324.702084 -415.02854) (xy 324.751671 -415.051182) (xy 324.797531 -415.08065) (xy 324.83873 -415.116346)
			(xy 324.874429 -415.157542) (xy 324.903902 -415.203399) (xy 324.926548 -415.252984) (xy 324.941907 -415.305287)
			(xy 324.949665 -415.359244) (xy 324.949665 -415.413752) (xy 326.387175 -415.413752) (xy 326.387175 -415.359248)
			(xy 326.394932 -415.3053) (xy 326.410288 -415.253004) (xy 326.432929 -415.203426) (xy 326.462396 -415.157575)
			(xy 326.498089 -415.116384) (xy 326.53928 -415.080693) (xy 326.585131 -415.051226) (xy 326.63471 -415.028585)
			(xy 326.687006 -415.013231) (xy 326.740954 -415.005475) (xy 326.768206 -415.005012) (xy 327.631806 -415.005012)
			(xy 327.659058 -415.005458) (xy 327.713008 -415.013216) (xy 327.765305 -415.028572) (xy 327.814884 -415.051215)
			(xy 327.860736 -415.080683) (xy 327.901928 -415.116376) (xy 327.937621 -415.157569) (xy 327.967088 -415.203421)
			(xy 327.98973 -415.253001) (xy 328.005085 -415.305298) (xy 328.012842 -415.359248) (xy 328.012842 -415.413752)
			(xy 328.012842 -415.413754) (xy 329.450375 -415.413754) (xy 329.450375 -415.359246) (xy 329.458133 -415.305294)
			(xy 329.473491 -415.252996) (xy 329.496135 -415.203415) (xy 329.525606 -415.157562) (xy 329.561303 -415.11637)
			(xy 329.602499 -415.080679) (xy 329.648355 -415.051213) (xy 329.697939 -415.028575) (xy 329.750239 -415.013223)
			(xy 329.804192 -415.005472) (xy 329.831446 -415.005012) (xy 330.695046 -415.005012) (xy 330.722297 -415.005461)
			(xy 330.776242 -415.013223) (xy 330.828534 -415.028583) (xy 330.878108 -415.051228) (xy 330.923955 -415.080697)
			(xy 330.965142 -415.116391) (xy 331.00083 -415.157582) (xy 331.030294 -415.203432) (xy 331.052933 -415.253009)
			(xy 331.068287 -415.305303) (xy 331.076042 -415.359249) (xy 331.076042 -415.413749) (xy 332.513698 -415.413749)
			(xy 332.513698 -415.359251) (xy 332.521454 -415.305307) (xy 332.536808 -415.253016) (xy 332.559446 -415.203443)
			(xy 332.58891 -415.157596) (xy 332.624598 -415.116408) (xy 332.665784 -415.080718) (xy 332.71163 -415.051253)
			(xy 332.761203 -415.028612) (xy 332.813494 -415.013257) (xy 332.867437 -415.005499) (xy 332.894686 -415.005012)
			(xy 333.758286 -415.005012) (xy 333.785541 -415.005434) (xy 333.839496 -415.01319) (xy 333.891799 -415.028545)
			(xy 333.941383 -415.051188) (xy 333.987241 -415.080657) (xy 334.028437 -415.116353) (xy 334.064134 -415.157548)
			(xy 334.093605 -415.203405) (xy 334.11625 -415.252988) (xy 334.131607 -415.30529) (xy 334.139365 -415.359245)
			(xy 334.139365 -415.413753) (xy 335.576875 -415.413753) (xy 335.576875 -415.359247) (xy 335.584633 -415.305297)
			(xy 335.599989 -415.253) (xy 335.622632 -415.203421) (xy 335.652101 -415.157569) (xy 335.687796 -415.116377)
			(xy 335.728989 -415.080686) (xy 335.774843 -415.05122) (xy 335.824424 -415.02858) (xy 335.876722 -415.013227)
			(xy 335.930673 -415.005474) (xy 335.957926 -415.005012) (xy 336.821526 -415.005012) (xy 336.848777 -415.00546)
			(xy 336.902725 -415.01322) (xy 336.95502 -415.028578) (xy 337.004596 -415.051222) (xy 337.050446 -415.08069)
			(xy 337.091635 -415.116383) (xy 337.127326 -415.157575) (xy 337.156791 -415.203427) (xy 337.179431 -415.253005)
			(xy 337.194786 -415.3053) (xy 337.202542 -415.359249) (xy 337.202542 -415.413748) (xy 338.640198 -415.413748)
			(xy 338.640198 -415.359252) (xy 338.647953 -415.30531) (xy 338.663306 -415.253021) (xy 338.685943 -415.203448)
			(xy 338.715405 -415.157602) (xy 338.751091 -415.116415) (xy 338.792275 -415.080725) (xy 338.838118 -415.05126)
			(xy 338.887689 -415.028618) (xy 338.939977 -415.013261) (xy 338.993918 -415.005501) (xy 339.021166 -415.005012)
			(xy 339.884766 -415.005012) (xy 339.912022 -415.005433) (xy 339.965979 -415.013186) (xy 340.018284 -415.02854)
			(xy 340.067871 -415.051182) (xy 340.113731 -415.08065) (xy 340.15493 -415.116346) (xy 340.190629 -415.157542)
			(xy 340.220102 -415.203399) (xy 340.242748 -415.252984) (xy 340.258107 -415.305287) (xy 340.265865 -415.359244)
			(xy 340.265865 -415.413752) (xy 341.703375 -415.413752) (xy 341.703375 -415.359248) (xy 341.711132 -415.3053)
			(xy 341.726488 -415.253004) (xy 341.749129 -415.203426) (xy 341.778596 -415.157575) (xy 341.814289 -415.116384)
			(xy 341.85548 -415.080693) (xy 341.901331 -415.051226) (xy 341.95091 -415.028585) (xy 342.003206 -415.013231)
			(xy 342.057154 -415.005475) (xy 342.084406 -415.005012) (xy 342.948006 -415.005012) (xy 342.975258 -415.005458)
			(xy 343.029208 -415.013216) (xy 343.081505 -415.028572) (xy 343.131084 -415.051215) (xy 343.176936 -415.080683)
			(xy 343.218128 -415.116376) (xy 343.253821 -415.157569) (xy 343.283288 -415.203421) (xy 343.30593 -415.253001)
			(xy 343.321285 -415.305298) (xy 343.329042 -415.359248) (xy 343.329042 -415.413752) (xy 343.329042 -415.413754)
			(xy 344.766575 -415.413754) (xy 344.766575 -415.359246) (xy 344.774333 -415.305294) (xy 344.789691 -415.252996)
			(xy 344.812335 -415.203415) (xy 344.841806 -415.157562) (xy 344.877503 -415.11637) (xy 344.918699 -415.080679)
			(xy 344.964555 -415.051213) (xy 345.014139 -415.028575) (xy 345.066439 -415.013223) (xy 345.120392 -415.005472)
			(xy 345.147646 -415.005012) (xy 346.011246 -415.005012) (xy 346.038497 -415.005461) (xy 346.092442 -415.013223)
			(xy 346.144734 -415.028583) (xy 346.194308 -415.051228) (xy 346.240155 -415.080697) (xy 346.281342 -415.116391)
			(xy 346.31703 -415.157582) (xy 346.346494 -415.203432) (xy 346.369133 -415.253009) (xy 346.384487 -415.305303)
			(xy 346.392242 -415.359249) (xy 346.392242 -415.413749) (xy 347.829898 -415.413749) (xy 347.829898 -415.359251)
			(xy 347.837654 -415.305307) (xy 347.853008 -415.253016) (xy 347.875646 -415.203443) (xy 347.90511 -415.157596)
			(xy 347.940798 -415.116408) (xy 347.981984 -415.080718) (xy 348.02783 -415.051253) (xy 348.077403 -415.028612)
			(xy 348.129694 -415.013257) (xy 348.183637 -415.005499) (xy 348.210886 -415.005012) (xy 349.074486 -415.005012)
			(xy 349.101741 -415.005434) (xy 349.155696 -415.01319) (xy 349.207999 -415.028545) (xy 349.257583 -415.051188)
			(xy 349.303441 -415.080657) (xy 349.344637 -415.116353) (xy 349.380334 -415.157548) (xy 349.409805 -415.203405)
			(xy 349.43245 -415.252988) (xy 349.447807 -415.30529) (xy 349.455565 -415.359245) (xy 349.455565 -415.413753)
			(xy 350.893075 -415.413753) (xy 350.893075 -415.359247) (xy 350.900833 -415.305297) (xy 350.916189 -415.253)
			(xy 350.938832 -415.203421) (xy 350.968301 -415.157569) (xy 351.003996 -415.116377) (xy 351.045189 -415.080686)
			(xy 351.091043 -415.05122) (xy 351.140624 -415.02858) (xy 351.192922 -415.013227) (xy 351.246873 -415.005474)
			(xy 351.274126 -415.005012) (xy 352.137726 -415.005012) (xy 352.164977 -415.00546) (xy 352.218925 -415.01322)
			(xy 352.27122 -415.028578) (xy 352.320796 -415.051222) (xy 352.366646 -415.08069) (xy 352.407835 -415.116383)
			(xy 352.443526 -415.157575) (xy 352.472991 -415.203427) (xy 352.495631 -415.253005) (xy 352.510986 -415.3053)
			(xy 352.518742 -415.359249) (xy 352.518742 -415.413751) (xy 352.518742 -415.413752) (xy 372.044675 -415.413752)
			(xy 372.044675 -415.359248) (xy 372.052432 -415.305298) (xy 372.067789 -415.253001) (xy 372.090432 -415.203422)
			(xy 372.1199 -415.15757) (xy 372.155594 -415.116379) (xy 372.196788 -415.080687) (xy 372.242641 -415.051221)
			(xy 372.292221 -415.028581) (xy 372.344519 -415.013228) (xy 372.39847 -415.005474) (xy 372.425722 -415.005012)
			(xy 373.289322 -415.005012) (xy 373.316574 -415.005459) (xy 373.370522 -415.013219) (xy 373.422817 -415.028577)
			(xy 373.472394 -415.05122) (xy 373.518244 -415.080689) (xy 373.559434 -415.116382) (xy 373.595125 -415.157574)
			(xy 373.62459 -415.203426) (xy 373.647231 -415.253004) (xy 373.662586 -415.3053) (xy 373.670342 -415.359248)
			(xy 373.670342 -415.413748) (xy 375.107998 -415.413748) (xy 375.107998 -415.359252) (xy 375.115753 -415.30531)
			(xy 375.131106 -415.253022) (xy 375.153743 -415.203449) (xy 375.183204 -415.157603) (xy 375.218889 -415.116416)
			(xy 375.260073 -415.080727) (xy 375.305916 -415.051261) (xy 375.355486 -415.028619) (xy 375.407773 -415.013261)
			(xy 375.461714 -415.005501) (xy 375.488962 -415.005012) (xy 376.352562 -415.005012) (xy 376.379818 -415.005432)
			(xy 376.433776 -415.013185) (xy 376.486081 -415.028539) (xy 376.535669 -415.05118) (xy 376.581529 -415.080649)
			(xy 376.622729 -415.116345) (xy 376.658428 -415.15754) (xy 376.687901 -415.203398) (xy 376.710548 -415.252983)
			(xy 376.725907 -415.305287) (xy 376.733665 -415.359244) (xy 376.733665 -415.413752) (xy 378.171175 -415.413752)
			(xy 378.171175 -415.359248) (xy 378.178932 -415.3053) (xy 378.194287 -415.253005) (xy 378.216929 -415.203427)
			(xy 378.246395 -415.157576) (xy 378.282087 -415.116386) (xy 378.323278 -415.080694) (xy 378.369129 -415.051228)
			(xy 378.418707 -415.028587) (xy 378.471002 -415.013231) (xy 378.52495 -415.005475) (xy 378.552202 -415.005012)
			(xy 379.415802 -415.005012) (xy 379.443055 -415.005458) (xy 379.497005 -415.013215) (xy 379.549302 -415.028571)
			(xy 379.598882 -415.051214) (xy 379.644734 -415.080682) (xy 379.685926 -415.116375) (xy 379.72162 -415.157567)
			(xy 379.751087 -415.20342) (xy 379.773729 -415.253) (xy 379.789085 -415.305297) (xy 379.796842 -415.359247)
			(xy 379.796842 -415.413753) (xy 381.234375 -415.413753) (xy 381.234375 -415.359247) (xy 381.242133 -415.305295)
			(xy 381.25749 -415.252996) (xy 381.280135 -415.203416) (xy 381.309605 -415.157563) (xy 381.345301 -415.116372)
			(xy 381.386497 -415.08068) (xy 381.432353 -415.051215) (xy 381.481936 -415.028576) (xy 381.534236 -415.013224)
			(xy 381.588189 -415.005472) (xy 381.615442 -415.005012) (xy 382.479042 -415.005012) (xy 382.506293 -415.005461)
			(xy 382.560239 -415.013222) (xy 382.612531 -415.028582) (xy 382.662106 -415.051227) (xy 382.707953 -415.080696)
			(xy 382.749141 -415.116389) (xy 382.784829 -415.15758) (xy 382.814293 -415.203431) (xy 382.836933 -415.253008)
			(xy 382.852286 -415.305302) (xy 382.860042 -415.359249) (xy 382.860042 -415.413749) (xy 384.297698 -415.413749)
			(xy 384.297698 -415.359251) (xy 384.305454 -415.305308) (xy 384.320807 -415.253017) (xy 384.343446 -415.203444)
			(xy 384.372909 -415.157597) (xy 384.408597 -415.116409) (xy 384.449782 -415.08072) (xy 384.495628 -415.051254)
			(xy 384.5452 -415.028613) (xy 384.59749 -415.013258) (xy 384.651433 -415.005499) (xy 384.678682 -415.005012)
			(xy 385.542282 -415.005012) (xy 385.569537 -415.005434) (xy 385.623493 -415.013189) (xy 385.675796 -415.028544)
			(xy 385.725381 -415.051187) (xy 385.771239 -415.080656) (xy 385.812436 -415.116352) (xy 385.848133 -415.157547)
			(xy 385.877604 -415.203403) (xy 385.900249 -415.252987) (xy 385.915607 -415.305289) (xy 385.923365 -415.359245)
			(xy 385.923365 -415.413752) (xy 387.360875 -415.413752) (xy 387.360875 -415.359248) (xy 387.368632 -415.305298)
			(xy 387.383989 -415.253001) (xy 387.406632 -415.203422) (xy 387.4361 -415.15757) (xy 387.471794 -415.116379)
			(xy 387.512988 -415.080687) (xy 387.558841 -415.051221) (xy 387.608421 -415.028581) (xy 387.660719 -415.013228)
			(xy 387.71467 -415.005474) (xy 387.741922 -415.005012) (xy 388.605522 -415.005012) (xy 388.632774 -415.005459)
			(xy 388.686722 -415.013219) (xy 388.739017 -415.028577) (xy 388.788594 -415.05122) (xy 388.834444 -415.080689)
			(xy 388.875634 -415.116382) (xy 388.911325 -415.157574) (xy 388.94079 -415.203426) (xy 388.963431 -415.253004)
			(xy 388.978786 -415.3053) (xy 388.986542 -415.359248) (xy 388.986542 -415.413748) (xy 390.424198 -415.413748)
			(xy 390.424198 -415.359252) (xy 390.431953 -415.30531) (xy 390.447306 -415.253022) (xy 390.469943 -415.203449)
			(xy 390.499404 -415.157603) (xy 390.535089 -415.116416) (xy 390.576273 -415.080727) (xy 390.622116 -415.051261)
			(xy 390.671686 -415.028619) (xy 390.723973 -415.013261) (xy 390.777914 -415.005501) (xy 390.805162 -415.005012)
			(xy 391.668762 -415.005012) (xy 391.696018 -415.005432) (xy 391.749976 -415.013185) (xy 391.802281 -415.028539)
			(xy 391.851869 -415.05118) (xy 391.897729 -415.080649) (xy 391.938929 -415.116345) (xy 391.974628 -415.15754)
			(xy 392.004101 -415.203398) (xy 392.026748 -415.252983) (xy 392.042107 -415.305287) (xy 392.049865 -415.359244)
			(xy 392.049865 -415.413752) (xy 393.487375 -415.413752) (xy 393.487375 -415.359248) (xy 393.495132 -415.3053)
			(xy 393.510487 -415.253005) (xy 393.533129 -415.203427) (xy 393.562595 -415.157576) (xy 393.598287 -415.116386)
			(xy 393.639478 -415.080694) (xy 393.685329 -415.051228) (xy 393.734907 -415.028587) (xy 393.787202 -415.013231)
			(xy 393.84115 -415.005475) (xy 393.868402 -415.005012) (xy 394.732002 -415.005012) (xy 394.759255 -415.005458)
			(xy 394.813205 -415.013215) (xy 394.865502 -415.028571) (xy 394.915082 -415.051214) (xy 394.960934 -415.080682)
			(xy 395.002126 -415.116375) (xy 395.03782 -415.157567) (xy 395.067287 -415.20342) (xy 395.089929 -415.253)
			(xy 395.105285 -415.305297) (xy 395.113042 -415.359247) (xy 395.113042 -415.413753) (xy 396.550575 -415.413753)
			(xy 396.550575 -415.359247) (xy 396.558333 -415.305295) (xy 396.57369 -415.252996) (xy 396.596335 -415.203416)
			(xy 396.625805 -415.157563) (xy 396.661501 -415.116372) (xy 396.702697 -415.08068) (xy 396.748553 -415.051215)
			(xy 396.798136 -415.028576) (xy 396.850436 -415.013224) (xy 396.904389 -415.005472) (xy 396.931642 -415.005012)
			(xy 397.795242 -415.005012) (xy 397.822493 -415.005461) (xy 397.876439 -415.013222) (xy 397.928731 -415.028582)
			(xy 397.978306 -415.051227) (xy 398.024153 -415.080696) (xy 398.065341 -415.116389) (xy 398.101029 -415.15758)
			(xy 398.130493 -415.203431) (xy 398.153133 -415.253008) (xy 398.168486 -415.305302) (xy 398.176242 -415.359249)
			(xy 398.176242 -415.413749) (xy 399.613898 -415.413749) (xy 399.613898 -415.359251) (xy 399.621654 -415.305308)
			(xy 399.637007 -415.253017) (xy 399.659646 -415.203444) (xy 399.689109 -415.157597) (xy 399.724797 -415.116409)
			(xy 399.765982 -415.08072) (xy 399.811828 -415.051254) (xy 399.8614 -415.028613) (xy 399.91369 -415.013258)
			(xy 399.967633 -415.005499) (xy 399.994882 -415.005012) (xy 400.858482 -415.005012) (xy 400.885737 -415.005434)
			(xy 400.939693 -415.013189) (xy 400.991996 -415.028544) (xy 401.041581 -415.051187) (xy 401.087439 -415.080656)
			(xy 401.128636 -415.116352) (xy 401.164333 -415.157547) (xy 401.193804 -415.203403) (xy 401.216449 -415.252987)
			(xy 401.231807 -415.305289) (xy 401.239565 -415.359245) (xy 401.239565 -415.413752) (xy 402.677075 -415.413752)
			(xy 402.677075 -415.359248) (xy 402.684832 -415.305298) (xy 402.700189 -415.253001) (xy 402.722832 -415.203422)
			(xy 402.7523 -415.15757) (xy 402.787994 -415.116379) (xy 402.829188 -415.080687) (xy 402.875041 -415.051221)
			(xy 402.924621 -415.028581) (xy 402.976919 -415.013228) (xy 403.03087 -415.005474) (xy 403.058122 -415.005012)
			(xy 403.921722 -415.005012) (xy 403.948974 -415.005459) (xy 404.002922 -415.013219) (xy 404.055217 -415.028577)
			(xy 404.104794 -415.05122) (xy 404.150644 -415.080689) (xy 404.191834 -415.116382) (xy 404.227525 -415.157574)
			(xy 404.25699 -415.203426) (xy 404.279631 -415.253004) (xy 404.294986 -415.3053) (xy 404.302742 -415.359248)
			(xy 404.302742 -415.413748) (xy 405.740398 -415.413748) (xy 405.740398 -415.359252) (xy 405.748153 -415.30531)
			(xy 405.763506 -415.253022) (xy 405.786143 -415.203449) (xy 405.815604 -415.157603) (xy 405.851289 -415.116416)
			(xy 405.892473 -415.080727) (xy 405.938316 -415.051261) (xy 405.987886 -415.028619) (xy 406.040173 -415.013261)
			(xy 406.094114 -415.005501) (xy 406.121362 -415.005012) (xy 406.984962 -415.005012) (xy 407.012218 -415.005432)
			(xy 407.066176 -415.013185) (xy 407.118481 -415.028539) (xy 407.168069 -415.05118) (xy 407.213929 -415.080649)
			(xy 407.255129 -415.116345) (xy 407.290828 -415.15754) (xy 407.320301 -415.203398) (xy 407.342948 -415.252983)
			(xy 407.358307 -415.305287) (xy 407.366065 -415.359244) (xy 407.366065 -415.413752) (xy 408.803575 -415.413752)
			(xy 408.803575 -415.359248) (xy 408.811332 -415.3053) (xy 408.826687 -415.253005) (xy 408.849329 -415.203427)
			(xy 408.878795 -415.157576) (xy 408.914487 -415.116386) (xy 408.955678 -415.080694) (xy 409.001529 -415.051228)
			(xy 409.051107 -415.028587) (xy 409.103402 -415.013231) (xy 409.15735 -415.005475) (xy 409.184602 -415.005012)
			(xy 410.048202 -415.005012) (xy 410.075455 -415.005458) (xy 410.129405 -415.013215) (xy 410.181702 -415.028571)
			(xy 410.231282 -415.051214) (xy 410.277134 -415.080682) (xy 410.318326 -415.116375) (xy 410.35402 -415.157567)
			(xy 410.383487 -415.20342) (xy 410.406129 -415.253) (xy 410.421485 -415.305297) (xy 410.429242 -415.359247)
			(xy 410.429242 -415.413753) (xy 411.866775 -415.413753) (xy 411.866775 -415.359247) (xy 411.874533 -415.305295)
			(xy 411.88989 -415.252996) (xy 411.912535 -415.203416) (xy 411.942005 -415.157563) (xy 411.977701 -415.116372)
			(xy 412.018897 -415.08068) (xy 412.064753 -415.051215) (xy 412.114336 -415.028576) (xy 412.166636 -415.013224)
			(xy 412.220589 -415.005472) (xy 412.247842 -415.005012) (xy 413.111442 -415.005012) (xy 413.138693 -415.005461)
			(xy 413.192639 -415.013222) (xy 413.244931 -415.028582) (xy 413.294506 -415.051227) (xy 413.340353 -415.080696)
			(xy 413.381541 -415.116389) (xy 413.417229 -415.15758) (xy 413.446693 -415.203431) (xy 413.469333 -415.253008)
			(xy 413.484686 -415.305302) (xy 413.492442 -415.359249) (xy 413.492442 -415.413749) (xy 414.930098 -415.413749)
			(xy 414.930098 -415.359251) (xy 414.937854 -415.305308) (xy 414.953207 -415.253017) (xy 414.975846 -415.203444)
			(xy 415.005309 -415.157597) (xy 415.040997 -415.116409) (xy 415.082182 -415.08072) (xy 415.128028 -415.051254)
			(xy 415.1776 -415.028613) (xy 415.22989 -415.013258) (xy 415.283833 -415.005499) (xy 415.311082 -415.005012)
			(xy 416.174682 -415.005012) (xy 416.201937 -415.005434) (xy 416.255893 -415.013189) (xy 416.308196 -415.028544)
			(xy 416.357781 -415.051187) (xy 416.403639 -415.080656) (xy 416.444836 -415.116352) (xy 416.480533 -415.157547)
			(xy 416.510004 -415.203403) (xy 416.532649 -415.252987) (xy 416.548007 -415.305289) (xy 416.555765 -415.359245)
			(xy 416.555765 -415.413752) (xy 417.993275 -415.413752) (xy 417.993275 -415.359248) (xy 418.001032 -415.305298)
			(xy 418.016389 -415.253001) (xy 418.039032 -415.203422) (xy 418.0685 -415.15757) (xy 418.104194 -415.116379)
			(xy 418.145388 -415.080687) (xy 418.191241 -415.051221) (xy 418.240821 -415.028581) (xy 418.293119 -415.013228)
			(xy 418.34707 -415.005474) (xy 418.374322 -415.005012) (xy 419.237922 -415.005012) (xy 419.265174 -415.005459)
			(xy 419.319122 -415.013219) (xy 419.371417 -415.028577) (xy 419.420994 -415.05122) (xy 419.466844 -415.080689)
			(xy 419.508034 -415.116382) (xy 419.543725 -415.157574) (xy 419.57319 -415.203426) (xy 419.595831 -415.253004)
			(xy 419.611186 -415.3053) (xy 419.618942 -415.359248) (xy 419.618942 -415.413752) (xy 419.611186 -415.4677)
			(xy 419.595831 -415.519996) (xy 419.57319 -415.569574) (xy 419.543725 -415.615426) (xy 419.508034 -415.656618)
			(xy 419.466844 -415.692311) (xy 419.420994 -415.72178) (xy 419.371417 -415.744423) (xy 419.319122 -415.759781)
			(xy 419.265174 -415.767541) (xy 419.237922 -415.768028) (xy 418.374322 -415.768028) (xy 418.34707 -415.767526)
			(xy 418.293119 -415.759772) (xy 418.240821 -415.744419) (xy 418.191241 -415.721779) (xy 418.145388 -415.692313)
			(xy 418.104194 -415.656621) (xy 418.0685 -415.61543) (xy 418.039032 -415.569578) (xy 418.016389 -415.519999)
			(xy 418.001032 -415.467702) (xy 417.993275 -415.413752) (xy 416.555765 -415.413752) (xy 416.555765 -415.413755)
			(xy 416.548007 -415.467711) (xy 416.532649 -415.520013) (xy 416.510004 -415.569597) (xy 416.480533 -415.615453)
			(xy 416.444836 -415.656648) (xy 416.403639 -415.692344) (xy 416.357781 -415.721813) (xy 416.308196 -415.744456)
			(xy 416.255893 -415.759811) (xy 416.201937 -415.767566) (xy 416.174682 -415.768028) (xy 415.311082 -415.768028)
			(xy 415.283833 -415.767501) (xy 415.22989 -415.759742) (xy 415.1776 -415.744387) (xy 415.128028 -415.721746)
			(xy 415.082182 -415.69228) (xy 415.040997 -415.656591) (xy 415.005309 -415.615403) (xy 414.975846 -415.569556)
			(xy 414.953207 -415.519983) (xy 414.937854 -415.467692) (xy 414.930098 -415.413749) (xy 413.492442 -415.413749)
			(xy 413.492442 -415.413751) (xy 413.484686 -415.467698) (xy 413.469333 -415.519992) (xy 413.446693 -415.569569)
			(xy 413.417229 -415.61542) (xy 413.381541 -415.656611) (xy 413.340353 -415.692304) (xy 413.294506 -415.721773)
			(xy 413.244931 -415.744418) (xy 413.192639 -415.759778) (xy 413.138693 -415.767539) (xy 413.111442 -415.768028)
			(xy 412.247842 -415.768028) (xy 412.220589 -415.767528) (xy 412.166636 -415.759776) (xy 412.114336 -415.744424)
			(xy 412.064753 -415.721785) (xy 412.018897 -415.69232) (xy 411.977701 -415.656628) (xy 411.942005 -415.615437)
			(xy 411.912535 -415.569584) (xy 411.88989 -415.520004) (xy 411.874533 -415.467705) (xy 411.866775 -415.413753)
			(xy 410.429242 -415.413753) (xy 410.421485 -415.467703) (xy 410.406129 -415.52) (xy 410.383487 -415.56958)
			(xy 410.35402 -415.615433) (xy 410.318326 -415.656625) (xy 410.277134 -415.692318) (xy 410.231282 -415.721786)
			(xy 410.181702 -415.744429) (xy 410.129405 -415.759785) (xy 410.075455 -415.767542) (xy 410.048202 -415.768028)
			(xy 409.184602 -415.768028) (xy 409.15735 -415.767525) (xy 409.103402 -415.759769) (xy 409.051107 -415.744413)
			(xy 409.001529 -415.721772) (xy 408.955678 -415.692306) (xy 408.914487 -415.656614) (xy 408.878795 -415.615424)
			(xy 408.849329 -415.569573) (xy 408.826687 -415.519995) (xy 408.811332 -415.4677) (xy 408.803575 -415.413752)
			(xy 407.366065 -415.413752) (xy 407.366065 -415.413756) (xy 407.358307 -415.467713) (xy 407.342948 -415.520017)
			(xy 407.320301 -415.569602) (xy 407.290828 -415.61546) (xy 407.255129 -415.656655) (xy 407.213929 -415.692351)
			(xy 407.168069 -415.72182) (xy 407.118481 -415.744461) (xy 407.066176 -415.759815) (xy 407.012218 -415.767568)
			(xy 406.984962 -415.768028) (xy 406.121362 -415.768028) (xy 406.094114 -415.767499) (xy 406.040173 -415.759739)
			(xy 405.987886 -415.744381) (xy 405.938316 -415.721739) (xy 405.892473 -415.692273) (xy 405.851289 -415.656584)
			(xy 405.815604 -415.615397) (xy 405.786143 -415.569551) (xy 405.763506 -415.519978) (xy 405.748153 -415.46769)
			(xy 405.740398 -415.413748) (xy 404.302742 -415.413748) (xy 404.302742 -415.413752) (xy 404.294986 -415.4677)
			(xy 404.279631 -415.519996) (xy 404.25699 -415.569574) (xy 404.227525 -415.615426) (xy 404.191834 -415.656618)
			(xy 404.150644 -415.692311) (xy 404.104794 -415.72178) (xy 404.055217 -415.744423) (xy 404.002922 -415.759781)
			(xy 403.948974 -415.767541) (xy 403.921722 -415.768028) (xy 403.058122 -415.768028) (xy 403.03087 -415.767526)
			(xy 402.976919 -415.759772) (xy 402.924621 -415.744419) (xy 402.875041 -415.721779) (xy 402.829188 -415.692313)
			(xy 402.787994 -415.656621) (xy 402.7523 -415.61543) (xy 402.722832 -415.569578) (xy 402.700189 -415.519999)
			(xy 402.684832 -415.467702) (xy 402.677075 -415.413752) (xy 401.239565 -415.413752) (xy 401.239565 -415.413755)
			(xy 401.231807 -415.467711) (xy 401.216449 -415.520013) (xy 401.193804 -415.569597) (xy 401.164333 -415.615453)
			(xy 401.128636 -415.656648) (xy 401.087439 -415.692344) (xy 401.041581 -415.721813) (xy 400.991996 -415.744456)
			(xy 400.939693 -415.759811) (xy 400.885737 -415.767566) (xy 400.858482 -415.768028) (xy 399.994882 -415.768028)
			(xy 399.967633 -415.767501) (xy 399.91369 -415.759742) (xy 399.8614 -415.744387) (xy 399.811828 -415.721746)
			(xy 399.765982 -415.69228) (xy 399.724797 -415.656591) (xy 399.689109 -415.615403) (xy 399.659646 -415.569556)
			(xy 399.637007 -415.519983) (xy 399.621654 -415.467692) (xy 399.613898 -415.413749) (xy 398.176242 -415.413749)
			(xy 398.176242 -415.413751) (xy 398.168486 -415.467698) (xy 398.153133 -415.519992) (xy 398.130493 -415.569569)
			(xy 398.101029 -415.61542) (xy 398.065341 -415.656611) (xy 398.024153 -415.692304) (xy 397.978306 -415.721773)
			(xy 397.928731 -415.744418) (xy 397.876439 -415.759778) (xy 397.822493 -415.767539) (xy 397.795242 -415.768028)
			(xy 396.931642 -415.768028) (xy 396.904389 -415.767528) (xy 396.850436 -415.759776) (xy 396.798136 -415.744424)
			(xy 396.748553 -415.721785) (xy 396.702697 -415.69232) (xy 396.661501 -415.656628) (xy 396.625805 -415.615437)
			(xy 396.596335 -415.569584) (xy 396.57369 -415.520004) (xy 396.558333 -415.467705) (xy 396.550575 -415.413753)
			(xy 395.113042 -415.413753) (xy 395.105285 -415.467703) (xy 395.089929 -415.52) (xy 395.067287 -415.56958)
			(xy 395.03782 -415.615433) (xy 395.002126 -415.656625) (xy 394.960934 -415.692318) (xy 394.915082 -415.721786)
			(xy 394.865502 -415.744429) (xy 394.813205 -415.759785) (xy 394.759255 -415.767542) (xy 394.732002 -415.768028)
			(xy 393.868402 -415.768028) (xy 393.84115 -415.767525) (xy 393.787202 -415.759769) (xy 393.734907 -415.744413)
			(xy 393.685329 -415.721772) (xy 393.639478 -415.692306) (xy 393.598287 -415.656614) (xy 393.562595 -415.615424)
			(xy 393.533129 -415.569573) (xy 393.510487 -415.519995) (xy 393.495132 -415.4677) (xy 393.487375 -415.413752)
			(xy 392.049865 -415.413752) (xy 392.049865 -415.413756) (xy 392.042107 -415.467713) (xy 392.026748 -415.520017)
			(xy 392.004101 -415.569602) (xy 391.974628 -415.61546) (xy 391.938929 -415.656655) (xy 391.897729 -415.692351)
			(xy 391.851869 -415.72182) (xy 391.802281 -415.744461) (xy 391.749976 -415.759815) (xy 391.696018 -415.767568)
			(xy 391.668762 -415.768028) (xy 390.805162 -415.768028) (xy 390.777914 -415.767499) (xy 390.723973 -415.759739)
			(xy 390.671686 -415.744381) (xy 390.622116 -415.721739) (xy 390.576273 -415.692273) (xy 390.535089 -415.656584)
			(xy 390.499404 -415.615397) (xy 390.469943 -415.569551) (xy 390.447306 -415.519978) (xy 390.431953 -415.46769)
			(xy 390.424198 -415.413748) (xy 388.986542 -415.413748) (xy 388.986542 -415.413752) (xy 388.978786 -415.4677)
			(xy 388.963431 -415.519996) (xy 388.94079 -415.569574) (xy 388.911325 -415.615426) (xy 388.875634 -415.656618)
			(xy 388.834444 -415.692311) (xy 388.788594 -415.72178) (xy 388.739017 -415.744423) (xy 388.686722 -415.759781)
			(xy 388.632774 -415.767541) (xy 388.605522 -415.768028) (xy 387.741922 -415.768028) (xy 387.71467 -415.767526)
			(xy 387.660719 -415.759772) (xy 387.608421 -415.744419) (xy 387.558841 -415.721779) (xy 387.512988 -415.692313)
			(xy 387.471794 -415.656621) (xy 387.4361 -415.61543) (xy 387.406632 -415.569578) (xy 387.383989 -415.519999)
			(xy 387.368632 -415.467702) (xy 387.360875 -415.413752) (xy 385.923365 -415.413752) (xy 385.923365 -415.413755)
			(xy 385.915607 -415.467711) (xy 385.900249 -415.520013) (xy 385.877604 -415.569597) (xy 385.848133 -415.615453)
			(xy 385.812436 -415.656648) (xy 385.771239 -415.692344) (xy 385.725381 -415.721813) (xy 385.675796 -415.744456)
			(xy 385.623493 -415.759811) (xy 385.569537 -415.767566) (xy 385.542282 -415.768028) (xy 384.678682 -415.768028)
			(xy 384.651433 -415.767501) (xy 384.59749 -415.759742) (xy 384.5452 -415.744387) (xy 384.495628 -415.721746)
			(xy 384.449782 -415.69228) (xy 384.408597 -415.656591) (xy 384.372909 -415.615403) (xy 384.343446 -415.569556)
			(xy 384.320807 -415.519983) (xy 384.305454 -415.467692) (xy 384.297698 -415.413749) (xy 382.860042 -415.413749)
			(xy 382.860042 -415.413751) (xy 382.852286 -415.467698) (xy 382.836933 -415.519992) (xy 382.814293 -415.569569)
			(xy 382.784829 -415.61542) (xy 382.749141 -415.656611) (xy 382.707953 -415.692304) (xy 382.662106 -415.721773)
			(xy 382.612531 -415.744418) (xy 382.560239 -415.759778) (xy 382.506293 -415.767539) (xy 382.479042 -415.768028)
			(xy 381.615442 -415.768028) (xy 381.588189 -415.767528) (xy 381.534236 -415.759776) (xy 381.481936 -415.744424)
			(xy 381.432353 -415.721785) (xy 381.386497 -415.69232) (xy 381.345301 -415.656628) (xy 381.309605 -415.615437)
			(xy 381.280135 -415.569584) (xy 381.25749 -415.520004) (xy 381.242133 -415.467705) (xy 381.234375 -415.413753)
			(xy 379.796842 -415.413753) (xy 379.789085 -415.467703) (xy 379.773729 -415.52) (xy 379.751087 -415.56958)
			(xy 379.72162 -415.615433) (xy 379.685926 -415.656625) (xy 379.644734 -415.692318) (xy 379.598882 -415.721786)
			(xy 379.549302 -415.744429) (xy 379.497005 -415.759785) (xy 379.443055 -415.767542) (xy 379.415802 -415.768028)
			(xy 378.552202 -415.768028) (xy 378.52495 -415.767525) (xy 378.471002 -415.759769) (xy 378.418707 -415.744413)
			(xy 378.369129 -415.721772) (xy 378.323278 -415.692306) (xy 378.282087 -415.656614) (xy 378.246395 -415.615424)
			(xy 378.216929 -415.569573) (xy 378.194287 -415.519995) (xy 378.178932 -415.4677) (xy 378.171175 -415.413752)
			(xy 376.733665 -415.413752) (xy 376.733665 -415.413756) (xy 376.725907 -415.467713) (xy 376.710548 -415.520017)
			(xy 376.687901 -415.569602) (xy 376.658428 -415.61546) (xy 376.622729 -415.656655) (xy 376.581529 -415.692351)
			(xy 376.535669 -415.72182) (xy 376.486081 -415.744461) (xy 376.433776 -415.759815) (xy 376.379818 -415.767568)
			(xy 376.352562 -415.768028) (xy 375.488962 -415.768028) (xy 375.461714 -415.767499) (xy 375.407773 -415.759739)
			(xy 375.355486 -415.744381) (xy 375.305916 -415.721739) (xy 375.260073 -415.692273) (xy 375.218889 -415.656584)
			(xy 375.183204 -415.615397) (xy 375.153743 -415.569551) (xy 375.131106 -415.519978) (xy 375.115753 -415.46769)
			(xy 375.107998 -415.413748) (xy 373.670342 -415.413748) (xy 373.670342 -415.413752) (xy 373.662586 -415.4677)
			(xy 373.647231 -415.519996) (xy 373.62459 -415.569574) (xy 373.595125 -415.615426) (xy 373.559434 -415.656618)
			(xy 373.518244 -415.692311) (xy 373.472394 -415.72178) (xy 373.422817 -415.744423) (xy 373.370522 -415.759781)
			(xy 373.316574 -415.767541) (xy 373.289322 -415.768028) (xy 372.425722 -415.768028) (xy 372.39847 -415.767526)
			(xy 372.344519 -415.759772) (xy 372.292221 -415.744419) (xy 372.242641 -415.721779) (xy 372.196788 -415.692313)
			(xy 372.155594 -415.656621) (xy 372.1199 -415.61543) (xy 372.090432 -415.569578) (xy 372.067789 -415.519999)
			(xy 372.052432 -415.467702) (xy 372.044675 -415.413752) (xy 352.518742 -415.413752) (xy 352.510986 -415.4677)
			(xy 352.495631 -415.519995) (xy 352.472991 -415.569573) (xy 352.443526 -415.615425) (xy 352.407835 -415.656617)
			(xy 352.366646 -415.69231) (xy 352.320796 -415.721778) (xy 352.27122 -415.744422) (xy 352.218925 -415.75978)
			(xy 352.164977 -415.76754) (xy 352.137726 -415.768028) (xy 351.274126 -415.768028) (xy 351.246873 -415.767526)
			(xy 351.192922 -415.759773) (xy 351.140624 -415.74442) (xy 351.091043 -415.72178) (xy 351.045189 -415.692314)
			(xy 351.003996 -415.656623) (xy 350.968301 -415.615431) (xy 350.938832 -415.569579) (xy 350.916189 -415.52)
			(xy 350.900833 -415.467703) (xy 350.893075 -415.413753) (xy 349.455565 -415.413753) (xy 349.455565 -415.413755)
			(xy 349.447807 -415.46771) (xy 349.43245 -415.520012) (xy 349.409805 -415.569595) (xy 349.380334 -415.615452)
			(xy 349.344637 -415.656647) (xy 349.303441 -415.692343) (xy 349.257583 -415.721812) (xy 349.207999 -415.744455)
			(xy 349.155696 -415.75981) (xy 349.101741 -415.767566) (xy 349.074486 -415.768028) (xy 348.210886 -415.768028)
			(xy 348.183637 -415.767501) (xy 348.129694 -415.759743) (xy 348.077403 -415.744388) (xy 348.02783 -415.721747)
			(xy 347.981984 -415.692282) (xy 347.940798 -415.656592) (xy 347.90511 -415.615404) (xy 347.875646 -415.569557)
			(xy 347.853008 -415.519984) (xy 347.837654 -415.467693) (xy 347.829898 -415.413749) (xy 346.392242 -415.413749)
			(xy 346.392242 -415.413751) (xy 346.384487 -415.467697) (xy 346.369133 -415.519991) (xy 346.346494 -415.569568)
			(xy 346.31703 -415.615418) (xy 346.281342 -415.656609) (xy 346.240155 -415.692303) (xy 346.194308 -415.721772)
			(xy 346.144734 -415.744417) (xy 346.092442 -415.759777) (xy 346.038497 -415.767539) (xy 346.011246 -415.768028)
			(xy 345.147646 -415.768028) (xy 345.120392 -415.767528) (xy 345.066439 -415.759777) (xy 345.014139 -415.744425)
			(xy 344.964555 -415.721787) (xy 344.918699 -415.692321) (xy 344.877503 -415.65663) (xy 344.841806 -415.615438)
			(xy 344.812335 -415.569585) (xy 344.789691 -415.520004) (xy 344.774333 -415.467706) (xy 344.766575 -415.413754)
			(xy 343.329042 -415.413754) (xy 343.321285 -415.467702) (xy 343.30593 -415.519999) (xy 343.283288 -415.569579)
			(xy 343.253821 -415.615431) (xy 343.218128 -415.656624) (xy 343.176936 -415.692317) (xy 343.131084 -415.721785)
			(xy 343.081505 -415.744428) (xy 343.029208 -415.759784) (xy 342.975258 -415.767542) (xy 342.948006 -415.768028)
			(xy 342.084406 -415.768028) (xy 342.057154 -415.767525) (xy 342.003206 -415.759769) (xy 341.95091 -415.744415)
			(xy 341.901331 -415.721774) (xy 341.85548 -415.692307) (xy 341.814289 -415.656616) (xy 341.778596 -415.615425)
			(xy 341.749129 -415.569574) (xy 341.726488 -415.519996) (xy 341.711132 -415.4677) (xy 341.703375 -415.413752)
			(xy 340.265865 -415.413752) (xy 340.265865 -415.413756) (xy 340.258107 -415.467713) (xy 340.242748 -415.520016)
			(xy 340.220102 -415.569601) (xy 340.190629 -415.615458) (xy 340.15493 -415.656654) (xy 340.113731 -415.69235)
			(xy 340.067871 -415.721818) (xy 340.018284 -415.74446) (xy 339.965979 -415.759814) (xy 339.912022 -415.767567)
			(xy 339.884766 -415.768028) (xy 339.021166 -415.768028) (xy 338.993918 -415.767499) (xy 338.939977 -415.759739)
			(xy 338.887689 -415.744382) (xy 338.838118 -415.72174) (xy 338.792275 -415.692275) (xy 338.751091 -415.656585)
			(xy 338.715405 -415.615398) (xy 338.685943 -415.569552) (xy 338.663306 -415.519979) (xy 338.647953 -415.46769)
			(xy 338.640198 -415.413748) (xy 337.202542 -415.413748) (xy 337.202542 -415.413751) (xy 337.194786 -415.4677)
			(xy 337.179431 -415.519995) (xy 337.156791 -415.569573) (xy 337.127326 -415.615425) (xy 337.091635 -415.656617)
			(xy 337.050446 -415.69231) (xy 337.004596 -415.721778) (xy 336.95502 -415.744422) (xy 336.902725 -415.75978)
			(xy 336.848777 -415.76754) (xy 336.821526 -415.768028) (xy 335.957926 -415.768028) (xy 335.930673 -415.767526)
			(xy 335.876722 -415.759773) (xy 335.824424 -415.74442) (xy 335.774843 -415.72178) (xy 335.728989 -415.692314)
			(xy 335.687796 -415.656623) (xy 335.652101 -415.615431) (xy 335.622632 -415.569579) (xy 335.599989 -415.52)
			(xy 335.584633 -415.467703) (xy 335.576875 -415.413753) (xy 334.139365 -415.413753) (xy 334.139365 -415.413755)
			(xy 334.131607 -415.46771) (xy 334.11625 -415.520012) (xy 334.093605 -415.569595) (xy 334.064134 -415.615452)
			(xy 334.028437 -415.656647) (xy 333.987241 -415.692343) (xy 333.941383 -415.721812) (xy 333.891799 -415.744455)
			(xy 333.839496 -415.75981) (xy 333.785541 -415.767566) (xy 333.758286 -415.768028) (xy 332.894686 -415.768028)
			(xy 332.867437 -415.767501) (xy 332.813494 -415.759743) (xy 332.761203 -415.744388) (xy 332.71163 -415.721747)
			(xy 332.665784 -415.692282) (xy 332.624598 -415.656592) (xy 332.58891 -415.615404) (xy 332.559446 -415.569557)
			(xy 332.536808 -415.519984) (xy 332.521454 -415.467693) (xy 332.513698 -415.413749) (xy 331.076042 -415.413749)
			(xy 331.076042 -415.413751) (xy 331.068287 -415.467697) (xy 331.052933 -415.519991) (xy 331.030294 -415.569568)
			(xy 331.00083 -415.615418) (xy 330.965142 -415.656609) (xy 330.923955 -415.692303) (xy 330.878108 -415.721772)
			(xy 330.828534 -415.744417) (xy 330.776242 -415.759777) (xy 330.722297 -415.767539) (xy 330.695046 -415.768028)
			(xy 329.831446 -415.768028) (xy 329.804192 -415.767528) (xy 329.750239 -415.759777) (xy 329.697939 -415.744425)
			(xy 329.648355 -415.721787) (xy 329.602499 -415.692321) (xy 329.561303 -415.65663) (xy 329.525606 -415.615438)
			(xy 329.496135 -415.569585) (xy 329.473491 -415.520004) (xy 329.458133 -415.467706) (xy 329.450375 -415.413754)
			(xy 328.012842 -415.413754) (xy 328.005085 -415.467702) (xy 327.98973 -415.519999) (xy 327.967088 -415.569579)
			(xy 327.937621 -415.615431) (xy 327.901928 -415.656624) (xy 327.860736 -415.692317) (xy 327.814884 -415.721785)
			(xy 327.765305 -415.744428) (xy 327.713008 -415.759784) (xy 327.659058 -415.767542) (xy 327.631806 -415.768028)
			(xy 326.768206 -415.768028) (xy 326.740954 -415.767525) (xy 326.687006 -415.759769) (xy 326.63471 -415.744415)
			(xy 326.585131 -415.721774) (xy 326.53928 -415.692307) (xy 326.498089 -415.656616) (xy 326.462396 -415.615425)
			(xy 326.432929 -415.569574) (xy 326.410288 -415.519996) (xy 326.394932 -415.4677) (xy 326.387175 -415.413752)
			(xy 324.949665 -415.413752) (xy 324.949665 -415.413756) (xy 324.941907 -415.467713) (xy 324.926548 -415.520016)
			(xy 324.903902 -415.569601) (xy 324.874429 -415.615458) (xy 324.83873 -415.656654) (xy 324.797531 -415.69235)
			(xy 324.751671 -415.721818) (xy 324.702084 -415.74446) (xy 324.649779 -415.759814) (xy 324.595822 -415.767567)
			(xy 324.568566 -415.768028) (xy 323.704966 -415.768028) (xy 323.677718 -415.767499) (xy 323.623777 -415.759739)
			(xy 323.571489 -415.744382) (xy 323.521918 -415.72174) (xy 323.476075 -415.692275) (xy 323.434891 -415.656585)
			(xy 323.399205 -415.615398) (xy 323.369743 -415.569552) (xy 323.347106 -415.519979) (xy 323.331753 -415.46769)
			(xy 323.323998 -415.413748) (xy 321.886342 -415.413748) (xy 321.886342 -415.413751) (xy 321.878586 -415.4677)
			(xy 321.863231 -415.519995) (xy 321.840591 -415.569573) (xy 321.811126 -415.615425) (xy 321.775435 -415.656617)
			(xy 321.734246 -415.69231) (xy 321.688396 -415.721778) (xy 321.63882 -415.744422) (xy 321.586525 -415.75978)
			(xy 321.532577 -415.76754) (xy 321.505326 -415.768028) (xy 320.641726 -415.768028) (xy 320.614473 -415.767526)
			(xy 320.560522 -415.759773) (xy 320.508224 -415.74442) (xy 320.458643 -415.72178) (xy 320.412789 -415.692314)
			(xy 320.371596 -415.656623) (xy 320.335901 -415.615431) (xy 320.306432 -415.569579) (xy 320.283789 -415.52)
			(xy 320.268433 -415.467703) (xy 320.260675 -415.413753) (xy 318.823165 -415.413753) (xy 318.823165 -415.413755)
			(xy 318.815407 -415.46771) (xy 318.80005 -415.520012) (xy 318.777405 -415.569595) (xy 318.747934 -415.615452)
			(xy 318.712237 -415.656647) (xy 318.671041 -415.692343) (xy 318.625183 -415.721812) (xy 318.575599 -415.744455)
			(xy 318.523296 -415.75981) (xy 318.469341 -415.767566) (xy 318.442086 -415.768028) (xy 317.578486 -415.768028)
			(xy 317.551237 -415.767501) (xy 317.497294 -415.759743) (xy 317.445003 -415.744388) (xy 317.39543 -415.721747)
			(xy 317.349584 -415.692282) (xy 317.308398 -415.656592) (xy 317.27271 -415.615404) (xy 317.243246 -415.569557)
			(xy 317.220608 -415.519984) (xy 317.205254 -415.467693) (xy 317.197498 -415.413749) (xy 315.759842 -415.413749)
			(xy 315.759842 -415.413751) (xy 315.752087 -415.467697) (xy 315.736733 -415.519991) (xy 315.714094 -415.569568)
			(xy 315.68463 -415.615418) (xy 315.648942 -415.656609) (xy 315.607755 -415.692303) (xy 315.561908 -415.721772)
			(xy 315.512334 -415.744417) (xy 315.460042 -415.759777) (xy 315.406097 -415.767539) (xy 315.378846 -415.768028)
			(xy 314.515246 -415.768028) (xy 314.487992 -415.767528) (xy 314.434039 -415.759777) (xy 314.381739 -415.744425)
			(xy 314.332155 -415.721787) (xy 314.286299 -415.692321) (xy 314.245103 -415.65663) (xy 314.209406 -415.615438)
			(xy 314.179935 -415.569585) (xy 314.157291 -415.520004) (xy 314.141933 -415.467706) (xy 314.134175 -415.413754)
			(xy 312.696642 -415.413754) (xy 312.688885 -415.467702) (xy 312.67353 -415.519999) (xy 312.650888 -415.569579)
			(xy 312.621421 -415.615431) (xy 312.585728 -415.656624) (xy 312.544536 -415.692317) (xy 312.498684 -415.721785)
			(xy 312.449105 -415.744428) (xy 312.396808 -415.759784) (xy 312.342858 -415.767542) (xy 312.315606 -415.768028)
			(xy 311.452006 -415.768028) (xy 311.424754 -415.767525) (xy 311.370806 -415.759769) (xy 311.31851 -415.744415)
			(xy 311.268931 -415.721774) (xy 311.22308 -415.692307) (xy 311.181889 -415.656616) (xy 311.146196 -415.615425)
			(xy 311.116729 -415.569574) (xy 311.094088 -415.519996) (xy 311.078732 -415.4677) (xy 311.070975 -415.413752)
			(xy 309.633465 -415.413752) (xy 309.633465 -415.413756) (xy 309.625707 -415.467713) (xy 309.610348 -415.520016)
			(xy 309.587702 -415.569601) (xy 309.558229 -415.615458) (xy 309.52253 -415.656654) (xy 309.481331 -415.69235)
			(xy 309.435471 -415.721818) (xy 309.385884 -415.74446) (xy 309.333579 -415.759814) (xy 309.279622 -415.767567)
			(xy 309.252366 -415.768028) (xy 308.388766 -415.768028) (xy 308.361518 -415.767499) (xy 308.307577 -415.759739)
			(xy 308.255289 -415.744382) (xy 308.205718 -415.72174) (xy 308.159875 -415.692275) (xy 308.118691 -415.656585)
			(xy 308.083005 -415.615398) (xy 308.053543 -415.569552) (xy 308.030906 -415.519979) (xy 308.015553 -415.46769)
			(xy 308.007798 -415.413748) (xy 306.570142 -415.413748) (xy 306.570142 -415.413751) (xy 306.562386 -415.4677)
			(xy 306.547031 -415.519995) (xy 306.524391 -415.569573) (xy 306.494926 -415.615425) (xy 306.459235 -415.656617)
			(xy 306.418046 -415.69231) (xy 306.372196 -415.721778) (xy 306.32262 -415.744422) (xy 306.270325 -415.75978)
			(xy 306.216377 -415.76754) (xy 306.189126 -415.768028) (xy 305.325526 -415.768028) (xy 305.298273 -415.767526)
			(xy 305.244322 -415.759773) (xy 305.192024 -415.74442) (xy 305.142443 -415.72178) (xy 305.096589 -415.692314)
			(xy 305.055396 -415.656623) (xy 305.019701 -415.615431) (xy 304.990232 -415.569579) (xy 304.967589 -415.52)
			(xy 304.952233 -415.467703) (xy 304.944475 -415.413753) (xy 300.882586 -415.413753) (xy 300.868941 -415.434612)
			(xy 300.76479 -415.579315) (xy 300.654297 -415.719235) (xy 300.53768 -415.854094) (xy 300.415171 -415.983624)
			(xy 300.287014 -416.107568) (xy 300.153463 -416.22568) (xy 300.014783 -416.337725) (xy 299.871249 -416.443482)
			(xy 299.723146 -416.542739) (xy 299.570769 -416.635301) (xy 299.41442 -416.720982) (xy 299.254409 -416.799614)
			(xy 299.091055 -416.87104) (xy 298.92468 -416.935118) (xy 298.755617 -416.99172) (xy 298.5842 -417.040736)
			(xy 298.410769 -417.082066) (xy 298.235669 -417.11563) (xy 298.059249 -417.14136) (xy 297.881857 -417.159206)
			(xy 297.703846 -417.169132) (xy 297.525569 -417.171118) (xy 297.347382 -417.165161) (xy 297.169636 -417.151271)
			(xy 296.992686 -417.129478) (xy 296.816882 -417.099824) (xy 296.642574 -417.062367) (xy 296.470107 -417.017183)
			(xy 296.299824 -416.964361) (xy 296.132063 -416.904005) (xy 295.967158 -416.836237) (xy 295.805435 -416.761189)
			(xy 295.647216 -416.679012) (xy 295.492815 -416.589869) (xy 295.342538 -416.493935) (xy 295.196683 -416.391403)
			(xy 295.055541 -416.282475) (xy 294.919392 -416.167368) (xy 294.788505 -416.04631) (xy 294.663141 -415.919541)
			(xy 294.543548 -415.787314) (xy 294.429965 -415.649891) (xy 294.322616 -415.507544) (xy 294.221715 -415.360556)
			(xy 294.127462 -415.20922) (xy 294.040044 -415.053835) (xy 293.959634 -414.89471) (xy 293.886393 -414.732161)
			(xy 293.820466 -414.566511) (xy 293.761983 -414.398089) (xy 293.711061 -414.227228) (xy 293.667801 -414.054269)
			(xy 293.632289 -413.879554) (xy 293.604595 -413.70343) (xy 293.584774 -413.526248) (xy 293.572866 -413.348359)
			(xy 293.568894 -413.170116) (xy 276.749256 -413.170116) (xy 272.414746 -417.504626) (xy 272.396783 -417.521953)
			(xy 272.356401 -417.55128) (xy 272.311928 -417.573928) (xy 272.264459 -417.589339) (xy 272.215164 -417.597133)
			(xy 272.19021 -417.59759) (xy 235.05033 -417.59759) (xy 235.040259 -417.598007) (xy 235.02166 -417.605731)
			(xy 235.014262 -417.612576) (xy 233.545126 -419.081712) (xy 276.721824 -419.081712) (xy 276.721824 -418.218112)
			(xy 276.72231 -418.190861) (xy 276.730066 -418.136913) (xy 276.745421 -418.084618) (xy 276.768063 -418.035041)
			(xy 276.797529 -417.989191) (xy 276.83322 -417.948) (xy 276.874411 -417.912309) (xy 276.920261 -417.882843)
			(xy 276.969838 -417.860201) (xy 277.022133 -417.844846) (xy 277.076081 -417.83709) (xy 277.130583 -417.83709)
			(xy 277.184531 -417.844846) (xy 277.236826 -417.860201) (xy 277.286403 -417.882843) (xy 277.332253 -417.912309)
			(xy 277.373444 -417.948) (xy 277.409135 -417.989191) (xy 277.438601 -418.035041) (xy 277.461243 -418.084618)
			(xy 277.476598 -418.136913) (xy 277.484354 -418.190861) (xy 277.48484 -418.218112) (xy 277.48484 -418.254688)
			(xy 289.453828 -418.254688) (xy 289.453828 -417.391088) (xy 289.454314 -417.363837) (xy 289.46207 -417.309889)
			(xy 289.477425 -417.257594) (xy 289.500067 -417.208017) (xy 289.529533 -417.162167) (xy 289.565224 -417.120976)
			(xy 289.606415 -417.085285) (xy 289.652265 -417.055819) (xy 289.701842 -417.033177) (xy 289.754137 -417.017822)
			(xy 289.808085 -417.010066) (xy 289.862587 -417.010066) (xy 289.916535 -417.017822) (xy 289.96883 -417.033177)
			(xy 290.018407 -417.055819) (xy 290.064257 -417.085285) (xy 290.105448 -417.120976) (xy 290.141139 -417.162167)
			(xy 290.170605 -417.208017) (xy 290.193247 -417.257594) (xy 290.208602 -417.309889) (xy 290.216358 -417.363837)
			(xy 290.216844 -417.391088) (xy 290.216844 -418.254688) (xy 290.216358 -418.281939) (xy 290.208602 -418.335887)
			(xy 290.193247 -418.388182) (xy 290.170605 -418.437759) (xy 290.169514 -418.439456) (xy 304.944423 -418.439456)
			(xy 304.944423 -418.384944) (xy 304.952181 -418.330986) (xy 304.96754 -418.278681) (xy 304.990186 -418.229095)
			(xy 305.019659 -418.183237) (xy 305.055359 -418.14204) (xy 305.096558 -418.106344) (xy 305.142418 -418.076874)
			(xy 305.192006 -418.054231) (xy 305.244311 -418.038876) (xy 305.29827 -418.031121) (xy 305.325526 -418.03066)
			(xy 306.189126 -418.03066) (xy 306.216374 -418.031212) (xy 306.270314 -418.038971) (xy 306.322601 -418.054327)
			(xy 306.372171 -418.076968) (xy 306.418014 -418.106432) (xy 306.459198 -418.142121) (xy 306.494884 -418.183307)
			(xy 306.524345 -418.229152) (xy 306.546982 -418.278723) (xy 306.562335 -418.331011) (xy 306.57009 -418.384952)
			(xy 306.57009 -418.439448) (xy 306.570089 -418.439452) (xy 308.007746 -418.439452) (xy 308.007746 -418.384948)
			(xy 308.015502 -418.330999) (xy 308.030857 -418.278702) (xy 308.053497 -418.229123) (xy 308.082963 -418.183271)
			(xy 308.118654 -418.142078) (xy 308.159843 -418.106383) (xy 308.205693 -418.076914) (xy 308.25527 -418.054269)
			(xy 308.307565 -418.038909) (xy 308.361514 -418.031148) (xy 308.388766 -418.03066) (xy 309.252366 -418.03066)
			(xy 309.279618 -418.031185) (xy 309.333568 -418.038937) (xy 309.385866 -418.054289) (xy 309.435446 -418.076928)
			(xy 309.4813 -418.106392) (xy 309.522493 -418.142083) (xy 309.558187 -418.183273) (xy 309.587656 -418.229124)
			(xy 309.610299 -418.278702) (xy 309.625655 -418.330999) (xy 309.633413 -418.384948) (xy 309.633413 -418.439452)
			(xy 309.633413 -418.439455) (xy 311.070923 -418.439455) (xy 311.070923 -418.384945) (xy 311.078681 -418.330989)
			(xy 311.094038 -418.278686) (xy 311.116683 -418.229101) (xy 311.146154 -418.183244) (xy 311.181852 -418.142047)
			(xy 311.223049 -418.106351) (xy 311.268906 -418.07688) (xy 311.318491 -418.054236) (xy 311.370794 -418.038879)
			(xy 311.424751 -418.031123) (xy 311.452006 -418.03066) (xy 312.315606 -418.03066) (xy 312.342855 -418.031211)
			(xy 312.396797 -418.038967) (xy 312.449087 -418.054321) (xy 312.498659 -418.076961) (xy 312.544505 -418.106425)
			(xy 312.585691 -418.142113) (xy 312.621379 -418.1833) (xy 312.650842 -418.229146) (xy 312.673481 -418.278719)
			(xy 312.688834 -418.331009) (xy 312.69659 -418.384951) (xy 312.69659 -418.439449) (xy 312.696589 -418.439457)
			(xy 314.134123 -418.439457) (xy 314.134123 -418.384943) (xy 314.141882 -418.330983) (xy 314.157242 -418.278677)
			(xy 314.179889 -418.22909) (xy 314.209364 -418.183231) (xy 314.245066 -418.142033) (xy 314.286267 -418.106337)
			(xy 314.33213 -418.076867) (xy 314.38172 -418.054225) (xy 314.434028 -418.038872) (xy 314.487989 -418.03112)
			(xy 314.515246 -418.03066) (xy 315.378846 -418.03066) (xy 315.406093 -418.031213) (xy 315.460031 -418.038975)
			(xy 315.512316 -418.054332) (xy 315.561883 -418.076974) (xy 315.607724 -418.106439) (xy 315.648905 -418.142128)
			(xy 315.684588 -418.183313) (xy 315.714048 -418.229157) (xy 315.736684 -418.278727) (xy 315.752035 -418.331014)
			(xy 315.75979 -418.384953) (xy 315.75979 -418.439447) (xy 315.759789 -418.439453) (xy 317.197446 -418.439453)
			(xy 317.197446 -418.384947) (xy 317.205203 -418.330996) (xy 317.220558 -418.278698) (xy 317.2432 -418.229118)
			(xy 317.272668 -418.183264) (xy 317.308361 -418.142071) (xy 317.349553 -418.106376) (xy 317.395405 -418.076907)
			(xy 317.444985 -418.054263) (xy 317.497282 -418.038906) (xy 317.551233 -418.031147) (xy 317.578486 -418.03066)
			(xy 318.442086 -418.03066) (xy 318.469337 -418.031186) (xy 318.523285 -418.038941) (xy 318.57558 -418.054295)
			(xy 318.625158 -418.076934) (xy 318.671009 -418.106399) (xy 318.7122 -418.14209) (xy 318.747892 -418.18328)
			(xy 318.777359 -418.22913) (xy 318.800001 -418.278707) (xy 318.815356 -418.331001) (xy 318.823113 -418.384949)
			(xy 318.823113 -418.439451) (xy 318.823112 -418.439456) (xy 320.260623 -418.439456) (xy 320.260623 -418.384944)
			(xy 320.268381 -418.330986) (xy 320.28374 -418.278681) (xy 320.306386 -418.229095) (xy 320.335859 -418.183237)
			(xy 320.371559 -418.14204) (xy 320.412758 -418.106344) (xy 320.458618 -418.076874) (xy 320.508206 -418.054231)
			(xy 320.560511 -418.038876) (xy 320.61447 -418.031121) (xy 320.641726 -418.03066) (xy 321.505326 -418.03066)
			(xy 321.532574 -418.031212) (xy 321.586514 -418.038971) (xy 321.638801 -418.054327) (xy 321.688371 -418.076968)
			(xy 321.734214 -418.106432) (xy 321.775398 -418.142121) (xy 321.811084 -418.183307) (xy 321.840545 -418.229152)
			(xy 321.863182 -418.278723) (xy 321.878535 -418.331011) (xy 321.88629 -418.384952) (xy 321.88629 -418.439448)
			(xy 321.886289 -418.439452) (xy 323.323946 -418.439452) (xy 323.323946 -418.384948) (xy 323.331702 -418.330999)
			(xy 323.347057 -418.278702) (xy 323.369697 -418.229123) (xy 323.399163 -418.183271) (xy 323.434854 -418.142078)
			(xy 323.476043 -418.106383) (xy 323.521893 -418.076914) (xy 323.57147 -418.054269) (xy 323.623765 -418.038909)
			(xy 323.677714 -418.031148) (xy 323.704966 -418.03066) (xy 324.568566 -418.03066) (xy 324.595818 -418.031185)
			(xy 324.649768 -418.038937) (xy 324.702066 -418.054289) (xy 324.751646 -418.076928) (xy 324.7975 -418.106392)
			(xy 324.838693 -418.142083) (xy 324.874387 -418.183273) (xy 324.903856 -418.229124) (xy 324.926499 -418.278702)
			(xy 324.941855 -418.330999) (xy 324.949613 -418.384948) (xy 324.949613 -418.439452) (xy 324.949613 -418.439455)
			(xy 326.387123 -418.439455) (xy 326.387123 -418.384945) (xy 326.394881 -418.330989) (xy 326.410238 -418.278686)
			(xy 326.432883 -418.229101) (xy 326.462354 -418.183244) (xy 326.498052 -418.142047) (xy 326.539249 -418.106351)
			(xy 326.585106 -418.07688) (xy 326.634691 -418.054236) (xy 326.686994 -418.038879) (xy 326.740951 -418.031123)
			(xy 326.768206 -418.03066) (xy 327.631806 -418.03066) (xy 327.659055 -418.031211) (xy 327.712997 -418.038967)
			(xy 327.765287 -418.054321) (xy 327.814859 -418.076961) (xy 327.860705 -418.106425) (xy 327.901891 -418.142113)
			(xy 327.937579 -418.1833) (xy 327.967042 -418.229146) (xy 327.989681 -418.278719) (xy 328.005034 -418.331009)
			(xy 328.01279 -418.384951) (xy 328.01279 -418.439449) (xy 328.012789 -418.439457) (xy 329.450323 -418.439457)
			(xy 329.450323 -418.384943) (xy 329.458082 -418.330983) (xy 329.473442 -418.278677) (xy 329.496089 -418.22909)
			(xy 329.525564 -418.183231) (xy 329.561266 -418.142033) (xy 329.602467 -418.106337) (xy 329.64833 -418.076867)
			(xy 329.69792 -418.054225) (xy 329.750228 -418.038872) (xy 329.804189 -418.03112) (xy 329.831446 -418.03066)
			(xy 330.695046 -418.03066) (xy 330.722293 -418.031213) (xy 330.776231 -418.038975) (xy 330.828516 -418.054332)
			(xy 330.878083 -418.076974) (xy 330.923924 -418.106439) (xy 330.965105 -418.142128) (xy 331.000788 -418.183313)
			(xy 331.030248 -418.229157) (xy 331.052884 -418.278727) (xy 331.068235 -418.331014) (xy 331.07599 -418.384953)
			(xy 331.07599 -418.439447) (xy 331.075989 -418.439453) (xy 332.513646 -418.439453) (xy 332.513646 -418.384947)
			(xy 332.521403 -418.330996) (xy 332.536758 -418.278698) (xy 332.5594 -418.229118) (xy 332.588868 -418.183264)
			(xy 332.624561 -418.142071) (xy 332.665753 -418.106376) (xy 332.711605 -418.076907) (xy 332.761185 -418.054263)
			(xy 332.813482 -418.038906) (xy 332.867433 -418.031147) (xy 332.894686 -418.03066) (xy 333.758286 -418.03066)
			(xy 333.785537 -418.031186) (xy 333.839485 -418.038941) (xy 333.89178 -418.054295) (xy 333.941358 -418.076934)
			(xy 333.987209 -418.106399) (xy 334.0284 -418.14209) (xy 334.064092 -418.18328) (xy 334.093559 -418.22913)
			(xy 334.116201 -418.278707) (xy 334.131556 -418.331001) (xy 334.139313 -418.384949) (xy 334.139313 -418.439451)
			(xy 334.139312 -418.439456) (xy 335.576823 -418.439456) (xy 335.576823 -418.384944) (xy 335.584581 -418.330986)
			(xy 335.59994 -418.278681) (xy 335.622586 -418.229095) (xy 335.652059 -418.183237) (xy 335.687759 -418.14204)
			(xy 335.728958 -418.106344) (xy 335.774818 -418.076874) (xy 335.824406 -418.054231) (xy 335.876711 -418.038876)
			(xy 335.93067 -418.031121) (xy 335.957926 -418.03066) (xy 336.821526 -418.03066) (xy 336.848774 -418.031212)
			(xy 336.902714 -418.038971) (xy 336.955001 -418.054327) (xy 337.004571 -418.076968) (xy 337.050414 -418.106432)
			(xy 337.091598 -418.142121) (xy 337.127284 -418.183307) (xy 337.156745 -418.229152) (xy 337.179382 -418.278723)
			(xy 337.194735 -418.331011) (xy 337.20249 -418.384952) (xy 337.20249 -418.439448) (xy 337.202489 -418.439452)
			(xy 338.640146 -418.439452) (xy 338.640146 -418.384948) (xy 338.647902 -418.330999) (xy 338.663257 -418.278702)
			(xy 338.685897 -418.229123) (xy 338.715363 -418.183271) (xy 338.751054 -418.142078) (xy 338.792243 -418.106383)
			(xy 338.838093 -418.076914) (xy 338.88767 -418.054269) (xy 338.939965 -418.038909) (xy 338.993914 -418.031148)
			(xy 339.021166 -418.03066) (xy 339.884766 -418.03066) (xy 339.912018 -418.031185) (xy 339.965968 -418.038937)
			(xy 340.018266 -418.054289) (xy 340.067846 -418.076928) (xy 340.1137 -418.106392) (xy 340.154893 -418.142083)
			(xy 340.190587 -418.183273) (xy 340.220056 -418.229124) (xy 340.242699 -418.278702) (xy 340.258055 -418.330999)
			(xy 340.265813 -418.384948) (xy 340.265813 -418.439452) (xy 340.265813 -418.439455) (xy 341.703323 -418.439455)
			(xy 341.703323 -418.384945) (xy 341.711081 -418.330989) (xy 341.726438 -418.278686) (xy 341.749083 -418.229101)
			(xy 341.778554 -418.183244) (xy 341.814252 -418.142047) (xy 341.855449 -418.106351) (xy 341.901306 -418.07688)
			(xy 341.950891 -418.054236) (xy 342.003194 -418.038879) (xy 342.057151 -418.031123) (xy 342.084406 -418.03066)
			(xy 342.948006 -418.03066) (xy 342.975255 -418.031211) (xy 343.029197 -418.038967) (xy 343.081487 -418.054321)
			(xy 343.131059 -418.076961) (xy 343.176905 -418.106425) (xy 343.218091 -418.142113) (xy 343.253779 -418.1833)
			(xy 343.283242 -418.229146) (xy 343.305881 -418.278719) (xy 343.321234 -418.331009) (xy 343.32899 -418.384951)
			(xy 343.32899 -418.439449) (xy 343.328989 -418.439457) (xy 344.766523 -418.439457) (xy 344.766523 -418.384943)
			(xy 344.774282 -418.330983) (xy 344.789642 -418.278677) (xy 344.812289 -418.22909) (xy 344.841764 -418.183231)
			(xy 344.877466 -418.142033) (xy 344.918667 -418.106337) (xy 344.96453 -418.076867) (xy 345.01412 -418.054225)
			(xy 345.066428 -418.038872) (xy 345.120389 -418.03112) (xy 345.147646 -418.03066) (xy 346.011246 -418.03066)
			(xy 346.038493 -418.031213) (xy 346.092431 -418.038975) (xy 346.144716 -418.054332) (xy 346.194283 -418.076974)
			(xy 346.240124 -418.106439) (xy 346.281305 -418.142128) (xy 346.316988 -418.183313) (xy 346.346448 -418.229157)
			(xy 346.369084 -418.278727) (xy 346.384435 -418.331014) (xy 346.39219 -418.384953) (xy 346.39219 -418.439447)
			(xy 346.392189 -418.439453) (xy 347.829846 -418.439453) (xy 347.829846 -418.384947) (xy 347.837603 -418.330996)
			(xy 347.852958 -418.278698) (xy 347.8756 -418.229118) (xy 347.905068 -418.183264) (xy 347.940761 -418.142071)
			(xy 347.981953 -418.106376) (xy 348.027805 -418.076907) (xy 348.077385 -418.054263) (xy 348.129682 -418.038906)
			(xy 348.183633 -418.031147) (xy 348.210886 -418.03066) (xy 349.074486 -418.03066) (xy 349.101737 -418.031186)
			(xy 349.155685 -418.038941) (xy 349.20798 -418.054295) (xy 349.257558 -418.076934) (xy 349.303409 -418.106399)
			(xy 349.3446 -418.14209) (xy 349.380292 -418.18328) (xy 349.409759 -418.22913) (xy 349.432401 -418.278707)
			(xy 349.447756 -418.331001) (xy 349.455513 -418.384949) (xy 349.455513 -418.439451) (xy 349.455512 -418.439456)
			(xy 350.893023 -418.439456) (xy 350.893023 -418.384944) (xy 350.900781 -418.330986) (xy 350.91614 -418.278681)
			(xy 350.938786 -418.229095) (xy 350.968259 -418.183237) (xy 351.003959 -418.14204) (xy 351.045158 -418.106344)
			(xy 351.091018 -418.076874) (xy 351.140606 -418.054231) (xy 351.192911 -418.038876) (xy 351.24687 -418.031121)
			(xy 351.274126 -418.03066) (xy 352.137726 -418.03066) (xy 352.164974 -418.031212) (xy 352.218914 -418.038971)
			(xy 352.271201 -418.054327) (xy 352.320771 -418.076968) (xy 352.366614 -418.106432) (xy 352.407798 -418.142121)
			(xy 352.443484 -418.183307) (xy 352.472945 -418.229152) (xy 352.495582 -418.278723) (xy 352.510935 -418.331011)
			(xy 352.51869 -418.384952) (xy 352.51869 -418.439448) (xy 352.510935 -418.493389) (xy 352.495582 -418.545677)
			(xy 352.472945 -418.595248) (xy 352.443484 -418.641093) (xy 352.407798 -418.682279) (xy 352.366614 -418.717968)
			(xy 352.320771 -418.747432) (xy 352.271201 -418.770073) (xy 352.218914 -418.785429) (xy 352.164974 -418.793188)
			(xy 352.137726 -418.793676) (xy 351.274126 -418.793676) (xy 351.24687 -418.793279) (xy 351.192911 -418.785524)
			(xy 351.140606 -418.770169) (xy 351.091018 -418.747526) (xy 351.045158 -418.718056) (xy 351.003959 -418.68236)
			(xy 350.968259 -418.641163) (xy 350.938786 -418.595305) (xy 350.91614 -418.545719) (xy 350.900781 -418.493414)
			(xy 350.893023 -418.439456) (xy 349.455512 -418.439456) (xy 349.447756 -418.493399) (xy 349.432401 -418.545693)
			(xy 349.409759 -418.59527) (xy 349.380292 -418.64112) (xy 349.3446 -418.68231) (xy 349.303409 -418.718001)
			(xy 349.257558 -418.747466) (xy 349.20798 -418.770105) (xy 349.155685 -418.785459) (xy 349.101737 -418.793214)
			(xy 349.074486 -418.793676) (xy 348.210886 -418.793676) (xy 348.183633 -418.793253) (xy 348.129682 -418.785494)
			(xy 348.077385 -418.770137) (xy 348.027805 -418.747493) (xy 347.981953 -418.718024) (xy 347.940761 -418.682329)
			(xy 347.905068 -418.641136) (xy 347.8756 -418.595282) (xy 347.852958 -418.545702) (xy 347.837603 -418.493404)
			(xy 347.829846 -418.439453) (xy 346.392189 -418.439453) (xy 346.384435 -418.493386) (xy 346.369084 -418.545673)
			(xy 346.346448 -418.595243) (xy 346.316988 -418.641087) (xy 346.281305 -418.682272) (xy 346.240124 -418.717961)
			(xy 346.194283 -418.747426) (xy 346.144716 -418.770068) (xy 346.092431 -418.785425) (xy 346.038493 -418.793187)
			(xy 346.011246 -418.793676) (xy 345.147646 -418.793676) (xy 345.120389 -418.79328) (xy 345.066428 -418.785528)
			(xy 345.01412 -418.770175) (xy 344.96453 -418.747533) (xy 344.918667 -418.718063) (xy 344.877466 -418.682367)
			(xy 344.841764 -418.641169) (xy 344.812289 -418.59531) (xy 344.789642 -418.545723) (xy 344.774282 -418.493417)
			(xy 344.766523 -418.439457) (xy 343.328989 -418.439457) (xy 343.321234 -418.493391) (xy 343.305881 -418.545681)
			(xy 343.283242 -418.595254) (xy 343.253779 -418.6411) (xy 343.218091 -418.682287) (xy 343.176905 -418.717975)
			(xy 343.131059 -418.747439) (xy 343.081487 -418.770079) (xy 343.029197 -418.785433) (xy 342.975255 -418.793189)
			(xy 342.948006 -418.793676) (xy 342.084406 -418.793676) (xy 342.057151 -418.793277) (xy 342.003194 -418.785521)
			(xy 341.950891 -418.770164) (xy 341.901306 -418.74752) (xy 341.855449 -418.718049) (xy 341.814252 -418.682353)
			(xy 341.778554 -418.641156) (xy 341.749083 -418.595299) (xy 341.726438 -418.545714) (xy 341.711081 -418.493411)
			(xy 341.703323 -418.439455) (xy 340.265813 -418.439455) (xy 340.258055 -418.493402) (xy 340.242699 -418.545698)
			(xy 340.220056 -418.595276) (xy 340.190587 -418.641127) (xy 340.154893 -418.682317) (xy 340.1137 -418.718008)
			(xy 340.067846 -418.747472) (xy 340.018266 -418.770111) (xy 339.965968 -418.785463) (xy 339.912018 -418.793215)
			(xy 339.884766 -418.793676) (xy 339.021166 -418.793676) (xy 338.993914 -418.793252) (xy 338.939965 -418.785491)
			(xy 338.88767 -418.770131) (xy 338.838093 -418.747486) (xy 338.792243 -418.718017) (xy 338.751054 -418.682322)
			(xy 338.715363 -418.641129) (xy 338.685897 -418.595277) (xy 338.663257 -418.545698) (xy 338.647902 -418.493401)
			(xy 338.640146 -418.439452) (xy 337.202489 -418.439452) (xy 337.194735 -418.493389) (xy 337.179382 -418.545677)
			(xy 337.156745 -418.595248) (xy 337.127284 -418.641093) (xy 337.091598 -418.682279) (xy 337.050414 -418.717968)
			(xy 337.004571 -418.747432) (xy 336.955001 -418.770073) (xy 336.902714 -418.785429) (xy 336.848774 -418.793188)
			(xy 336.821526 -418.793676) (xy 335.957926 -418.793676) (xy 335.93067 -418.793279) (xy 335.876711 -418.785524)
			(xy 335.824406 -418.770169) (xy 335.774818 -418.747526) (xy 335.728958 -418.718056) (xy 335.687759 -418.68236)
			(xy 335.652059 -418.641163) (xy 335.622586 -418.595305) (xy 335.59994 -418.545719) (xy 335.584581 -418.493414)
			(xy 335.576823 -418.439456) (xy 334.139312 -418.439456) (xy 334.131556 -418.493399) (xy 334.116201 -418.545693)
			(xy 334.093559 -418.59527) (xy 334.064092 -418.64112) (xy 334.0284 -418.68231) (xy 333.987209 -418.718001)
			(xy 333.941358 -418.747466) (xy 333.89178 -418.770105) (xy 333.839485 -418.785459) (xy 333.785537 -418.793214)
			(xy 333.758286 -418.793676) (xy 332.894686 -418.793676) (xy 332.867433 -418.793253) (xy 332.813482 -418.785494)
			(xy 332.761185 -418.770137) (xy 332.711605 -418.747493) (xy 332.665753 -418.718024) (xy 332.624561 -418.682329)
			(xy 332.588868 -418.641136) (xy 332.5594 -418.595282) (xy 332.536758 -418.545702) (xy 332.521403 -418.493404)
			(xy 332.513646 -418.439453) (xy 331.075989 -418.439453) (xy 331.068235 -418.493386) (xy 331.052884 -418.545673)
			(xy 331.030248 -418.595243) (xy 331.000788 -418.641087) (xy 330.965105 -418.682272) (xy 330.923924 -418.717961)
			(xy 330.878083 -418.747426) (xy 330.828516 -418.770068) (xy 330.776231 -418.785425) (xy 330.722293 -418.793187)
			(xy 330.695046 -418.793676) (xy 329.831446 -418.793676) (xy 329.804189 -418.79328) (xy 329.750228 -418.785528)
			(xy 329.69792 -418.770175) (xy 329.64833 -418.747533) (xy 329.602467 -418.718063) (xy 329.561266 -418.682367)
			(xy 329.525564 -418.641169) (xy 329.496089 -418.59531) (xy 329.473442 -418.545723) (xy 329.458082 -418.493417)
			(xy 329.450323 -418.439457) (xy 328.012789 -418.439457) (xy 328.005034 -418.493391) (xy 327.989681 -418.545681)
			(xy 327.967042 -418.595254) (xy 327.937579 -418.6411) (xy 327.901891 -418.682287) (xy 327.860705 -418.717975)
			(xy 327.814859 -418.747439) (xy 327.765287 -418.770079) (xy 327.712997 -418.785433) (xy 327.659055 -418.793189)
			(xy 327.631806 -418.793676) (xy 326.768206 -418.793676) (xy 326.740951 -418.793277) (xy 326.686994 -418.785521)
			(xy 326.634691 -418.770164) (xy 326.585106 -418.74752) (xy 326.539249 -418.718049) (xy 326.498052 -418.682353)
			(xy 326.462354 -418.641156) (xy 326.432883 -418.595299) (xy 326.410238 -418.545714) (xy 326.394881 -418.493411)
			(xy 326.387123 -418.439455) (xy 324.949613 -418.439455) (xy 324.941855 -418.493402) (xy 324.926499 -418.545698)
			(xy 324.903856 -418.595276) (xy 324.874387 -418.641127) (xy 324.838693 -418.682317) (xy 324.7975 -418.718008)
			(xy 324.751646 -418.747472) (xy 324.702066 -418.770111) (xy 324.649768 -418.785463) (xy 324.595818 -418.793215)
			(xy 324.568566 -418.793676) (xy 323.704966 -418.793676) (xy 323.677714 -418.793252) (xy 323.623765 -418.785491)
			(xy 323.57147 -418.770131) (xy 323.521893 -418.747486) (xy 323.476043 -418.718017) (xy 323.434854 -418.682322)
			(xy 323.399163 -418.641129) (xy 323.369697 -418.595277) (xy 323.347057 -418.545698) (xy 323.331702 -418.493401)
			(xy 323.323946 -418.439452) (xy 321.886289 -418.439452) (xy 321.878535 -418.493389) (xy 321.863182 -418.545677)
			(xy 321.840545 -418.595248) (xy 321.811084 -418.641093) (xy 321.775398 -418.682279) (xy 321.734214 -418.717968)
			(xy 321.688371 -418.747432) (xy 321.638801 -418.770073) (xy 321.586514 -418.785429) (xy 321.532574 -418.793188)
			(xy 321.505326 -418.793676) (xy 320.641726 -418.793676) (xy 320.61447 -418.793279) (xy 320.560511 -418.785524)
			(xy 320.508206 -418.770169) (xy 320.458618 -418.747526) (xy 320.412758 -418.718056) (xy 320.371559 -418.68236)
			(xy 320.335859 -418.641163) (xy 320.306386 -418.595305) (xy 320.28374 -418.545719) (xy 320.268381 -418.493414)
			(xy 320.260623 -418.439456) (xy 318.823112 -418.439456) (xy 318.815356 -418.493399) (xy 318.800001 -418.545693)
			(xy 318.777359 -418.59527) (xy 318.747892 -418.64112) (xy 318.7122 -418.68231) (xy 318.671009 -418.718001)
			(xy 318.625158 -418.747466) (xy 318.57558 -418.770105) (xy 318.523285 -418.785459) (xy 318.469337 -418.793214)
			(xy 318.442086 -418.793676) (xy 317.578486 -418.793676) (xy 317.551233 -418.793253) (xy 317.497282 -418.785494)
			(xy 317.444985 -418.770137) (xy 317.395405 -418.747493) (xy 317.349553 -418.718024) (xy 317.308361 -418.682329)
			(xy 317.272668 -418.641136) (xy 317.2432 -418.595282) (xy 317.220558 -418.545702) (xy 317.205203 -418.493404)
			(xy 317.197446 -418.439453) (xy 315.759789 -418.439453) (xy 315.752035 -418.493386) (xy 315.736684 -418.545673)
			(xy 315.714048 -418.595243) (xy 315.684588 -418.641087) (xy 315.648905 -418.682272) (xy 315.607724 -418.717961)
			(xy 315.561883 -418.747426) (xy 315.512316 -418.770068) (xy 315.460031 -418.785425) (xy 315.406093 -418.793187)
			(xy 315.378846 -418.793676) (xy 314.515246 -418.793676) (xy 314.487989 -418.79328) (xy 314.434028 -418.785528)
			(xy 314.38172 -418.770175) (xy 314.33213 -418.747533) (xy 314.286267 -418.718063) (xy 314.245066 -418.682367)
			(xy 314.209364 -418.641169) (xy 314.179889 -418.59531) (xy 314.157242 -418.545723) (xy 314.141882 -418.493417)
			(xy 314.134123 -418.439457) (xy 312.696589 -418.439457) (xy 312.688834 -418.493391) (xy 312.673481 -418.545681)
			(xy 312.650842 -418.595254) (xy 312.621379 -418.6411) (xy 312.585691 -418.682287) (xy 312.544505 -418.717975)
			(xy 312.498659 -418.747439) (xy 312.449087 -418.770079) (xy 312.396797 -418.785433) (xy 312.342855 -418.793189)
			(xy 312.315606 -418.793676) (xy 311.452006 -418.793676) (xy 311.424751 -418.793277) (xy 311.370794 -418.785521)
			(xy 311.318491 -418.770164) (xy 311.268906 -418.74752) (xy 311.223049 -418.718049) (xy 311.181852 -418.682353)
			(xy 311.146154 -418.641156) (xy 311.116683 -418.595299) (xy 311.094038 -418.545714) (xy 311.078681 -418.493411)
			(xy 311.070923 -418.439455) (xy 309.633413 -418.439455) (xy 309.625655 -418.493402) (xy 309.610299 -418.545698)
			(xy 309.587656 -418.595276) (xy 309.558187 -418.641127) (xy 309.522493 -418.682317) (xy 309.4813 -418.718008)
			(xy 309.435446 -418.747472) (xy 309.385866 -418.770111) (xy 309.333568 -418.785463) (xy 309.279618 -418.793215)
			(xy 309.252366 -418.793676) (xy 308.388766 -418.793676) (xy 308.361514 -418.793252) (xy 308.307565 -418.785491)
			(xy 308.25527 -418.770131) (xy 308.205693 -418.747486) (xy 308.159843 -418.718017) (xy 308.118654 -418.682322)
			(xy 308.082963 -418.641129) (xy 308.053497 -418.595277) (xy 308.030857 -418.545698) (xy 308.015502 -418.493401)
			(xy 308.007746 -418.439452) (xy 306.570089 -418.439452) (xy 306.562335 -418.493389) (xy 306.546982 -418.545677)
			(xy 306.524345 -418.595248) (xy 306.494884 -418.641093) (xy 306.459198 -418.682279) (xy 306.418014 -418.717968)
			(xy 306.372171 -418.747432) (xy 306.322601 -418.770073) (xy 306.270314 -418.785429) (xy 306.216374 -418.793188)
			(xy 306.189126 -418.793676) (xy 305.325526 -418.793676) (xy 305.29827 -418.793279) (xy 305.244311 -418.785524)
			(xy 305.192006 -418.770169) (xy 305.142418 -418.747526) (xy 305.096558 -418.718056) (xy 305.055359 -418.68236)
			(xy 305.019659 -418.641163) (xy 304.990186 -418.595305) (xy 304.96754 -418.545719) (xy 304.952181 -418.493414)
			(xy 304.944423 -418.439456) (xy 290.169514 -418.439456) (xy 290.141139 -418.483609) (xy 290.105448 -418.5248)
			(xy 290.064257 -418.560491) (xy 290.018407 -418.589957) (xy 289.96883 -418.612599) (xy 289.916535 -418.627954)
			(xy 289.862587 -418.63571) (xy 289.808085 -418.63571) (xy 289.754137 -418.627954) (xy 289.701842 -418.612599)
			(xy 289.652265 -418.589957) (xy 289.606415 -418.560491) (xy 289.565224 -418.5248) (xy 289.529533 -418.483609)
			(xy 289.500067 -418.437759) (xy 289.477425 -418.388182) (xy 289.46207 -418.335887) (xy 289.454314 -418.281939)
			(xy 289.453828 -418.254688) (xy 277.48484 -418.254688) (xy 277.48484 -419.081712) (xy 277.484354 -419.108963)
			(xy 277.476598 -419.162911) (xy 277.461243 -419.215206) (xy 277.438601 -419.264783) (xy 277.409135 -419.310633)
			(xy 277.373444 -419.351824) (xy 277.332253 -419.387515) (xy 277.286403 -419.416981) (xy 277.236826 -419.439623)
			(xy 277.184531 -419.454978) (xy 277.130583 -419.462734) (xy 277.076081 -419.462734) (xy 277.022133 -419.454978)
			(xy 276.969838 -419.439623) (xy 276.920261 -419.416981) (xy 276.874411 -419.387515) (xy 276.83322 -419.351824)
			(xy 276.797529 -419.310633) (xy 276.768063 -419.264783) (xy 276.745421 -419.215206) (xy 276.730066 -419.162911)
			(xy 276.72231 -419.108963) (xy 276.721824 -419.081712) (xy 233.545126 -419.081712) (xy 232.102406 -420.524432)
			(xy 290.829492 -420.524432) (xy 290.829492 -419.660832) (xy 290.829978 -419.633563) (xy 290.83774 -419.579579)
			(xy 290.853105 -419.527249) (xy 290.875762 -419.477639) (xy 290.905248 -419.431758) (xy 290.940963 -419.390541)
			(xy 290.98218 -419.354826) (xy 291.028061 -419.32534) (xy 291.077671 -419.302683) (xy 291.130001 -419.287318)
			(xy 291.183985 -419.279556) (xy 291.238523 -419.279556) (xy 291.292507 -419.287318) (xy 291.344837 -419.302683)
			(xy 291.394447 -419.32534) (xy 291.440328 -419.354826) (xy 291.481545 -419.390541) (xy 291.51726 -419.431758)
			(xy 291.546746 -419.477639) (xy 291.569403 -419.527249) (xy 291.584768 -419.579579) (xy 291.59253 -419.633563)
			(xy 291.593016 -419.660832) (xy 291.593016 -420.524432) (xy 291.59253 -420.551701) (xy 291.584768 -420.605685)
			(xy 291.569403 -420.658015) (xy 291.546746 -420.707625) (xy 291.51726 -420.753506) (xy 291.481545 -420.794723)
			(xy 291.440328 -420.830438) (xy 291.394447 -420.859924) (xy 291.344837 -420.882581) (xy 291.292507 -420.897946)
			(xy 291.238523 -420.905708) (xy 291.183985 -420.905708) (xy 291.130001 -420.897946) (xy 291.077671 -420.882581)
			(xy 291.028061 -420.859924) (xy 290.98218 -420.830438) (xy 290.940963 -420.794723) (xy 290.905248 -420.753506)
			(xy 290.875762 -420.707625) (xy 290.853105 -420.658015) (xy 290.83774 -420.605685) (xy 290.829978 -420.551701)
			(xy 290.829492 -420.524432) (xy 232.102406 -420.524432) (xy 231.647383 -420.979455) (xy 303.412823 -420.979455)
			(xy 303.412823 -420.924945) (xy 303.420581 -420.870989) (xy 303.435938 -420.818686) (xy 303.458583 -420.769101)
			(xy 303.488054 -420.723244) (xy 303.523752 -420.682047) (xy 303.564949 -420.646351) (xy 303.610806 -420.61688)
			(xy 303.660391 -420.594236) (xy 303.712694 -420.578879) (xy 303.766651 -420.571123) (xy 303.793906 -420.57066)
			(xy 304.657506 -420.57066) (xy 304.684755 -420.571211) (xy 304.738697 -420.578967) (xy 304.790987 -420.594321)
			(xy 304.840559 -420.616961) (xy 304.886405 -420.646425) (xy 304.927591 -420.682113) (xy 304.963279 -420.7233)
			(xy 304.992742 -420.769146) (xy 305.015381 -420.818719) (xy 305.030734 -420.871009) (xy 305.03849 -420.924951)
			(xy 305.03849 -420.979449) (xy 305.038489 -420.979457) (xy 306.476023 -420.979457) (xy 306.476023 -420.924943)
			(xy 306.483782 -420.870983) (xy 306.499142 -420.818677) (xy 306.521789 -420.76909) (xy 306.551264 -420.723231)
			(xy 306.586966 -420.682033) (xy 306.628167 -420.646337) (xy 306.67403 -420.616867) (xy 306.72362 -420.594225)
			(xy 306.775928 -420.578872) (xy 306.829889 -420.57112) (xy 306.857146 -420.57066) (xy 307.720746 -420.57066)
			(xy 307.747993 -420.571213) (xy 307.801931 -420.578975) (xy 307.854216 -420.594332) (xy 307.903783 -420.616974)
			(xy 307.949624 -420.646439) (xy 307.990805 -420.682128) (xy 308.026488 -420.723313) (xy 308.055948 -420.769157)
			(xy 308.078584 -420.818727) (xy 308.093935 -420.871014) (xy 308.10169 -420.924953) (xy 308.10169 -420.979447)
			(xy 308.101689 -420.979453) (xy 309.539346 -420.979453) (xy 309.539346 -420.924947) (xy 309.547103 -420.870996)
			(xy 309.562458 -420.818698) (xy 309.5851 -420.769118) (xy 309.614568 -420.723264) (xy 309.650261 -420.682071)
			(xy 309.691453 -420.646376) (xy 309.737305 -420.616907) (xy 309.786885 -420.594263) (xy 309.839182 -420.578906)
			(xy 309.893133 -420.571147) (xy 309.920386 -420.57066) (xy 310.783986 -420.57066) (xy 310.811237 -420.571186)
			(xy 310.865185 -420.578941) (xy 310.91748 -420.594295) (xy 310.967058 -420.616934) (xy 311.012909 -420.646399)
			(xy 311.0541 -420.68209) (xy 311.089792 -420.72328) (xy 311.119259 -420.76913) (xy 311.141901 -420.818707)
			(xy 311.157256 -420.871001) (xy 311.165013 -420.924949) (xy 311.165013 -420.979451) (xy 311.165012 -420.979456)
			(xy 312.602523 -420.979456) (xy 312.602523 -420.924944) (xy 312.610281 -420.870986) (xy 312.62564 -420.818681)
			(xy 312.648286 -420.769095) (xy 312.677759 -420.723237) (xy 312.713459 -420.68204) (xy 312.754658 -420.646344)
			(xy 312.800518 -420.616874) (xy 312.850106 -420.594231) (xy 312.902411 -420.578876) (xy 312.95637 -420.571121)
			(xy 312.983626 -420.57066) (xy 313.847226 -420.57066) (xy 313.874474 -420.571212) (xy 313.928414 -420.578971)
			(xy 313.980701 -420.594327) (xy 314.030271 -420.616968) (xy 314.076114 -420.646432) (xy 314.117298 -420.682121)
			(xy 314.152984 -420.723307) (xy 314.182445 -420.769152) (xy 314.205082 -420.818723) (xy 314.220435 -420.871011)
			(xy 314.22819 -420.924952) (xy 314.22819 -420.979448) (xy 314.228189 -420.979452) (xy 315.665846 -420.979452)
			(xy 315.665846 -420.924948) (xy 315.673602 -420.870999) (xy 315.688957 -420.818702) (xy 315.711597 -420.769123)
			(xy 315.741063 -420.723271) (xy 315.776754 -420.682078) (xy 315.817943 -420.646383) (xy 315.863793 -420.616914)
			(xy 315.91337 -420.594269) (xy 315.965665 -420.578909) (xy 316.019614 -420.571148) (xy 316.046866 -420.57066)
			(xy 316.910466 -420.57066) (xy 316.937718 -420.571185) (xy 316.991668 -420.578937) (xy 317.043966 -420.594289)
			(xy 317.093546 -420.616928) (xy 317.1394 -420.646392) (xy 317.180593 -420.682083) (xy 317.216287 -420.723273)
			(xy 317.245756 -420.769124) (xy 317.268399 -420.818702) (xy 317.283755 -420.870999) (xy 317.291513 -420.924948)
			(xy 317.291513 -420.979452) (xy 317.291513 -420.979455) (xy 318.729023 -420.979455) (xy 318.729023 -420.924945)
			(xy 318.736781 -420.870989) (xy 318.752138 -420.818686) (xy 318.774783 -420.769101) (xy 318.804254 -420.723244)
			(xy 318.839952 -420.682047) (xy 318.881149 -420.646351) (xy 318.927006 -420.61688) (xy 318.976591 -420.594236)
			(xy 319.028894 -420.578879) (xy 319.082851 -420.571123) (xy 319.110106 -420.57066) (xy 319.973706 -420.57066)
			(xy 320.000955 -420.571211) (xy 320.054897 -420.578967) (xy 320.107187 -420.594321) (xy 320.156759 -420.616961)
			(xy 320.202605 -420.646425) (xy 320.243791 -420.682113) (xy 320.279479 -420.7233) (xy 320.308942 -420.769146)
			(xy 320.331581 -420.818719) (xy 320.346934 -420.871009) (xy 320.35469 -420.924951) (xy 320.35469 -420.979449)
			(xy 320.354689 -420.979457) (xy 321.792223 -420.979457) (xy 321.792223 -420.924943) (xy 321.799982 -420.870983)
			(xy 321.815342 -420.818677) (xy 321.837989 -420.76909) (xy 321.867464 -420.723231) (xy 321.903166 -420.682033)
			(xy 321.944367 -420.646337) (xy 321.99023 -420.616867) (xy 322.03982 -420.594225) (xy 322.092128 -420.578872)
			(xy 322.146089 -420.57112) (xy 322.173346 -420.57066) (xy 323.036946 -420.57066) (xy 323.064193 -420.571213)
			(xy 323.118131 -420.578975) (xy 323.170416 -420.594332) (xy 323.219983 -420.616974) (xy 323.265824 -420.646439)
			(xy 323.307005 -420.682128) (xy 323.342688 -420.723313) (xy 323.372148 -420.769157) (xy 323.394784 -420.818727)
			(xy 323.410135 -420.871014) (xy 323.41789 -420.924953) (xy 323.41789 -420.979447) (xy 323.417889 -420.979453)
			(xy 324.855546 -420.979453) (xy 324.855546 -420.924947) (xy 324.863303 -420.870996) (xy 324.878658 -420.818698)
			(xy 324.9013 -420.769118) (xy 324.930768 -420.723264) (xy 324.966461 -420.682071) (xy 325.007653 -420.646376)
			(xy 325.053505 -420.616907) (xy 325.103085 -420.594263) (xy 325.155382 -420.578906) (xy 325.209333 -420.571147)
			(xy 325.236586 -420.57066) (xy 326.100186 -420.57066) (xy 326.127437 -420.571186) (xy 326.181385 -420.578941)
			(xy 326.23368 -420.594295) (xy 326.283258 -420.616934) (xy 326.329109 -420.646399) (xy 326.3703 -420.68209)
			(xy 326.405992 -420.72328) (xy 326.435459 -420.76913) (xy 326.458101 -420.818707) (xy 326.473456 -420.871001)
			(xy 326.481213 -420.924949) (xy 326.481213 -420.979451) (xy 326.481212 -420.979456) (xy 327.918723 -420.979456)
			(xy 327.918723 -420.924944) (xy 327.926481 -420.870986) (xy 327.94184 -420.818681) (xy 327.964486 -420.769095)
			(xy 327.993959 -420.723237) (xy 328.029659 -420.68204) (xy 328.070858 -420.646344) (xy 328.116718 -420.616874)
			(xy 328.166306 -420.594231) (xy 328.218611 -420.578876) (xy 328.27257 -420.571121) (xy 328.299826 -420.57066)
			(xy 329.163426 -420.57066) (xy 329.190674 -420.571212) (xy 329.244614 -420.578971) (xy 329.296901 -420.594327)
			(xy 329.346471 -420.616968) (xy 329.392314 -420.646432) (xy 329.433498 -420.682121) (xy 329.469184 -420.723307)
			(xy 329.498645 -420.769152) (xy 329.521282 -420.818723) (xy 329.536635 -420.871011) (xy 329.54439 -420.924952)
			(xy 329.54439 -420.979448) (xy 329.544389 -420.979452) (xy 330.982046 -420.979452) (xy 330.982046 -420.924948)
			(xy 330.989802 -420.870999) (xy 331.005157 -420.818702) (xy 331.027797 -420.769123) (xy 331.057263 -420.723271)
			(xy 331.092954 -420.682078) (xy 331.134143 -420.646383) (xy 331.179993 -420.616914) (xy 331.22957 -420.594269)
			(xy 331.281865 -420.578909) (xy 331.335814 -420.571148) (xy 331.363066 -420.57066) (xy 332.226666 -420.57066)
			(xy 332.253918 -420.571185) (xy 332.307868 -420.578937) (xy 332.360166 -420.594289) (xy 332.409746 -420.616928)
			(xy 332.4556 -420.646392) (xy 332.496793 -420.682083) (xy 332.532487 -420.723273) (xy 332.561956 -420.769124)
			(xy 332.584599 -420.818702) (xy 332.599955 -420.870999) (xy 332.607713 -420.924948) (xy 332.607713 -420.979452)
			(xy 332.607713 -420.979455) (xy 334.045223 -420.979455) (xy 334.045223 -420.924945) (xy 334.052981 -420.870989)
			(xy 334.068338 -420.818686) (xy 334.090983 -420.769101) (xy 334.120454 -420.723244) (xy 334.156152 -420.682047)
			(xy 334.197349 -420.646351) (xy 334.243206 -420.61688) (xy 334.292791 -420.594236) (xy 334.345094 -420.578879)
			(xy 334.399051 -420.571123) (xy 334.426306 -420.57066) (xy 335.289906 -420.57066) (xy 335.317155 -420.571211)
			(xy 335.371097 -420.578967) (xy 335.423387 -420.594321) (xy 335.472959 -420.616961) (xy 335.518805 -420.646425)
			(xy 335.559991 -420.682113) (xy 335.595679 -420.7233) (xy 335.625142 -420.769146) (xy 335.647781 -420.818719)
			(xy 335.663134 -420.871009) (xy 335.67089 -420.924951) (xy 335.67089 -420.979449) (xy 335.670889 -420.979457)
			(xy 337.108423 -420.979457) (xy 337.108423 -420.924943) (xy 337.116182 -420.870983) (xy 337.131542 -420.818677)
			(xy 337.154189 -420.76909) (xy 337.183664 -420.723231) (xy 337.219366 -420.682033) (xy 337.260567 -420.646337)
			(xy 337.30643 -420.616867) (xy 337.35602 -420.594225) (xy 337.408328 -420.578872) (xy 337.462289 -420.57112)
			(xy 337.489546 -420.57066) (xy 338.353146 -420.57066) (xy 338.380393 -420.571213) (xy 338.434331 -420.578975)
			(xy 338.486616 -420.594332) (xy 338.536183 -420.616974) (xy 338.582024 -420.646439) (xy 338.623205 -420.682128)
			(xy 338.658888 -420.723313) (xy 338.688348 -420.769157) (xy 338.710984 -420.818727) (xy 338.726335 -420.871014)
			(xy 338.73409 -420.924953) (xy 338.73409 -420.979447) (xy 338.734089 -420.979453) (xy 340.171746 -420.979453)
			(xy 340.171746 -420.924947) (xy 340.179503 -420.870996) (xy 340.194858 -420.818698) (xy 340.2175 -420.769118)
			(xy 340.246968 -420.723264) (xy 340.282661 -420.682071) (xy 340.323853 -420.646376) (xy 340.369705 -420.616907)
			(xy 340.419285 -420.594263) (xy 340.471582 -420.578906) (xy 340.525533 -420.571147) (xy 340.552786 -420.57066)
			(xy 341.416386 -420.57066) (xy 341.443637 -420.571186) (xy 341.497585 -420.578941) (xy 341.54988 -420.594295)
			(xy 341.599458 -420.616934) (xy 341.645309 -420.646399) (xy 341.6865 -420.68209) (xy 341.722192 -420.72328)
			(xy 341.751659 -420.76913) (xy 341.774301 -420.818707) (xy 341.789656 -420.871001) (xy 341.797413 -420.924949)
			(xy 341.797413 -420.979451) (xy 341.797412 -420.979456) (xy 343.234923 -420.979456) (xy 343.234923 -420.924944)
			(xy 343.242681 -420.870986) (xy 343.25804 -420.818681) (xy 343.280686 -420.769095) (xy 343.310159 -420.723237)
			(xy 343.345859 -420.68204) (xy 343.387058 -420.646344) (xy 343.432918 -420.616874) (xy 343.482506 -420.594231)
			(xy 343.534811 -420.578876) (xy 343.58877 -420.571121) (xy 343.616026 -420.57066) (xy 344.479626 -420.57066)
			(xy 344.506874 -420.571212) (xy 344.560814 -420.578971) (xy 344.613101 -420.594327) (xy 344.662671 -420.616968)
			(xy 344.708514 -420.646432) (xy 344.749698 -420.682121) (xy 344.785384 -420.723307) (xy 344.814845 -420.769152)
			(xy 344.837482 -420.818723) (xy 344.852835 -420.871011) (xy 344.86059 -420.924952) (xy 344.86059 -420.979448)
			(xy 344.860589 -420.979452) (xy 346.298246 -420.979452) (xy 346.298246 -420.924948) (xy 346.306002 -420.870999)
			(xy 346.321357 -420.818702) (xy 346.343997 -420.769123) (xy 346.373463 -420.723271) (xy 346.409154 -420.682078)
			(xy 346.450343 -420.646383) (xy 346.496193 -420.616914) (xy 346.54577 -420.594269) (xy 346.598065 -420.578909)
			(xy 346.652014 -420.571148) (xy 346.679266 -420.57066) (xy 347.542866 -420.57066) (xy 347.570118 -420.571185)
			(xy 347.624068 -420.578937) (xy 347.676366 -420.594289) (xy 347.725946 -420.616928) (xy 347.7718 -420.646392)
			(xy 347.812993 -420.682083) (xy 347.848687 -420.723273) (xy 347.878156 -420.769124) (xy 347.900799 -420.818702)
			(xy 347.916155 -420.870999) (xy 347.923913 -420.924948) (xy 347.923913 -420.979452) (xy 347.923913 -420.979455)
			(xy 349.361423 -420.979455) (xy 349.361423 -420.924945) (xy 349.369181 -420.870989) (xy 349.384538 -420.818686)
			(xy 349.407183 -420.769101) (xy 349.436654 -420.723244) (xy 349.472352 -420.682047) (xy 349.513549 -420.646351)
			(xy 349.559406 -420.61688) (xy 349.608991 -420.594236) (xy 349.661294 -420.578879) (xy 349.715251 -420.571123)
			(xy 349.742506 -420.57066) (xy 350.606106 -420.57066) (xy 350.633355 -420.571211) (xy 350.687297 -420.578967)
			(xy 350.739587 -420.594321) (xy 350.789159 -420.616961) (xy 350.835005 -420.646425) (xy 350.876191 -420.682113)
			(xy 350.911879 -420.7233) (xy 350.941342 -420.769146) (xy 350.963981 -420.818719) (xy 350.979334 -420.871009)
			(xy 350.98709 -420.924951) (xy 350.98709 -420.979449) (xy 350.979334 -421.033391) (xy 350.963981 -421.085681)
			(xy 350.941342 -421.135254) (xy 350.911879 -421.1811) (xy 350.876191 -421.222287) (xy 350.835005 -421.257975)
			(xy 350.789159 -421.287439) (xy 350.739587 -421.310079) (xy 350.687297 -421.325433) (xy 350.633355 -421.333189)
			(xy 350.606106 -421.333676) (xy 349.742506 -421.333676) (xy 349.715251 -421.333277) (xy 349.661294 -421.325521)
			(xy 349.608991 -421.310164) (xy 349.559406 -421.28752) (xy 349.513549 -421.258049) (xy 349.472352 -421.222353)
			(xy 349.436654 -421.181156) (xy 349.407183 -421.135299) (xy 349.384538 -421.085714) (xy 349.369181 -421.033411)
			(xy 349.361423 -420.979455) (xy 347.923913 -420.979455) (xy 347.916155 -421.033402) (xy 347.900799 -421.085698)
			(xy 347.878156 -421.135276) (xy 347.848687 -421.181127) (xy 347.812993 -421.222317) (xy 347.7718 -421.258008)
			(xy 347.725946 -421.287472) (xy 347.676366 -421.310111) (xy 347.624068 -421.325463) (xy 347.570118 -421.333215)
			(xy 347.542866 -421.333676) (xy 346.679266 -421.333676) (xy 346.652014 -421.333252) (xy 346.598065 -421.325491)
			(xy 346.54577 -421.310131) (xy 346.496193 -421.287486) (xy 346.450343 -421.258017) (xy 346.409154 -421.222322)
			(xy 346.373463 -421.181129) (xy 346.343997 -421.135277) (xy 346.321357 -421.085698) (xy 346.306002 -421.033401)
			(xy 346.298246 -420.979452) (xy 344.860589 -420.979452) (xy 344.852835 -421.033389) (xy 344.837482 -421.085677)
			(xy 344.814845 -421.135248) (xy 344.785384 -421.181093) (xy 344.749698 -421.222279) (xy 344.708514 -421.257968)
			(xy 344.662671 -421.287432) (xy 344.613101 -421.310073) (xy 344.560814 -421.325429) (xy 344.506874 -421.333188)
			(xy 344.479626 -421.333676) (xy 343.616026 -421.333676) (xy 343.58877 -421.333279) (xy 343.534811 -421.325524)
			(xy 343.482506 -421.310169) (xy 343.432918 -421.287526) (xy 343.387058 -421.258056) (xy 343.345859 -421.22236)
			(xy 343.310159 -421.181163) (xy 343.280686 -421.135305) (xy 343.25804 -421.085719) (xy 343.242681 -421.033414)
			(xy 343.234923 -420.979456) (xy 341.797412 -420.979456) (xy 341.789656 -421.033399) (xy 341.774301 -421.085693)
			(xy 341.751659 -421.13527) (xy 341.722192 -421.18112) (xy 341.6865 -421.22231) (xy 341.645309 -421.258001)
			(xy 341.599458 -421.287466) (xy 341.54988 -421.310105) (xy 341.497585 -421.325459) (xy 341.443637 -421.333214)
			(xy 341.416386 -421.333676) (xy 340.552786 -421.333676) (xy 340.525533 -421.333253) (xy 340.471582 -421.325494)
			(xy 340.419285 -421.310137) (xy 340.369705 -421.287493) (xy 340.323853 -421.258024) (xy 340.282661 -421.222329)
			(xy 340.246968 -421.181136) (xy 340.2175 -421.135282) (xy 340.194858 -421.085702) (xy 340.179503 -421.033404)
			(xy 340.171746 -420.979453) (xy 338.734089 -420.979453) (xy 338.726335 -421.033386) (xy 338.710984 -421.085673)
			(xy 338.688348 -421.135243) (xy 338.658888 -421.181087) (xy 338.623205 -421.222272) (xy 338.582024 -421.257961)
			(xy 338.536183 -421.287426) (xy 338.486616 -421.310068) (xy 338.434331 -421.325425) (xy 338.380393 -421.333187)
			(xy 338.353146 -421.333676) (xy 337.489546 -421.333676) (xy 337.462289 -421.33328) (xy 337.408328 -421.325528)
			(xy 337.35602 -421.310175) (xy 337.30643 -421.287533) (xy 337.260567 -421.258063) (xy 337.219366 -421.222367)
			(xy 337.183664 -421.181169) (xy 337.154189 -421.13531) (xy 337.131542 -421.085723) (xy 337.116182 -421.033417)
			(xy 337.108423 -420.979457) (xy 335.670889 -420.979457) (xy 335.663134 -421.033391) (xy 335.647781 -421.085681)
			(xy 335.625142 -421.135254) (xy 335.595679 -421.1811) (xy 335.559991 -421.222287) (xy 335.518805 -421.257975)
			(xy 335.472959 -421.287439) (xy 335.423387 -421.310079) (xy 335.371097 -421.325433) (xy 335.317155 -421.333189)
			(xy 335.289906 -421.333676) (xy 334.426306 -421.333676) (xy 334.399051 -421.333277) (xy 334.345094 -421.325521)
			(xy 334.292791 -421.310164) (xy 334.243206 -421.28752) (xy 334.197349 -421.258049) (xy 334.156152 -421.222353)
			(xy 334.120454 -421.181156) (xy 334.090983 -421.135299) (xy 334.068338 -421.085714) (xy 334.052981 -421.033411)
			(xy 334.045223 -420.979455) (xy 332.607713 -420.979455) (xy 332.599955 -421.033402) (xy 332.584599 -421.085698)
			(xy 332.561956 -421.135276) (xy 332.532487 -421.181127) (xy 332.496793 -421.222317) (xy 332.4556 -421.258008)
			(xy 332.409746 -421.287472) (xy 332.360166 -421.310111) (xy 332.307868 -421.325463) (xy 332.253918 -421.333215)
			(xy 332.226666 -421.333676) (xy 331.363066 -421.333676) (xy 331.335814 -421.333252) (xy 331.281865 -421.325491)
			(xy 331.22957 -421.310131) (xy 331.179993 -421.287486) (xy 331.134143 -421.258017) (xy 331.092954 -421.222322)
			(xy 331.057263 -421.181129) (xy 331.027797 -421.135277) (xy 331.005157 -421.085698) (xy 330.989802 -421.033401)
			(xy 330.982046 -420.979452) (xy 329.544389 -420.979452) (xy 329.536635 -421.033389) (xy 329.521282 -421.085677)
			(xy 329.498645 -421.135248) (xy 329.469184 -421.181093) (xy 329.433498 -421.222279) (xy 329.392314 -421.257968)
			(xy 329.346471 -421.287432) (xy 329.296901 -421.310073) (xy 329.244614 -421.325429) (xy 329.190674 -421.333188)
			(xy 329.163426 -421.333676) (xy 328.299826 -421.333676) (xy 328.27257 -421.333279) (xy 328.218611 -421.325524)
			(xy 328.166306 -421.310169) (xy 328.116718 -421.287526) (xy 328.070858 -421.258056) (xy 328.029659 -421.22236)
			(xy 327.993959 -421.181163) (xy 327.964486 -421.135305) (xy 327.94184 -421.085719) (xy 327.926481 -421.033414)
			(xy 327.918723 -420.979456) (xy 326.481212 -420.979456) (xy 326.473456 -421.033399) (xy 326.458101 -421.085693)
			(xy 326.435459 -421.13527) (xy 326.405992 -421.18112) (xy 326.3703 -421.22231) (xy 326.329109 -421.258001)
			(xy 326.283258 -421.287466) (xy 326.23368 -421.310105) (xy 326.181385 -421.325459) (xy 326.127437 -421.333214)
			(xy 326.100186 -421.333676) (xy 325.236586 -421.333676) (xy 325.209333 -421.333253) (xy 325.155382 -421.325494)
			(xy 325.103085 -421.310137) (xy 325.053505 -421.287493) (xy 325.007653 -421.258024) (xy 324.966461 -421.222329)
			(xy 324.930768 -421.181136) (xy 324.9013 -421.135282) (xy 324.878658 -421.085702) (xy 324.863303 -421.033404)
			(xy 324.855546 -420.979453) (xy 323.417889 -420.979453) (xy 323.410135 -421.033386) (xy 323.394784 -421.085673)
			(xy 323.372148 -421.135243) (xy 323.342688 -421.181087) (xy 323.307005 -421.222272) (xy 323.265824 -421.257961)
			(xy 323.219983 -421.287426) (xy 323.170416 -421.310068) (xy 323.118131 -421.325425) (xy 323.064193 -421.333187)
			(xy 323.036946 -421.333676) (xy 322.173346 -421.333676) (xy 322.146089 -421.33328) (xy 322.092128 -421.325528)
			(xy 322.03982 -421.310175) (xy 321.99023 -421.287533) (xy 321.944367 -421.258063) (xy 321.903166 -421.222367)
			(xy 321.867464 -421.181169) (xy 321.837989 -421.13531) (xy 321.815342 -421.085723) (xy 321.799982 -421.033417)
			(xy 321.792223 -420.979457) (xy 320.354689 -420.979457) (xy 320.346934 -421.033391) (xy 320.331581 -421.085681)
			(xy 320.308942 -421.135254) (xy 320.279479 -421.1811) (xy 320.243791 -421.222287) (xy 320.202605 -421.257975)
			(xy 320.156759 -421.287439) (xy 320.107187 -421.310079) (xy 320.054897 -421.325433) (xy 320.000955 -421.333189)
			(xy 319.973706 -421.333676) (xy 319.110106 -421.333676) (xy 319.082851 -421.333277) (xy 319.028894 -421.325521)
			(xy 318.976591 -421.310164) (xy 318.927006 -421.28752) (xy 318.881149 -421.258049) (xy 318.839952 -421.222353)
			(xy 318.804254 -421.181156) (xy 318.774783 -421.135299) (xy 318.752138 -421.085714) (xy 318.736781 -421.033411)
			(xy 318.729023 -420.979455) (xy 317.291513 -420.979455) (xy 317.283755 -421.033402) (xy 317.268399 -421.085698)
			(xy 317.245756 -421.135276) (xy 317.216287 -421.181127) (xy 317.180593 -421.222317) (xy 317.1394 -421.258008)
			(xy 317.093546 -421.287472) (xy 317.043966 -421.310111) (xy 316.991668 -421.325463) (xy 316.937718 -421.333215)
			(xy 316.910466 -421.333676) (xy 316.046866 -421.333676) (xy 316.019614 -421.333252) (xy 315.965665 -421.325491)
			(xy 315.91337 -421.310131) (xy 315.863793 -421.287486) (xy 315.817943 -421.258017) (xy 315.776754 -421.222322)
			(xy 315.741063 -421.181129) (xy 315.711597 -421.135277) (xy 315.688957 -421.085698) (xy 315.673602 -421.033401)
			(xy 315.665846 -420.979452) (xy 314.228189 -420.979452) (xy 314.220435 -421.033389) (xy 314.205082 -421.085677)
			(xy 314.182445 -421.135248) (xy 314.152984 -421.181093) (xy 314.117298 -421.222279) (xy 314.076114 -421.257968)
			(xy 314.030271 -421.287432) (xy 313.980701 -421.310073) (xy 313.928414 -421.325429) (xy 313.874474 -421.333188)
			(xy 313.847226 -421.333676) (xy 312.983626 -421.333676) (xy 312.95637 -421.333279) (xy 312.902411 -421.325524)
			(xy 312.850106 -421.310169) (xy 312.800518 -421.287526) (xy 312.754658 -421.258056) (xy 312.713459 -421.22236)
			(xy 312.677759 -421.181163) (xy 312.648286 -421.135305) (xy 312.62564 -421.085719) (xy 312.610281 -421.033414)
			(xy 312.602523 -420.979456) (xy 311.165012 -420.979456) (xy 311.157256 -421.033399) (xy 311.141901 -421.085693)
			(xy 311.119259 -421.13527) (xy 311.089792 -421.18112) (xy 311.0541 -421.22231) (xy 311.012909 -421.258001)
			(xy 310.967058 -421.287466) (xy 310.91748 -421.310105) (xy 310.865185 -421.325459) (xy 310.811237 -421.333214)
			(xy 310.783986 -421.333676) (xy 309.920386 -421.333676) (xy 309.893133 -421.333253) (xy 309.839182 -421.325494)
			(xy 309.786885 -421.310137) (xy 309.737305 -421.287493) (xy 309.691453 -421.258024) (xy 309.650261 -421.222329)
			(xy 309.614568 -421.181136) (xy 309.5851 -421.135282) (xy 309.562458 -421.085702) (xy 309.547103 -421.033404)
			(xy 309.539346 -420.979453) (xy 308.101689 -420.979453) (xy 308.093935 -421.033386) (xy 308.078584 -421.085673)
			(xy 308.055948 -421.135243) (xy 308.026488 -421.181087) (xy 307.990805 -421.222272) (xy 307.949624 -421.257961)
			(xy 307.903783 -421.287426) (xy 307.854216 -421.310068) (xy 307.801931 -421.325425) (xy 307.747993 -421.333187)
			(xy 307.720746 -421.333676) (xy 306.857146 -421.333676) (xy 306.829889 -421.33328) (xy 306.775928 -421.325528)
			(xy 306.72362 -421.310175) (xy 306.67403 -421.287533) (xy 306.628167 -421.258063) (xy 306.586966 -421.222367)
			(xy 306.551264 -421.181169) (xy 306.521789 -421.13531) (xy 306.499142 -421.085723) (xy 306.483782 -421.033417)
			(xy 306.476023 -420.979457) (xy 305.038489 -420.979457) (xy 305.030734 -421.033391) (xy 305.015381 -421.085681)
			(xy 304.992742 -421.135254) (xy 304.963279 -421.1811) (xy 304.927591 -421.222287) (xy 304.886405 -421.257975)
			(xy 304.840559 -421.287439) (xy 304.790987 -421.310079) (xy 304.738697 -421.325433) (xy 304.684755 -421.333189)
			(xy 304.657506 -421.333676) (xy 303.793906 -421.333676) (xy 303.766651 -421.333277) (xy 303.712694 -421.325521)
			(xy 303.660391 -421.310164) (xy 303.610806 -421.28752) (xy 303.564949 -421.258049) (xy 303.523752 -421.222353)
			(xy 303.488054 -421.181156) (xy 303.458583 -421.135299) (xy 303.435938 -421.085714) (xy 303.420581 -421.033411)
			(xy 303.412823 -420.979455) (xy 231.647383 -420.979455) (xy 230.329486 -422.297352) (xy 230.322673 -422.304773)
			(xy 230.314938 -422.323356) (xy 230.3145 -422.33342) (xy 230.3145 -422.354375) (xy 285.567772 -422.354375)
			(xy 285.567772 -422.299825) (xy 285.575535 -422.245831) (xy 285.590905 -422.193491) (xy 285.613567 -422.143872)
			(xy 285.64306 -422.097983) (xy 285.678784 -422.056759) (xy 285.720012 -422.021038) (xy 285.765903 -421.991549)
			(xy 285.815525 -421.968892) (xy 285.867866 -421.953528) (xy 285.921861 -421.945769) (xy 285.949136 -421.945308)
			(xy 286.812736 -421.945308) (xy 286.840002 -421.945857) (xy 286.893977 -421.953622) (xy 286.946298 -421.968989)
			(xy 286.9959 -421.991646) (xy 287.041773 -422.02113) (xy 287.082983 -422.056843) (xy 287.118691 -422.098056)
			(xy 287.148172 -422.143932) (xy 287.170823 -422.193536) (xy 287.186186 -422.245858) (xy 287.193946 -422.299834)
			(xy 287.193946 -422.354366) (xy 287.186186 -422.408342) (xy 287.170823 -422.460664) (xy 287.148172 -422.510268)
			(xy 287.118691 -422.556144) (xy 287.082983 -422.597357) (xy 287.041773 -422.63307) (xy 286.9959 -422.662554)
			(xy 286.946298 -422.685211) (xy 286.893977 -422.700578) (xy 286.840002 -422.708343) (xy 286.812736 -422.708832)
			(xy 285.949136 -422.708832) (xy 285.921861 -422.708431) (xy 285.867866 -422.700672) (xy 285.815525 -422.685308)
			(xy 285.765903 -422.662651) (xy 285.720012 -422.633162) (xy 285.678784 -422.597441) (xy 285.64306 -422.556217)
			(xy 285.613567 -422.510328) (xy 285.590905 -422.460709) (xy 285.575535 -422.408369) (xy 285.567772 -422.354375)
			(xy 230.3145 -422.354375) (xy 230.3145 -424.80464) (xy 357.679233 -424.80464) (xy 357.679233 -424.6755)
			(xy 357.687183 -424.546605) (xy 357.703053 -424.418445) (xy 357.726782 -424.291504) (xy 357.758281 -424.166265)
			(xy 357.79743 -424.043202) (xy 357.844081 -423.922783) (xy 357.898056 -423.805464) (xy 357.959151 -423.69169)
			(xy 358.027134 -423.581893) (xy 358.101748 -423.47649) (xy 358.182709 -423.37588) (xy 358.269709 -423.280445)
			(xy 358.36242 -423.190546) (xy 358.46049 -423.106525) (xy 358.563545 -423.028701) (xy 358.671196 -422.957369)
			(xy 358.783035 -422.892799) (xy 358.898636 -422.835237) (xy 359.017561 -422.7849) (xy 359.13936 -422.74198)
			(xy 359.26357 -422.706639) (xy 359.389719 -422.679012) (xy 359.517331 -422.659203) (xy 359.64592 -422.647287)
			(xy 359.774998 -422.643311) (xy 359.904076 -422.647287) (xy 360.032665 -422.659203) (xy 360.160277 -422.679012)
			(xy 360.222212 -422.692576) (xy 365.310928 -422.692576) (xy 365.310928 -415.898584) (xy 365.3113 -415.888356)
			(xy 365.319137 -415.86946) (xy 365.33361 -415.855003) (xy 365.352515 -415.847188) (xy 365.362744 -415.846768)
			(xy 370.261388 -415.846768) (xy 370.271593 -415.847291) (xy 370.290451 -415.855097) (xy 370.304887 -415.869525)
			(xy 370.312703 -415.888379) (xy 370.313204 -415.898584) (xy 370.313204 -418.439456) (xy 372.044623 -418.439456)
			(xy 372.044623 -418.384944) (xy 372.052381 -418.330986) (xy 372.06774 -418.278682) (xy 372.090386 -418.229097)
			(xy 372.119858 -418.183238) (xy 372.155557 -418.142042) (xy 372.196756 -418.106345) (xy 372.242616 -418.076875)
			(xy 372.292203 -418.054232) (xy 372.344508 -418.038877) (xy 372.398466 -418.031121) (xy 372.425722 -418.03066)
			(xy 373.289322 -418.03066) (xy 373.31657 -418.031212) (xy 373.370511 -418.03897) (xy 373.422798 -418.054326)
			(xy 373.472369 -418.076966) (xy 373.518212 -418.106431) (xy 373.559396 -418.142119) (xy 373.595083 -418.183305)
			(xy 373.624544 -418.229151) (xy 373.647182 -418.278722) (xy 373.662535 -418.331011) (xy 373.67029 -418.384952)
			(xy 373.67029 -418.439448) (xy 373.670289 -418.439452) (xy 375.107946 -418.439452) (xy 375.107946 -418.384948)
			(xy 375.115702 -418.330999) (xy 375.131056 -418.278703) (xy 375.153697 -418.229124) (xy 375.183162 -418.183272)
			(xy 375.218852 -418.142079) (xy 375.260041 -418.106385) (xy 375.305891 -418.076915) (xy 375.355468 -418.05427)
			(xy 375.407762 -418.03891) (xy 375.46171 -418.031148) (xy 375.488962 -418.03066) (xy 376.352562 -418.03066)
			(xy 376.379814 -418.031185) (xy 376.433765 -418.038937) (xy 376.486063 -418.054288) (xy 376.535644 -418.076926)
			(xy 376.581498 -418.106391) (xy 376.622691 -418.142082) (xy 376.658386 -418.183272) (xy 376.687855 -418.229123)
			(xy 376.710499 -418.278701) (xy 376.725855 -418.330998) (xy 376.733613 -418.384948) (xy 376.733613 -418.439452)
			(xy 376.733613 -418.439455) (xy 378.171123 -418.439455) (xy 378.171123 -418.384945) (xy 378.178881 -418.330989)
			(xy 378.194238 -418.278687) (xy 378.216883 -418.229102) (xy 378.246353 -418.183245) (xy 378.28205 -418.142049)
			(xy 378.323247 -418.106352) (xy 378.369104 -418.076882) (xy 378.418688 -418.054237) (xy 378.470991 -418.03888)
			(xy 378.524947 -418.031123) (xy 378.552202 -418.03066) (xy 379.415802 -418.03066) (xy 379.443051 -418.03121)
			(xy 379.496994 -418.038966) (xy 379.549284 -418.05432) (xy 379.598857 -418.07696) (xy 379.644703 -418.106424)
			(xy 379.685889 -418.142112) (xy 379.721578 -418.183299) (xy 379.751041 -418.229145) (xy 379.77368 -418.278718)
			(xy 379.789034 -418.331008) (xy 379.79679 -418.384951) (xy 379.79679 -418.439449) (xy 379.796789 -418.439457)
			(xy 381.234323 -418.439457) (xy 381.234323 -418.384943) (xy 381.242082 -418.330984) (xy 381.257441 -418.278678)
			(xy 381.280089 -418.229091) (xy 381.309563 -418.183232) (xy 381.345264 -418.142035) (xy 381.386466 -418.106338)
			(xy 381.432328 -418.076869) (xy 381.481917 -418.054227) (xy 381.534225 -418.038873) (xy 381.588185 -418.03112)
			(xy 381.615442 -418.03066) (xy 382.479042 -418.03066) (xy 382.506289 -418.031213) (xy 382.560228 -418.038974)
			(xy 382.612513 -418.054331) (xy 382.662081 -418.076973) (xy 382.707922 -418.106438) (xy 382.749103 -418.142126)
			(xy 382.784787 -418.183312) (xy 382.814247 -418.229156) (xy 382.836883 -418.278727) (xy 382.852235 -418.331014)
			(xy 382.85999 -418.384953) (xy 382.85999 -418.439447) (xy 382.859989 -418.439453) (xy 384.297646 -418.439453)
			(xy 384.297646 -418.384947) (xy 384.305403 -418.330997) (xy 384.320758 -418.278699) (xy 384.3434 -418.229119)
			(xy 384.372867 -418.183265) (xy 384.408559 -418.142072) (xy 384.449751 -418.106378) (xy 384.495603 -418.076908)
			(xy 384.545182 -418.054264) (xy 384.597479 -418.038906) (xy 384.651429 -418.031147) (xy 384.678682 -418.03066)
			(xy 385.542282 -418.03066) (xy 385.569533 -418.031186) (xy 385.623482 -418.03894) (xy 385.675777 -418.054293)
			(xy 385.725356 -418.076933) (xy 385.771207 -418.106398) (xy 385.812399 -418.142089) (xy 385.848091 -418.183278)
			(xy 385.877558 -418.229129) (xy 385.9002 -418.278706) (xy 385.915556 -418.331001) (xy 385.923313 -418.384949)
			(xy 385.923313 -418.439451) (xy 385.923312 -418.439456) (xy 387.360823 -418.439456) (xy 387.360823 -418.384944)
			(xy 387.368581 -418.330986) (xy 387.38394 -418.278682) (xy 387.406586 -418.229097) (xy 387.436058 -418.183238)
			(xy 387.471757 -418.142042) (xy 387.512956 -418.106345) (xy 387.558816 -418.076875) (xy 387.608403 -418.054232)
			(xy 387.660708 -418.038877) (xy 387.714666 -418.031121) (xy 387.741922 -418.03066) (xy 388.605522 -418.03066)
			(xy 388.63277 -418.031212) (xy 388.686711 -418.03897) (xy 388.738998 -418.054326) (xy 388.788569 -418.076966)
			(xy 388.834412 -418.106431) (xy 388.875596 -418.142119) (xy 388.911283 -418.183305) (xy 388.940744 -418.229151)
			(xy 388.963382 -418.278722) (xy 388.978735 -418.331011) (xy 388.98649 -418.384952) (xy 388.98649 -418.439448)
			(xy 388.986489 -418.439452) (xy 390.424146 -418.439452) (xy 390.424146 -418.384948) (xy 390.431902 -418.330999)
			(xy 390.447256 -418.278703) (xy 390.469897 -418.229124) (xy 390.499362 -418.183272) (xy 390.535052 -418.142079)
			(xy 390.576241 -418.106385) (xy 390.622091 -418.076915) (xy 390.671668 -418.05427) (xy 390.723962 -418.03891)
			(xy 390.77791 -418.031148) (xy 390.805162 -418.03066) (xy 391.668762 -418.03066) (xy 391.696014 -418.031185)
			(xy 391.749965 -418.038937) (xy 391.802263 -418.054288) (xy 391.851844 -418.076926) (xy 391.897698 -418.106391)
			(xy 391.938891 -418.142082) (xy 391.974586 -418.183272) (xy 392.004055 -418.229123) (xy 392.026699 -418.278701)
			(xy 392.042055 -418.330998) (xy 392.049813 -418.384948) (xy 392.049813 -418.439452) (xy 392.049813 -418.439455)
			(xy 393.487323 -418.439455) (xy 393.487323 -418.384945) (xy 393.495081 -418.330989) (xy 393.510438 -418.278687)
			(xy 393.533083 -418.229102) (xy 393.562553 -418.183245) (xy 393.59825 -418.142049) (xy 393.639447 -418.106352)
			(xy 393.685304 -418.076882) (xy 393.734888 -418.054237) (xy 393.787191 -418.03888) (xy 393.841147 -418.031123)
			(xy 393.868402 -418.03066) (xy 394.732002 -418.03066) (xy 394.759251 -418.03121) (xy 394.813194 -418.038966)
			(xy 394.865484 -418.05432) (xy 394.915057 -418.07696) (xy 394.960903 -418.106424) (xy 395.002089 -418.142112)
			(xy 395.037778 -418.183299) (xy 395.067241 -418.229145) (xy 395.08988 -418.278718) (xy 395.105234 -418.331008)
			(xy 395.11299 -418.384951) (xy 395.11299 -418.439449) (xy 395.112989 -418.439457) (xy 396.550523 -418.439457)
			(xy 396.550523 -418.384943) (xy 396.558282 -418.330984) (xy 396.573641 -418.278678) (xy 396.596289 -418.229091)
			(xy 396.625763 -418.183232) (xy 396.661464 -418.142035) (xy 396.702666 -418.106338) (xy 396.748528 -418.076869)
			(xy 396.798117 -418.054227) (xy 396.850425 -418.038873) (xy 396.904385 -418.03112) (xy 396.931642 -418.03066)
			(xy 397.795242 -418.03066) (xy 397.822489 -418.031213) (xy 397.876428 -418.038974) (xy 397.928713 -418.054331)
			(xy 397.978281 -418.076973) (xy 398.024122 -418.106438) (xy 398.065303 -418.142126) (xy 398.100987 -418.183312)
			(xy 398.130447 -418.229156) (xy 398.153083 -418.278727) (xy 398.168435 -418.331014) (xy 398.17619 -418.384953)
			(xy 398.17619 -418.439447) (xy 398.176189 -418.439453) (xy 399.613846 -418.439453) (xy 399.613846 -418.384947)
			(xy 399.621603 -418.330997) (xy 399.636958 -418.278699) (xy 399.6596 -418.229119) (xy 399.689067 -418.183265)
			(xy 399.724759 -418.142072) (xy 399.765951 -418.106378) (xy 399.811803 -418.076908) (xy 399.861382 -418.054264)
			(xy 399.913679 -418.038906) (xy 399.967629 -418.031147) (xy 399.994882 -418.03066) (xy 400.858482 -418.03066)
			(xy 400.885733 -418.031186) (xy 400.939682 -418.03894) (xy 400.991977 -418.054293) (xy 401.041556 -418.076933)
			(xy 401.087407 -418.106398) (xy 401.128599 -418.142089) (xy 401.164291 -418.183278) (xy 401.193758 -418.229129)
			(xy 401.2164 -418.278706) (xy 401.231756 -418.331001) (xy 401.239513 -418.384949) (xy 401.239513 -418.439451)
			(xy 401.239512 -418.439456) (xy 402.677023 -418.439456) (xy 402.677023 -418.384944) (xy 402.684781 -418.330986)
			(xy 402.70014 -418.278682) (xy 402.722786 -418.229097) (xy 402.752258 -418.183238) (xy 402.787957 -418.142042)
			(xy 402.829156 -418.106345) (xy 402.875016 -418.076875) (xy 402.924603 -418.054232) (xy 402.976908 -418.038877)
			(xy 403.030866 -418.031121) (xy 403.058122 -418.03066) (xy 403.921722 -418.03066) (xy 403.94897 -418.031212)
			(xy 404.002911 -418.03897) (xy 404.055198 -418.054326) (xy 404.104769 -418.076966) (xy 404.150612 -418.106431)
			(xy 404.191796 -418.142119) (xy 404.227483 -418.183305) (xy 404.256944 -418.229151) (xy 404.279582 -418.278722)
			(xy 404.294935 -418.331011) (xy 404.30269 -418.384952) (xy 404.30269 -418.439448) (xy 404.302689 -418.439452)
			(xy 405.740346 -418.439452) (xy 405.740346 -418.384948) (xy 405.748102 -418.330999) (xy 405.763456 -418.278703)
			(xy 405.786097 -418.229124) (xy 405.815562 -418.183272) (xy 405.851252 -418.142079) (xy 405.892441 -418.106385)
			(xy 405.938291 -418.076915) (xy 405.987868 -418.05427) (xy 406.040162 -418.03891) (xy 406.09411 -418.031148)
			(xy 406.121362 -418.03066) (xy 406.984962 -418.03066) (xy 407.012214 -418.031185) (xy 407.066165 -418.038937)
			(xy 407.118463 -418.054288) (xy 407.168044 -418.076926) (xy 407.213898 -418.106391) (xy 407.255091 -418.142082)
			(xy 407.290786 -418.183272) (xy 407.320255 -418.229123) (xy 407.342899 -418.278701) (xy 407.358255 -418.330998)
			(xy 407.366013 -418.384948) (xy 407.366013 -418.439452) (xy 407.366013 -418.439455) (xy 408.803523 -418.439455)
			(xy 408.803523 -418.384945) (xy 408.811281 -418.330989) (xy 408.826638 -418.278687) (xy 408.849283 -418.229102)
			(xy 408.878753 -418.183245) (xy 408.91445 -418.142049) (xy 408.955647 -418.106352) (xy 409.001504 -418.076882)
			(xy 409.051088 -418.054237) (xy 409.103391 -418.03888) (xy 409.157347 -418.031123) (xy 409.184602 -418.03066)
			(xy 410.048202 -418.03066) (xy 410.075451 -418.03121) (xy 410.129394 -418.038966) (xy 410.181684 -418.05432)
			(xy 410.231257 -418.07696) (xy 410.277103 -418.106424) (xy 410.318289 -418.142112) (xy 410.353978 -418.183299)
			(xy 410.383441 -418.229145) (xy 410.40608 -418.278718) (xy 410.421434 -418.331008) (xy 410.42919 -418.384951)
			(xy 410.42919 -418.439449) (xy 410.429189 -418.439457) (xy 411.866723 -418.439457) (xy 411.866723 -418.384943)
			(xy 411.874482 -418.330984) (xy 411.889841 -418.278678) (xy 411.912489 -418.229091) (xy 411.941963 -418.183232)
			(xy 411.977664 -418.142035) (xy 412.018866 -418.106338) (xy 412.064728 -418.076869) (xy 412.114317 -418.054227)
			(xy 412.166625 -418.038873) (xy 412.220585 -418.03112) (xy 412.247842 -418.03066) (xy 413.111442 -418.03066)
			(xy 413.138689 -418.031213) (xy 413.192628 -418.038974) (xy 413.244913 -418.054331) (xy 413.294481 -418.076973)
			(xy 413.340322 -418.106438) (xy 413.381503 -418.142126) (xy 413.417187 -418.183312) (xy 413.446647 -418.229156)
			(xy 413.469283 -418.278727) (xy 413.484635 -418.331014) (xy 413.49239 -418.384953) (xy 413.49239 -418.439447)
			(xy 413.492389 -418.439453) (xy 414.930046 -418.439453) (xy 414.930046 -418.384947) (xy 414.937803 -418.330997)
			(xy 414.953158 -418.278699) (xy 414.9758 -418.229119) (xy 415.005267 -418.183265) (xy 415.040959 -418.142072)
			(xy 415.082151 -418.106378) (xy 415.128003 -418.076908) (xy 415.177582 -418.054264) (xy 415.229879 -418.038906)
			(xy 415.283829 -418.031147) (xy 415.311082 -418.03066) (xy 416.174682 -418.03066) (xy 416.201933 -418.031186)
			(xy 416.255882 -418.03894) (xy 416.308177 -418.054293) (xy 416.357756 -418.076933) (xy 416.403607 -418.106398)
			(xy 416.444799 -418.142089) (xy 416.480491 -418.183278) (xy 416.509958 -418.229129) (xy 416.5326 -418.278706)
			(xy 416.547956 -418.331001) (xy 416.555713 -418.384949) (xy 416.555713 -418.439451) (xy 416.555712 -418.439456)
			(xy 417.993223 -418.439456) (xy 417.993223 -418.384944) (xy 418.000981 -418.330986) (xy 418.01634 -418.278682)
			(xy 418.038986 -418.229097) (xy 418.068458 -418.183238) (xy 418.104157 -418.142042) (xy 418.145356 -418.106345)
			(xy 418.191216 -418.076875) (xy 418.240803 -418.054232) (xy 418.293108 -418.038877) (xy 418.347066 -418.031121)
			(xy 418.374322 -418.03066) (xy 419.237922 -418.03066) (xy 419.26517 -418.031212) (xy 419.319111 -418.03897)
			(xy 419.371398 -418.054326) (xy 419.420969 -418.076966) (xy 419.466812 -418.106431) (xy 419.507996 -418.142119)
			(xy 419.543683 -418.183305) (xy 419.573144 -418.229151) (xy 419.595782 -418.278722) (xy 419.611135 -418.331011)
			(xy 419.61889 -418.384952) (xy 419.61889 -418.439448) (xy 419.611135 -418.493389) (xy 419.595782 -418.545678)
			(xy 419.573144 -418.595249) (xy 419.543683 -418.641095) (xy 419.507996 -418.682281) (xy 419.466812 -418.717969)
			(xy 419.420969 -418.747434) (xy 419.371398 -418.770074) (xy 419.319111 -418.78543) (xy 419.26517 -418.793188)
			(xy 419.237922 -418.793676) (xy 418.374322 -418.793676) (xy 418.347066 -418.793279) (xy 418.293108 -418.785523)
			(xy 418.240803 -418.770168) (xy 418.191216 -418.747525) (xy 418.145356 -418.718055) (xy 418.104157 -418.682358)
			(xy 418.068458 -418.641162) (xy 418.038986 -418.595303) (xy 418.01634 -418.545718) (xy 418.000981 -418.493414)
			(xy 417.993223 -418.439456) (xy 416.555712 -418.439456) (xy 416.547956 -418.493399) (xy 416.5326 -418.545694)
			(xy 416.509958 -418.595271) (xy 416.480491 -418.641122) (xy 416.444799 -418.682311) (xy 416.403607 -418.718002)
			(xy 416.357756 -418.747467) (xy 416.308177 -418.770107) (xy 416.255882 -418.78546) (xy 416.201933 -418.793214)
			(xy 416.174682 -418.793676) (xy 415.311082 -418.793676) (xy 415.283829 -418.793253) (xy 415.229879 -418.785494)
			(xy 415.177582 -418.770136) (xy 415.128003 -418.747492) (xy 415.082151 -418.718022) (xy 415.040959 -418.682328)
			(xy 415.005267 -418.641135) (xy 414.9758 -418.595281) (xy 414.953158 -418.545701) (xy 414.937803 -418.493403)
			(xy 414.930046 -418.439453) (xy 413.492389 -418.439453) (xy 413.484635 -418.493386) (xy 413.469283 -418.545673)
			(xy 413.446647 -418.595244) (xy 413.417187 -418.641088) (xy 413.381503 -418.682274) (xy 413.340322 -418.717962)
			(xy 413.294481 -418.747427) (xy 413.244913 -418.770069) (xy 413.192628 -418.785426) (xy 413.138689 -418.793187)
			(xy 413.111442 -418.793676) (xy 412.247842 -418.793676) (xy 412.220585 -418.79328) (xy 412.166625 -418.785527)
			(xy 412.114317 -418.770173) (xy 412.064728 -418.747531) (xy 412.018866 -418.718062) (xy 411.977664 -418.682365)
			(xy 411.941963 -418.641168) (xy 411.912489 -418.595309) (xy 411.889841 -418.545722) (xy 411.874482 -418.493416)
			(xy 411.866723 -418.439457) (xy 410.429189 -418.439457) (xy 410.421434 -418.493392) (xy 410.40608 -418.545682)
			(xy 410.383441 -418.595255) (xy 410.353978 -418.641101) (xy 410.318289 -418.682288) (xy 410.277103 -418.717976)
			(xy 410.231257 -418.74744) (xy 410.181684 -418.77008) (xy 410.129394 -418.785434) (xy 410.075451 -418.79319)
			(xy 410.048202 -418.793676) (xy 409.184602 -418.793676) (xy 409.157347 -418.793277) (xy 409.103391 -418.78552)
			(xy 409.051088 -418.770163) (xy 409.001504 -418.747518) (xy 408.955647 -418.718048) (xy 408.91445 -418.682351)
			(xy 408.878753 -418.641155) (xy 408.849283 -418.595298) (xy 408.826638 -418.545713) (xy 408.811281 -418.493411)
			(xy 408.803523 -418.439455) (xy 407.366013 -418.439455) (xy 407.358255 -418.493402) (xy 407.342899 -418.545699)
			(xy 407.320255 -418.595277) (xy 407.290786 -418.641128) (xy 407.255091 -418.682318) (xy 407.213898 -418.718009)
			(xy 407.168044 -418.747474) (xy 407.118463 -418.770112) (xy 407.066165 -418.785463) (xy 407.012214 -418.793215)
			(xy 406.984962 -418.793676) (xy 406.121362 -418.793676) (xy 406.09411 -418.793252) (xy 406.040162 -418.78549)
			(xy 405.987868 -418.77013) (xy 405.938291 -418.747485) (xy 405.892441 -418.718015) (xy 405.851252 -418.682321)
			(xy 405.815562 -418.641128) (xy 405.786097 -418.595276) (xy 405.763456 -418.545697) (xy 405.748102 -418.493401)
			(xy 405.740346 -418.439452) (xy 404.302689 -418.439452) (xy 404.294935 -418.493389) (xy 404.279582 -418.545678)
			(xy 404.256944 -418.595249) (xy 404.227483 -418.641095) (xy 404.191796 -418.682281) (xy 404.150612 -418.717969)
			(xy 404.104769 -418.747434) (xy 404.055198 -418.770074) (xy 404.002911 -418.78543) (xy 403.94897 -418.793188)
			(xy 403.921722 -418.793676) (xy 403.058122 -418.793676) (xy 403.030866 -418.793279) (xy 402.976908 -418.785523)
			(xy 402.924603 -418.770168) (xy 402.875016 -418.747525) (xy 402.829156 -418.718055) (xy 402.787957 -418.682358)
			(xy 402.752258 -418.641162) (xy 402.722786 -418.595303) (xy 402.70014 -418.545718) (xy 402.684781 -418.493414)
			(xy 402.677023 -418.439456) (xy 401.239512 -418.439456) (xy 401.231756 -418.493399) (xy 401.2164 -418.545694)
			(xy 401.193758 -418.595271) (xy 401.164291 -418.641122) (xy 401.128599 -418.682311) (xy 401.087407 -418.718002)
			(xy 401.041556 -418.747467) (xy 400.991977 -418.770107) (xy 400.939682 -418.78546) (xy 400.885733 -418.793214)
			(xy 400.858482 -418.793676) (xy 399.994882 -418.793676) (xy 399.967629 -418.793253) (xy 399.913679 -418.785494)
			(xy 399.861382 -418.770136) (xy 399.811803 -418.747492) (xy 399.765951 -418.718022) (xy 399.724759 -418.682328)
			(xy 399.689067 -418.641135) (xy 399.6596 -418.595281) (xy 399.636958 -418.545701) (xy 399.621603 -418.493403)
			(xy 399.613846 -418.439453) (xy 398.176189 -418.439453) (xy 398.168435 -418.493386) (xy 398.153083 -418.545673)
			(xy 398.130447 -418.595244) (xy 398.100987 -418.641088) (xy 398.065303 -418.682274) (xy 398.024122 -418.717962)
			(xy 397.978281 -418.747427) (xy 397.928713 -418.770069) (xy 397.876428 -418.785426) (xy 397.822489 -418.793187)
			(xy 397.795242 -418.793676) (xy 396.931642 -418.793676) (xy 396.904385 -418.79328) (xy 396.850425 -418.785527)
			(xy 396.798117 -418.770173) (xy 396.748528 -418.747531) (xy 396.702666 -418.718062) (xy 396.661464 -418.682365)
			(xy 396.625763 -418.641168) (xy 396.596289 -418.595309) (xy 396.573641 -418.545722) (xy 396.558282 -418.493416)
			(xy 396.550523 -418.439457) (xy 395.112989 -418.439457) (xy 395.105234 -418.493392) (xy 395.08988 -418.545682)
			(xy 395.067241 -418.595255) (xy 395.037778 -418.641101) (xy 395.002089 -418.682288) (xy 394.960903 -418.717976)
			(xy 394.915057 -418.74744) (xy 394.865484 -418.77008) (xy 394.813194 -418.785434) (xy 394.759251 -418.79319)
			(xy 394.732002 -418.793676) (xy 393.868402 -418.793676) (xy 393.841147 -418.793277) (xy 393.787191 -418.78552)
			(xy 393.734888 -418.770163) (xy 393.685304 -418.747518) (xy 393.639447 -418.718048) (xy 393.59825 -418.682351)
			(xy 393.562553 -418.641155) (xy 393.533083 -418.595298) (xy 393.510438 -418.545713) (xy 393.495081 -418.493411)
			(xy 393.487323 -418.439455) (xy 392.049813 -418.439455) (xy 392.042055 -418.493402) (xy 392.026699 -418.545699)
			(xy 392.004055 -418.595277) (xy 391.974586 -418.641128) (xy 391.938891 -418.682318) (xy 391.897698 -418.718009)
			(xy 391.851844 -418.747474) (xy 391.802263 -418.770112) (xy 391.749965 -418.785463) (xy 391.696014 -418.793215)
			(xy 391.668762 -418.793676) (xy 390.805162 -418.793676) (xy 390.77791 -418.793252) (xy 390.723962 -418.78549)
			(xy 390.671668 -418.77013) (xy 390.622091 -418.747485) (xy 390.576241 -418.718015) (xy 390.535052 -418.682321)
			(xy 390.499362 -418.641128) (xy 390.469897 -418.595276) (xy 390.447256 -418.545697) (xy 390.431902 -418.493401)
			(xy 390.424146 -418.439452) (xy 388.986489 -418.439452) (xy 388.978735 -418.493389) (xy 388.963382 -418.545678)
			(xy 388.940744 -418.595249) (xy 388.911283 -418.641095) (xy 388.875596 -418.682281) (xy 388.834412 -418.717969)
			(xy 388.788569 -418.747434) (xy 388.738998 -418.770074) (xy 388.686711 -418.78543) (xy 388.63277 -418.793188)
			(xy 388.605522 -418.793676) (xy 387.741922 -418.793676) (xy 387.714666 -418.793279) (xy 387.660708 -418.785523)
			(xy 387.608403 -418.770168) (xy 387.558816 -418.747525) (xy 387.512956 -418.718055) (xy 387.471757 -418.682358)
			(xy 387.436058 -418.641162) (xy 387.406586 -418.595303) (xy 387.38394 -418.545718) (xy 387.368581 -418.493414)
			(xy 387.360823 -418.439456) (xy 385.923312 -418.439456) (xy 385.915556 -418.493399) (xy 385.9002 -418.545694)
			(xy 385.877558 -418.595271) (xy 385.848091 -418.641122) (xy 385.812399 -418.682311) (xy 385.771207 -418.718002)
			(xy 385.725356 -418.747467) (xy 385.675777 -418.770107) (xy 385.623482 -418.78546) (xy 385.569533 -418.793214)
			(xy 385.542282 -418.793676) (xy 384.678682 -418.793676) (xy 384.651429 -418.793253) (xy 384.597479 -418.785494)
			(xy 384.545182 -418.770136) (xy 384.495603 -418.747492) (xy 384.449751 -418.718022) (xy 384.408559 -418.682328)
			(xy 384.372867 -418.641135) (xy 384.3434 -418.595281) (xy 384.320758 -418.545701) (xy 384.305403 -418.493403)
			(xy 384.297646 -418.439453) (xy 382.859989 -418.439453) (xy 382.852235 -418.493386) (xy 382.836883 -418.545673)
			(xy 382.814247 -418.595244) (xy 382.784787 -418.641088) (xy 382.749103 -418.682274) (xy 382.707922 -418.717962)
			(xy 382.662081 -418.747427) (xy 382.612513 -418.770069) (xy 382.560228 -418.785426) (xy 382.506289 -418.793187)
			(xy 382.479042 -418.793676) (xy 381.615442 -418.793676) (xy 381.588185 -418.79328) (xy 381.534225 -418.785527)
			(xy 381.481917 -418.770173) (xy 381.432328 -418.747531) (xy 381.386466 -418.718062) (xy 381.345264 -418.682365)
			(xy 381.309563 -418.641168) (xy 381.280089 -418.595309) (xy 381.257441 -418.545722) (xy 381.242082 -418.493416)
			(xy 381.234323 -418.439457) (xy 379.796789 -418.439457) (xy 379.789034 -418.493392) (xy 379.77368 -418.545682)
			(xy 379.751041 -418.595255) (xy 379.721578 -418.641101) (xy 379.685889 -418.682288) (xy 379.644703 -418.717976)
			(xy 379.598857 -418.74744) (xy 379.549284 -418.77008) (xy 379.496994 -418.785434) (xy 379.443051 -418.79319)
			(xy 379.415802 -418.793676) (xy 378.552202 -418.793676) (xy 378.524947 -418.793277) (xy 378.470991 -418.78552)
			(xy 378.418688 -418.770163) (xy 378.369104 -418.747518) (xy 378.323247 -418.718048) (xy 378.28205 -418.682351)
			(xy 378.246353 -418.641155) (xy 378.216883 -418.595298) (xy 378.194238 -418.545713) (xy 378.178881 -418.493411)
			(xy 378.171123 -418.439455) (xy 376.733613 -418.439455) (xy 376.725855 -418.493402) (xy 376.710499 -418.545699)
			(xy 376.687855 -418.595277) (xy 376.658386 -418.641128) (xy 376.622691 -418.682318) (xy 376.581498 -418.718009)
			(xy 376.535644 -418.747474) (xy 376.486063 -418.770112) (xy 376.433765 -418.785463) (xy 376.379814 -418.793215)
			(xy 376.352562 -418.793676) (xy 375.488962 -418.793676) (xy 375.46171 -418.793252) (xy 375.407762 -418.78549)
			(xy 375.355468 -418.77013) (xy 375.305891 -418.747485) (xy 375.260041 -418.718015) (xy 375.218852 -418.682321)
			(xy 375.183162 -418.641128) (xy 375.153697 -418.595276) (xy 375.131056 -418.545697) (xy 375.115702 -418.493401)
			(xy 375.107946 -418.439452) (xy 373.670289 -418.439452) (xy 373.662535 -418.493389) (xy 373.647182 -418.545678)
			(xy 373.624544 -418.595249) (xy 373.595083 -418.641095) (xy 373.559396 -418.682281) (xy 373.518212 -418.717969)
			(xy 373.472369 -418.747434) (xy 373.422798 -418.770074) (xy 373.370511 -418.78543) (xy 373.31657 -418.793188)
			(xy 373.289322 -418.793676) (xy 372.425722 -418.793676) (xy 372.398466 -418.793279) (xy 372.344508 -418.785523)
			(xy 372.292203 -418.770168) (xy 372.242616 -418.747525) (xy 372.196756 -418.718055) (xy 372.155557 -418.682358)
			(xy 372.119858 -418.641162) (xy 372.090386 -418.595303) (xy 372.06774 -418.545718) (xy 372.052381 -418.493414)
			(xy 372.044623 -418.439456) (xy 370.313204 -418.439456) (xy 370.313204 -420.692072) (xy 370.313204 -420.739316)
			(xy 370.262404 -420.739316) (xy 370.16182 -420.739316) (xy 370.150438 -420.74117) (xy 370.131001 -420.753543)
			(xy 370.118864 -420.773128) (xy 370.117116 -420.784528) (xy 370.117116 -420.979455) (xy 370.513023 -420.979455)
			(xy 370.513023 -420.924945) (xy 370.520781 -420.870989) (xy 370.536138 -420.818687) (xy 370.558783 -420.769102)
			(xy 370.588253 -420.723245) (xy 370.62395 -420.682049) (xy 370.665147 -420.646352) (xy 370.711004 -420.616882)
			(xy 370.760588 -420.594237) (xy 370.812891 -420.57888) (xy 370.866847 -420.571123) (xy 370.894102 -420.57066)
			(xy 371.757702 -420.57066) (xy 371.784951 -420.57121) (xy 371.838894 -420.578966) (xy 371.891184 -420.59432)
			(xy 371.940757 -420.61696) (xy 371.986603 -420.646424) (xy 372.027789 -420.682112) (xy 372.063478 -420.723299)
			(xy 372.092941 -420.769145) (xy 372.11558 -420.818718) (xy 372.130934 -420.871008) (xy 372.13869 -420.924951)
			(xy 372.13869 -420.979449) (xy 372.138689 -420.979457) (xy 373.576223 -420.979457) (xy 373.576223 -420.924943)
			(xy 373.583982 -420.870984) (xy 373.599341 -420.818678) (xy 373.621989 -420.769091) (xy 373.651463 -420.723232)
			(xy 373.687164 -420.682035) (xy 373.728366 -420.646338) (xy 373.774228 -420.616869) (xy 373.823817 -420.594227)
			(xy 373.876125 -420.578873) (xy 373.930085 -420.57112) (xy 373.957342 -420.57066) (xy 374.820942 -420.57066)
			(xy 374.848189 -420.571213) (xy 374.902128 -420.578974) (xy 374.954413 -420.594331) (xy 375.003981 -420.616973)
			(xy 375.049822 -420.646438) (xy 375.091003 -420.682126) (xy 375.126687 -420.723312) (xy 375.156147 -420.769156)
			(xy 375.178783 -420.818727) (xy 375.194135 -420.871014) (xy 375.20189 -420.924953) (xy 375.20189 -420.979447)
			(xy 375.201889 -420.979453) (xy 376.639546 -420.979453) (xy 376.639546 -420.924947) (xy 376.647303 -420.870997)
			(xy 376.662658 -420.818699) (xy 376.6853 -420.769119) (xy 376.714767 -420.723265) (xy 376.750459 -420.682072)
			(xy 376.791651 -420.646378) (xy 376.837503 -420.616908) (xy 376.887082 -420.594264) (xy 376.939379 -420.578906)
			(xy 376.993329 -420.571147) (xy 377.020582 -420.57066) (xy 377.884182 -420.57066) (xy 377.911433 -420.571186)
			(xy 377.965382 -420.57894) (xy 378.017677 -420.594293) (xy 378.067256 -420.616933) (xy 378.113107 -420.646398)
			(xy 378.154299 -420.682089) (xy 378.189991 -420.723278) (xy 378.219458 -420.769129) (xy 378.2421 -420.818706)
			(xy 378.257456 -420.871001) (xy 378.265213 -420.924949) (xy 378.265213 -420.979451) (xy 378.265212 -420.979456)
			(xy 379.702723 -420.979456) (xy 379.702723 -420.924944) (xy 379.710481 -420.870986) (xy 379.72584 -420.818682)
			(xy 379.748486 -420.769097) (xy 379.777958 -420.723238) (xy 379.813657 -420.682042) (xy 379.854856 -420.646345)
			(xy 379.900716 -420.616875) (xy 379.950303 -420.594232) (xy 380.002608 -420.578877) (xy 380.056566 -420.571121)
			(xy 380.083822 -420.57066) (xy 380.947422 -420.57066) (xy 380.97467 -420.571212) (xy 381.028611 -420.57897)
			(xy 381.080898 -420.594326) (xy 381.130469 -420.616966) (xy 381.176312 -420.646431) (xy 381.217496 -420.682119)
			(xy 381.253183 -420.723305) (xy 381.282644 -420.769151) (xy 381.305282 -420.818722) (xy 381.320635 -420.871011)
			(xy 381.32839 -420.924952) (xy 381.32839 -420.979448) (xy 381.328389 -420.979452) (xy 382.766046 -420.979452)
			(xy 382.766046 -420.924948) (xy 382.773802 -420.870999) (xy 382.789156 -420.818703) (xy 382.811797 -420.769124)
			(xy 382.841262 -420.723272) (xy 382.876952 -420.682079) (xy 382.918141 -420.646385) (xy 382.963991 -420.616915)
			(xy 383.013568 -420.59427) (xy 383.065862 -420.57891) (xy 383.11981 -420.571148) (xy 383.147062 -420.57066)
			(xy 384.010662 -420.57066) (xy 384.037914 -420.571185) (xy 384.091865 -420.578937) (xy 384.144163 -420.594288)
			(xy 384.193744 -420.616926) (xy 384.239598 -420.646391) (xy 384.280791 -420.682082) (xy 384.316486 -420.723272)
			(xy 384.345955 -420.769123) (xy 384.368599 -420.818701) (xy 384.383955 -420.870998) (xy 384.391713 -420.924948)
			(xy 384.391713 -420.979452) (xy 384.391713 -420.979455) (xy 385.829223 -420.979455) (xy 385.829223 -420.924945)
			(xy 385.836981 -420.870989) (xy 385.852338 -420.818687) (xy 385.874983 -420.769102) (xy 385.904453 -420.723245)
			(xy 385.94015 -420.682049) (xy 385.981347 -420.646352) (xy 386.027204 -420.616882) (xy 386.076788 -420.594237)
			(xy 386.129091 -420.57888) (xy 386.183047 -420.571123) (xy 386.210302 -420.57066) (xy 387.073902 -420.57066)
			(xy 387.101151 -420.57121) (xy 387.155094 -420.578966) (xy 387.207384 -420.59432) (xy 387.256957 -420.61696)
			(xy 387.302803 -420.646424) (xy 387.343989 -420.682112) (xy 387.379678 -420.723299) (xy 387.409141 -420.769145)
			(xy 387.43178 -420.818718) (xy 387.447134 -420.871008) (xy 387.45489 -420.924951) (xy 387.45489 -420.979449)
			(xy 387.454889 -420.979457) (xy 388.892423 -420.979457) (xy 388.892423 -420.924943) (xy 388.900182 -420.870984)
			(xy 388.915541 -420.818678) (xy 388.938189 -420.769091) (xy 388.967663 -420.723232) (xy 389.003364 -420.682035)
			(xy 389.044566 -420.646338) (xy 389.090428 -420.616869) (xy 389.140017 -420.594227) (xy 389.192325 -420.578873)
			(xy 389.246285 -420.57112) (xy 389.273542 -420.57066) (xy 390.137142 -420.57066) (xy 390.164389 -420.571213)
			(xy 390.218328 -420.578974) (xy 390.270613 -420.594331) (xy 390.320181 -420.616973) (xy 390.366022 -420.646438)
			(xy 390.407203 -420.682126) (xy 390.442887 -420.723312) (xy 390.472347 -420.769156) (xy 390.494983 -420.818727)
			(xy 390.510335 -420.871014) (xy 390.51809 -420.924953) (xy 390.51809 -420.979447) (xy 390.518089 -420.979453)
			(xy 391.955746 -420.979453) (xy 391.955746 -420.924947) (xy 391.963503 -420.870997) (xy 391.978858 -420.818699)
			(xy 392.0015 -420.769119) (xy 392.030967 -420.723265) (xy 392.066659 -420.682072) (xy 392.107851 -420.646378)
			(xy 392.153703 -420.616908) (xy 392.203282 -420.594264) (xy 392.255579 -420.578906) (xy 392.309529 -420.571147)
			(xy 392.336782 -420.57066) (xy 393.200382 -420.57066) (xy 393.227633 -420.571186) (xy 393.281582 -420.57894)
			(xy 393.333877 -420.594293) (xy 393.383456 -420.616933) (xy 393.429307 -420.646398) (xy 393.470499 -420.682089)
			(xy 393.506191 -420.723278) (xy 393.535658 -420.769129) (xy 393.5583 -420.818706) (xy 393.573656 -420.871001)
			(xy 393.581413 -420.924949) (xy 393.581413 -420.979451) (xy 393.581412 -420.979456) (xy 395.018923 -420.979456)
			(xy 395.018923 -420.924944) (xy 395.026681 -420.870986) (xy 395.04204 -420.818682) (xy 395.064686 -420.769097)
			(xy 395.094158 -420.723238) (xy 395.129857 -420.682042) (xy 395.171056 -420.646345) (xy 395.216916 -420.616875)
			(xy 395.266503 -420.594232) (xy 395.318808 -420.578877) (xy 395.372766 -420.571121) (xy 395.400022 -420.57066)
			(xy 396.263622 -420.57066) (xy 396.29087 -420.571212) (xy 396.344811 -420.57897) (xy 396.397098 -420.594326)
			(xy 396.446669 -420.616966) (xy 396.492512 -420.646431) (xy 396.533696 -420.682119) (xy 396.569383 -420.723305)
			(xy 396.598844 -420.769151) (xy 396.621482 -420.818722) (xy 396.636835 -420.871011) (xy 396.64459 -420.924952)
			(xy 396.64459 -420.979448) (xy 396.644589 -420.979452) (xy 398.082246 -420.979452) (xy 398.082246 -420.924948)
			(xy 398.090002 -420.870999) (xy 398.105356 -420.818703) (xy 398.127997 -420.769124) (xy 398.157462 -420.723272)
			(xy 398.193152 -420.682079) (xy 398.234341 -420.646385) (xy 398.280191 -420.616915) (xy 398.329768 -420.59427)
			(xy 398.382062 -420.57891) (xy 398.43601 -420.571148) (xy 398.463262 -420.57066) (xy 399.326862 -420.57066)
			(xy 399.354114 -420.571185) (xy 399.408065 -420.578937) (xy 399.460363 -420.594288) (xy 399.509944 -420.616926)
			(xy 399.555798 -420.646391) (xy 399.596991 -420.682082) (xy 399.632686 -420.723272) (xy 399.662155 -420.769123)
			(xy 399.684799 -420.818701) (xy 399.700155 -420.870998) (xy 399.707913 -420.924948) (xy 399.707913 -420.979452)
			(xy 399.707913 -420.979455) (xy 401.145423 -420.979455) (xy 401.145423 -420.924945) (xy 401.153181 -420.870989)
			(xy 401.168538 -420.818687) (xy 401.191183 -420.769102) (xy 401.220653 -420.723245) (xy 401.25635 -420.682049)
			(xy 401.297547 -420.646352) (xy 401.343404 -420.616882) (xy 401.392988 -420.594237) (xy 401.445291 -420.57888)
			(xy 401.499247 -420.571123) (xy 401.526502 -420.57066) (xy 402.390102 -420.57066) (xy 402.417351 -420.57121)
			(xy 402.471294 -420.578966) (xy 402.523584 -420.59432) (xy 402.573157 -420.61696) (xy 402.619003 -420.646424)
			(xy 402.660189 -420.682112) (xy 402.695878 -420.723299) (xy 402.725341 -420.769145) (xy 402.74798 -420.818718)
			(xy 402.763334 -420.871008) (xy 402.77109 -420.924951) (xy 402.77109 -420.979449) (xy 402.771089 -420.979457)
			(xy 404.208623 -420.979457) (xy 404.208623 -420.924943) (xy 404.216382 -420.870984) (xy 404.231741 -420.818678)
			(xy 404.254389 -420.769091) (xy 404.283863 -420.723232) (xy 404.319564 -420.682035) (xy 404.360766 -420.646338)
			(xy 404.406628 -420.616869) (xy 404.456217 -420.594227) (xy 404.508525 -420.578873) (xy 404.562485 -420.57112)
			(xy 404.589742 -420.57066) (xy 405.453342 -420.57066) (xy 405.480589 -420.571213) (xy 405.534528 -420.578974)
			(xy 405.586813 -420.594331) (xy 405.636381 -420.616973) (xy 405.682222 -420.646438) (xy 405.723403 -420.682126)
			(xy 405.759087 -420.723312) (xy 405.788547 -420.769156) (xy 405.811183 -420.818727) (xy 405.826535 -420.871014)
			(xy 405.83429 -420.924953) (xy 405.83429 -420.979447) (xy 405.834289 -420.979453) (xy 407.271946 -420.979453)
			(xy 407.271946 -420.924947) (xy 407.279703 -420.870997) (xy 407.295058 -420.818699) (xy 407.3177 -420.769119)
			(xy 407.347167 -420.723265) (xy 407.382859 -420.682072) (xy 407.424051 -420.646378) (xy 407.469903 -420.616908)
			(xy 407.519482 -420.594264) (xy 407.571779 -420.578906) (xy 407.625729 -420.571147) (xy 407.652982 -420.57066)
			(xy 408.516582 -420.57066) (xy 408.543833 -420.571186) (xy 408.597782 -420.57894) (xy 408.650077 -420.594293)
			(xy 408.699656 -420.616933) (xy 408.745507 -420.646398) (xy 408.786699 -420.682089) (xy 408.822391 -420.723278)
			(xy 408.851858 -420.769129) (xy 408.8745 -420.818706) (xy 408.889856 -420.871001) (xy 408.897613 -420.924949)
			(xy 408.897613 -420.979451) (xy 408.897612 -420.979456) (xy 410.335123 -420.979456) (xy 410.335123 -420.924944)
			(xy 410.342881 -420.870986) (xy 410.35824 -420.818682) (xy 410.380886 -420.769097) (xy 410.410358 -420.723238)
			(xy 410.446057 -420.682042) (xy 410.487256 -420.646345) (xy 410.533116 -420.616875) (xy 410.582703 -420.594232)
			(xy 410.635008 -420.578877) (xy 410.688966 -420.571121) (xy 410.716222 -420.57066) (xy 411.579822 -420.57066)
			(xy 411.60707 -420.571212) (xy 411.661011 -420.57897) (xy 411.713298 -420.594326) (xy 411.762869 -420.616966)
			(xy 411.808712 -420.646431) (xy 411.849896 -420.682119) (xy 411.885583 -420.723305) (xy 411.915044 -420.769151)
			(xy 411.937682 -420.818722) (xy 411.953035 -420.871011) (xy 411.96079 -420.924952) (xy 411.96079 -420.979448)
			(xy 411.960789 -420.979452) (xy 413.398446 -420.979452) (xy 413.398446 -420.924948) (xy 413.406202 -420.870999)
			(xy 413.421556 -420.818703) (xy 413.444197 -420.769124) (xy 413.473662 -420.723272) (xy 413.509352 -420.682079)
			(xy 413.550541 -420.646385) (xy 413.596391 -420.616915) (xy 413.645968 -420.59427) (xy 413.698262 -420.57891)
			(xy 413.75221 -420.571148) (xy 413.779462 -420.57066) (xy 414.643062 -420.57066) (xy 414.670314 -420.571185)
			(xy 414.724265 -420.578937) (xy 414.776563 -420.594288) (xy 414.826144 -420.616926) (xy 414.871998 -420.646391)
			(xy 414.913191 -420.682082) (xy 414.948886 -420.723272) (xy 414.978355 -420.769123) (xy 415.000999 -420.818701)
			(xy 415.016355 -420.870998) (xy 415.024113 -420.924948) (xy 415.024113 -420.979452) (xy 415.024113 -420.979455)
			(xy 416.461623 -420.979455) (xy 416.461623 -420.924945) (xy 416.469381 -420.870989) (xy 416.484738 -420.818687)
			(xy 416.507383 -420.769102) (xy 416.536853 -420.723245) (xy 416.57255 -420.682049) (xy 416.613747 -420.646352)
			(xy 416.659604 -420.616882) (xy 416.709188 -420.594237) (xy 416.761491 -420.57888) (xy 416.815447 -420.571123)
			(xy 416.842702 -420.57066) (xy 417.706302 -420.57066) (xy 417.733551 -420.57121) (xy 417.787494 -420.578966)
			(xy 417.839784 -420.59432) (xy 417.889357 -420.61696) (xy 417.935203 -420.646424) (xy 417.976389 -420.682112)
			(xy 418.012078 -420.723299) (xy 418.041541 -420.769145) (xy 418.06418 -420.818718) (xy 418.079534 -420.871008)
			(xy 418.08729 -420.924951) (xy 418.08729 -420.979449) (xy 418.079534 -421.033392) (xy 418.06418 -421.085682)
			(xy 418.041541 -421.135255) (xy 418.012078 -421.181101) (xy 417.976389 -421.222288) (xy 417.935203 -421.257976)
			(xy 417.889357 -421.28744) (xy 417.839784 -421.31008) (xy 417.787494 -421.325434) (xy 417.733551 -421.33319)
			(xy 417.706302 -421.333676) (xy 416.842702 -421.333676) (xy 416.815447 -421.333277) (xy 416.761491 -421.32552)
			(xy 416.709188 -421.310163) (xy 416.659604 -421.287518) (xy 416.613747 -421.258048) (xy 416.57255 -421.222351)
			(xy 416.536853 -421.181155) (xy 416.507383 -421.135298) (xy 416.484738 -421.085713) (xy 416.469381 -421.033411)
			(xy 416.461623 -420.979455) (xy 415.024113 -420.979455) (xy 415.016355 -421.033402) (xy 415.000999 -421.085699)
			(xy 414.978355 -421.135277) (xy 414.948886 -421.181128) (xy 414.913191 -421.222318) (xy 414.871998 -421.258009)
			(xy 414.826144 -421.287474) (xy 414.776563 -421.310112) (xy 414.724265 -421.325463) (xy 414.670314 -421.333215)
			(xy 414.643062 -421.333676) (xy 413.779462 -421.333676) (xy 413.75221 -421.333252) (xy 413.698262 -421.32549)
			(xy 413.645968 -421.31013) (xy 413.596391 -421.287485) (xy 413.550541 -421.258015) (xy 413.509352 -421.222321)
			(xy 413.473662 -421.181128) (xy 413.444197 -421.135276) (xy 413.421556 -421.085697) (xy 413.406202 -421.033401)
			(xy 413.398446 -420.979452) (xy 411.960789 -420.979452) (xy 411.953035 -421.033389) (xy 411.937682 -421.085678)
			(xy 411.915044 -421.135249) (xy 411.885583 -421.181095) (xy 411.849896 -421.222281) (xy 411.808712 -421.257969)
			(xy 411.762869 -421.287434) (xy 411.713298 -421.310074) (xy 411.661011 -421.32543) (xy 411.60707 -421.333188)
			(xy 411.579822 -421.333676) (xy 410.716222 -421.333676) (xy 410.688966 -421.333279) (xy 410.635008 -421.325523)
			(xy 410.582703 -421.310168) (xy 410.533116 -421.287525) (xy 410.487256 -421.258055) (xy 410.446057 -421.222358)
			(xy 410.410358 -421.181162) (xy 410.380886 -421.135303) (xy 410.35824 -421.085718) (xy 410.342881 -421.033414)
			(xy 410.335123 -420.979456) (xy 408.897612 -420.979456) (xy 408.889856 -421.033399) (xy 408.8745 -421.085694)
			(xy 408.851858 -421.135271) (xy 408.822391 -421.181122) (xy 408.786699 -421.222311) (xy 408.745507 -421.258002)
			(xy 408.699656 -421.287467) (xy 408.650077 -421.310107) (xy 408.597782 -421.32546) (xy 408.543833 -421.333214)
			(xy 408.516582 -421.333676) (xy 407.652982 -421.333676) (xy 407.625729 -421.333253) (xy 407.571779 -421.325494)
			(xy 407.519482 -421.310136) (xy 407.469903 -421.287492) (xy 407.424051 -421.258022) (xy 407.382859 -421.222328)
			(xy 407.347167 -421.181135) (xy 407.3177 -421.135281) (xy 407.295058 -421.085701) (xy 407.279703 -421.033403)
			(xy 407.271946 -420.979453) (xy 405.834289 -420.979453) (xy 405.826535 -421.033386) (xy 405.811183 -421.085673)
			(xy 405.788547 -421.135244) (xy 405.759087 -421.181088) (xy 405.723403 -421.222274) (xy 405.682222 -421.257962)
			(xy 405.636381 -421.287427) (xy 405.586813 -421.310069) (xy 405.534528 -421.325426) (xy 405.480589 -421.333187)
			(xy 405.453342 -421.333676) (xy 404.589742 -421.333676) (xy 404.562485 -421.33328) (xy 404.508525 -421.325527)
			(xy 404.456217 -421.310173) (xy 404.406628 -421.287531) (xy 404.360766 -421.258062) (xy 404.319564 -421.222365)
			(xy 404.283863 -421.181168) (xy 404.254389 -421.135309) (xy 404.231741 -421.085722) (xy 404.216382 -421.033416)
			(xy 404.208623 -420.979457) (xy 402.771089 -420.979457) (xy 402.763334 -421.033392) (xy 402.74798 -421.085682)
			(xy 402.725341 -421.135255) (xy 402.695878 -421.181101) (xy 402.660189 -421.222288) (xy 402.619003 -421.257976)
			(xy 402.573157 -421.28744) (xy 402.523584 -421.31008) (xy 402.471294 -421.325434) (xy 402.417351 -421.33319)
			(xy 402.390102 -421.333676) (xy 401.526502 -421.333676) (xy 401.499247 -421.333277) (xy 401.445291 -421.32552)
			(xy 401.392988 -421.310163) (xy 401.343404 -421.287518) (xy 401.297547 -421.258048) (xy 401.25635 -421.222351)
			(xy 401.220653 -421.181155) (xy 401.191183 -421.135298) (xy 401.168538 -421.085713) (xy 401.153181 -421.033411)
			(xy 401.145423 -420.979455) (xy 399.707913 -420.979455) (xy 399.700155 -421.033402) (xy 399.684799 -421.085699)
			(xy 399.662155 -421.135277) (xy 399.632686 -421.181128) (xy 399.596991 -421.222318) (xy 399.555798 -421.258009)
			(xy 399.509944 -421.287474) (xy 399.460363 -421.310112) (xy 399.408065 -421.325463) (xy 399.354114 -421.333215)
			(xy 399.326862 -421.333676) (xy 398.463262 -421.333676) (xy 398.43601 -421.333252) (xy 398.382062 -421.32549)
			(xy 398.329768 -421.31013) (xy 398.280191 -421.287485) (xy 398.234341 -421.258015) (xy 398.193152 -421.222321)
			(xy 398.157462 -421.181128) (xy 398.127997 -421.135276) (xy 398.105356 -421.085697) (xy 398.090002 -421.033401)
			(xy 398.082246 -420.979452) (xy 396.644589 -420.979452) (xy 396.636835 -421.033389) (xy 396.621482 -421.085678)
			(xy 396.598844 -421.135249) (xy 396.569383 -421.181095) (xy 396.533696 -421.222281) (xy 396.492512 -421.257969)
			(xy 396.446669 -421.287434) (xy 396.397098 -421.310074) (xy 396.344811 -421.32543) (xy 396.29087 -421.333188)
			(xy 396.263622 -421.333676) (xy 395.400022 -421.333676) (xy 395.372766 -421.333279) (xy 395.318808 -421.325523)
			(xy 395.266503 -421.310168) (xy 395.216916 -421.287525) (xy 395.171056 -421.258055) (xy 395.129857 -421.222358)
			(xy 395.094158 -421.181162) (xy 395.064686 -421.135303) (xy 395.04204 -421.085718) (xy 395.026681 -421.033414)
			(xy 395.018923 -420.979456) (xy 393.581412 -420.979456) (xy 393.573656 -421.033399) (xy 393.5583 -421.085694)
			(xy 393.535658 -421.135271) (xy 393.506191 -421.181122) (xy 393.470499 -421.222311) (xy 393.429307 -421.258002)
			(xy 393.383456 -421.287467) (xy 393.333877 -421.310107) (xy 393.281582 -421.32546) (xy 393.227633 -421.333214)
			(xy 393.200382 -421.333676) (xy 392.336782 -421.333676) (xy 392.309529 -421.333253) (xy 392.255579 -421.325494)
			(xy 392.203282 -421.310136) (xy 392.153703 -421.287492) (xy 392.107851 -421.258022) (xy 392.066659 -421.222328)
			(xy 392.030967 -421.181135) (xy 392.0015 -421.135281) (xy 391.978858 -421.085701) (xy 391.963503 -421.033403)
			(xy 391.955746 -420.979453) (xy 390.518089 -420.979453) (xy 390.510335 -421.033386) (xy 390.494983 -421.085673)
			(xy 390.472347 -421.135244) (xy 390.442887 -421.181088) (xy 390.407203 -421.222274) (xy 390.366022 -421.257962)
			(xy 390.320181 -421.287427) (xy 390.270613 -421.310069) (xy 390.218328 -421.325426) (xy 390.164389 -421.333187)
			(xy 390.137142 -421.333676) (xy 389.273542 -421.333676) (xy 389.246285 -421.33328) (xy 389.192325 -421.325527)
			(xy 389.140017 -421.310173) (xy 389.090428 -421.287531) (xy 389.044566 -421.258062) (xy 389.003364 -421.222365)
			(xy 388.967663 -421.181168) (xy 388.938189 -421.135309) (xy 388.915541 -421.085722) (xy 388.900182 -421.033416)
			(xy 388.892423 -420.979457) (xy 387.454889 -420.979457) (xy 387.447134 -421.033392) (xy 387.43178 -421.085682)
			(xy 387.409141 -421.135255) (xy 387.379678 -421.181101) (xy 387.343989 -421.222288) (xy 387.302803 -421.257976)
			(xy 387.256957 -421.28744) (xy 387.207384 -421.31008) (xy 387.155094 -421.325434) (xy 387.101151 -421.33319)
			(xy 387.073902 -421.333676) (xy 386.210302 -421.333676) (xy 386.183047 -421.333277) (xy 386.129091 -421.32552)
			(xy 386.076788 -421.310163) (xy 386.027204 -421.287518) (xy 385.981347 -421.258048) (xy 385.94015 -421.222351)
			(xy 385.904453 -421.181155) (xy 385.874983 -421.135298) (xy 385.852338 -421.085713) (xy 385.836981 -421.033411)
			(xy 385.829223 -420.979455) (xy 384.391713 -420.979455) (xy 384.383955 -421.033402) (xy 384.368599 -421.085699)
			(xy 384.345955 -421.135277) (xy 384.316486 -421.181128) (xy 384.280791 -421.222318) (xy 384.239598 -421.258009)
			(xy 384.193744 -421.287474) (xy 384.144163 -421.310112) (xy 384.091865 -421.325463) (xy 384.037914 -421.333215)
			(xy 384.010662 -421.333676) (xy 383.147062 -421.333676) (xy 383.11981 -421.333252) (xy 383.065862 -421.32549)
			(xy 383.013568 -421.31013) (xy 382.963991 -421.287485) (xy 382.918141 -421.258015) (xy 382.876952 -421.222321)
			(xy 382.841262 -421.181128) (xy 382.811797 -421.135276) (xy 382.789156 -421.085697) (xy 382.773802 -421.033401)
			(xy 382.766046 -420.979452) (xy 381.328389 -420.979452) (xy 381.320635 -421.033389) (xy 381.305282 -421.085678)
			(xy 381.282644 -421.135249) (xy 381.253183 -421.181095) (xy 381.217496 -421.222281) (xy 381.176312 -421.257969)
			(xy 381.130469 -421.287434) (xy 381.080898 -421.310074) (xy 381.028611 -421.32543) (xy 380.97467 -421.333188)
			(xy 380.947422 -421.333676) (xy 380.083822 -421.333676) (xy 380.056566 -421.333279) (xy 380.002608 -421.325523)
			(xy 379.950303 -421.310168) (xy 379.900716 -421.287525) (xy 379.854856 -421.258055) (xy 379.813657 -421.222358)
			(xy 379.777958 -421.181162) (xy 379.748486 -421.135303) (xy 379.72584 -421.085718) (xy 379.710481 -421.033414)
			(xy 379.702723 -420.979456) (xy 378.265212 -420.979456) (xy 378.257456 -421.033399) (xy 378.2421 -421.085694)
			(xy 378.219458 -421.135271) (xy 378.189991 -421.181122) (xy 378.154299 -421.222311) (xy 378.113107 -421.258002)
			(xy 378.067256 -421.287467) (xy 378.017677 -421.310107) (xy 377.965382 -421.32546) (xy 377.911433 -421.333214)
			(xy 377.884182 -421.333676) (xy 377.020582 -421.333676) (xy 376.993329 -421.333253) (xy 376.939379 -421.325494)
			(xy 376.887082 -421.310136) (xy 376.837503 -421.287492) (xy 376.791651 -421.258022) (xy 376.750459 -421.222328)
			(xy 376.714767 -421.181135) (xy 376.6853 -421.135281) (xy 376.662658 -421.085701) (xy 376.647303 -421.033403)
			(xy 376.639546 -420.979453) (xy 375.201889 -420.979453) (xy 375.194135 -421.033386) (xy 375.178783 -421.085673)
			(xy 375.156147 -421.135244) (xy 375.126687 -421.181088) (xy 375.091003 -421.222274) (xy 375.049822 -421.257962)
			(xy 375.003981 -421.287427) (xy 374.954413 -421.310069) (xy 374.902128 -421.325426) (xy 374.848189 -421.333187)
			(xy 374.820942 -421.333676) (xy 373.957342 -421.333676) (xy 373.930085 -421.33328) (xy 373.876125 -421.325527)
			(xy 373.823817 -421.310173) (xy 373.774228 -421.287531) (xy 373.728366 -421.258062) (xy 373.687164 -421.222365)
			(xy 373.651463 -421.181168) (xy 373.621989 -421.135309) (xy 373.599341 -421.085722) (xy 373.583982 -421.033416)
			(xy 373.576223 -420.979457) (xy 372.138689 -420.979457) (xy 372.130934 -421.033392) (xy 372.11558 -421.085682)
			(xy 372.092941 -421.135255) (xy 372.063478 -421.181101) (xy 372.027789 -421.222288) (xy 371.986603 -421.257976)
			(xy 371.940757 -421.28744) (xy 371.891184 -421.31008) (xy 371.838894 -421.325434) (xy 371.784951 -421.33319)
			(xy 371.757702 -421.333676) (xy 370.894102 -421.333676) (xy 370.866847 -421.333277) (xy 370.812891 -421.32552)
			(xy 370.760588 -421.310163) (xy 370.711004 -421.287518) (xy 370.665147 -421.258048) (xy 370.62395 -421.222351)
			(xy 370.588253 -421.181155) (xy 370.558783 -421.135298) (xy 370.536138 -421.085713) (xy 370.520781 -421.033411)
			(xy 370.513023 -420.979455) (xy 370.117116 -420.979455) (xy 370.117116 -421.134032) (xy 370.118827 -421.145443)
			(xy 370.130963 -421.165042) (xy 370.150431 -421.17739) (xy 370.16182 -421.179244) (xy 370.26596 -421.179244)
			(xy 370.313204 -421.179244) (xy 370.313204 -421.230044) (xy 370.313204 -422.692576) (xy 370.312768 -422.702798)
			(xy 370.30495 -422.721687) (xy 370.290497 -422.736144) (xy 370.27161 -422.743966) (xy 370.261388 -422.744392)
			(xy 365.362744 -422.744392) (xy 365.352522 -422.743952) (xy 365.333631 -422.736138) (xy 365.319173 -422.721686)
			(xy 365.311352 -422.702798) (xy 365.310928 -422.692576) (xy 360.222212 -422.692576) (xy 360.286426 -422.706639)
			(xy 360.410636 -422.74198) (xy 360.532435 -422.7849) (xy 360.65136 -422.835237) (xy 360.766961 -422.892799)
			(xy 360.8788 -422.957369) (xy 360.986451 -423.028701) (xy 361.089506 -423.106525) (xy 361.187576 -423.190546)
			(xy 361.280287 -423.280445) (xy 361.367287 -423.37588) (xy 361.448248 -423.47649) (xy 361.505055 -423.556738)
			(xy 456.285335 -423.556738) (xy 456.285335 -423.427598) (xy 456.293285 -423.298703) (xy 456.309155 -423.170543)
			(xy 456.332884 -423.043602) (xy 456.364383 -422.918363) (xy 456.403532 -422.7953) (xy 456.450183 -422.674881)
			(xy 456.504158 -422.557562) (xy 456.565253 -422.443788) (xy 456.633236 -422.333991) (xy 456.70785 -422.228588)
			(xy 456.788811 -422.127978) (xy 456.875811 -422.032543) (xy 456.968522 -421.942644) (xy 457.066592 -421.858623)
			(xy 457.169647 -421.780799) (xy 457.277298 -421.709467) (xy 457.389137 -421.644897) (xy 457.504738 -421.587335)
			(xy 457.623663 -421.536998) (xy 457.745462 -421.494078) (xy 457.869672 -421.458737) (xy 457.995821 -421.43111)
			(xy 458.123433 -421.411301) (xy 458.252022 -421.399385) (xy 458.3811 -421.395409) (xy 458.510178 -421.399385)
			(xy 458.638767 -421.411301) (xy 458.766379 -421.43111) (xy 458.892528 -421.458737) (xy 459.016738 -421.494078)
			(xy 459.138537 -421.536998) (xy 459.257462 -421.587335) (xy 459.373063 -421.644897) (xy 459.484902 -421.709467)
			(xy 459.592553 -421.780799) (xy 459.695608 -421.858623) (xy 459.793678 -421.942644) (xy 459.886389 -422.032543)
			(xy 459.973389 -422.127978) (xy 460.05435 -422.228588) (xy 460.128964 -422.333991) (xy 460.196947 -422.443788)
			(xy 460.258042 -422.557562) (xy 460.312017 -422.674881) (xy 460.358668 -422.7953) (xy 460.397817 -422.918363)
			(xy 460.429316 -423.043602) (xy 460.453045 -423.170543) (xy 460.468915 -423.298703) (xy 460.476865 -423.427598)
			(xy 460.477362 -423.492168) (xy 460.476865 -423.556738) (xy 460.468915 -423.685633) (xy 460.453045 -423.813793)
			(xy 460.429316 -423.940734) (xy 460.397817 -424.065973) (xy 460.358668 -424.189036) (xy 460.312017 -424.309455)
			(xy 460.258042 -424.426774) (xy 460.196947 -424.540548) (xy 460.128964 -424.650345) (xy 460.05435 -424.755748)
			(xy 459.973389 -424.856358) (xy 459.886389 -424.951793) (xy 459.793678 -425.041692) (xy 459.695608 -425.125713)
			(xy 459.592553 -425.203537) (xy 459.484902 -425.274869) (xy 459.373063 -425.339439) (xy 459.257462 -425.397001)
			(xy 459.138537 -425.447338) (xy 459.016738 -425.490258) (xy 458.892528 -425.525599) (xy 458.766379 -425.553226)
			(xy 458.638767 -425.573035) (xy 458.510178 -425.584951) (xy 458.3811 -425.588928) (xy 458.252022 -425.584951)
			(xy 458.123433 -425.573035) (xy 457.995821 -425.553226) (xy 457.869672 -425.525599) (xy 457.745462 -425.490258)
			(xy 457.623663 -425.447338) (xy 457.504738 -425.397001) (xy 457.389137 -425.339439) (xy 457.277298 -425.274869)
			(xy 457.169647 -425.203537) (xy 457.066592 -425.125713) (xy 456.968522 -425.041692) (xy 456.875811 -424.951793)
			(xy 456.788811 -424.856358) (xy 456.70785 -424.755748) (xy 456.633236 -424.650345) (xy 456.565253 -424.540548)
			(xy 456.504158 -424.426774) (xy 456.450183 -424.309455) (xy 456.403532 -424.189036) (xy 456.364383 -424.065973)
			(xy 456.332884 -423.940734) (xy 456.309155 -423.813793) (xy 456.293285 -423.685633) (xy 456.285335 -423.556738)
			(xy 361.505055 -423.556738) (xy 361.522862 -423.581893) (xy 361.590845 -423.69169) (xy 361.65194 -423.805464)
			(xy 361.705915 -423.922783) (xy 361.752566 -424.043202) (xy 361.791715 -424.166265) (xy 361.823214 -424.291504)
			(xy 361.846943 -424.418445) (xy 361.862813 -424.546605) (xy 361.870763 -424.6755) (xy 361.87126 -424.74007)
			(xy 361.870763 -424.80464) (xy 361.862813 -424.933535) (xy 361.846943 -425.061695) (xy 361.823214 -425.188636)
			(xy 361.791715 -425.313875) (xy 361.752566 -425.436938) (xy 361.705915 -425.557357) (xy 361.65194 -425.674676)
			(xy 361.590845 -425.78845) (xy 361.522862 -425.898247) (xy 361.448248 -426.00365) (xy 361.367287 -426.10426)
			(xy 361.280287 -426.199695) (xy 361.187576 -426.289594) (xy 361.089506 -426.373615) (xy 360.986451 -426.451439)
			(xy 360.8788 -426.522771) (xy 360.766961 -426.587341) (xy 360.65136 -426.644903) (xy 360.532435 -426.69524)
			(xy 360.410636 -426.73816) (xy 360.286426 -426.773501) (xy 360.160277 -426.801128) (xy 360.032665 -426.820937)
			(xy 359.904076 -426.832853) (xy 359.774998 -426.83683) (xy 359.64592 -426.832853) (xy 359.517331 -426.820937)
			(xy 359.389719 -426.801128) (xy 359.26357 -426.773501) (xy 359.13936 -426.73816) (xy 359.017561 -426.69524)
			(xy 358.898636 -426.644903) (xy 358.783035 -426.587341) (xy 358.671196 -426.522771) (xy 358.563545 -426.451439)
			(xy 358.46049 -426.373615) (xy 358.36242 -426.289594) (xy 358.269709 -426.199695) (xy 358.182709 -426.10426)
			(xy 358.101748 -426.00365) (xy 358.027134 -425.898247) (xy 357.959151 -425.78845) (xy 357.898056 -425.674676)
			(xy 357.844081 -425.557357) (xy 357.79743 -425.436938) (xy 357.758281 -425.313875) (xy 357.726782 -425.188636)
			(xy 357.703053 -425.061695) (xy 357.687183 -424.933535) (xy 357.679233 -424.80464) (xy 230.3145 -424.80464)
			(xy 230.3145 -427.960536) (xy 314.141104 -427.960536) (xy 314.141104 -427.233588) (xy 314.141386 -427.224753)
			(xy 314.1455 -427.207565) (xy 314.149232 -427.199552) (xy 314.382658 -426.723302) (xy 314.387343 -426.71278)
			(xy 314.390836 -426.690025) (xy 314.387358 -426.667269) (xy 314.382658 -426.656754) (xy 314.149232 -426.180504)
			(xy 314.145478 -426.172498) (xy 314.14136 -426.155306) (xy 314.141104 -426.146468) (xy 314.141104 -425.419012)
			(xy 314.141527 -425.406903) (xy 314.149023 -425.383876) (xy 314.163283 -425.364302) (xy 314.182904 -425.350107)
			(xy 314.205956 -425.342687) (xy 314.218066 -425.342304) (xy 315.157866 -425.342304) (xy 315.16995 -425.342836)
			(xy 315.192944 -425.350279) (xy 315.212521 -425.36445) (xy 315.226774 -425.383968) (xy 315.234313 -425.40693)
			(xy 315.234828 -425.419012) (xy 315.234828 -427.960536) (xy 315.234415 -427.972644) (xy 315.226909 -427.995668)
			(xy 315.212645 -428.015238) (xy 315.193025 -428.029432) (xy 315.169975 -428.036857) (xy 315.157866 -428.037244)
			(xy 314.218066 -428.037244) (xy 314.205973 -428.036821) (xy 314.182969 -428.029353) (xy 314.163388 -428.015156)
			(xy 314.149139 -427.995612) (xy 314.141611 -427.972628) (xy 314.141104 -427.960536) (xy 230.3145 -427.960536)
			(xy 230.3145 -433.130695) (xy 266.885917 -433.130695) (xy 266.885917 -432.953425) (xy 266.89387 -432.776334)
			(xy 266.909761 -432.599778) (xy 266.933556 -432.424113) (xy 266.965209 -432.249692) (xy 267.004655 -432.076867)
			(xy 267.051815 -431.905986) (xy 267.106594 -431.737392) (xy 267.168882 -431.571427) (xy 267.238554 -431.408422)
			(xy 267.315468 -431.248708) (xy 267.399471 -431.092605) (xy 267.490392 -430.940428) (xy 267.588049 -430.792484)
			(xy 267.692246 -430.64907) (xy 267.802772 -430.510475) (xy 267.919404 -430.376978) (xy 268.041909 -430.248849)
			(xy 268.170038 -430.126344) (xy 268.303535 -430.009712) (xy 268.44213 -429.899186) (xy 268.585544 -429.794989)
			(xy 268.733488 -429.697332) (xy 268.885665 -429.606411) (xy 269.041768 -429.522408) (xy 269.201482 -429.445494)
			(xy 269.364487 -429.375822) (xy 269.530452 -429.313534) (xy 269.699046 -429.258755) (xy 269.869927 -429.211595)
			(xy 270.042752 -429.172149) (xy 270.217173 -429.140496) (xy 270.392838 -429.116701) (xy 270.569394 -429.10081)
			(xy 270.746485 -429.092857) (xy 270.923755 -429.092857) (xy 271.100846 -429.10081) (xy 271.277402 -429.116701)
			(xy 271.453067 -429.140496) (xy 271.627488 -429.172149) (xy 271.800313 -429.211595) (xy 271.971194 -429.258755)
			(xy 272.139788 -429.313534) (xy 272.305753 -429.375822) (xy 272.468758 -429.445494) (xy 272.628472 -429.522408)
			(xy 272.784575 -429.606411) (xy 272.936752 -429.697332) (xy 273.084696 -429.794989) (xy 273.22811 -429.899186)
			(xy 273.366705 -430.009712) (xy 273.500202 -430.126344) (xy 273.628331 -430.248849) (xy 273.750836 -430.376978)
			(xy 273.867468 -430.510475) (xy 273.977994 -430.64907) (xy 274.082191 -430.792484) (xy 274.179848 -430.940428)
			(xy 274.270769 -431.092605) (xy 274.354772 -431.248708) (xy 274.431686 -431.408422) (xy 274.496787 -431.560732)
			(xy 314.141104 -431.560732) (xy 314.141104 -429.019208) (xy 314.141523 -429.007099) (xy 314.149021 -428.984071)
			(xy 314.163281 -428.964498) (xy 314.182903 -428.950303) (xy 314.205956 -428.942883) (xy 314.218066 -428.9425)
			(xy 315.157866 -428.9425) (xy 315.16995 -428.943036) (xy 315.192943 -428.950478) (xy 315.206836 -428.960534)
			(xy 316.1411 -428.960534) (xy 316.1411 -428.233586) (xy 316.141382 -428.224751) (xy 316.145496 -428.207563)
			(xy 316.149228 -428.19955) (xy 316.382654 -427.7233) (xy 316.387341 -427.712778) (xy 316.390833 -427.690023)
			(xy 316.387355 -427.667267) (xy 316.382654 -427.656752) (xy 316.149228 -427.180502) (xy 316.145474 -427.172496)
			(xy 316.141356 -427.155304) (xy 316.1411 -427.146466) (xy 316.1411 -426.41901) (xy 316.14162 -426.4069)
			(xy 316.1491 -426.383863) (xy 316.163331 -426.364265) (xy 316.18292 -426.350022) (xy 316.205952 -426.342527)
			(xy 316.218062 -426.342048) (xy 317.157862 -426.342048) (xy 317.169984 -426.342492) (xy 317.193043 -426.349975)
			(xy 317.21266 -426.36422) (xy 317.226912 -426.383832) (xy 317.234403 -426.406888) (xy 317.234824 -426.41901)
			(xy 317.234824 -427.960536) (xy 318.141096 -427.960536) (xy 318.141096 -427.233588) (xy 318.141379 -427.224753)
			(xy 318.145492 -427.207566) (xy 318.149224 -427.199552) (xy 318.38265 -426.723302) (xy 318.387336 -426.71278)
			(xy 318.390828 -426.690025) (xy 318.387351 -426.667269) (xy 318.38265 -426.656754) (xy 318.149224 -426.180504)
			(xy 318.14547 -426.172498) (xy 318.141352 -426.155306) (xy 318.141096 -426.146468) (xy 318.141096 -425.419012)
			(xy 318.141527 -425.406904) (xy 318.149022 -425.383878) (xy 318.16328 -425.364305) (xy 318.182899 -425.35011)
			(xy 318.205949 -425.342688) (xy 318.218058 -425.342304) (xy 319.157858 -425.342304) (xy 319.169942 -425.342842)
			(xy 319.192935 -425.350283) (xy 319.212513 -425.364453) (xy 319.226766 -425.383969) (xy 319.234305 -425.40693)
			(xy 319.23482 -425.419012) (xy 319.23482 -427.960536) (xy 319.234415 -427.972645) (xy 319.226908 -427.99567)
			(xy 319.212643 -428.01524) (xy 319.19302 -428.029435) (xy 319.169968 -428.036858) (xy 319.157858 -428.037244)
			(xy 318.218058 -428.037244) (xy 318.205965 -428.036828) (xy 318.18296 -428.029358) (xy 318.163379 -428.015159)
			(xy 318.149131 -427.995614) (xy 318.141603 -427.972628) (xy 318.141096 -427.960536) (xy 317.234824 -427.960536)
			(xy 317.234824 -428.960534) (xy 317.234469 -428.972662) (xy 317.226962 -428.995729) (xy 317.212695 -429.015347)
			(xy 317.193064 -429.029595) (xy 317.169991 -429.03708) (xy 317.157862 -429.037496) (xy 316.218062 -429.037496)
			(xy 316.205949 -429.037021) (xy 316.18291 -429.029528) (xy 316.163312 -429.015285) (xy 316.14907 -428.995686)
			(xy 316.141578 -428.972647) (xy 316.1411 -428.960534) (xy 315.206836 -428.960534) (xy 315.21252 -428.964648)
			(xy 315.226773 -428.984165) (xy 315.234313 -429.007126) (xy 315.234828 -429.019208) (xy 315.234828 -431.560732)
			(xy 315.234411 -431.57284) (xy 315.226906 -431.595863) (xy 315.212644 -431.615433) (xy 315.193025 -431.629628)
			(xy 315.169975 -431.637053) (xy 315.157866 -431.63744) (xy 314.218066 -431.63744) (xy 314.205973 -431.637021)
			(xy 314.182968 -431.629553) (xy 314.163386 -431.615354) (xy 314.149138 -431.59581) (xy 314.14161 -431.572824)
			(xy 314.141104 -431.560732) (xy 274.496787 -431.560732) (xy 274.501358 -431.571427) (xy 274.563646 -431.737392)
			(xy 274.618425 -431.905986) (xy 274.665585 -432.076867) (xy 274.705031 -432.249692) (xy 274.736684 -432.424113)
			(xy 274.760479 -432.599778) (xy 274.77637 -432.776334) (xy 274.784323 -432.953425) (xy 274.78482 -433.04206)
			(xy 274.784323 -433.130695) (xy 274.77637 -433.307786) (xy 274.760479 -433.484342) (xy 274.736684 -433.660007)
			(xy 274.705031 -433.834428) (xy 274.665585 -434.007253) (xy 274.618425 -434.178134) (xy 274.563646 -434.346728)
			(xy 274.501358 -434.512693) (xy 274.431686 -434.675698) (xy 274.354772 -434.835412) (xy 274.270769 -434.991515)
			(xy 274.179848 -435.143692) (xy 274.168638 -435.160674) (xy 314.141104 -435.160674) (xy 314.141104 -432.61915)
			(xy 314.141569 -432.607036) (xy 314.149065 -432.583997) (xy 314.163311 -432.564399) (xy 314.182911 -432.550158)
			(xy 314.205952 -432.542666) (xy 314.218066 -432.542188) (xy 315.157866 -432.542188) (xy 315.169974 -432.54274)
			(xy 315.193008 -432.550212) (xy 315.207501 -432.56073) (xy 316.1411 -432.56073) (xy 316.1411 -430.019206)
			(xy 316.141616 -430.007096) (xy 316.149097 -429.984059) (xy 316.163329 -429.96446) (xy 316.18292 -429.950217)
			(xy 316.205952 -429.942723) (xy 316.218062 -429.942244) (xy 317.157862 -429.942244) (xy 317.169983 -429.942692)
			(xy 317.193042 -429.950175) (xy 317.212658 -429.964419) (xy 317.226911 -429.984029) (xy 317.234403 -430.007085)
			(xy 317.234824 -430.019206) (xy 317.234824 -431.560732) (xy 318.141096 -431.560732) (xy 318.141096 -429.019208)
			(xy 318.141523 -429.0071) (xy 318.14902 -428.984073) (xy 318.163279 -428.964501) (xy 318.182898 -428.950305)
			(xy 318.205949 -428.942884) (xy 318.218058 -428.9425) (xy 319.157858 -428.9425) (xy 319.169941 -428.943042)
			(xy 319.192934 -428.950483) (xy 319.206822 -428.960534) (xy 320.141092 -428.960534) (xy 320.141092 -428.233586)
			(xy 320.141375 -428.224751) (xy 320.145488 -428.207564) (xy 320.14922 -428.19955) (xy 320.382646 -427.7233)
			(xy 320.387333 -427.712778) (xy 320.390826 -427.690023) (xy 320.387347 -427.667267) (xy 320.382646 -427.656752)
			(xy 320.14922 -427.180502) (xy 320.145465 -427.172496) (xy 320.141348 -427.155304) (xy 320.141092 -427.146466)
			(xy 320.141092 -426.41901) (xy 320.14162 -426.406901) (xy 320.149099 -426.383865) (xy 320.163328 -426.364268)
			(xy 320.182915 -426.350024) (xy 320.205945 -426.342528) (xy 320.218054 -426.342048) (xy 321.157854 -426.342048)
			(xy 321.169975 -426.342499) (xy 321.193034 -426.34998) (xy 321.212651 -426.364223) (xy 321.226904 -426.383833)
			(xy 321.234395 -426.406889) (xy 321.234816 -426.41901) (xy 321.234816 -427.960536) (xy 322.141088 -427.960536)
			(xy 322.141088 -427.233588) (xy 322.141372 -427.224753) (xy 322.145485 -427.207566) (xy 322.149216 -427.199552)
			(xy 322.382642 -426.723302) (xy 322.387328 -426.71278) (xy 322.390821 -426.690025) (xy 322.387343 -426.667269)
			(xy 322.382642 -426.656754) (xy 322.149216 -426.180504) (xy 322.145461 -426.172498) (xy 322.141344 -426.155306)
			(xy 322.141088 -426.146468) (xy 322.141088 -425.419012) (xy 322.141527 -425.406905) (xy 322.149021 -425.38388)
			(xy 322.163277 -425.364308) (xy 322.182894 -425.350113) (xy 322.205942 -425.342689) (xy 322.21805 -425.342304)
			(xy 323.15785 -425.342304) (xy 323.169933 -425.342849) (xy 323.192926 -425.350288) (xy 323.212504 -425.364455)
			(xy 323.226758 -425.383971) (xy 323.234297 -425.406931) (xy 323.234812 -425.419012) (xy 323.234812 -427.960536)
			(xy 323.234414 -427.972646) (xy 323.226907 -427.995672) (xy 323.21264 -428.015243) (xy 323.193015 -428.029437)
			(xy 323.169961 -428.036859) (xy 323.15785 -428.037244) (xy 322.21805 -428.037244) (xy 322.205961 -428.03675)
			(xy 322.18296 -428.029305) (xy 322.163378 -428.015126) (xy 322.149126 -427.995597) (xy 322.141595 -427.972623)
			(xy 322.141088 -427.960536) (xy 321.234816 -427.960536) (xy 321.234816 -428.960534) (xy 321.234468 -428.972663)
			(xy 321.226961 -428.995731) (xy 321.212692 -429.015349) (xy 321.193059 -429.029598) (xy 321.169984 -429.037081)
			(xy 321.157854 -429.037496) (xy 320.218054 -429.037496) (xy 320.20594 -429.037028) (xy 320.182901 -429.029532)
			(xy 320.163303 -429.015288) (xy 320.149062 -428.995688) (xy 320.14157 -428.972648) (xy 320.141092 -428.960534)
			(xy 319.206822 -428.960534) (xy 319.212511 -428.964651) (xy 319.226765 -428.984167) (xy 319.234305 -429.007127)
			(xy 319.23482 -429.019208) (xy 319.23482 -431.560732) (xy 319.234411 -431.572841) (xy 319.226905 -431.595865)
			(xy 319.212641 -431.615436) (xy 319.19302 -431.62963) (xy 319.169968 -431.637054) (xy 319.157858 -431.63744)
			(xy 318.218058 -431.63744) (xy 318.205964 -431.637028) (xy 318.182959 -431.629557) (xy 318.163378 -431.615357)
			(xy 318.149129 -431.595811) (xy 318.141602 -431.572825) (xy 318.141096 -431.560732) (xy 317.234824 -431.560732)
			(xy 317.234824 -432.56073) (xy 317.234465 -432.572858) (xy 317.22696 -432.595924) (xy 317.212694 -432.615542)
			(xy 317.193063 -432.629791) (xy 317.169991 -432.637276) (xy 317.157862 -432.637692) (xy 316.218062 -432.637692)
			(xy 316.205948 -432.637221) (xy 316.182909 -432.629727) (xy 316.163311 -432.615484) (xy 316.149069 -432.595884)
			(xy 316.141578 -432.572844) (xy 316.1411 -432.56073) (xy 315.207501 -432.56073) (xy 315.212606 -432.564435)
			(xy 315.22685 -432.584017) (xy 315.234347 -432.607043) (xy 315.234828 -432.61915) (xy 315.234828 -435.160674)
			(xy 315.234417 -435.172799) (xy 315.226928 -435.195863) (xy 315.212675 -435.215481) (xy 315.193055 -435.229732)
			(xy 315.169991 -435.237219) (xy 315.157866 -435.237636) (xy 314.218066 -435.237636) (xy 314.205947 -435.237217)
			(xy 314.182898 -435.229717) (xy 314.163295 -435.215462) (xy 314.149055 -435.195848) (xy 314.141574 -435.172793)
			(xy 314.141104 -435.160674) (xy 274.168638 -435.160674) (xy 274.082191 -435.291636) (xy 273.977994 -435.43505)
			(xy 273.867468 -435.573645) (xy 273.750836 -435.707142) (xy 273.628331 -435.835271) (xy 273.500202 -435.957776)
			(xy 273.366705 -436.074408) (xy 273.22811 -436.184934) (xy 273.084696 -436.289131) (xy 272.936752 -436.386788)
			(xy 272.784575 -436.477709) (xy 272.628472 -436.561712) (xy 272.468758 -436.638626) (xy 272.305753 -436.708298)
			(xy 272.139788 -436.770586) (xy 271.971194 -436.825365) (xy 271.800313 -436.872525) (xy 271.627488 -436.911971)
			(xy 271.453067 -436.943624) (xy 271.277402 -436.967419) (xy 271.100846 -436.98331) (xy 270.923755 -436.991263)
			(xy 270.746485 -436.991263) (xy 270.569394 -436.98331) (xy 270.392838 -436.967419) (xy 270.217173 -436.943624)
			(xy 270.042752 -436.911971) (xy 269.869927 -436.872525) (xy 269.699046 -436.825365) (xy 269.530452 -436.770586)
			(xy 269.364487 -436.708298) (xy 269.201482 -436.638626) (xy 269.041768 -436.561712) (xy 268.885665 -436.477709)
			(xy 268.733488 -436.386788) (xy 268.585544 -436.289131) (xy 268.44213 -436.184934) (xy 268.303535 -436.074408)
			(xy 268.170038 -435.957776) (xy 268.041909 -435.835271) (xy 267.919404 -435.707142) (xy 267.802772 -435.573645)
			(xy 267.692246 -435.43505) (xy 267.588049 -435.291636) (xy 267.490392 -435.143692) (xy 267.399471 -434.991515)
			(xy 267.315468 -434.835412) (xy 267.238554 -434.675698) (xy 267.168882 -434.512693) (xy 267.106594 -434.346728)
			(xy 267.051815 -434.178134) (xy 267.004655 -434.007253) (xy 266.965209 -433.834428) (xy 266.933556 -433.660007)
			(xy 266.909761 -433.484342) (xy 266.89387 -433.307786) (xy 266.885917 -433.130695) (xy 230.3145 -433.130695)
			(xy 230.3145 -435.873652) (xy 230.314033 -435.898602) (xy 230.306213 -435.947887) (xy 230.29079 -435.995345)
			(xy 230.268141 -436.03981) (xy 230.238824 -436.080191) (xy 230.221536 -436.098188) (xy 229.299008 -437.020716)
			(xy 229.281016 -437.03801) (xy 229.240639 -437.067332) (xy 229.196172 -437.089979) (xy 229.148711 -437.105393)
			(xy 229.099423 -437.113193) (xy 229.074472 -437.11368) (xy 207.302608 -437.11368) (xy 207.27766 -437.113152)
			(xy 207.22838 -437.105344) (xy 207.180923 -437.089933) (xy 207.136457 -437.067299) (xy 207.096072 -437.037997)
			(xy 207.078072 -437.020716) (xy 205.512924 -435.455568) (xy 205.495618 -435.437587) (xy 205.466295 -435.397208)
			(xy 205.44365 -435.352738) (xy 205.42824 -435.305274) (xy 205.420444 -435.255984) (xy 205.41996 -435.231032)
			(xy 205.41996 -431.836068) (xy 205.419562 -431.825996) (xy 205.411823 -431.807397) (xy 205.404974 -431.8)
			(xy 204.586586 -430.981612) (xy 204.579871 -430.975414) (xy 204.563254 -430.96784) (xy 204.545036 -430.96659)
			(xy 204.52754 -430.971821) (xy 204.520038 -430.97704) (xy 204.424534 -431.04943) (xy 204.416914 -431.086514)
			(xy 204.426312 -431.103278) (xy 204.471058 -431.183788) (xy 204.553904 -431.348323) (xy 204.628987 -431.516542)
			(xy 204.696145 -431.688079) (xy 204.75523 -431.862561) (xy 204.806115 -432.039609) (xy 204.848688 -432.218837)
			(xy 204.882858 -432.399855) (xy 204.908549 -432.58227) (xy 204.925705 -432.765684) (xy 204.934291 -432.949699)
			(xy 204.93482 -433.041806) (xy 204.93482 -433.04206) (xy 204.934323 -433.130695) (xy 204.92637 -433.307786)
			(xy 204.910479 -433.484342) (xy 204.886684 -433.660007) (xy 204.855031 -433.834428) (xy 204.815585 -434.007253)
			(xy 204.768425 -434.178134) (xy 204.713646 -434.346728) (xy 204.651358 -434.512693) (xy 204.581686 -434.675698)
			(xy 204.504772 -434.835412) (xy 204.420769 -434.991515) (xy 204.329848 -435.143692) (xy 204.232191 -435.291636)
			(xy 204.127994 -435.43505) (xy 204.017468 -435.573645) (xy 203.900836 -435.707142) (xy 203.778331 -435.835271)
			(xy 203.650202 -435.957776) (xy 203.516705 -436.074408) (xy 203.37811 -436.184934) (xy 203.234696 -436.289131)
			(xy 203.086752 -436.386788) (xy 202.934575 -436.477709) (xy 202.778472 -436.561712) (xy 202.618758 -436.638626)
			(xy 202.455753 -436.708298) (xy 202.289788 -436.770586) (xy 202.121194 -436.825365) (xy 201.950313 -436.872525)
			(xy 201.777488 -436.911971) (xy 201.603067 -436.943624) (xy 201.427402 -436.967419) (xy 201.250846 -436.98331)
			(xy 201.073755 -436.991263) (xy 200.896485 -436.991263) (xy 200.719394 -436.98331) (xy 200.542838 -436.967419)
			(xy 200.367173 -436.943624) (xy 200.192752 -436.911971) (xy 200.019927 -436.872525) (xy 199.849046 -436.825365)
			(xy 199.680452 -436.770586) (xy 199.514487 -436.708298) (xy 199.351482 -436.638626) (xy 199.191768 -436.561712)
			(xy 199.035665 -436.477709) (xy 198.883488 -436.386788) (xy 198.735544 -436.289131) (xy 198.59213 -436.184934)
			(xy 198.453535 -436.074408) (xy 198.320038 -435.957776) (xy 198.191909 -435.835271) (xy 198.069404 -435.707142)
			(xy 197.952772 -435.573645) (xy 197.842246 -435.43505) (xy 197.738049 -435.291636) (xy 197.640392 -435.143692)
			(xy 197.549471 -434.991515) (xy 197.465468 -434.835412) (xy 197.388554 -434.675698) (xy 197.318882 -434.512693)
			(xy 197.256594 -434.346728) (xy 197.201815 -434.178134) (xy 197.154655 -434.007253) (xy 197.115209 -433.834428)
			(xy 197.083556 -433.660007) (xy 197.059761 -433.484342) (xy 197.04387 -433.307786) (xy 197.035917 -433.130695)
			(xy 197.035917 -432.953425) (xy 197.04387 -432.776334) (xy 197.059761 -432.599778) (xy 197.083556 -432.424113)
			(xy 197.115209 -432.249692) (xy 197.154655 -432.076867) (xy 197.201815 -431.905986) (xy 197.256594 -431.737392)
			(xy 197.318882 -431.571427) (xy 197.388554 -431.408422) (xy 197.465468 -431.248708) (xy 197.549471 -431.092605)
			(xy 197.640392 -430.940428) (xy 197.738049 -430.792484) (xy 197.842246 -430.64907) (xy 197.952772 -430.510475)
			(xy 198.069404 -430.376978) (xy 198.191909 -430.248849) (xy 198.320038 -430.126344) (xy 198.453535 -430.009712)
			(xy 198.59213 -429.899186) (xy 198.735544 -429.794989) (xy 198.883488 -429.697332) (xy 199.035665 -429.606411)
			(xy 199.191768 -429.522408) (xy 199.351482 -429.445494) (xy 199.514487 -429.375822) (xy 199.680452 -429.313534)
			(xy 199.849046 -429.258755) (xy 200.019927 -429.211595) (xy 200.192752 -429.172149) (xy 200.367173 -429.140496)
			(xy 200.542838 -429.116701) (xy 200.719394 -429.10081) (xy 200.896485 -429.092857) (xy 200.98512 -429.09236)
			(xy 200.985374 -429.09236) (xy 201.07748 -429.092926) (xy 201.261492 -429.101525) (xy 201.444903 -429.118692)
			(xy 201.627315 -429.144389) (xy 201.80833 -429.17856) (xy 201.987556 -429.221132) (xy 202.164603 -429.272011)
			(xy 202.339086 -429.331088) (xy 202.510625 -429.398233) (xy 202.678849 -429.4733) (xy 202.84339 -429.556127)
			(xy 202.923902 -429.600868) (xy 202.932044 -429.605072) (xy 202.950138 -429.607899) (xy 202.968075 -429.604204)
			(xy 202.983579 -429.594457) (xy 202.989434 -429.587406) (xy 203.05014 -429.507396) (xy 203.055391 -429.49992)
			(xy 203.060685 -429.482447) (xy 203.059501 -429.464229) (xy 203.05199 -429.447588) (xy 203.045822 -429.440848)
			(xy 194.790822 -421.185594) (xy 194.763915 -421.158053) (xy 194.715832 -421.097913) (xy 194.674792 -421.032763)
			(xy 194.641312 -420.963424) (xy 194.615814 -420.89077) (xy 194.598619 -420.815716) (xy 194.589944 -420.739207)
			(xy 194.5894 -420.700708) (xy 102.15118 -420.700708) (xy 102.15118 -421.122094) (xy 102.150662 -421.132249)
			(xy 102.142893 -421.151015) (xy 102.128535 -421.16538) (xy 102.109773 -421.173157) (xy 102.099618 -421.173656)
			(xy 97.200974 -421.173656) (xy 97.190814 -421.173188) (xy 97.172043 -421.165404) (xy 97.157678 -421.15103)
			(xy 97.149906 -421.132255) (xy 97.149412 -421.122094) (xy 75.844472 -421.122094) (xy 75.826048 -421.150762)
			(xy 75.790333 -421.191979) (xy 75.749116 -421.227694) (xy 75.703235 -421.25718) (xy 75.653625 -421.279837)
			(xy 75.601295 -421.295202) (xy 75.547311 -421.302964) (xy 75.492773 -421.302964) (xy 75.438789 -421.295202)
			(xy 75.386459 -421.279837) (xy 75.336849 -421.25718) (xy 75.290968 -421.227694) (xy 75.249751 -421.191979)
			(xy 75.214036 -421.150762) (xy 75.18455 -421.104881) (xy 75.161893 -421.055271) (xy 75.146528 -421.002941)
			(xy 75.138766 -420.948957) (xy 75.13828 -420.921688) (xy 73.234804 -420.921688) (xy 73.234804 -421.760396)
			(xy 73.234381 -421.772504) (xy 73.226883 -421.795531) (xy 73.212623 -421.815104) (xy 73.193003 -421.829299)
			(xy 73.169952 -421.83672) (xy 73.157842 -421.837104) (xy 72.218042 -421.837104) (xy 72.205959 -421.836558)
			(xy 72.182967 -421.829118) (xy 72.16339 -421.81495) (xy 72.149137 -421.795436) (xy 72.141596 -421.772477)
			(xy 72.14108 -421.760396) (xy 71.207209 -421.760396) (xy 71.212598 -421.764313) (xy 71.226839 -421.783915)
			(xy 71.23433 -421.806956) (xy 71.234808 -421.81907) (xy 71.234808 -424.360594) (xy 71.234284 -424.372704)
			(xy 71.226804 -424.395739) (xy 71.212574 -424.415337) (xy 71.192985 -424.42958) (xy 71.169955 -424.437076)
			(xy 71.157846 -424.437556) (xy 70.218046 -424.437556) (xy 70.205925 -424.437101) (xy 70.182867 -424.429621)
			(xy 70.16325 -424.415378) (xy 70.148998 -424.395769) (xy 70.141505 -424.372715) (xy 70.141084 -424.360594)
			(xy 69.234812 -424.360594) (xy 69.234812 -425.360592) (xy 69.234377 -425.372699) (xy 69.226881 -425.395724)
			(xy 69.212624 -425.415297) (xy 69.193007 -425.429492) (xy 69.169959 -425.436915) (xy 69.15785 -425.4373)
			(xy 68.21805 -425.4373) (xy 68.205967 -425.436751) (xy 68.182975 -425.429313) (xy 68.163397 -425.415146)
			(xy 68.149144 -425.395632) (xy 68.141603 -425.372673) (xy 68.141088 -425.360592) (xy 67.207172 -425.360592)
			(xy 67.212508 -425.364454) (xy 67.226762 -425.38397) (xy 67.234301 -425.40693) (xy 67.234816 -425.419012)
			(xy 67.234816 -427.960536) (xy 67.234415 -427.972645) (xy 67.226907 -427.995671) (xy 67.212641 -428.015242)
			(xy 67.193018 -428.029436) (xy 67.169965 -428.036859) (xy 67.157854 -428.037244) (xy 66.218054 -428.037244)
			(xy 66.20596 -428.036832) (xy 66.182956 -428.02936) (xy 66.163375 -428.01516) (xy 66.149127 -427.995615)
			(xy 66.141599 -427.972628) (xy 66.141092 -427.960536) (xy 65.23482 -427.960536) (xy 65.23482 -428.960534)
			(xy 65.234469 -428.972663) (xy 65.226962 -428.99573) (xy 65.212694 -429.015348) (xy 65.193062 -429.029597)
			(xy 65.169987 -429.03708) (xy 65.157858 -429.037496) (xy 64.218058 -429.037496) (xy 64.205945 -429.037025)
			(xy 64.182906 -429.02953) (xy 64.163308 -429.015287) (xy 64.149066 -428.995687) (xy 64.141574 -428.972647)
			(xy 64.141096 -428.960534) (xy 63.207499 -428.960534) (xy 63.212603 -428.964238) (xy 63.226847 -428.98382)
			(xy 63.234343 -429.006847) (xy 63.234824 -429.018954) (xy 63.234824 -431.560478) (xy 63.234421 -431.572603)
			(xy 63.22693 -431.595668) (xy 63.212675 -431.615287) (xy 63.193054 -431.629537) (xy 63.169987 -431.637023)
			(xy 63.157862 -431.63744) (xy 62.218062 -431.63744) (xy 62.205943 -431.63702) (xy 62.182895 -431.62952)
			(xy 62.163292 -431.615265) (xy 62.149053 -431.595651) (xy 62.14157 -431.572597) (xy 62.1411 -431.560478)
			(xy 61.234828 -431.560478) (xy 61.234828 -432.560476) (xy 61.234363 -432.572581) (xy 61.226874 -432.595602)
			(xy 61.212624 -432.615174) (xy 61.193014 -432.62937) (xy 61.169972 -432.636796) (xy 61.157866 -432.637184)
			(xy 60.218066 -432.637184) (xy 60.205977 -432.636722) (xy 60.182979 -432.629259) (xy 60.163402 -432.61507)
			(xy 60.149152 -432.595538) (xy 60.141616 -432.572563) (xy 60.141104 -432.560476) (xy 59.207158 -432.560476)
			(xy 59.21261 -432.564433) (xy 59.226854 -432.584016) (xy 59.234351 -432.607042) (xy 59.234832 -432.61915)
			(xy 59.234832 -435.160674) (xy 59.234417 -435.172798) (xy 59.226929 -435.195861) (xy 59.212677 -435.21548)
			(xy 59.193058 -435.229731) (xy 59.169994 -435.237218) (xy 59.15787 -435.237636) (xy 58.21807 -435.237636)
			(xy 58.205951 -435.237214) (xy 58.182903 -435.229715) (xy 58.163299 -435.215461) (xy 58.14906 -435.195847)
			(xy 58.141578 -435.172793) (xy 58.141108 -435.160674) (xy 7.00913 -435.160674) (xy 7.00913 -438.760616)
			(xy 58.141108 -438.760616) (xy 58.141108 -436.219092) (xy 58.141509 -436.206982) (xy 58.149012 -436.183953)
			(xy 58.163277 -436.164379) (xy 58.182902 -436.150185) (xy 58.205958 -436.142766) (xy 58.21807 -436.142384)
			(xy 59.15787 -436.142384) (xy 59.169962 -436.142834) (xy 59.192969 -436.150288) (xy 59.207302 -436.160672)
			(xy 60.141104 -436.160672) (xy 60.141104 -433.619148) (xy 60.141557 -433.607041) (xy 60.149044 -433.584015)
			(xy 60.163296 -433.564441) (xy 60.18291 -433.550244) (xy 60.205958 -433.542823) (xy 60.218066 -433.54244)
			(xy 61.157866 -433.54244) (xy 61.169954 -433.542936) (xy 61.192953 -433.550384) (xy 61.212534 -433.564563)
			(xy 61.226786 -433.58409) (xy 61.234318 -433.607062) (xy 61.234828 -433.619148) (xy 61.234828 -435.160674)
			(xy 62.1411 -435.160674) (xy 62.1411 -432.61915) (xy 62.141569 -432.607037) (xy 62.149065 -432.583998)
			(xy 62.163309 -432.564401) (xy 62.182909 -432.550159) (xy 62.205949 -432.542667) (xy 62.218062 -432.542188)
			(xy 63.157862 -432.542188) (xy 63.16997 -432.542743) (xy 63.193003 -432.550214) (xy 63.207144 -432.560476)
			(xy 64.141096 -432.560476) (xy 64.141096 -430.018952) (xy 64.141476 -430.006841) (xy 64.148988 -429.983813)
			(xy 64.163259 -429.964241) (xy 64.182888 -429.950048) (xy 64.205945 -429.942628) (xy 64.218058 -429.942244)
			(xy 65.157858 -429.942244) (xy 65.169946 -429.942743) (xy 65.192946 -429.950189) (xy 65.212527 -429.964367)
			(xy 65.226779 -429.983894) (xy 65.234311 -430.006866) (xy 65.23482 -430.018952) (xy 65.23482 -431.560478)
			(xy 66.141092 -431.560478) (xy 66.141092 -429.018954) (xy 66.141572 -429.006842) (xy 66.149066 -428.983805)
			(xy 66.163308 -428.964208) (xy 66.182905 -428.949966) (xy 66.205942 -428.942472) (xy 66.218054 -428.941992)
			(xy 67.157854 -428.941992) (xy 67.169962 -428.94255) (xy 67.192996 -428.950019) (xy 67.207487 -428.960534)
			(xy 68.141088 -428.960534) (xy 68.141088 -428.233586) (xy 68.141371 -428.224751) (xy 68.145484 -428.207564)
			(xy 68.149216 -428.19955) (xy 68.382642 -427.7233) (xy 68.387329 -427.712778) (xy 68.390822 -427.690023)
			(xy 68.387343 -427.667267) (xy 68.382642 -427.656752) (xy 68.149216 -427.180502) (xy 68.145461 -427.172496)
			(xy 68.141344 -427.155304) (xy 68.141088 -427.146466) (xy 68.141088 -426.41901) (xy 68.14162 -426.406901)
			(xy 68.149098 -426.383867) (xy 68.163326 -426.364269) (xy 68.182913 -426.350025) (xy 68.205941 -426.342529)
			(xy 68.21805 -426.342048) (xy 69.15785 -426.342048) (xy 69.169968 -426.342469) (xy 69.193015 -426.349972)
			(xy 69.212616 -426.364226) (xy 69.226856 -426.383839) (xy 69.23434 -426.406891) (xy 69.234812 -426.41901)
			(xy 69.234812 -427.960536) (xy 70.141084 -427.960536) (xy 70.141084 -427.233588) (xy 70.141368 -427.224753)
			(xy 70.145481 -427.207566) (xy 70.149212 -427.199552) (xy 70.382638 -426.723302) (xy 70.387324 -426.71278)
			(xy 70.390818 -426.690025) (xy 70.387339 -426.667268) (xy 70.382638 -426.656754) (xy 70.149212 -426.180504)
			(xy 70.145457 -426.172498) (xy 70.14134 -426.155306) (xy 70.141084 -426.146468) (xy 70.141084 -425.419012)
			(xy 70.141527 -425.406905) (xy 70.149021 -425.383881) (xy 70.163276 -425.364309) (xy 70.182891 -425.350114)
			(xy 70.205938 -425.34269) (xy 70.218046 -425.342304) (xy 71.157846 -425.342304) (xy 71.169934 -425.342767)
			(xy 71.19293 -425.350232) (xy 71.207224 -425.360592) (xy 72.14108 -425.360592) (xy 72.14108 -422.819068)
			(xy 72.141489 -422.806959) (xy 72.148995 -422.783935) (xy 72.163259 -422.764364) (xy 72.18288 -422.75017)
			(xy 72.205932 -422.742746) (xy 72.218042 -422.74236) (xy 73.157842 -422.74236) (xy 73.169936 -422.742772)
			(xy 73.192941 -422.750243) (xy 73.212522 -422.764443) (xy 73.226771 -422.783989) (xy 73.234298 -422.806975)
			(xy 73.234804 -422.819068) (xy 73.234804 -424.80464) (xy 109.929157 -424.80464) (xy 109.929157 -424.6755)
			(xy 109.937107 -424.546605) (xy 109.952977 -424.418445) (xy 109.976706 -424.291504) (xy 110.008205 -424.166265)
			(xy 110.047354 -424.043202) (xy 110.094005 -423.922783) (xy 110.14798 -423.805464) (xy 110.209075 -423.69169)
			(xy 110.277058 -423.581893) (xy 110.351672 -423.47649) (xy 110.432633 -423.37588) (xy 110.519633 -423.280445)
			(xy 110.612344 -423.190546) (xy 110.710414 -423.106525) (xy 110.813469 -423.028701) (xy 110.92112 -422.957369)
			(xy 111.032959 -422.892799) (xy 111.14856 -422.835237) (xy 111.267485 -422.7849) (xy 111.389284 -422.74198)
			(xy 111.513494 -422.706639) (xy 111.639643 -422.679012) (xy 111.767255 -422.659203) (xy 111.895844 -422.647287)
			(xy 112.024922 -422.643311) (xy 112.154 -422.647287) (xy 112.282589 -422.659203) (xy 112.410201 -422.679012)
			(xy 112.53635 -422.706639) (xy 112.66056 -422.74198) (xy 112.782359 -422.7849) (xy 112.901284 -422.835237)
			(xy 113.016885 -422.892799) (xy 113.128724 -422.957369) (xy 113.236375 -423.028701) (xy 113.33943 -423.106525)
			(xy 113.4375 -423.190546) (xy 113.530211 -423.280445) (xy 113.617211 -423.37588) (xy 113.698172 -423.47649)
			(xy 113.772786 -423.581893) (xy 113.840769 -423.69169) (xy 113.901864 -423.805464) (xy 113.955839 -423.922783)
			(xy 114.00249 -424.043202) (xy 114.041639 -424.166265) (xy 114.073138 -424.291504) (xy 114.096867 -424.418445)
			(xy 114.112737 -424.546605) (xy 114.120687 -424.6755) (xy 114.121184 -424.74007) (xy 114.120687 -424.80464)
			(xy 114.112737 -424.933535) (xy 114.096867 -425.061695) (xy 114.073138 -425.188636) (xy 114.041639 -425.313875)
			(xy 114.00249 -425.436938) (xy 113.955839 -425.557357) (xy 113.901864 -425.674676) (xy 113.840769 -425.78845)
			(xy 113.772786 -425.898247) (xy 113.698172 -426.00365) (xy 113.617211 -426.10426) (xy 113.530211 -426.199695)
			(xy 113.4375 -426.289594) (xy 113.33943 -426.373615) (xy 113.236375 -426.451439) (xy 113.128724 -426.522771)
			(xy 113.016885 -426.587341) (xy 112.901284 -426.644903) (xy 112.782359 -426.69524) (xy 112.66056 -426.73816)
			(xy 112.53635 -426.773501) (xy 112.410201 -426.801128) (xy 112.282589 -426.820937) (xy 112.154 -426.832853)
			(xy 112.024922 -426.83683) (xy 111.895844 -426.832853) (xy 111.767255 -426.820937) (xy 111.639643 -426.801128)
			(xy 111.513494 -426.773501) (xy 111.389284 -426.73816) (xy 111.267485 -426.69524) (xy 111.14856 -426.644903)
			(xy 111.032959 -426.587341) (xy 110.92112 -426.522771) (xy 110.813469 -426.451439) (xy 110.710414 -426.373615)
			(xy 110.612344 -426.289594) (xy 110.519633 -426.199695) (xy 110.432633 -426.10426) (xy 110.351672 -426.00365)
			(xy 110.277058 -425.898247) (xy 110.209075 -425.78845) (xy 110.14798 -425.674676) (xy 110.094005 -425.557357)
			(xy 110.047354 -425.436938) (xy 110.008205 -425.313875) (xy 109.976706 -425.188636) (xy 109.952977 -425.061695)
			(xy 109.937107 -424.933535) (xy 109.929157 -424.80464) (xy 73.234804 -424.80464) (xy 73.234804 -425.360592)
			(xy 73.234377 -425.3727) (xy 73.22688 -425.395727) (xy 73.212621 -425.415299) (xy 73.193002 -425.429495)
			(xy 73.169951 -425.436916) (xy 73.157842 -425.4373) (xy 72.218042 -425.4373) (xy 72.205959 -425.436758)
			(xy 72.182966 -425.429317) (xy 72.163389 -425.415149) (xy 72.149135 -425.395633) (xy 72.141595 -425.372673)
			(xy 72.14108 -425.360592) (xy 71.207224 -425.360592) (xy 71.212507 -425.364421) (xy 71.226757 -425.383953)
			(xy 71.234294 -425.406925) (xy 71.234808 -425.419012) (xy 71.234808 -427.960536) (xy 71.234414 -427.972646)
			(xy 71.226906 -427.995673) (xy 71.212638 -428.015245) (xy 71.193013 -428.029438) (xy 71.169957 -428.03686)
			(xy 71.157846 -428.037244) (xy 70.218046 -428.037244) (xy 70.205957 -428.036753) (xy 70.182955 -428.029307)
			(xy 70.163373 -428.015127) (xy 70.149122 -427.995597) (xy 70.141591 -427.972623) (xy 70.141084 -427.960536)
			(xy 69.234812 -427.960536) (xy 69.234812 -428.960534) (xy 69.234318 -428.972645) (xy 69.226828 -428.995681)
			(xy 69.21259 -429.015278) (xy 69.192996 -429.02952) (xy 69.169961 -429.037016) (xy 69.15785 -429.037496)
			(xy 68.21805 -429.037496) (xy 68.205936 -429.037031) (xy 68.182897 -429.029535) (xy 68.163299 -429.015289)
			(xy 68.149058 -428.995689) (xy 68.141566 -428.972648) (xy 68.141088 -428.960534) (xy 67.207487 -428.960534)
			(xy 67.212594 -428.96424) (xy 67.226839 -428.983822) (xy 67.234335 -429.006847) (xy 67.234816 -429.018954)
			(xy 67.234816 -431.560478) (xy 67.234421 -431.572604) (xy 67.226929 -431.59567) (xy 67.212672 -431.61529)
			(xy 67.193049 -431.62954) (xy 67.16998 -431.637024) (xy 67.157854 -431.63744) (xy 66.218054 -431.63744)
			(xy 66.205935 -431.637027) (xy 66.182886 -431.629525) (xy 66.163284 -431.615268) (xy 66.149044 -431.595653)
			(xy 66.141562 -431.572598) (xy 66.141092 -431.560478) (xy 65.23482 -431.560478) (xy 65.23482 -432.560476)
			(xy 65.234363 -432.572582) (xy 65.226873 -432.595605) (xy 65.212621 -432.615176) (xy 65.193009 -432.629373)
			(xy 65.169965 -432.636797) (xy 65.157858 -432.637184) (xy 64.218058 -432.637184) (xy 64.205969 -432.636729)
			(xy 64.182971 -432.629264) (xy 64.163393 -432.615073) (xy 64.149143 -432.595539) (xy 64.141608 -432.572564)
			(xy 64.141096 -432.560476) (xy 63.207144 -432.560476) (xy 63.212601 -432.564436) (xy 63.226846 -432.584018)
			(xy 63.234343 -432.607043) (xy 63.234824 -432.61915) (xy 63.234824 -435.160674) (xy 63.234417 -435.172799)
			(xy 63.226928 -435.195864) (xy 63.212674 -435.215482) (xy 63.193053 -435.229733) (xy 63.169987 -435.237219)
			(xy 63.157862 -435.237636) (xy 62.218062 -435.237636) (xy 62.205943 -435.23722) (xy 62.182894 -435.229719)
			(xy 62.163291 -435.215464) (xy 62.149051 -435.195849) (xy 62.14157 -435.172794) (xy 62.1411 -435.160674)
			(xy 61.234828 -435.160674) (xy 61.234828 -436.160672) (xy 61.23436 -436.172777) (xy 61.226872 -436.195798)
			(xy 61.212623 -436.215369) (xy 61.193013 -436.229566) (xy 61.169972 -436.236992) (xy 61.157866 -436.23738)
			(xy 60.218066 -436.23738) (xy 60.205977 -436.236922) (xy 60.182978 -436.229458) (xy 60.163401 -436.215269)
			(xy 60.14915 -436.195735) (xy 60.141616 -436.17276) (xy 60.141104 -436.160672) (xy 59.207302 -436.160672)
			(xy 59.212554 -436.164477) (xy 59.226804 -436.184017) (xy 59.234329 -436.207001) (xy 59.234832 -436.219092)
			(xy 59.234832 -438.760616) (xy 59.234398 -438.772723) (xy 59.226898 -438.795745) (xy 59.21264 -438.815315)
			(xy 59.193024 -438.82951) (xy 59.169978 -438.836936) (xy 59.15787 -438.837324) (xy 58.21807 -438.837324)
			(xy 58.205975 -438.836918) (xy 58.182968 -438.829448) (xy 58.163385 -438.815247) (xy 58.149137 -438.795699)
			(xy 58.141612 -438.77271) (xy 58.141108 -438.760616) (xy 7.00913 -438.760616) (xy 7.00913 -439.760614)
			(xy 60.141104 -439.760614) (xy 60.141104 -437.21909) (xy 60.141603 -437.206978) (xy 60.149089 -437.183941)
			(xy 60.163325 -437.164342) (xy 60.182919 -437.1501) (xy 60.205954 -437.142607) (xy 60.218066 -437.142128)
			(xy 61.157866 -437.142128) (xy 61.169986 -437.142589) (xy 61.193042 -437.15007) (xy 61.212657 -437.164312)
			(xy 61.22691 -437.183918) (xy 61.234404 -437.20697) (xy 61.234828 -437.21909) (xy 61.234828 -438.760616)
			(xy 62.1411 -438.760616) (xy 62.1411 -436.219092) (xy 62.141509 -436.206983) (xy 62.149011 -436.183955)
			(xy 62.163274 -436.164382) (xy 62.182897 -436.150188) (xy 62.205951 -436.142767) (xy 62.218062 -436.142384)
			(xy 63.157862 -436.142384) (xy 63.169954 -436.142841) (xy 63.192961 -436.150292) (xy 63.207289 -436.160672)
			(xy 64.141096 -436.160672) (xy 64.141096 -433.619148) (xy 64.141557 -433.607042) (xy 64.149043 -433.584017)
			(xy 64.163293 -433.564443) (xy 64.182905 -433.550247) (xy 64.205951 -433.542824) (xy 64.218058 -433.54244)
			(xy 65.157858 -433.54244) (xy 65.169945 -433.542943) (xy 65.192945 -433.550388) (xy 65.212525 -433.564566)
			(xy 65.226777 -433.584092) (xy 65.23431 -433.607062) (xy 65.23482 -433.619148) (xy 65.23482 -435.160674)
			(xy 66.141092 -435.160674) (xy 66.141092 -432.61915) (xy 66.141568 -432.607037) (xy 66.149064 -432.584)
			(xy 66.163306 -432.564403) (xy 66.182904 -432.550162) (xy 66.205941 -432.542668) (xy 66.218054 -432.542188)
			(xy 67.157854 -432.542188) (xy 67.169961 -432.54275) (xy 67.192995 -432.550219) (xy 67.207131 -432.560476)
			(xy 68.141088 -432.560476) (xy 68.141088 -430.018952) (xy 68.141475 -430.006842) (xy 68.148987 -429.983815)
			(xy 68.163256 -429.964244) (xy 68.182883 -429.95005) (xy 68.205938 -429.942629) (xy 68.21805 -429.942244)
			(xy 69.15785 -429.942244) (xy 69.169937 -429.94275) (xy 69.192937 -429.950193) (xy 69.212518 -429.96437)
			(xy 69.22677 -429.983896) (xy 69.234303 -430.006866) (xy 69.234812 -430.018952) (xy 69.234812 -431.560478)
			(xy 70.141084 -431.560478) (xy 70.141084 -429.018954) (xy 70.141473 -429.006832) (xy 70.148979 -428.98378)
			(xy 70.16324 -428.964175) (xy 70.182862 -428.949937) (xy 70.205924 -428.942459) (xy 70.218046 -428.941992)
			(xy 71.157846 -428.941992) (xy 71.169958 -428.942472) (xy 71.192995 -428.949966) (xy 71.207537 -428.960534)
			(xy 72.14108 -428.960534) (xy 72.14108 -428.233586) (xy 72.141364 -428.224751) (xy 72.145477 -428.207564)
			(xy 72.149208 -428.19955) (xy 72.382634 -427.7233) (xy 72.387322 -427.712778) (xy 72.390815 -427.690023)
			(xy 72.387336 -427.667266) (xy 72.382634 -427.656752) (xy 72.149208 -427.180502) (xy 72.145452 -427.172496)
			(xy 72.141336 -427.155304) (xy 72.14108 -427.146466) (xy 72.14108 -426.41901) (xy 72.141469 -426.406884)
			(xy 72.148964 -426.383818) (xy 72.163222 -426.364199) (xy 72.182847 -426.349949) (xy 72.205915 -426.342464)
			(xy 72.218042 -426.342048) (xy 73.157842 -426.342048) (xy 73.16996 -426.342476) (xy 73.193006 -426.349976)
			(xy 73.212608 -426.364229) (xy 73.226848 -426.383841) (xy 73.234332 -426.406892) (xy 73.234804 -426.41901)
			(xy 73.234804 -427.960536) (xy 75.141328 -427.960536) (xy 75.141328 -427.233588) (xy 75.141574 -427.224768)
			(xy 75.145542 -427.20758) (xy 75.149202 -427.199552) (xy 75.382628 -426.723302) (xy 75.387315 -426.71278)
			(xy 75.390809 -426.690025) (xy 75.38733 -426.667268) (xy 75.382628 -426.656754) (xy 75.149202 -426.180504)
			(xy 75.145519 -426.172483) (xy 75.141542 -426.155292) (xy 75.141328 -426.146468) (xy 75.141328 -425.419012)
			(xy 75.141724 -425.406926) (xy 75.149192 -425.383938) (xy 75.163402 -425.364384) (xy 75.18296 -425.350181)
			(xy 75.20595 -425.34272) (xy 75.218036 -425.342304) (xy 76.157836 -425.342304) (xy 76.169914 -425.342734)
			(xy 76.192884 -425.350207) (xy 76.212422 -425.364413) (xy 76.226615 -425.383959) (xy 76.234074 -425.406934)
			(xy 76.234544 -425.419012) (xy 76.234544 -427.960536) (xy 76.234067 -427.972609) (xy 76.226599 -427.995571)
			(xy 76.212405 -428.015105) (xy 76.192871 -428.029299) (xy 76.169909 -428.036767) (xy 76.157836 -428.037244)
			(xy 75.218036 -428.037244) (xy 75.205967 -428.036706) (xy 75.183007 -428.029258) (xy 75.163472 -428.015079)
			(xy 75.149275 -427.995558) (xy 75.141806 -427.972605) (xy 75.141328 -427.960536) (xy 73.234804 -427.960536)
			(xy 73.234804 -428.960534) (xy 73.234318 -428.972646) (xy 73.226827 -428.995683) (xy 73.212587 -429.015281)
			(xy 73.192991 -429.029523) (xy 73.169954 -429.037017) (xy 73.157842 -429.037496) (xy 72.218042 -429.037496)
			(xy 72.205925 -429.037005) (xy 72.182873 -429.029528) (xy 72.16326 -429.015294) (xy 72.149006 -428.995695)
			(xy 72.141507 -428.972651) (xy 72.14108 -428.960534) (xy 71.207537 -428.960534) (xy 71.212592 -428.964208)
			(xy 71.226834 -428.983805) (xy 71.234328 -429.006842) (xy 71.234808 -429.018954) (xy 71.234808 -431.560478)
			(xy 71.23427 -431.572587) (xy 71.226795 -431.595622) (xy 71.212568 -431.61522) (xy 71.192983 -431.629464)
			(xy 71.169954 -431.636959) (xy 71.157846 -431.63744) (xy 70.218046 -431.63744) (xy 70.205923 -431.637001)
			(xy 70.182862 -431.629518) (xy 70.163245 -431.615273) (xy 70.148993 -431.595659) (xy 70.141503 -431.5726)
			(xy 70.141084 -431.560478) (xy 69.234812 -431.560478) (xy 69.234812 -432.560476) (xy 69.234363 -432.572582)
			(xy 69.226872 -432.595607) (xy 69.212618 -432.615179) (xy 69.193004 -432.629375) (xy 69.169958 -432.636799)
			(xy 69.15785 -432.637184) (xy 68.21805 -432.637184) (xy 68.205965 -432.636651) (xy 68.18297 -432.62921)
			(xy 68.163392 -432.61504) (xy 68.149139 -432.595522) (xy 68.141601 -432.572559) (xy 68.141088 -432.560476)
			(xy 67.207131 -432.560476) (xy 67.212593 -432.564439) (xy 67.226838 -432.584019) (xy 67.234335 -432.607043)
			(xy 67.234816 -432.61915) (xy 67.234816 -435.160674) (xy 67.234417 -435.1728) (xy 67.226927 -435.195866)
			(xy 67.212671 -435.215485) (xy 67.193048 -435.229736) (xy 67.16998 -435.23722) (xy 67.157854 -435.237636)
			(xy 66.218054 -435.237636) (xy 66.205934 -435.237227) (xy 66.182885 -435.229724) (xy 66.163282 -435.215467)
			(xy 66.149043 -435.19585) (xy 66.141562 -435.172794) (xy 66.141092 -435.160674) (xy 65.23482 -435.160674)
			(xy 65.23482 -436.160672) (xy 65.23436 -436.172777) (xy 65.226871 -436.1958) (xy 65.21262 -436.215372)
			(xy 65.193008 -436.229568) (xy 65.169964 -436.236993) (xy 65.157858 -436.23738) (xy 64.218058 -436.23738)
			(xy 64.205968 -436.236929) (xy 64.18297 -436.229463) (xy 64.163392 -436.215272) (xy 64.149142 -436.195737)
			(xy 64.141608 -436.17276) (xy 64.141096 -436.160672) (xy 63.207289 -436.160672) (xy 63.212545 -436.16448)
			(xy 63.226795 -436.184019) (xy 63.234321 -436.207002) (xy 63.234824 -436.219092) (xy 63.234824 -438.760616)
			(xy 63.234398 -438.772723) (xy 63.226897 -438.795747) (xy 63.212637 -438.815318) (xy 63.193019 -438.829513)
			(xy 63.169971 -438.836937) (xy 63.157862 -438.837324) (xy 62.218062 -438.837324) (xy 62.205967 -438.836924)
			(xy 62.182959 -438.829453) (xy 62.163377 -438.81525) (xy 62.149129 -438.795701) (xy 62.141604 -438.77271)
			(xy 62.1411 -438.760616) (xy 61.234828 -438.760616) (xy 61.234828 -439.760614) (xy 64.141096 -439.760614)
			(xy 64.141096 -437.21909) (xy 64.141603 -437.206979) (xy 64.149088 -437.183943) (xy 64.163322 -437.164345)
			(xy 64.182914 -437.150102) (xy 64.205947 -437.142608) (xy 64.218058 -437.142128) (xy 65.157858 -437.142128)
			(xy 65.169978 -437.142595) (xy 65.193033 -437.150075) (xy 65.212648 -437.164315) (xy 65.226901 -437.18392)
			(xy 65.234396 -437.206971) (xy 65.23482 -437.21909) (xy 65.23482 -438.760616) (xy 66.141092 -438.760616)
			(xy 66.141092 -436.219092) (xy 66.141509 -436.206983) (xy 66.14901 -436.183957) (xy 66.163272 -436.164385)
			(xy 66.182892 -436.15019) (xy 66.205944 -436.142768) (xy 66.218054 -436.142384) (xy 67.157854 -436.142384)
			(xy 67.169946 -436.142847) (xy 67.192952 -436.150297) (xy 67.207276 -436.160672) (xy 68.141088 -436.160672)
			(xy 68.141088 -433.619148) (xy 68.141557 -433.607043) (xy 68.149042 -433.584019) (xy 68.16329 -433.564446)
			(xy 68.1829 -433.55025) (xy 68.205944 -433.542826) (xy 68.21805 -433.54244) (xy 69.15785 -433.54244)
			(xy 69.169937 -433.54295) (xy 69.192936 -433.550393) (xy 69.212517 -433.564568) (xy 69.226769 -433.584093)
			(xy 69.234302 -433.607063) (xy 69.234812 -433.619148) (xy 69.234812 -435.160674) (xy 70.141084 -435.160674)
			(xy 70.141084 -432.61915) (xy 70.14147 -432.607028) (xy 70.148976 -432.583976) (xy 70.163239 -432.564371)
			(xy 70.182862 -432.550133) (xy 70.205924 -432.542655) (xy 70.218046 -432.542188) (xy 71.157846 -432.542188)
			(xy 71.169958 -432.542672) (xy 71.192994 -432.550166) (xy 71.207183 -432.560476) (xy 72.14108 -432.560476)
			(xy 72.14108 -430.018952) (xy 72.141475 -430.006843) (xy 72.148986 -429.983817) (xy 72.163253 -429.964247)
			(xy 72.182877 -429.950053) (xy 72.205931 -429.94263) (xy 72.218042 -429.942244) (xy 73.157842 -429.942244)
			(xy 73.169934 -429.942672) (xy 73.192937 -429.95014) (xy 73.212516 -429.964337) (xy 73.226765 -429.983879)
			(xy 73.234296 -430.006861) (xy 73.234804 -430.018952) (xy 73.234804 -431.560478) (xy 75.141328 -431.560478)
			(xy 75.141328 -429.018954) (xy 75.141768 -429.006863) (xy 75.149236 -428.983863) (xy 75.16343 -428.964285)
			(xy 75.182968 -428.950036) (xy 75.205947 -428.942503) (xy 75.218036 -428.941992) (xy 76.157836 -428.941992)
			(xy 76.169946 -428.942386) (xy 76.192973 -428.949894) (xy 76.207568 -428.960534) (xy 77.141324 -428.960534)
			(xy 77.141324 -428.233586) (xy 77.14157 -428.224766) (xy 77.145538 -428.207578) (xy 77.149198 -428.19955)
			(xy 77.382624 -427.7233) (xy 77.387312 -427.712778) (xy 77.390806 -427.690023) (xy 77.387326 -427.667266)
			(xy 77.382624 -427.656752) (xy 77.149198 -427.180502) (xy 77.145514 -427.172481) (xy 77.141538 -427.15529)
			(xy 77.141324 -427.146466) (xy 77.141324 -426.41901) (xy 77.141816 -426.406923) (xy 77.149268 -426.383925)
			(xy 77.163449 -426.364346) (xy 77.182976 -426.350095) (xy 77.205946 -426.34256) (xy 77.218032 -426.342048)
			(xy 78.157832 -426.342048) (xy 78.169937 -426.342488) (xy 78.192957 -426.34999) (xy 78.212525 -426.364248)
			(xy 78.22672 -426.38386) (xy 78.234149 -426.406903) (xy 78.23454 -426.41901) (xy 78.23454 -427.960536)
			(xy 79.14132 -427.960536) (xy 79.14132 -427.233588) (xy 79.141567 -427.224768) (xy 79.145535 -427.20758)
			(xy 79.149194 -427.199552) (xy 79.38262 -426.723302) (xy 79.387307 -426.71278) (xy 79.390801 -426.690025)
			(xy 79.387322 -426.667268) (xy 79.38262 -426.656754) (xy 79.149194 -426.180504) (xy 79.14551 -426.172483)
			(xy 79.141534 -426.155292) (xy 79.14132 -426.146468) (xy 79.14132 -425.419012) (xy 79.141724 -425.406927)
			(xy 79.149191 -425.38394) (xy 79.163399 -425.364387) (xy 79.182954 -425.350184) (xy 79.205943 -425.342721)
			(xy 79.218028 -425.342304) (xy 80.157828 -425.342304) (xy 80.169905 -425.34274) (xy 80.192875 -425.350212)
			(xy 80.212413 -425.364415) (xy 80.226606 -425.38396) (xy 80.234066 -425.406935) (xy 80.234536 -425.419012)
			(xy 80.234536 -427.960536) (xy 80.234067 -427.97261) (xy 80.226598 -427.995573) (xy 80.212402 -428.015107)
			(xy 80.192866 -428.029302) (xy 80.169902 -428.036768) (xy 80.157828 -428.037244) (xy 79.218028 -428.037244)
			(xy 79.205958 -428.036713) (xy 79.182998 -428.029262) (xy 79.163464 -428.015082) (xy 79.149267 -427.995559)
			(xy 79.141797 -427.972605) (xy 79.14132 -427.960536) (xy 78.23454 -427.960536) (xy 78.23454 -428.960534)
			(xy 78.234121 -428.972627) (xy 78.226653 -428.995632) (xy 78.212454 -429.015214) (xy 78.19291 -429.029462)
			(xy 78.169924 -429.03699) (xy 78.157832 -429.037496) (xy 77.218032 -429.037496) (xy 77.205924 -429.037056)
			(xy 77.182898 -429.029565) (xy 77.163324 -429.01531) (xy 77.149128 -428.995692) (xy 77.141707 -428.972643)
			(xy 77.141324 -428.960534) (xy 76.207568 -428.960534) (xy 76.212545 -428.964162) (xy 76.226738 -428.983787)
			(xy 76.23416 -429.006843) (xy 76.234544 -429.018954) (xy 76.234544 -431.560478) (xy 76.234074 -431.572568)
			(xy 76.226621 -431.595571) (xy 76.212436 -431.615152) (xy 76.192902 -431.629403) (xy 76.169924 -431.636933)
			(xy 76.157836 -431.63744) (xy 75.218036 -431.63744) (xy 75.205933 -431.636953) (xy 75.182914 -431.629469)
			(xy 75.163344 -431.615224) (xy 75.149146 -431.595619) (xy 75.141718 -431.572582) (xy 75.141328 -431.560478)
			(xy 73.234804 -431.560478) (xy 73.234804 -432.560476) (xy 73.234363 -432.572583) (xy 73.226871 -432.595609)
			(xy 73.212615 -432.615182) (xy 73.192999 -432.629378) (xy 73.16995 -432.6368) (xy 73.157842 -432.637184)
			(xy 72.218042 -432.637184) (xy 72.205957 -432.636657) (xy 72.182962 -432.629215) (xy 72.163383 -432.615043)
			(xy 72.14913 -432.595523) (xy 72.141593 -432.572559) (xy 72.14108 -432.560476) (xy 71.207183 -432.560476)
			(xy 71.212591 -432.564406) (xy 71.226833 -432.584002) (xy 71.234328 -432.607038) (xy 71.234808 -432.61915)
			(xy 71.234808 -435.160674) (xy 71.234267 -435.172783) (xy 71.226792 -435.195817) (xy 71.212567 -435.215415)
			(xy 71.192982 -435.229659) (xy 71.169954 -435.237155) (xy 71.157846 -435.237636) (xy 70.218046 -435.237636)
			(xy 70.205923 -435.237201) (xy 70.182861 -435.229718) (xy 70.163243 -435.215471) (xy 70.148991 -435.195857)
			(xy 70.141503 -435.172797) (xy 70.141084 -435.160674) (xy 69.234812 -435.160674) (xy 69.234812 -436.160672)
			(xy 69.23436 -436.172778) (xy 69.22687 -436.195802) (xy 69.212617 -436.215375) (xy 69.193003 -436.229571)
			(xy 69.169957 -436.236994) (xy 69.15785 -436.23738) (xy 68.21805 -436.23738) (xy 68.205965 -436.23685)
			(xy 68.182969 -436.22941) (xy 68.16339 -436.215239) (xy 68.149137 -436.195719) (xy 68.141601 -436.172755)
			(xy 68.141088 -436.160672) (xy 67.207276 -436.160672) (xy 67.212537 -436.164483) (xy 67.226787 -436.18402)
			(xy 67.234312 -436.207002) (xy 67.234816 -436.219092) (xy 67.234816 -438.760616) (xy 67.234398 -438.772724)
			(xy 67.226896 -438.795749) (xy 67.212634 -438.815321) (xy 67.193014 -438.829515) (xy 67.169963 -438.836939)
			(xy 67.157854 -438.837324) (xy 66.218054 -438.837324) (xy 66.205958 -438.836931) (xy 66.18295 -438.829457)
			(xy 66.163368 -438.815253) (xy 66.14912 -438.795702) (xy 66.141596 -438.77271) (xy 66.141092 -438.760616)
			(xy 65.23482 -438.760616) (xy 65.23482 -439.760614) (xy 68.141088 -439.760614) (xy 68.141088 -437.21909)
			(xy 68.141603 -437.20698) (xy 68.149087 -437.183945) (xy 68.163319 -437.164348) (xy 68.182909 -437.150105)
			(xy 68.20594 -437.142609) (xy 68.21805 -437.142128) (xy 69.15785 -437.142128) (xy 69.169966 -437.142569)
			(xy 69.193009 -437.150069) (xy 69.212609 -437.164319) (xy 69.22685 -437.183927) (xy 69.234337 -437.206974)
			(xy 69.234812 -437.21909) (xy 69.234812 -438.760616) (xy 70.141084 -438.760616) (xy 70.141084 -436.219092)
			(xy 70.141509 -436.206984) (xy 70.149009 -436.183959) (xy 70.163269 -436.164388) (xy 70.182887 -436.150193)
			(xy 70.205937 -436.142769) (xy 70.218046 -436.142384) (xy 71.157846 -436.142384) (xy 71.169942 -436.142769)
			(xy 71.192952 -436.150244) (xy 71.207327 -436.160672) (xy 72.14108 -436.160672) (xy 72.14108 -433.619148)
			(xy 72.141557 -433.607044) (xy 72.149041 -433.584021) (xy 72.163287 -433.564449) (xy 72.182895 -433.550252)
			(xy 72.205937 -433.542827) (xy 72.218042 -433.54244) (xy 73.157842 -433.54244) (xy 73.169934 -433.542872)
			(xy 73.192936 -433.55034) (xy 73.212515 -433.564536) (xy 73.226764 -433.584076) (xy 73.234295 -433.607058)
			(xy 73.234804 -433.619148) (xy 73.234804 -435.160674) (xy 75.141328 -435.160674) (xy 75.141328 -432.61915)
			(xy 75.14185 -432.607064) (xy 75.149291 -432.584067) (xy 75.163464 -432.564487) (xy 75.182986 -432.550235)
			(xy 75.205952 -432.542699) (xy 75.218036 -432.542188) (xy 76.157836 -432.542188) (xy 76.169946 -432.542586)
			(xy 76.192972 -432.550093) (xy 76.207215 -432.560476) (xy 77.141324 -432.560476) (xy 77.141324 -430.018952)
			(xy 77.141724 -430.006872) (xy 77.149203 -429.983898) (xy 77.163415 -429.964358) (xy 77.182969 -429.950167)
			(xy 77.205951 -429.942711) (xy 77.218032 -429.942244) (xy 78.157832 -429.942244) (xy 78.169903 -429.942736)
			(xy 78.192864 -429.950201) (xy 78.212396 -429.964393) (xy 78.226591 -429.983922) (xy 78.234062 -430.006881)
			(xy 78.23454 -430.018952) (xy 78.23454 -431.560478) (xy 79.14132 -431.560478) (xy 79.14132 -429.018954)
			(xy 79.141768 -429.006864) (xy 79.149235 -428.983865) (xy 79.163427 -428.964288) (xy 79.182963 -428.950038)
			(xy 79.205939 -428.942504) (xy 79.218028 -428.941992) (xy 80.157828 -428.941992) (xy 80.169938 -428.942392)
			(xy 80.192964 -428.949899) (xy 80.207555 -428.960534) (xy 81.141316 -428.960534) (xy 81.141316 -428.233586)
			(xy 81.141562 -428.224766) (xy 81.145531 -428.207578) (xy 81.14919 -428.19955) (xy 81.382616 -427.7233)
			(xy 81.387304 -427.712778) (xy 81.390798 -427.690023) (xy 81.387318 -427.667266) (xy 81.382616 -427.656752)
			(xy 81.14919 -427.180502) (xy 81.145505 -427.172482) (xy 81.14153 -427.15529) (xy 81.141316 -427.146466)
			(xy 81.141316 -426.41901) (xy 81.141816 -426.406923) (xy 81.149267 -426.383927) (xy 81.163446 -426.364349)
			(xy 81.182971 -426.350097) (xy 81.205939 -426.342561) (xy 81.218024 -426.342048) (xy 82.157824 -426.342048)
			(xy 82.169929 -426.342495) (xy 82.192948 -426.349995) (xy 82.212516 -426.36425) (xy 82.226712 -426.383862)
			(xy 82.234141 -426.406904) (xy 82.234532 -426.41901) (xy 82.234532 -427.960536) (xy 83.141312 -427.960536)
			(xy 83.141312 -427.233588) (xy 83.14156 -427.224768) (xy 83.145527 -427.207581) (xy 83.149186 -427.199552)
			(xy 83.382612 -426.723302) (xy 83.387299 -426.71278) (xy 83.390794 -426.690025) (xy 83.387314 -426.667268)
			(xy 83.382612 -426.656754) (xy 83.149186 -426.180504) (xy 83.145502 -426.172483) (xy 83.141526 -426.155292)
			(xy 83.141312 -426.146468) (xy 83.141312 -425.419012) (xy 83.141723 -425.406928) (xy 83.14919 -425.383942)
			(xy 83.163396 -425.36439) (xy 83.182949 -425.350186) (xy 83.205936 -425.342722) (xy 83.21802 -425.342304)
			(xy 84.15782 -425.342304) (xy 84.169897 -425.342748) (xy 84.192867 -425.350217) (xy 84.212404 -425.364419)
			(xy 84.226598 -425.383962) (xy 84.234057 -425.406935) (xy 84.234528 -425.419012) (xy 84.234528 -427.960536)
			(xy 84.234067 -427.97261) (xy 84.226597 -427.995576) (xy 84.212399 -428.01511) (xy 84.192861 -428.029304)
			(xy 84.169895 -428.036769) (xy 84.15782 -428.037244) (xy 83.21802 -428.037244) (xy 83.20595 -428.036719)
			(xy 83.18299 -428.029267) (xy 83.163455 -428.015085) (xy 83.149259 -427.995561) (xy 83.141789 -427.972606)
			(xy 83.141312 -427.960536) (xy 82.234532 -427.960536) (xy 82.234532 -428.960534) (xy 82.234121 -428.972628)
			(xy 82.226652 -428.995635) (xy 82.212452 -429.015216) (xy 82.192905 -429.029465) (xy 82.169917 -429.036991)
			(xy 82.157824 -429.037496) (xy 81.218024 -429.037496) (xy 81.205916 -429.037063) (xy 81.182889 -429.02957)
			(xy 81.163315 -429.015313) (xy 81.14912 -428.995694) (xy 81.141699 -428.972643) (xy 81.141316 -428.960534)
			(xy 80.207555 -428.960534) (xy 80.212536 -428.964165) (xy 80.22673 -428.983789) (xy 80.234152 -429.006843)
			(xy 80.234536 -429.018954) (xy 80.234536 -431.560478) (xy 80.234073 -431.572569) (xy 80.22662 -431.595573)
			(xy 80.212433 -431.615155) (xy 80.192897 -431.629405) (xy 80.169917 -431.636934) (xy 80.157828 -431.63744)
			(xy 79.218028 -431.63744) (xy 79.205925 -431.63696) (xy 79.182905 -431.629473) (xy 79.163335 -431.615227)
			(xy 79.149138 -431.595621) (xy 79.141709 -431.572582) (xy 79.14132 -431.560478) (xy 78.23454 -431.560478)
			(xy 78.23454 -432.560476) (xy 78.234016 -432.572546) (xy 78.226564 -432.595507) (xy 78.212382 -432.615042)
			(xy 78.192857 -432.629238) (xy 78.169902 -432.636707) (xy 78.157832 -432.637184) (xy 77.218032 -432.637184)
			(xy 77.205949 -432.63676) (xy 77.182963 -432.629298) (xy 77.16341 -432.615096) (xy 77.149206 -432.595544)
			(xy 77.141742 -432.572559) (xy 77.141324 -432.560476) (xy 76.207215 -432.560476) (xy 76.212543 -432.56436)
			(xy 76.226737 -432.583985) (xy 76.234159 -432.607039) (xy 76.234544 -432.61915) (xy 76.234544 -435.160674)
			(xy 76.23407 -435.172764) (xy 76.226619 -435.195766) (xy 76.212434 -435.215348) (xy 76.192901 -435.229599)
			(xy 76.169924 -435.237129) (xy 76.157836 -435.237636) (xy 75.218036 -435.237636) (xy 75.205933 -435.237153)
			(xy 75.182913 -435.229668) (xy 75.163342 -435.215423) (xy 75.149145 -435.195817) (xy 75.141717 -435.172778)
			(xy 75.141328 -435.160674) (xy 73.234804 -435.160674) (xy 73.234804 -436.160672) (xy 73.23436 -436.172779)
			(xy 73.226869 -436.195805) (xy 73.212614 -436.215378) (xy 73.192998 -436.229574) (xy 73.16995 -436.236996)
			(xy 73.157842 -436.23738) (xy 72.218042 -436.23738) (xy 72.205957 -436.236857) (xy 72.182961 -436.229415)
			(xy 72.163382 -436.215242) (xy 72.149129 -436.195721) (xy 72.141593 -436.172755) (xy 72.14108 -436.160672)
			(xy 71.207327 -436.160672) (xy 71.212535 -436.16445) (xy 71.226782 -436.184003) (xy 71.234305 -436.206997)
			(xy 71.234808 -436.219092) (xy 71.234808 -438.760616) (xy 71.234398 -438.772725) (xy 71.226895 -438.795751)
			(xy 71.212631 -438.815324) (xy 71.193009 -438.829518) (xy 71.169956 -438.83694) (xy 71.157846 -438.837324)
			(xy 70.218046 -438.837324) (xy 70.205955 -438.836853) (xy 70.18295 -438.829404) (xy 70.163366 -438.81522)
			(xy 70.149115 -438.795685) (xy 70.141589 -438.772705) (xy 70.141084 -438.760616) (xy 69.234812 -438.760616)
			(xy 69.234812 -439.760614) (xy 72.14108 -439.760614) (xy 72.14108 -437.21909) (xy 72.141452 -437.206963)
			(xy 72.148952 -437.183896) (xy 72.163215 -437.164278) (xy 72.182843 -437.150029) (xy 72.205914 -437.142544)
			(xy 72.218042 -437.142128) (xy 73.157842 -437.142128) (xy 73.169958 -437.142576) (xy 73.193001 -437.150073)
			(xy 73.212601 -437.164322) (xy 73.226841 -437.183928) (xy 73.234329 -437.206974) (xy 73.234804 -437.21909)
			(xy 73.234804 -438.760616) (xy 75.141328 -438.760616) (xy 75.141328 -436.219092) (xy 75.141706 -436.207005)
			(xy 75.14918 -436.184016) (xy 75.163394 -436.164463) (xy 75.182956 -436.15026) (xy 75.205949 -436.142799)
			(xy 75.218036 -436.142384) (xy 76.157836 -436.142384) (xy 76.169912 -436.142833) (xy 76.192879 -436.150305)
			(xy 76.207142 -436.160672) (xy 77.141324 -436.160672) (xy 77.141324 -433.619148) (xy 77.141754 -433.607065)
			(xy 77.149212 -433.584078) (xy 77.163413 -433.564524) (xy 77.182964 -433.55032) (xy 77.205949 -433.542857)
			(xy 77.218032 -433.54244) (xy 78.157832 -433.54244) (xy 78.169921 -433.542786) (xy 78.192913 -433.550268)
			(xy 78.212467 -433.56449) (xy 78.226668 -433.584059) (xy 78.234126 -433.607058) (xy 78.23454 -433.619148)
			(xy 78.23454 -435.160674) (xy 79.14132 -435.160674) (xy 79.14132 -432.61915) (xy 79.14185 -432.607065)
			(xy 79.14929 -432.584069) (xy 79.163461 -432.56449) (xy 79.182981 -432.550237) (xy 79.205945 -432.542701)
			(xy 79.218028 -432.542188) (xy 80.157828 -432.542188) (xy 80.169937 -432.542592) (xy 80.192963 -432.550098)
			(xy 80.207202 -432.560476) (xy 81.141316 -432.560476) (xy 81.141316 -430.018952) (xy 81.141724 -430.006873)
			(xy 81.149202 -429.9839) (xy 81.163413 -429.964361) (xy 81.182964 -429.950169) (xy 81.205944 -429.942712)
			(xy 81.218024 -429.942244) (xy 82.157824 -429.942244) (xy 82.169895 -429.942743) (xy 82.192855 -429.950206)
			(xy 82.212387 -429.964396) (xy 82.226583 -429.983924) (xy 82.234053 -430.006881) (xy 82.234532 -430.018952)
			(xy 82.234532 -431.560478) (xy 83.141312 -431.560478) (xy 83.141312 -429.018954) (xy 83.141768 -429.006865)
			(xy 83.149234 -428.983867) (xy 83.163424 -428.964291) (xy 83.182958 -428.950041) (xy 83.205932 -428.942505)
			(xy 83.21802 -428.941992) (xy 84.15782 -428.941992) (xy 84.169929 -428.942399) (xy 84.192956 -428.949903)
			(xy 84.207543 -428.960534) (xy 85.141308 -428.960534) (xy 85.141308 -428.233586) (xy 85.141555 -428.224766)
			(xy 85.145523 -428.207579) (xy 85.149182 -428.19955) (xy 85.382608 -427.7233) (xy 85.387297 -427.712779)
			(xy 85.390791 -427.690023) (xy 85.387311 -427.667266) (xy 85.382608 -427.656752) (xy 85.149182 -427.180502)
			(xy 85.145497 -427.172482) (xy 85.141522 -427.15529) (xy 85.141308 -427.146466) (xy 85.141308 -426.41901)
			(xy 85.141815 -426.406924) (xy 85.149265 -426.383929) (xy 85.163443 -426.364352) (xy 85.182966 -426.3501)
			(xy 85.205932 -426.342562) (xy 85.218016 -426.342048) (xy 86.157816 -426.342048) (xy 86.169921 -426.342502)
			(xy 86.192939 -426.349999) (xy 86.212508 -426.364253) (xy 86.226704 -426.383863) (xy 86.234133 -426.406904)
			(xy 86.234524 -426.41901) (xy 86.234524 -427.960536) (xy 87.141304 -427.960536) (xy 87.141304 -427.233588)
			(xy 87.141552 -427.224768) (xy 87.145519 -427.207581) (xy 87.149178 -427.199552) (xy 87.382604 -426.723302)
			(xy 87.387292 -426.71278) (xy 87.390787 -426.690025) (xy 87.387307 -426.667268) (xy 87.382604 -426.656754)
			(xy 87.149178 -426.180504) (xy 87.145493 -426.172484) (xy 87.141518 -426.155292) (xy 87.141304 -426.146468)
			(xy 87.141304 -425.419012) (xy 87.141723 -425.406929) (xy 87.149189 -425.383944) (xy 87.163393 -425.364393)
			(xy 87.182944 -425.350189) (xy 87.205929 -425.342723) (xy 87.218012 -425.342304) (xy 88.157812 -425.342304)
			(xy 88.169888 -425.342754) (xy 88.192858 -425.350222) (xy 88.212396 -425.364421) (xy 88.226589 -425.383964)
			(xy 88.234049 -425.406935) (xy 88.23452 -425.419012) (xy 88.23452 -427.960536) (xy 88.234067 -427.972611)
			(xy 88.226596 -427.995578) (xy 88.212396 -428.015113) (xy 88.192856 -428.029307) (xy 88.169887 -428.036771)
			(xy 88.157812 -428.037244) (xy 87.218012 -428.037244) (xy 87.205942 -428.036726) (xy 87.182981 -428.029271)
			(xy 87.163447 -428.015087) (xy 87.149251 -427.995562) (xy 87.141781 -427.972606) (xy 87.141304 -427.960536)
			(xy 86.234524 -427.960536) (xy 86.234524 -428.960534) (xy 86.234121 -428.972629) (xy 86.226651 -428.995637)
			(xy 86.212449 -429.015219) (xy 86.1929 -429.029467) (xy 86.16991 -429.036992) (xy 86.157816 -429.037496)
			(xy 85.218016 -429.037496) (xy 85.205908 -429.03707) (xy 85.18288 -429.029574) (xy 85.163307 -429.015315)
			(xy 85.149112 -428.995695) (xy 85.141691 -428.972644) (xy 85.141308 -428.960534) (xy 84.207543 -428.960534)
			(xy 84.212528 -428.964167) (xy 84.226722 -428.98379) (xy 84.234144 -429.006843) (xy 84.234528 -429.018954)
			(xy 84.234528 -431.560478) (xy 84.234073 -431.57257) (xy 84.226619 -431.595575) (xy 84.21243 -431.615158)
			(xy 84.192892 -431.629408) (xy 84.16991 -431.636935) (xy 84.15782 -431.63744) (xy 83.21802 -431.63744)
			(xy 83.205916 -431.636967) (xy 83.182896 -431.629478) (xy 83.163327 -431.61523) (xy 83.14913 -431.595622)
			(xy 83.141701 -431.572583) (xy 83.141312 -431.560478) (xy 82.234532 -431.560478) (xy 82.234532 -432.560476)
			(xy 82.234016 -432.572547) (xy 82.226563 -432.595509) (xy 82.212379 -432.615045) (xy 82.192852 -432.629241)
			(xy 82.169895 -432.636708) (xy 82.157824 -432.637184) (xy 81.218024 -432.637184) (xy 81.20594 -432.636766)
			(xy 81.182954 -432.629303) (xy 81.163401 -432.615099) (xy 81.149197 -432.595546) (xy 81.141734 -432.57256)
			(xy 81.141316 -432.560476) (xy 80.207202 -432.560476) (xy 80.212535 -432.564363) (xy 80.226729 -432.583986)
			(xy 80.234151 -432.607039) (xy 80.234536 -432.61915) (xy 80.234536 -435.160674) (xy 80.23407 -435.172765)
			(xy 80.226618 -435.195768) (xy 80.212432 -435.215351) (xy 80.192896 -435.229601) (xy 80.169917 -435.23713)
			(xy 80.157828 -435.237636) (xy 79.218028 -435.237636) (xy 79.205924 -435.23716) (xy 79.182904 -435.229673)
			(xy 79.163334 -435.215425) (xy 79.149137 -435.195818) (xy 79.141709 -435.172779) (xy 79.14132 -435.160674)
			(xy 78.23454 -435.160674) (xy 78.23454 -436.160672) (xy 78.234013 -436.172742) (xy 78.226562 -436.195703)
			(xy 78.21238 -436.215238) (xy 78.192857 -436.229434) (xy 78.169902 -436.236903) (xy 78.157832 -436.23738)
			(xy 77.218032 -436.23738) (xy 77.205948 -436.23696) (xy 77.182962 -436.229497) (xy 77.163409 -436.215294)
			(xy 77.149204 -436.195742) (xy 77.141741 -436.172756) (xy 77.141324 -436.160672) (xy 76.207142 -436.160672)
			(xy 76.212415 -436.164505) (xy 76.226608 -436.184046) (xy 76.234071 -436.207016) (xy 76.234544 -436.219092)
			(xy 76.234544 -438.760616) (xy 76.23405 -438.772688) (xy 76.226587 -438.795649) (xy 76.212397 -438.815183)
			(xy 76.192867 -438.829378) (xy 76.169908 -438.836847) (xy 76.157836 -438.837324) (xy 75.218036 -438.837324)
			(xy 75.205957 -438.836857) (xy 75.182978 -438.829401) (xy 75.163428 -438.815209) (xy 75.149223 -438.795669)
			(xy 75.141751 -438.772695) (xy 75.141328 -438.760616) (xy 73.234804 -438.760616) (xy 73.234804 -439.760614)
			(xy 77.141324 -439.760614) (xy 77.141324 -437.21909) (xy 77.141799 -437.207002) (xy 77.149256 -437.184003)
			(xy 77.163441 -437.164425) (xy 77.182972 -437.150174) (xy 77.205945 -437.14264) (xy 77.218032 -437.142128)
			(xy 78.157832 -437.142128) (xy 78.169945 -437.142489) (xy 78.192978 -437.150001) (xy 78.212553 -437.164276)
			(xy 78.226746 -437.183911) (xy 78.234161 -437.206975) (xy 78.23454 -437.21909) (xy 78.23454 -438.760616)
			(xy 79.14132 -438.760616) (xy 79.14132 -436.219092) (xy 79.141706 -436.207006) (xy 79.149179 -436.184018)
			(xy 79.163391 -436.164466) (xy 79.182951 -436.150263) (xy 79.205942 -436.1428) (xy 79.218028 -436.142384)
			(xy 80.157828 -436.142384) (xy 80.169903 -436.14284) (xy 80.19287 -436.150309) (xy 80.207128 -436.160672)
			(xy 81.141316 -436.160672) (xy 81.141316 -433.619148) (xy 81.141754 -433.607065) (xy 81.149211 -433.58408)
			(xy 81.16341 -433.564527) (xy 81.182959 -433.550322) (xy 81.205942 -433.542858) (xy 81.218024 -433.54244)
			(xy 82.157824 -433.54244) (xy 82.169913 -433.542793) (xy 82.192904 -433.550273) (xy 82.212458 -433.564493)
			(xy 82.22666 -433.58406) (xy 82.234118 -433.607059) (xy 82.234532 -433.619148) (xy 82.234532 -435.160674)
			(xy 83.141312 -435.160674) (xy 83.141312 -432.61915) (xy 83.141849 -432.607066) (xy 83.149289 -432.584071)
			(xy 83.163458 -432.564493) (xy 83.182976 -432.55024) (xy 83.205938 -432.542702) (xy 83.21802 -432.542188)
			(xy 84.15782 -432.542188) (xy 84.169929 -432.542599) (xy 84.192955 -432.550103) (xy 84.207188 -432.560476)
			(xy 85.141308 -432.560476) (xy 85.141308 -430.018952) (xy 85.141723 -430.006873) (xy 85.149201 -429.983902)
			(xy 85.16341 -429.964364) (xy 85.182959 -429.950172) (xy 85.205937 -429.942713) (xy 85.218016 -429.942244)
			(xy 86.157816 -429.942244) (xy 86.169887 -429.94275) (xy 86.192846 -429.950211) (xy 86.212379 -429.964399)
			(xy 86.226574 -429.983925) (xy 86.234045 -430.006882) (xy 86.234524 -430.018952) (xy 86.234524 -431.560478)
			(xy 87.141304 -431.560478) (xy 87.141304 -429.018954) (xy 87.141767 -429.006866) (xy 87.149232 -428.98387)
			(xy 87.163421 -428.964293) (xy 87.182953 -428.950043) (xy 87.205925 -428.942506) (xy 87.218012 -428.941992)
			(xy 88.157812 -428.941992) (xy 88.169921 -428.942406) (xy 88.192947 -428.949908) (xy 88.207529 -428.960534)
			(xy 89.1413 -428.960534) (xy 89.1413 -428.233586) (xy 89.141548 -428.224766) (xy 89.145515 -428.207579)
			(xy 89.149174 -428.19955) (xy 89.3826 -427.7233) (xy 89.387289 -427.712779) (xy 89.390784 -427.690023)
			(xy 89.387303 -427.667266) (xy 89.3826 -427.656752) (xy 89.149174 -427.180502) (xy 89.145489 -427.172482)
			(xy 89.141514 -427.15529) (xy 89.1413 -427.146466) (xy 89.1413 -426.41901) (xy 89.141815 -426.406925)
			(xy 89.149264 -426.383931) (xy 89.16344 -426.364355) (xy 89.182961 -426.350103) (xy 89.205925 -426.342563)
			(xy 89.218008 -426.342048) (xy 90.157808 -426.342048) (xy 90.169912 -426.342509) (xy 90.192931 -426.350004)
			(xy 90.212499 -426.364256) (xy 90.226696 -426.383865) (xy 90.234125 -426.406905) (xy 90.234516 -426.41901)
			(xy 90.234516 -428.960534) (xy 90.234121 -428.97263) (xy 90.226649 -428.995639) (xy 90.212446 -429.015222)
			(xy 90.192895 -429.02947) (xy 90.169903 -429.036993) (xy 90.157808 -429.037496) (xy 89.218008 -429.037496)
			(xy 89.205899 -429.037077) (xy 89.182871 -429.029579) (xy 89.163298 -429.015319) (xy 89.149103 -428.995697)
			(xy 89.141683 -428.972644) (xy 89.1413 -428.960534) (xy 88.207529 -428.960534) (xy 88.212519 -428.96417)
			(xy 88.226714 -428.983792) (xy 88.234136 -429.006844) (xy 88.23452 -429.018954) (xy 88.23452 -431.560478)
			(xy 88.234073 -431.57257) (xy 88.226618 -431.595577) (xy 88.212427 -431.615161) (xy 88.192887 -431.629411)
			(xy 88.169903 -431.636936) (xy 88.157812 -431.63744) (xy 87.218012 -431.63744) (xy 87.205908 -431.636974)
			(xy 87.182888 -431.629483) (xy 87.163318 -431.615232) (xy 87.149122 -431.595624) (xy 87.141693 -431.572583)
			(xy 87.141304 -431.560478) (xy 86.234524 -431.560478) (xy 86.234524 -432.560476) (xy 86.234067 -432.572556)
			(xy 86.226608 -432.595535) (xy 86.212413 -432.615084) (xy 86.192871 -432.62929) (xy 86.169896 -432.636761)
			(xy 86.157816 -432.637184) (xy 85.218016 -432.637184) (xy 85.205932 -432.636773) (xy 85.182946 -432.629307)
			(xy 85.163393 -432.615101) (xy 85.149189 -432.595547) (xy 85.141726 -432.57256) (xy 85.141308 -432.560476)
			(xy 84.207188 -432.560476) (xy 84.212526 -432.564366) (xy 84.226721 -432.583988) (xy 84.234143 -432.60704)
			(xy 84.234528 -432.61915) (xy 84.234528 -435.160674) (xy 84.23407 -435.172765) (xy 84.226616 -435.195771)
			(xy 84.212429 -435.215354) (xy 84.192891 -435.229604) (xy 84.16991 -435.237131) (xy 84.15782 -435.237636)
			(xy 83.21802 -435.237636) (xy 83.205916 -435.237167) (xy 83.182895 -435.229677) (xy 83.163325 -435.215428)
			(xy 83.149129 -435.19582) (xy 83.141701 -435.172779) (xy 83.141312 -435.160674) (xy 82.234532 -435.160674)
			(xy 82.234532 -436.160672) (xy 82.234064 -436.172751) (xy 82.226607 -436.195729) (xy 82.212414 -436.215277)
			(xy 82.192875 -436.229483) (xy 82.169903 -436.236956) (xy 82.157824 -436.23738) (xy 81.218024 -436.23738)
			(xy 81.20594 -436.236966) (xy 81.182953 -436.229502) (xy 81.1634 -436.215297) (xy 81.149196 -436.195743)
			(xy 81.141733 -436.172756) (xy 81.141316 -436.160672) (xy 80.207128 -436.160672) (xy 80.212406 -436.164508)
			(xy 80.2266 -436.184048) (xy 80.234063 -436.207017) (xy 80.234536 -436.219092) (xy 80.234536 -438.760616)
			(xy 80.23405 -438.772689) (xy 80.226586 -438.795651) (xy 80.212394 -438.815186) (xy 80.192862 -438.829381)
			(xy 80.169901 -438.836848) (xy 80.157828 -438.837324) (xy 79.218028 -438.837324) (xy 79.205948 -438.836864)
			(xy 79.182969 -438.829406) (xy 79.16342 -438.815211) (xy 79.149214 -438.79567) (xy 79.141743 -438.772695)
			(xy 79.14132 -438.760616) (xy 78.23454 -438.760616) (xy 78.23454 -439.760614) (xy 81.141316 -439.760614)
			(xy 81.141316 -437.21909) (xy 81.141799 -437.207002) (xy 81.149255 -437.184006) (xy 81.163439 -437.164428)
			(xy 81.182967 -437.150177) (xy 81.205938 -437.142641) (xy 81.218024 -437.142128) (xy 82.157824 -437.142128)
			(xy 82.169937 -437.142496) (xy 82.19297 -437.150006) (xy 82.212545 -437.164279) (xy 82.226738 -437.183912)
			(xy 82.234153 -437.206975) (xy 82.234532 -437.21909) (xy 82.234532 -438.760616) (xy 83.141312 -438.760616)
			(xy 83.141312 -436.219092) (xy 83.141706 -436.207007) (xy 83.149178 -436.18402) (xy 83.163388 -436.164469)
			(xy 83.182946 -436.150265) (xy 83.205935 -436.142802) (xy 83.21802 -436.142384) (xy 84.15782 -436.142384)
			(xy 84.169895 -436.142847) (xy 84.192861 -436.150314) (xy 84.207114 -436.160672) (xy 85.141308 -436.160672)
			(xy 85.141308 -433.619148) (xy 85.141754 -433.607066) (xy 85.14921 -433.584082) (xy 85.163407 -433.56453)
			(xy 85.182954 -433.550325) (xy 85.205934 -433.542859) (xy 85.218016 -433.54244) (xy 86.157816 -433.54244)
			(xy 86.169904 -433.5428) (xy 86.192896 -433.550277) (xy 86.21245 -433.564496) (xy 86.226652 -433.584062)
			(xy 86.23411 -433.607059) (xy 86.234524 -433.619148) (xy 86.234524 -435.160674) (xy 87.141304 -435.160674)
			(xy 87.141304 -432.61915) (xy 87.141849 -432.607067) (xy 87.149288 -432.584074) (xy 87.163455 -432.564496)
			(xy 87.182971 -432.550242) (xy 87.205931 -432.542703) (xy 87.218012 -432.542188) (xy 88.157812 -432.542188)
			(xy 88.16992 -432.542606) (xy 88.192946 -432.550107) (xy 88.207176 -432.560476) (xy 89.1413 -432.560476)
			(xy 89.1413 -430.018952) (xy 89.141723 -430.006874) (xy 89.1492 -429.983904) (xy 89.163407 -429.964367)
			(xy 89.182954 -429.950174) (xy 89.20593 -429.942714) (xy 89.218008 -429.942244) (xy 90.157808 -429.942244)
			(xy 90.169878 -429.942757) (xy 90.192837 -429.950216) (xy 90.21237 -429.964401) (xy 90.226566 -429.983927)
			(xy 90.234037 -430.006882) (xy 90.234516 -430.018952) (xy 90.234516 -431.360072) (xy 108.40466 -431.360072)
			(xy 108.405158 -431.275192) (xy 108.413115 -431.105619) (xy 108.429011 -430.936605) (xy 108.452812 -430.768522)
			(xy 108.484466 -430.601739) (xy 108.523902 -430.436623) (xy 108.571034 -430.273538) (xy 108.625758 -430.11284)
			(xy 108.687955 -429.954885) (xy 108.757487 -429.800018) (xy 108.834202 -429.648581) (xy 108.91793 -429.500905)
			(xy 109.008488 -429.357317) (xy 109.105677 -429.218131) (xy 109.209284 -429.083654) (xy 109.319079 -428.954181)
			(xy 109.434823 -428.829996) (xy 109.55626 -428.711373) (xy 109.683124 -428.598572) (xy 109.815135 -428.491842)
			(xy 109.952005 -428.391417) (xy 110.09343 -428.297518) (xy 110.239102 -428.21035) (xy 110.3887 -428.130107)
			(xy 110.541894 -428.056963) (xy 110.698348 -427.991081) (xy 110.857718 -427.932604) (xy 111.019654 -427.881662)
			(xy 111.1838 -427.838366) (xy 111.349795 -427.802811) (xy 111.517274 -427.775076) (xy 111.685869 -427.755222)
			(xy 111.855209 -427.743292) (xy 112.024922 -427.739313) (xy 112.194635 -427.743292) (xy 112.363975 -427.755222)
			(xy 112.53257 -427.775076) (xy 112.700049 -427.802811) (xy 112.866044 -427.838366) (xy 113.03019 -427.881662)
			(xy 113.192126 -427.932604) (xy 113.26825 -427.960536) (xy 125.241304 -427.960536) (xy 125.241304 -427.233588)
			(xy 125.241552 -427.224768) (xy 125.245519 -427.207581) (xy 125.249178 -427.199552) (xy 125.482604 -426.723302)
			(xy 125.487292 -426.71278) (xy 125.490787 -426.690025) (xy 125.487307 -426.667268) (xy 125.482604 -426.656754)
			(xy 125.249178 -426.180504) (xy 125.245493 -426.172484) (xy 125.241518 -426.155292) (xy 125.241304 -426.146468)
			(xy 125.241304 -425.419012) (xy 125.241723 -425.406929) (xy 125.249189 -425.383944) (xy 125.263393 -425.364393)
			(xy 125.282944 -425.350189) (xy 125.305929 -425.342723) (xy 125.318012 -425.342304) (xy 126.257812 -425.342304)
			(xy 126.269888 -425.342754) (xy 126.292858 -425.350222) (xy 126.312396 -425.364421) (xy 126.326589 -425.383964)
			(xy 126.334049 -425.406935) (xy 126.33452 -425.419012) (xy 126.33452 -427.960536) (xy 126.334067 -427.972611)
			(xy 126.326596 -427.995578) (xy 126.312396 -428.015113) (xy 126.292856 -428.029307) (xy 126.269887 -428.036771)
			(xy 126.257812 -428.037244) (xy 125.318012 -428.037244) (xy 125.305942 -428.036726) (xy 125.282981 -428.029271)
			(xy 125.263447 -428.015087) (xy 125.249251 -427.995562) (xy 125.241781 -427.972606) (xy 125.241304 -427.960536)
			(xy 113.26825 -427.960536) (xy 113.351496 -427.991081) (xy 113.50795 -428.056963) (xy 113.661144 -428.130107)
			(xy 113.810742 -428.21035) (xy 113.956414 -428.297518) (xy 114.097839 -428.391417) (xy 114.234709 -428.491842)
			(xy 114.36672 -428.598572) (xy 114.493584 -428.711373) (xy 114.615021 -428.829996) (xy 114.730765 -428.954181)
			(xy 114.84056 -429.083654) (xy 114.944167 -429.218131) (xy 115.041356 -429.357317) (xy 115.131914 -429.500905)
			(xy 115.215642 -429.648581) (xy 115.292357 -429.800018) (xy 115.361889 -429.954885) (xy 115.424086 -430.11284)
			(xy 115.47881 -430.273538) (xy 115.525942 -430.436623) (xy 115.565378 -430.601739) (xy 115.597032 -430.768522)
			(xy 115.620833 -430.936605) (xy 115.636729 -431.105619) (xy 115.644686 -431.275192) (xy 115.645184 -431.360072)
			(xy 115.644698 -431.445674) (xy 115.639268 -431.560478) (xy 125.241304 -431.560478) (xy 125.241304 -429.018954)
			(xy 125.241767 -429.006866) (xy 125.249232 -428.98387) (xy 125.263421 -428.964293) (xy 125.282953 -428.950043)
			(xy 125.305925 -428.942506) (xy 125.318012 -428.941992) (xy 126.257812 -428.941992) (xy 126.269921 -428.942406)
			(xy 126.292947 -428.949908) (xy 126.307181 -428.96028) (xy 127.2413 -428.96028) (xy 127.2413 -428.233332)
			(xy 127.24153 -428.224511) (xy 127.24551 -428.207323) (xy 127.249174 -428.199296) (xy 127.4826 -427.723046)
			(xy 127.487327 -427.712539) (xy 127.490808 -427.689775) (xy 127.487312 -427.667012) (xy 127.4826 -427.656498)
			(xy 127.249174 -427.180248) (xy 127.245503 -427.172222) (xy 127.241519 -427.155034) (xy 127.2413 -427.146212)
			(xy 127.2413 -426.418756) (xy 127.241727 -426.406678) (xy 127.249202 -426.383708) (xy 127.263408 -426.364171)
			(xy 127.282955 -426.349979) (xy 127.30593 -426.342519) (xy 127.318008 -426.342048) (xy 128.257808 -426.342048)
			(xy 128.269879 -426.342557) (xy 128.292839 -426.350016) (xy 128.312372 -426.364203) (xy 128.326567 -426.383729)
			(xy 128.334038 -426.406686) (xy 128.334516 -426.418756) (xy 128.334516 -427.960536) (xy 129.241296 -427.960536)
			(xy 129.241296 -427.233588) (xy 129.241545 -427.224768) (xy 129.245512 -427.207581) (xy 129.24917 -427.199552)
			(xy 129.482596 -426.723302) (xy 129.487284 -426.71278) (xy 129.490779 -426.690025) (xy 129.487299 -426.667268)
			(xy 129.482596 -426.656754) (xy 129.24917 -426.180504) (xy 129.245485 -426.172484) (xy 129.24151 -426.155292)
			(xy 129.241296 -426.146468) (xy 129.241296 -425.419012) (xy 129.241723 -425.40693) (xy 129.249188 -425.383947)
			(xy 129.26339 -425.364396) (xy 129.282939 -425.350191) (xy 129.305922 -425.342724) (xy 129.318004 -425.342304)
			(xy 130.257804 -425.342304) (xy 130.269888 -425.342709) (xy 130.292873 -425.350179) (xy 130.312424 -425.364387)
			(xy 130.326628 -425.383941) (xy 130.334093 -425.406928) (xy 130.334512 -425.419012) (xy 130.334512 -427.960536)
			(xy 130.334067 -427.972612) (xy 130.326595 -427.99558) (xy 130.312393 -428.015116) (xy 130.292851 -428.029309)
			(xy 130.26988 -428.036772) (xy 130.257804 -428.037244) (xy 129.318004 -428.037244) (xy 129.305933 -428.036733)
			(xy 129.282972 -428.029276) (xy 129.263438 -428.01509) (xy 129.249242 -427.995564) (xy 129.241773 -427.972607)
			(xy 129.241296 -427.960536) (xy 128.334516 -427.960536) (xy 128.334516 -428.96028) (xy 128.33407 -428.972361)
			(xy 128.326609 -428.995342) (xy 128.312411 -429.014891) (xy 128.292867 -429.029096) (xy 128.269889 -429.036566)
			(xy 128.257808 -429.036988) (xy 127.318008 -429.036988) (xy 127.305924 -429.03658) (xy 127.282938 -429.029113)
			(xy 127.263386 -429.014906) (xy 127.249182 -428.995352) (xy 127.241718 -428.972364) (xy 127.2413 -428.96028)
			(xy 126.307181 -428.96028) (xy 126.312519 -428.96417) (xy 126.326714 -428.983792) (xy 126.334136 -429.006844)
			(xy 126.33452 -429.018954) (xy 126.33452 -431.560478) (xy 126.334073 -431.57257) (xy 126.326618 -431.595577)
			(xy 126.312427 -431.615161) (xy 126.292887 -431.629411) (xy 126.269903 -431.636936) (xy 126.257812 -431.63744)
			(xy 125.318012 -431.63744) (xy 125.305908 -431.636974) (xy 125.282888 -431.629483) (xy 125.263318 -431.615232)
			(xy 125.249122 -431.595624) (xy 125.241693 -431.572583) (xy 125.241304 -431.560478) (xy 115.639268 -431.560478)
			(xy 115.63661 -431.616688) (xy 115.620446 -431.787128) (xy 115.596243 -431.956613) (xy 115.564055 -432.124765)
			(xy 115.523953 -432.291207) (xy 115.476027 -432.455567) (xy 115.420385 -432.617477) (xy 115.35715 -432.776576)
			(xy 115.286464 -432.932508) (xy 115.208486 -433.084923) (xy 115.12339 -433.233482) (xy 115.031365 -433.377851)
			(xy 114.932619 -433.517709) (xy 114.82737 -433.652742) (xy 114.715856 -433.782648) (xy 114.598325 -433.907137)
			(xy 114.47504 -434.02593) (xy 114.346277 -434.138763) (xy 114.212324 -434.245381) (xy 114.07348 -434.345548)
			(xy 113.930056 -434.439039) (xy 113.782372 -434.525645) (xy 113.630759 -434.605172) (xy 113.475556 -434.677443)
			(xy 113.396522 -434.710332) (xy 113.388621 -434.713964) (xy 113.375731 -434.725623) (xy 113.367472 -434.740915)
			(xy 113.365788 -434.749448) (xy 113.35004 -434.849016) (xy 113.359438 -434.873654) (xy 113.369852 -434.88229)
			(xy 113.419298 -434.924299) (xy 113.513487 -435.013553) (xy 113.601975 -435.108462) (xy 113.644727 -435.16042)
			(xy 125.241304 -435.16042) (xy 125.241304 -432.618896) (xy 125.241709 -432.606812) (xy 125.249179 -432.583827)
			(xy 125.263387 -432.564276) (xy 125.282941 -432.550072) (xy 125.305928 -432.542607) (xy 125.318012 -432.542188)
			(xy 126.257812 -432.542188) (xy 126.269887 -432.542654) (xy 126.292854 -432.550119) (xy 126.307106 -432.560476)
			(xy 127.2413 -432.560476) (xy 127.2413 -430.018952) (xy 127.241723 -430.006874) (xy 127.2492 -429.983904)
			(xy 127.263407 -429.964367) (xy 127.282954 -429.950174) (xy 127.30593 -429.942714) (xy 127.318008 -429.942244)
			(xy 128.257808 -429.942244) (xy 128.269878 -429.942757) (xy 128.292837 -429.950216) (xy 128.31237 -429.964401)
			(xy 128.326566 -429.983927) (xy 128.334037 -430.006882) (xy 128.334516 -430.018952) (xy 128.334516 -431.560478)
			(xy 129.241296 -431.560478) (xy 129.241296 -429.018954) (xy 129.241767 -429.006866) (xy 129.249231 -428.983872)
			(xy 129.263418 -428.964296) (xy 129.282948 -428.950046) (xy 129.305918 -428.942507) (xy 129.318004 -428.941992)
			(xy 130.257804 -428.941992) (xy 130.269912 -428.942413) (xy 130.292938 -428.949912) (xy 130.307168 -428.96028)
			(xy 131.241292 -428.96028) (xy 131.241292 -428.233332) (xy 131.241523 -428.224511) (xy 131.245502 -428.207324)
			(xy 131.249166 -428.199296) (xy 131.482592 -427.723046) (xy 131.487319 -427.712539) (xy 131.4908 -427.689775)
			(xy 131.487304 -427.667012) (xy 131.482592 -427.656498) (xy 131.249166 -427.180248) (xy 131.245495 -427.172222)
			(xy 131.241511 -427.155035) (xy 131.241292 -427.146212) (xy 131.241292 -426.418756) (xy 131.241727 -426.406679)
			(xy 131.249201 -426.38371) (xy 131.263405 -426.364174) (xy 131.28295 -426.349981) (xy 131.305923 -426.34252)
			(xy 131.318 -426.342048) (xy 132.2578 -426.342048) (xy 132.26987 -426.342564) (xy 132.29283 -426.350021)
			(xy 132.312363 -426.364206) (xy 132.326559 -426.383731) (xy 132.334029 -426.406686) (xy 132.334508 -426.418756)
			(xy 132.334508 -427.960536) (xy 133.241288 -427.960536) (xy 133.241288 -427.233588) (xy 133.241538 -427.224768)
			(xy 133.245504 -427.207581) (xy 133.249162 -427.199552) (xy 133.482588 -426.723302) (xy 133.487276 -426.71278)
			(xy 133.490772 -426.690025) (xy 133.487292 -426.667268) (xy 133.482588 -426.656754) (xy 133.249162 -426.180504)
			(xy 133.245477 -426.172484) (xy 133.241502 -426.155292) (xy 133.241288 -426.146468) (xy 133.241288 -425.419012)
			(xy 133.241723 -425.40693) (xy 133.249187 -425.383949) (xy 133.263387 -425.364399) (xy 133.282934 -425.350194)
			(xy 133.305914 -425.342726) (xy 133.317996 -425.342304) (xy 134.257796 -425.342304) (xy 134.26988 -425.342716)
			(xy 134.292864 -425.350184) (xy 134.312416 -425.36439) (xy 134.32662 -425.383943) (xy 134.334085 -425.406928)
			(xy 134.334504 -425.419012) (xy 134.334504 -427.960536) (xy 134.334067 -427.972613) (xy 134.326594 -427.995582)
			(xy 134.31239 -428.015119) (xy 134.292846 -428.029312) (xy 134.269873 -428.036773) (xy 134.257796 -428.037244)
			(xy 133.317996 -428.037244) (xy 133.305925 -428.03674) (xy 133.282964 -428.02928) (xy 133.26343 -428.015093)
			(xy 133.249234 -427.995565) (xy 133.241765 -427.972607) (xy 133.241288 -427.960536) (xy 132.334508 -427.960536)
			(xy 132.334508 -428.96028) (xy 132.33407 -428.972362) (xy 132.326608 -428.995344) (xy 132.312408 -429.014894)
			(xy 132.292862 -429.029099) (xy 132.269882 -429.036567) (xy 132.2578 -429.036988) (xy 131.318 -429.036988)
			(xy 131.305915 -429.036587) (xy 131.282929 -429.029117) (xy 131.263377 -429.014909) (xy 131.249174 -428.995353)
			(xy 131.24171 -428.972365) (xy 131.241292 -428.96028) (xy 130.307168 -428.96028) (xy 130.312511 -428.964173)
			(xy 130.326706 -428.983793) (xy 130.334128 -429.006844) (xy 130.334512 -429.018954) (xy 130.334512 -431.560478)
			(xy 130.334073 -431.572571) (xy 130.326616 -431.595579) (xy 130.312424 -431.615164) (xy 130.292882 -431.629413)
			(xy 130.269896 -431.636937) (xy 130.257804 -431.63744) (xy 129.318004 -431.63744) (xy 129.305899 -431.636981)
			(xy 129.282879 -431.629488) (xy 129.263309 -431.615236) (xy 129.249113 -431.595625) (xy 129.241685 -431.572584)
			(xy 129.241296 -431.560478) (xy 128.334516 -431.560478) (xy 128.334516 -432.560476) (xy 128.334067 -432.572557)
			(xy 128.326607 -432.595537) (xy 128.31241 -432.615087) (xy 128.292866 -432.629292) (xy 128.269888 -432.636762)
			(xy 128.257808 -432.637184) (xy 127.318008 -432.637184) (xy 127.305923 -432.63678) (xy 127.282937 -432.629312)
			(xy 127.263384 -432.615105) (xy 127.249181 -432.595549) (xy 127.241717 -432.572561) (xy 127.2413 -432.560476)
			(xy 126.307106 -432.560476) (xy 126.31239 -432.564316) (xy 126.326584 -432.583854) (xy 126.334047 -432.606821)
			(xy 126.33452 -432.618896) (xy 126.33452 -435.16042) (xy 126.334053 -435.172494) (xy 126.326586 -435.19546)
			(xy 126.31239 -435.214996) (xy 126.292853 -435.22919) (xy 126.269886 -435.236654) (xy 126.257812 -435.237128)
			(xy 125.318012 -435.237128) (xy 125.30594 -435.236626) (xy 125.282977 -435.229169) (xy 125.263441 -435.214982)
			(xy 125.249246 -435.195452) (xy 125.241779 -435.172492) (xy 125.241304 -435.16042) (xy 113.644727 -435.16042)
			(xy 113.684422 -435.208663) (xy 113.760513 -435.313772) (xy 113.829956 -435.423387) (xy 113.892486 -435.537087)
			(xy 113.947862 -435.654438) (xy 113.995874 -435.77499) (xy 114.036336 -435.89828) (xy 114.069094 -436.023838)
			(xy 114.094022 -436.151181) (xy 114.111025 -436.279823) (xy 114.120038 -436.40927) (xy 114.121027 -436.539027)
			(xy 114.113986 -436.668596) (xy 114.098945 -436.797482) (xy 114.075959 -436.92519) (xy 114.045118 -437.051232)
			(xy 114.006538 -437.175125) (xy 113.960369 -437.296394) (xy 113.906786 -437.414574) (xy 113.845996 -437.529214)
			(xy 113.77823 -437.639874) (xy 113.703749 -437.74613) (xy 113.622838 -437.847575) (xy 113.535806 -437.943821)
			(xy 113.442988 -438.034499) (xy 113.344738 -438.119261) (xy 113.241432 -438.197784) (xy 113.133467 -438.269766)
			(xy 113.021257 -438.334931) (xy 112.90523 -438.39303) (xy 112.785831 -438.443841) (xy 112.663518 -438.487169)
			(xy 112.538759 -438.522847) (xy 112.412032 -438.550739) (xy 112.283822 -438.570739) (xy 112.15462 -438.58277)
			(xy 112.024922 -438.586785) (xy 111.895224 -438.58277) (xy 111.766022 -438.570739) (xy 111.637812 -438.550739)
			(xy 111.511085 -438.522847) (xy 111.386326 -438.487169) (xy 111.264013 -438.443841) (xy 111.144614 -438.39303)
			(xy 111.028587 -438.334931) (xy 110.916377 -438.269766) (xy 110.808412 -438.197784) (xy 110.705106 -438.119261)
			(xy 110.606856 -438.034499) (xy 110.514038 -437.943821) (xy 110.427006 -437.847575) (xy 110.346095 -437.74613)
			(xy 110.271614 -437.639874) (xy 110.203848 -437.529214) (xy 110.143058 -437.414574) (xy 110.089475 -437.296394)
			(xy 110.043306 -437.175125) (xy 110.004726 -437.051232) (xy 109.973885 -436.92519) (xy 109.950899 -436.797482)
			(xy 109.935858 -436.668596) (xy 109.928817 -436.539027) (xy 109.929806 -436.40927) (xy 109.938819 -436.279823)
			(xy 109.955822 -436.151181) (xy 109.98075 -436.023838) (xy 110.013508 -435.89828) (xy 110.05397 -435.77499)
			(xy 110.101982 -435.654438) (xy 110.157358 -435.537087) (xy 110.219888 -435.423387) (xy 110.289331 -435.313772)
			(xy 110.365422 -435.208663) (xy 110.447869 -435.108462) (xy 110.536357 -435.013553) (xy 110.630546 -434.924299)
			(xy 110.679992 -434.88229) (xy 110.690406 -434.873654) (xy 110.699804 -434.849016) (xy 110.682024 -434.73624)
			(xy 110.665768 -434.715412) (xy 110.653322 -434.710332) (xy 110.574304 -434.677407) (xy 110.419107 -434.605131)
			(xy 110.267499 -434.5256) (xy 110.119821 -434.438991) (xy 109.976402 -434.345497) (xy 109.837562 -434.245328)
			(xy 109.703613 -434.138709) (xy 109.574854 -434.025876) (xy 109.451573 -433.907083) (xy 109.334045 -433.782595)
			(xy 109.222533 -433.65269) (xy 109.117287 -433.517659) (xy 109.018541 -433.377804) (xy 108.926517 -433.233438)
			(xy 108.84142 -433.084883) (xy 108.763441 -432.932471) (xy 108.692754 -432.776543) (xy 108.629516 -432.617449)
			(xy 108.57387 -432.455542) (xy 108.52594 -432.291187) (xy 108.485833 -432.124749) (xy 108.453638 -431.956601)
			(xy 108.429428 -431.78712) (xy 108.413257 -431.616683) (xy 108.405161 -431.445673) (xy 108.40466 -431.360072)
			(xy 90.234516 -431.360072) (xy 90.234516 -432.560476) (xy 90.234067 -432.572557) (xy 90.226607 -432.595537)
			(xy 90.21241 -432.615087) (xy 90.192866 -432.629292) (xy 90.169888 -432.636762) (xy 90.157808 -432.637184)
			(xy 89.218008 -432.637184) (xy 89.205923 -432.63678) (xy 89.182937 -432.629312) (xy 89.163384 -432.615105)
			(xy 89.149181 -432.595549) (xy 89.141717 -432.572561) (xy 89.1413 -432.560476) (xy 88.207176 -432.560476)
			(xy 88.212518 -432.564369) (xy 88.226713 -432.583989) (xy 88.234135 -432.60704) (xy 88.23452 -432.61915)
			(xy 88.23452 -435.160674) (xy 88.23407 -435.172766) (xy 88.226615 -435.195773) (xy 88.212426 -435.215356)
			(xy 88.192886 -435.229606) (xy 88.169903 -435.237132) (xy 88.157812 -435.237636) (xy 87.218012 -435.237636)
			(xy 87.205907 -435.237174) (xy 87.182887 -435.229682) (xy 87.163317 -435.215431) (xy 87.14912 -435.195821)
			(xy 87.141693 -435.17278) (xy 87.141304 -435.160674) (xy 86.234524 -435.160674) (xy 86.234524 -436.160672)
			(xy 86.234064 -436.172752) (xy 86.226606 -436.195731) (xy 86.212411 -436.21528) (xy 86.19287 -436.229486)
			(xy 86.169895 -436.236957) (xy 86.157816 -436.23738) (xy 85.218016 -436.23738) (xy 85.205931 -436.236973)
			(xy 85.182944 -436.229507) (xy 85.163392 -436.2153) (xy 85.149188 -436.195745) (xy 85.141725 -436.172757)
			(xy 85.141308 -436.160672) (xy 84.207114 -436.160672) (xy 84.212397 -436.164511) (xy 84.226591 -436.18405)
			(xy 84.234055 -436.207017) (xy 84.234528 -436.219092) (xy 84.234528 -438.760616) (xy 84.23405 -438.772689)
			(xy 84.226585 -438.795654) (xy 84.212391 -438.815189) (xy 84.192857 -438.829383) (xy 84.169893 -438.836849)
			(xy 84.15782 -438.837324) (xy 83.21802 -438.837324) (xy 83.20594 -438.83687) (xy 83.182961 -438.82941)
			(xy 83.163411 -438.815214) (xy 83.149206 -438.795672) (xy 83.141735 -438.772696) (xy 83.141312 -438.760616)
			(xy 82.234532 -438.760616) (xy 82.234532 -439.760614) (xy 85.141308 -439.760614) (xy 85.141308 -437.21909)
			(xy 85.141798 -437.207003) (xy 85.149254 -437.184008) (xy 85.163436 -437.164431) (xy 85.182962 -437.150179)
			(xy 85.205931 -437.142642) (xy 85.218016 -437.142128) (xy 86.157816 -437.142128) (xy 86.169929 -437.142503)
			(xy 86.192961 -437.15001) (xy 86.212536 -437.164281) (xy 86.226729 -437.183914) (xy 86.234145 -437.206976)
			(xy 86.234524 -437.21909) (xy 86.234524 -438.760616) (xy 87.141304 -438.760616) (xy 87.141304 -436.219092)
			(xy 87.141706 -436.207008) (xy 87.149177 -436.184023) (xy 87.163386 -436.164471) (xy 87.182941 -436.150268)
			(xy 87.205928 -436.142803) (xy 87.218012 -436.142384) (xy 88.157812 -436.142384) (xy 88.169886 -436.142854)
			(xy 88.192853 -436.150319) (xy 88.207101 -436.160672) (xy 89.1413 -436.160672) (xy 89.1413 -433.619148)
			(xy 89.141754 -433.607067) (xy 89.149209 -433.584084) (xy 89.163404 -433.564533) (xy 89.182949 -433.550327)
			(xy 89.205927 -433.54286) (xy 89.218008 -433.54244) (xy 90.157808 -433.54244) (xy 90.169896 -433.542806)
			(xy 90.192887 -433.550282) (xy 90.212441 -433.564498) (xy 90.226644 -433.584063) (xy 90.234102 -433.60706)
			(xy 90.234516 -433.619148) (xy 90.234516 -436.160672) (xy 90.234064 -436.172752) (xy 90.226605 -436.195733)
			(xy 90.212409 -436.215283) (xy 90.192865 -436.229488) (xy 90.169888 -436.236958) (xy 90.157808 -436.23738)
			(xy 89.218008 -436.23738) (xy 89.205923 -436.23698) (xy 89.182936 -436.229512) (xy 89.163383 -436.215303)
			(xy 89.149179 -436.195746) (xy 89.141716 -436.172757) (xy 89.1413 -436.160672) (xy 88.207101 -436.160672)
			(xy 88.212389 -436.164514) (xy 88.226583 -436.184051) (xy 88.234047 -436.207018) (xy 88.23452 -436.219092)
			(xy 88.23452 -438.760616) (xy 88.234049 -438.77269) (xy 88.226584 -438.795656) (xy 88.212389 -438.815191)
			(xy 88.192852 -438.829386) (xy 88.169886 -438.83685) (xy 88.157812 -438.837324) (xy 87.218012 -438.837324)
			(xy 87.20594 -438.836826) (xy 87.182976 -438.829369) (xy 87.16344 -438.81518) (xy 87.149244 -438.79565)
			(xy 87.141779 -438.772688) (xy 87.141304 -438.760616) (xy 86.234524 -438.760616) (xy 86.234524 -439.760614)
			(xy 89.1413 -439.760614) (xy 89.1413 -437.21909) (xy 89.141798 -437.207004) (xy 89.149253 -437.18401)
			(xy 89.163433 -437.164434) (xy 89.182957 -437.150182) (xy 89.205924 -437.142643) (xy 89.218008 -437.142128)
			(xy 90.157808 -437.142128) (xy 90.16992 -437.14251) (xy 90.192952 -437.150015) (xy 90.212528 -437.164284)
			(xy 90.226721 -437.183915) (xy 90.234137 -437.206976) (xy 90.234516 -437.21909) (xy 90.234516 -438.760362)
			(xy 125.241304 -438.760362) (xy 125.241304 -436.218838) (xy 125.241839 -436.206754) (xy 125.249281 -436.183761)
			(xy 125.263451 -436.164183) (xy 125.282968 -436.14993) (xy 125.30593 -436.142391) (xy 125.318012 -436.141876)
			(xy 126.257812 -436.141876) (xy 126.269919 -436.142306) (xy 126.292943 -436.149805) (xy 126.30751 -436.160418)
			(xy 127.2413 -436.160418) (xy 127.2413 -433.618894) (xy 127.241802 -433.606808) (xy 127.249255 -433.583814)
			(xy 127.263434 -433.564238) (xy 127.282958 -433.549986) (xy 127.305924 -433.542447) (xy 127.318008 -433.541932)
			(xy 128.257808 -433.541932) (xy 128.269921 -433.54231) (xy 128.292954 -433.549815) (xy 128.312529 -433.564086)
			(xy 128.326723 -433.583717) (xy 128.334137 -433.60678) (xy 128.334516 -433.618894) (xy 128.334516 -435.16042)
			(xy 129.241296 -435.16042) (xy 129.241296 -432.618896) (xy 129.241761 -432.606821) (xy 129.249225 -432.583853)
			(xy 129.263421 -432.564316) (xy 129.28296 -432.550121) (xy 129.305929 -432.54266) (xy 129.318004 -432.542188)
			(xy 130.257804 -432.542188) (xy 130.269878 -432.542661) (xy 130.292845 -432.550124) (xy 130.307094 -432.560476)
			(xy 131.241292 -432.560476) (xy 131.241292 -430.018952) (xy 131.241723 -430.006875) (xy 131.249199 -429.983906)
			(xy 131.263404 -429.96437) (xy 131.282949 -429.950177) (xy 131.305923 -429.942716) (xy 131.318 -429.942244)
			(xy 132.2578 -429.942244) (xy 132.26987 -429.942764) (xy 132.292829 -429.95022) (xy 132.312362 -429.964404)
			(xy 132.326558 -429.983928) (xy 132.334029 -430.006883) (xy 132.334508 -430.018952) (xy 132.334508 -431.560478)
			(xy 133.241288 -431.560478) (xy 133.241288 -429.018954) (xy 133.241669 -429.006857) (xy 133.249144 -428.983847)
			(xy 133.263351 -428.964264) (xy 133.282905 -428.950016) (xy 133.3059 -428.942494) (xy 133.317996 -428.941992)
			(xy 134.257796 -428.941992) (xy 134.269904 -428.942419) (xy 134.29293 -428.949917) (xy 134.307154 -428.96028)
			(xy 135.241284 -428.96028) (xy 135.241284 -428.233332) (xy 135.241516 -428.224511) (xy 135.245494 -428.207324)
			(xy 135.249158 -428.199296) (xy 135.482584 -427.723046) (xy 135.487311 -427.712539) (xy 135.490793 -427.689775)
			(xy 135.487296 -427.667012) (xy 135.482584 -427.656498) (xy 135.249158 -427.180248) (xy 135.245486 -427.172222)
			(xy 135.241503 -427.155035) (xy 135.241284 -427.146212) (xy 135.241284 -426.418756) (xy 135.241726 -426.40668)
			(xy 135.2492 -426.383713) (xy 135.263403 -426.364177) (xy 135.282945 -426.349984) (xy 135.305916 -426.342521)
			(xy 135.317992 -426.342048) (xy 136.257792 -426.342048) (xy 136.269862 -426.34257) (xy 136.292821 -426.350025)
			(xy 136.312355 -426.364208) (xy 136.326551 -426.383732) (xy 136.334021 -426.406687) (xy 136.3345 -426.418756)
			(xy 136.3345 -427.960536) (xy 137.24128 -427.960536) (xy 137.24128 -427.233588) (xy 137.241531 -427.224768)
			(xy 137.245496 -427.207581) (xy 137.249154 -427.199552) (xy 137.48258 -426.723302) (xy 137.487269 -426.71278)
			(xy 137.490765 -426.690025) (xy 137.487284 -426.667268) (xy 137.48258 -426.656754) (xy 137.249154 -426.180504)
			(xy 137.245468 -426.172484) (xy 137.241494 -426.155292) (xy 137.24128 -426.146468) (xy 137.24128 -425.419012)
			(xy 137.241774 -425.406939) (xy 137.249232 -425.383974) (xy 137.263421 -425.364438) (xy 137.282953 -425.350243)
			(xy 137.305915 -425.342778) (xy 137.317988 -425.342304) (xy 138.257788 -425.342304) (xy 138.269871 -425.342723)
			(xy 138.292856 -425.350189) (xy 138.312407 -425.364393) (xy 138.326611 -425.383944) (xy 138.334077 -425.406929)
			(xy 138.334496 -425.419012) (xy 138.334496 -427.960536) (xy 138.334066 -427.972614) (xy 138.326593 -427.995584)
			(xy 138.312387 -428.015122) (xy 138.292841 -428.029315) (xy 138.269866 -428.036774) (xy 138.257788 -428.037244)
			(xy 137.317988 -428.037244) (xy 137.305916 -428.036746) (xy 137.282955 -428.029285) (xy 137.263421 -428.015096)
			(xy 137.249226 -427.995567) (xy 137.241757 -427.972607) (xy 137.24128 -427.960536) (xy 136.3345 -427.960536)
			(xy 136.3345 -428.96028) (xy 136.33407 -428.972362) (xy 136.326607 -428.995346) (xy 136.312406 -429.014897)
			(xy 136.292857 -429.029102) (xy 136.269874 -429.036568) (xy 136.257792 -429.036988) (xy 135.317992 -429.036988)
			(xy 135.305907 -429.036594) (xy 135.28292 -429.029122) (xy 135.263369 -429.014912) (xy 135.249165 -428.995354)
			(xy 135.241702 -428.972365) (xy 135.241284 -428.96028) (xy 134.307154 -428.96028) (xy 134.312502 -428.964176)
			(xy 134.326697 -428.983795) (xy 134.33412 -429.006845) (xy 134.334504 -429.018954) (xy 134.334504 -431.560478)
			(xy 134.333975 -431.572562) (xy 134.326529 -431.595555) (xy 134.312357 -431.615131) (xy 134.29284 -431.629384)
			(xy 134.269878 -431.636924) (xy 134.257796 -431.63744) (xy 133.317996 -431.63744) (xy 133.305891 -431.636988)
			(xy 133.28287 -431.629492) (xy 133.263301 -431.615238) (xy 133.249105 -431.595627) (xy 133.241677 -431.572584)
			(xy 133.241288 -431.560478) (xy 132.334508 -431.560478) (xy 132.334508 -432.560476) (xy 132.334067 -432.572557)
			(xy 132.326606 -432.595539) (xy 132.312407 -432.61509) (xy 132.292861 -432.629295) (xy 132.269881 -432.636763)
			(xy 132.2578 -432.637184) (xy 131.318 -432.637184) (xy 131.305915 -432.636787) (xy 131.282928 -432.629317)
			(xy 131.263376 -432.615107) (xy 131.249172 -432.59555) (xy 131.241709 -432.572561) (xy 131.241292 -432.560476)
			(xy 130.307094 -432.560476) (xy 130.312382 -432.564318) (xy 130.326576 -432.583855) (xy 130.334039 -432.606822)
			(xy 130.334512 -432.618896) (xy 130.334512 -435.16042) (xy 130.334053 -435.172495) (xy 130.326585 -435.195462)
			(xy 130.312387 -435.214999) (xy 130.292848 -435.229193) (xy 130.269879 -435.236655) (xy 130.257804 -435.237128)
			(xy 129.318004 -435.237128) (xy 129.305932 -435.236633) (xy 129.282968 -435.229174) (xy 129.263433 -435.214984)
			(xy 129.249237 -435.195454) (xy 129.241771 -435.172492) (xy 129.241296 -435.16042) (xy 128.334516 -435.16042)
			(xy 128.334516 -436.160418) (xy 128.334107 -436.172513) (xy 128.32664 -436.195522) (xy 128.31244 -436.215105)
			(xy 128.292892 -436.229353) (xy 128.269902 -436.236877) (xy 128.257808 -436.23738) (xy 127.318008 -436.23738)
			(xy 127.305898 -436.236977) (xy 127.282867 -436.229477) (xy 127.263292 -436.215213) (xy 127.249098 -436.195587)
			(xy 127.24168 -436.17253) (xy 127.2413 -436.160418) (xy 126.30751 -436.160418) (xy 126.312514 -436.164064)
			(xy 126.326709 -436.183682) (xy 126.334133 -436.20673) (xy 126.33452 -436.218838) (xy 126.33452 -438.760362)
			(xy 126.33406 -438.772454) (xy 126.326608 -438.79546) (xy 126.312422 -438.815044) (xy 126.292884 -438.829294)
			(xy 126.269902 -438.83682) (xy 126.257812 -438.837324) (xy 125.318012 -438.837324) (xy 125.305906 -438.836874)
			(xy 125.282883 -438.82938) (xy 125.263312 -438.815127) (xy 125.249116 -438.795514) (xy 125.241691 -438.772469)
			(xy 125.241304 -438.760362) (xy 90.234516 -438.760362) (xy 90.234516 -439.76036) (xy 127.2413 -439.76036)
			(xy 127.2413 -437.218836) (xy 127.241744 -437.206754) (xy 127.249202 -437.183771) (xy 127.2634 -437.16422)
			(xy 127.282946 -437.150015) (xy 127.305927 -437.142548) (xy 127.318008 -437.142128) (xy 128.257808 -437.142128)
			(xy 128.269895 -437.142506) (xy 128.292884 -437.14998) (xy 128.312437 -437.164194) (xy 128.32664 -437.183756)
			(xy 128.334101 -437.206749) (xy 128.334516 -437.218836) (xy 128.334516 -438.760362) (xy 129.241296 -438.760362)
			(xy 129.241296 -436.218838) (xy 129.241839 -436.206755) (xy 129.24928 -436.183763) (xy 129.263448 -436.164186)
			(xy 129.282963 -436.149933) (xy 129.305923 -436.142392) (xy 129.318004 -436.141876) (xy 130.257804 -436.141876)
			(xy 130.269911 -436.142312) (xy 130.292934 -436.14981) (xy 130.307496 -436.160418) (xy 131.241292 -436.160418)
			(xy 131.241292 -433.618894) (xy 131.241802 -433.606809) (xy 131.249254 -433.583816) (xy 131.263431 -433.564241)
			(xy 131.282953 -433.549989) (xy 131.305917 -433.542448) (xy 131.318 -433.541932) (xy 132.2578 -433.541932)
			(xy 132.269912 -433.542317) (xy 132.292945 -433.54982) (xy 132.312521 -433.564088) (xy 132.326714 -433.583719)
			(xy 132.334129 -433.60678) (xy 132.334508 -433.618894) (xy 132.334508 -435.16042) (xy 133.241288 -435.16042)
			(xy 133.241288 -432.618896) (xy 133.241761 -432.606822) (xy 133.249224 -432.583855) (xy 133.263418 -432.564318)
			(xy 133.282955 -432.550124) (xy 133.305922 -432.542661) (xy 133.317996 -432.542188) (xy 134.257796 -432.542188)
			(xy 134.26987 -432.542668) (xy 134.292836 -432.550129) (xy 134.30708 -432.560476) (xy 135.241284 -432.560476)
			(xy 135.241284 -430.018952) (xy 135.241723 -430.006876) (xy 135.249198 -429.983908) (xy 135.263401 -429.964373)
			(xy 135.282944 -429.95018) (xy 135.305915 -429.942717) (xy 135.317992 -429.942244) (xy 136.257792 -429.942244)
			(xy 136.269861 -429.94277) (xy 136.29282 -429.950225) (xy 136.312353 -429.964407) (xy 136.32655 -429.98393)
			(xy 136.334021 -430.006883) (xy 136.3345 -430.018952) (xy 136.3345 -431.560478) (xy 137.24128 -431.560478)
			(xy 137.24128 -429.018954) (xy 137.241669 -429.006858) (xy 137.249143 -428.983849) (xy 137.263348 -428.964267)
			(xy 137.2829 -428.950019) (xy 137.305893 -428.942495) (xy 137.317988 -428.941992) (xy 138.257788 -428.941992)
			(xy 138.269895 -428.942427) (xy 138.292921 -428.949922) (xy 138.30714 -428.96028) (xy 139.241276 -428.96028)
			(xy 139.241276 -428.233332) (xy 139.241509 -428.224511) (xy 139.245487 -428.207324) (xy 139.24915 -428.199296)
			(xy 139.482576 -427.723046) (xy 139.487304 -427.71254) (xy 139.490786 -427.689775) (xy 139.487289 -427.667012)
			(xy 139.482576 -427.656498) (xy 139.24915 -427.180248) (xy 139.245478 -427.172223) (xy 139.241495 -427.155035)
			(xy 139.241276 -427.146212) (xy 139.241276 -426.418756) (xy 139.241726 -426.406681) (xy 139.249199 -426.383715)
			(xy 139.2634 -426.36418) (xy 139.28294 -426.349986) (xy 139.305909 -426.342522) (xy 139.317984 -426.342048)
			(xy 140.257784 -426.342048) (xy 140.269853 -426.342577) (xy 140.292813 -426.35003) (xy 140.312346 -426.364211)
			(xy 140.326543 -426.383734) (xy 140.334013 -426.406687) (xy 140.334492 -426.418756) (xy 140.334492 -427.960536)
			(xy 142.241524 -427.960536) (xy 142.241524 -427.233588) (xy 142.24177 -427.224768) (xy 142.245738 -427.20758)
			(xy 142.249398 -427.199552) (xy 142.482824 -426.723302) (xy 142.487511 -426.71278) (xy 142.491005 -426.690025)
			(xy 142.487526 -426.667268) (xy 142.482824 -426.656754) (xy 142.249398 -426.180504) (xy 142.245715 -426.172483)
			(xy 142.241738 -426.155292) (xy 142.241524 -426.146468) (xy 142.241524 -425.419012) (xy 142.241924 -425.406927)
			(xy 142.249392 -425.383939) (xy 142.2636 -425.364386) (xy 142.283157 -425.350183) (xy 142.306147 -425.34272)
			(xy 142.318232 -425.342304) (xy 143.258032 -425.342304) (xy 143.270109 -425.342737) (xy 143.29308 -425.35021)
			(xy 143.312617 -425.364414) (xy 143.32681 -425.38396) (xy 143.33427 -425.406934) (xy 143.33474 -425.419012)
			(xy 143.33474 -427.960536) (xy 143.334267 -427.972609) (xy 143.326799 -427.995572) (xy 143.312603 -428.015106)
			(xy 143.293069 -428.0293) (xy 143.270105 -428.036768) (xy 143.258032 -428.037244) (xy 142.318232 -428.037244)
			(xy 142.306163 -428.036709) (xy 142.283203 -428.02926) (xy 142.263668 -428.01508) (xy 142.249471 -427.995558)
			(xy 142.242001 -427.972605) (xy 142.241524 -427.960536) (xy 140.334492 -427.960536) (xy 140.334492 -428.96028)
			(xy 140.33407 -428.972363) (xy 140.326606 -428.995348) (xy 140.312403 -429.0149) (xy 140.292852 -429.029104)
			(xy 140.269867 -429.036569) (xy 140.257784 -429.036988) (xy 139.317984 -429.036988) (xy 139.305898 -429.036601)
			(xy 139.282912 -429.029126) (xy 139.26336 -429.014914) (xy 139.249157 -428.995356) (xy 139.241694 -428.972366)
			(xy 139.241276 -428.96028) (xy 138.30714 -428.96028) (xy 138.312493 -428.964179) (xy 138.326689 -428.983796)
			(xy 138.334111 -429.006845) (xy 138.334496 -429.018954) (xy 138.334496 -431.560478) (xy 138.333975 -431.572563)
			(xy 138.326528 -431.595557) (xy 138.312354 -431.615134) (xy 138.292834 -431.629386) (xy 138.269871 -431.636925)
			(xy 138.257788 -431.63744) (xy 137.317988 -431.63744) (xy 137.305882 -431.636995) (xy 137.282862 -431.629497)
			(xy 137.263292 -431.615241) (xy 137.249096 -431.595628) (xy 137.241669 -431.572585) (xy 137.24128 -431.560478)
			(xy 136.3345 -431.560478) (xy 136.3345 -432.560476) (xy 136.334067 -432.572558) (xy 136.326605 -432.595542)
			(xy 136.312404 -432.615093) (xy 136.292856 -432.629297) (xy 136.269874 -432.636764) (xy 136.257792 -432.637184)
			(xy 135.317992 -432.637184) (xy 135.305906 -432.636794) (xy 135.282919 -432.629321) (xy 135.263367 -432.61511)
			(xy 135.249164 -432.595552) (xy 135.241701 -432.572562) (xy 135.241284 -432.560476) (xy 134.30708 -432.560476)
			(xy 134.312373 -432.564321) (xy 134.326568 -432.583857) (xy 134.334031 -432.606822) (xy 134.334504 -432.618896)
			(xy 134.334504 -435.16042) (xy 134.334053 -435.172496) (xy 134.326584 -435.195464) (xy 134.312384 -435.215001)
			(xy 134.292843 -435.229195) (xy 134.269872 -435.236656) (xy 134.257796 -435.237128) (xy 133.317996 -435.237128)
			(xy 133.305923 -435.236639) (xy 133.282959 -435.229178) (xy 133.263424 -435.214987) (xy 133.249229 -435.195455)
			(xy 133.241763 -435.172493) (xy 133.241288 -435.16042) (xy 132.334508 -435.16042) (xy 132.334508 -436.160418)
			(xy 132.334009 -436.172504) (xy 132.326553 -436.195497) (xy 132.312373 -436.215072) (xy 132.29285 -436.229324)
			(xy 132.269884 -436.236864) (xy 132.2578 -436.23738) (xy 131.318 -436.23738) (xy 131.305889 -436.236984)
			(xy 131.282858 -436.229482) (xy 131.263283 -436.215216) (xy 131.24909 -436.195589) (xy 131.241672 -436.17253)
			(xy 131.241292 -436.160418) (xy 130.307496 -436.160418) (xy 130.312505 -436.164067) (xy 130.3267 -436.183683)
			(xy 130.334125 -436.20673) (xy 130.334512 -436.218838) (xy 130.334512 -438.760362) (xy 130.334059 -438.772454)
			(xy 130.326607 -438.795462) (xy 130.312419 -438.815047) (xy 130.292879 -438.829297) (xy 130.269895 -438.836821)
			(xy 130.257804 -438.837324) (xy 129.318004 -438.837324) (xy 129.305898 -438.836881) (xy 129.282875 -438.829385)
			(xy 129.263303 -438.81513) (xy 129.249108 -438.795515) (xy 129.241683 -438.77247) (xy 129.241296 -438.760362)
			(xy 128.334516 -438.760362) (xy 128.334516 -439.76036) (xy 131.241292 -439.76036) (xy 131.241292 -437.218836)
			(xy 131.241743 -437.206755) (xy 131.249201 -437.183774) (xy 131.263397 -437.164223) (xy 131.282941 -437.150017)
			(xy 131.305919 -437.142549) (xy 131.318 -437.142128) (xy 132.2578 -437.142128) (xy 132.269886 -437.142513)
			(xy 132.292875 -437.149985) (xy 132.312429 -437.164197) (xy 132.326632 -437.183757) (xy 132.334093 -437.206749)
			(xy 132.334508 -437.218836) (xy 132.334508 -438.760362) (xy 133.241288 -438.760362) (xy 133.241288 -436.218838)
			(xy 133.241741 -436.206746) (xy 133.249193 -436.183738) (xy 133.263381 -436.164153) (xy 133.282921 -436.149903)
			(xy 133.305905 -436.142379) (xy 133.317996 -436.141876) (xy 134.257796 -436.141876) (xy 134.269902 -436.142319)
			(xy 134.292925 -436.149815) (xy 134.307483 -436.160418) (xy 135.241284 -436.160418) (xy 135.241284 -433.618894)
			(xy 135.241703 -433.6068) (xy 135.249167 -433.583792) (xy 135.263364 -433.564208) (xy 135.282911 -433.549959)
			(xy 135.305899 -433.542435) (xy 135.317992 -433.541932) (xy 136.257792 -433.541932) (xy 136.269904 -433.542323)
			(xy 136.292936 -433.549824) (xy 136.312512 -433.564091) (xy 136.326706 -433.58372) (xy 136.334121 -433.606781)
			(xy 136.3345 -433.618894) (xy 136.3345 -435.16042) (xy 137.24128 -435.16042) (xy 137.24128 -432.618896)
			(xy 137.241761 -432.606822) (xy 137.249223 -432.583857) (xy 137.263416 -432.564321) (xy 137.28295 -432.550126)
			(xy 137.305914 -432.542662) (xy 137.317988 -432.542188) (xy 138.257788 -432.542188) (xy 138.26987 -432.542623)
			(xy 138.292851 -432.550087) (xy 138.307154 -432.560476) (xy 139.241276 -432.560476) (xy 139.241276 -430.018952)
			(xy 139.241723 -430.006877) (xy 139.249197 -429.98391) (xy 139.263398 -429.964376) (xy 139.282939 -429.950182)
			(xy 139.305908 -429.942718) (xy 139.317984 -429.942244) (xy 140.257784 -429.942244) (xy 140.269853 -429.942777)
			(xy 140.292812 -429.950229) (xy 140.312345 -429.96441) (xy 140.326541 -429.983931) (xy 140.334013 -430.006883)
			(xy 140.334492 -430.018952) (xy 140.334492 -431.560478) (xy 142.241524 -431.560478) (xy 142.241524 -429.018954)
			(xy 142.241968 -429.006864) (xy 142.249435 -428.983864) (xy 142.263628 -428.964286) (xy 142.283165 -428.950037)
			(xy 142.306143 -428.942503) (xy 142.318232 -428.941992) (xy 143.258032 -428.941992) (xy 143.270142 -428.942389)
			(xy 143.293169 -428.949896) (xy 143.307414 -428.96028) (xy 144.24152 -428.96028) (xy 144.24152 -428.233332)
			(xy 144.241748 -428.224511) (xy 144.245729 -428.207323) (xy 144.249394 -428.199296) (xy 144.48282 -427.723046)
			(xy 144.487546 -427.712539) (xy 144.491026 -427.689775) (xy 144.487531 -427.667013) (xy 144.48282 -427.656498)
			(xy 144.249394 -427.180248) (xy 144.245724 -427.172221) (xy 144.241739 -427.155034) (xy 144.24152 -427.146212)
			(xy 144.24152 -426.418756) (xy 144.241927 -426.406676) (xy 144.249405 -426.383703) (xy 144.263615 -426.364164)
			(xy 144.283168 -426.349972) (xy 144.306148 -426.342516) (xy 144.318228 -426.342048) (xy 145.258028 -426.342048)
			(xy 145.2701 -426.342539) (xy 145.29306 -426.350004) (xy 145.312593 -426.364195) (xy 145.326788 -426.383725)
			(xy 145.334258 -426.406684) (xy 145.334736 -426.418756) (xy 145.334736 -427.960536) (xy 146.241516 -427.960536)
			(xy 146.241516 -427.233588) (xy 146.241763 -427.224768) (xy 146.245731 -427.20758) (xy 146.24939 -427.199552)
			(xy 146.482816 -426.723302) (xy 146.487503 -426.71278) (xy 146.490997 -426.690025) (xy 146.487518 -426.667268)
			(xy 146.482816 -426.656754) (xy 146.24939 -426.180504) (xy 146.245706 -426.172483) (xy 146.24173 -426.155292)
			(xy 146.241516 -426.146468) (xy 146.241516 -425.419012) (xy 146.241923 -425.406928) (xy 146.249391 -425.383941)
			(xy 146.263597 -425.364389) (xy 146.283152 -425.350185) (xy 146.306139 -425.342722) (xy 146.318224 -425.342304)
			(xy 147.258024 -425.342304) (xy 147.270101 -425.342744) (xy 147.293071 -425.350215) (xy 147.312609 -425.364417)
			(xy 147.326802 -425.383961) (xy 147.334261 -425.406935) (xy 147.334732 -425.419012) (xy 147.334732 -427.960536)
			(xy 147.334267 -427.97261) (xy 147.326798 -427.995574) (xy 147.3126 -428.015109) (xy 147.293064 -428.029303)
			(xy 147.270098 -428.036769) (xy 147.258024 -428.037244) (xy 146.318224 -428.037244) (xy 146.306154 -428.036716)
			(xy 146.283194 -428.029264) (xy 146.26366 -428.015083) (xy 146.249463 -427.99556) (xy 146.241993 -427.972605)
			(xy 146.241516 -427.960536) (xy 145.334736 -427.960536) (xy 145.334736 -428.96028) (xy 145.334219 -428.972351)
			(xy 145.326766 -428.995313) (xy 145.312582 -429.014848) (xy 145.293056 -429.029044) (xy 145.270098 -429.036512)
			(xy 145.258028 -429.036988) (xy 144.318228 -429.036988) (xy 144.306145 -429.036563) (xy 144.28316 -429.029101)
			(xy 144.263607 -429.014899) (xy 144.249403 -428.995348) (xy 144.241938 -428.972363) (xy 144.24152 -428.96028)
			(xy 143.307414 -428.96028) (xy 143.312741 -428.964163) (xy 143.326934 -428.983788) (xy 143.334356 -429.006843)
			(xy 143.33474 -429.018954) (xy 143.33474 -431.560478) (xy 143.334273 -431.572568) (xy 143.32682 -431.595572)
			(xy 143.312634 -431.615154) (xy 143.293099 -431.629404) (xy 143.270121 -431.636933) (xy 143.258032 -431.63744)
			(xy 142.318232 -431.63744) (xy 142.306129 -431.636957) (xy 142.283109 -431.629471) (xy 142.263539 -431.615225)
			(xy 142.249342 -431.59562) (xy 142.241913 -431.572582) (xy 142.241524 -431.560478) (xy 140.334492 -431.560478)
			(xy 140.334492 -432.560476) (xy 140.334067 -432.572559) (xy 140.326604 -432.595544) (xy 140.312401 -432.615096)
			(xy 140.292851 -432.6293) (xy 140.269867 -432.636765) (xy 140.257784 -432.637184) (xy 139.317984 -432.637184)
			(xy 139.305898 -432.636801) (xy 139.282911 -432.629326) (xy 139.263359 -432.615113) (xy 139.249156 -432.595553)
			(xy 139.241693 -432.572562) (xy 139.241276 -432.560476) (xy 138.307154 -432.560476) (xy 138.312401 -432.564287)
			(xy 138.326606 -432.583834) (xy 138.334074 -432.606814) (xy 138.334496 -432.618896) (xy 138.334496 -435.16042)
			(xy 138.334052 -435.172497) (xy 138.326583 -435.195467) (xy 138.312381 -435.215004) (xy 138.292838 -435.229198)
			(xy 138.269865 -435.236657) (xy 138.257788 -435.237128) (xy 137.317988 -435.237128) (xy 137.305915 -435.236646)
			(xy 137.282951 -435.229183) (xy 137.263416 -435.21499) (xy 137.249221 -435.195456) (xy 137.241755 -435.172493)
			(xy 137.24128 -435.16042) (xy 136.3345 -435.16042) (xy 136.3345 -436.160418) (xy 136.334009 -436.172505)
			(xy 136.326552 -436.195499) (xy 136.31237 -436.215075) (xy 136.292845 -436.229327) (xy 136.269877 -436.236865)
			(xy 136.257792 -436.23738) (xy 135.317992 -436.23738) (xy 135.305881 -436.23699) (xy 135.28285 -436.229486)
			(xy 135.263275 -436.215219) (xy 135.249081 -436.19559) (xy 135.241664 -436.172531) (xy 135.241284 -436.160418)
			(xy 134.307483 -436.160418) (xy 134.312497 -436.16407) (xy 134.326692 -436.183685) (xy 134.334117 -436.20673)
			(xy 134.334504 -436.218838) (xy 134.334504 -438.760362) (xy 134.333961 -438.772445) (xy 134.32652 -438.795437)
			(xy 134.312352 -438.815014) (xy 134.292837 -438.829267) (xy 134.269877 -438.836808) (xy 134.257796 -438.837324)
			(xy 133.317996 -438.837324) (xy 133.305889 -438.836888) (xy 133.282866 -438.82939) (xy 133.263295 -438.815133)
			(xy 133.2491 -438.795517) (xy 133.241675 -438.77247) (xy 133.241288 -438.760362) (xy 132.334508 -438.760362)
			(xy 132.334508 -439.76036) (xy 135.241284 -439.76036) (xy 135.241284 -437.218836) (xy 135.241743 -437.206756)
			(xy 135.2492 -437.183776) (xy 135.263394 -437.164226) (xy 135.282936 -437.15002) (xy 135.305912 -437.14255)
			(xy 135.317992 -437.142128) (xy 136.257792 -437.142128) (xy 136.269878 -437.14252) (xy 136.292867 -437.149989)
			(xy 136.31242 -437.1642) (xy 136.326623 -437.183759) (xy 136.334085 -437.20675) (xy 136.3345 -437.218836)
			(xy 136.3345 -438.760362) (xy 137.24128 -438.760362) (xy 137.24128 -436.218838) (xy 137.24174 -436.206746)
			(xy 137.249192 -436.18374) (xy 137.263378 -436.164156) (xy 137.282916 -436.149906) (xy 137.305898 -436.14238)
			(xy 137.317988 -436.141876) (xy 138.257788 -436.141876) (xy 138.269894 -436.142326) (xy 138.292917 -436.14982)
			(xy 138.307469 -436.160418) (xy 139.241276 -436.160418) (xy 139.241276 -433.618894) (xy 139.241703 -433.606801)
			(xy 139.249166 -433.583794) (xy 139.263361 -433.564211) (xy 139.282906 -433.549962) (xy 139.305892 -433.542436)
			(xy 139.317984 -433.541932) (xy 140.257784 -433.541932) (xy 140.269895 -433.542331) (xy 140.292927 -433.549829)
			(xy 140.312503 -433.564094) (xy 140.326697 -433.583722) (xy 140.334113 -433.606781) (xy 140.334492 -433.618894)
			(xy 140.334492 -435.16042) (xy 142.241016 -435.16042) (xy 142.241016 -432.618896) (xy 142.241413 -432.606785)
			(xy 142.248915 -432.583755) (xy 142.263181 -432.564181) (xy 142.282808 -432.549987) (xy 142.305866 -432.542569)
			(xy 142.317978 -432.542188) (xy 143.257778 -432.542188) (xy 143.269871 -432.542627) (xy 143.292879 -432.550084)
			(xy 143.30722 -432.560476) (xy 144.24152 -432.560476) (xy 144.24152 -430.018952) (xy 144.241924 -430.006872)
			(xy 144.249403 -429.983899) (xy 144.263614 -429.96436) (xy 144.283167 -429.950168) (xy 144.306148 -429.942712)
			(xy 144.318228 -429.942244) (xy 145.258028 -429.942244) (xy 145.270099 -429.942739) (xy 145.293059 -429.950204)
			(xy 145.312592 -429.964394) (xy 145.326787 -429.983923) (xy 145.334258 -430.006881) (xy 145.334736 -430.018952)
			(xy 145.334736 -431.560478) (xy 146.241516 -431.560478) (xy 146.241516 -429.018954) (xy 146.241968 -429.006864)
			(xy 146.249434 -428.983866) (xy 146.263626 -428.964289) (xy 146.28316 -428.950039) (xy 146.306136 -428.942504)
			(xy 146.318224 -428.941992) (xy 147.258024 -428.941992) (xy 147.270133 -428.942396) (xy 147.29316 -428.949901)
			(xy 147.3074 -428.96028) (xy 148.241512 -428.96028) (xy 148.241512 -428.233332) (xy 148.241741 -428.224511)
			(xy 148.245721 -428.207323) (xy 148.249386 -428.199296) (xy 148.482812 -427.723046) (xy 148.487538 -427.712539)
			(xy 148.491019 -427.689775) (xy 148.487523 -427.667012) (xy 148.482812 -427.656498) (xy 148.249386 -427.180248)
			(xy 148.245716 -427.172222) (xy 148.241731 -427.155034) (xy 148.241512 -427.146212) (xy 148.241512 -426.418756)
			(xy 148.241927 -426.406677) (xy 148.249404 -426.383705) (xy 148.263613 -426.364167) (xy 148.283162 -426.349975)
			(xy 148.306141 -426.342517) (xy 148.31822 -426.342048) (xy 149.25802 -426.342048) (xy 149.270091 -426.342547)
			(xy 149.293052 -426.350009) (xy 149.312584 -426.364199) (xy 149.32678 -426.383727) (xy 149.33425 -426.406685)
			(xy 149.334728 -426.418756) (xy 149.334728 -427.960536) (xy 150.241508 -427.960536) (xy 150.241508 -427.233588)
			(xy 150.241756 -427.224768) (xy 150.245723 -427.207581) (xy 150.249382 -427.199552) (xy 150.482808 -426.723302)
			(xy 150.487495 -426.71278) (xy 150.49099 -426.690025) (xy 150.487511 -426.667268) (xy 150.482808 -426.656754)
			(xy 150.249382 -426.180504) (xy 150.245698 -426.172483) (xy 150.241722 -426.155292) (xy 150.241508 -426.146468)
			(xy 150.241508 -425.419012) (xy 150.241923 -425.406928) (xy 150.249389 -425.383943) (xy 150.263594 -425.364392)
			(xy 150.283147 -425.350188) (xy 150.306132 -425.342723) (xy 150.318216 -425.342304) (xy 151.258016 -425.342304)
			(xy 151.270093 -425.342751) (xy 151.293062 -425.350219) (xy 151.3126 -425.36442) (xy 151.326794 -425.383963)
			(xy 151.334253 -425.406935) (xy 151.334724 -425.419012) (xy 151.334724 -427.960536) (xy 151.334267 -427.972611)
			(xy 151.326796 -427.995577) (xy 151.312597 -428.015112) (xy 151.293059 -428.029306) (xy 151.270091 -428.03677)
			(xy 151.258016 -428.037244) (xy 150.318216 -428.037244) (xy 150.306146 -428.036723) (xy 150.283185 -428.029269)
			(xy 150.263651 -428.015086) (xy 150.249455 -427.995561) (xy 150.241985 -427.972606) (xy 150.241508 -427.960536)
			(xy 149.334728 -427.960536) (xy 149.334728 -428.96028) (xy 149.334219 -428.972352) (xy 149.326765 -428.995315)
			(xy 149.312579 -429.01485) (xy 149.293051 -429.029046) (xy 149.270091 -429.036513) (xy 149.25802 -429.036988)
			(xy 148.31822 -429.036988) (xy 148.306136 -429.03657) (xy 148.283151 -429.029105) (xy 148.263599 -429.014901)
			(xy 148.249395 -428.995349) (xy 148.24193 -428.972364) (xy 148.241512 -428.96028) (xy 147.3074 -428.96028)
			(xy 147.312732 -428.964166) (xy 147.326926 -428.983789) (xy 147.334348 -429.006843) (xy 147.334732 -429.018954)
			(xy 147.334732 -431.560478) (xy 147.334273 -431.572569) (xy 147.326819 -431.595574) (xy 147.312632 -431.615156)
			(xy 147.293094 -431.629407) (xy 147.270114 -431.636934) (xy 147.258024 -431.63744) (xy 146.318224 -431.63744)
			(xy 146.30612 -431.636964) (xy 146.283101 -431.629476) (xy 146.263531 -431.615228) (xy 146.249334 -431.595622)
			(xy 146.241905 -431.572583) (xy 146.241516 -431.560478) (xy 145.334736 -431.560478) (xy 145.334736 -432.560476)
			(xy 145.334216 -432.572547) (xy 145.326763 -432.595508) (xy 145.31258 -432.615043) (xy 145.293055 -432.62924)
			(xy 145.270098 -432.636708) (xy 145.258028 -432.637184) (xy 144.318228 -432.637184) (xy 144.306144 -432.636763)
			(xy 144.283159 -432.6293) (xy 144.263606 -432.615097) (xy 144.249402 -432.595545) (xy 144.241938 -432.57256)
			(xy 144.24152 -432.560476) (xy 143.30722 -432.560476) (xy 143.312464 -432.564276) (xy 143.326713 -432.583818)
			(xy 143.334237 -432.606804) (xy 143.33474 -432.618896) (xy 143.33474 -435.16042) (xy 143.334301 -435.172526)
			(xy 143.326801 -435.195547) (xy 143.312544 -435.215116) (xy 143.29293 -435.229312) (xy 143.269885 -435.236739)
			(xy 143.257778 -435.237128) (xy 142.317978 -435.237128) (xy 142.305884 -435.236711) (xy 142.282877 -435.229244)
			(xy 142.263295 -435.215046) (xy 142.249046 -435.1955) (xy 142.24152 -435.172513) (xy 142.241016 -435.16042)
			(xy 140.334492 -435.16042) (xy 140.334492 -436.160418) (xy 140.334009 -436.172505) (xy 140.326551 -436.195501)
			(xy 140.312367 -436.215078) (xy 140.29284 -436.229329) (xy 140.26987 -436.236866) (xy 140.257784 -436.23738)
			(xy 139.317984 -436.23738) (xy 139.305872 -436.236997) (xy 139.282841 -436.229491) (xy 139.263266 -436.215221)
			(xy 139.249073 -436.195592) (xy 139.241656 -436.172531) (xy 139.241276 -436.160418) (xy 138.307469 -436.160418)
			(xy 138.312488 -436.164073) (xy 138.326684 -436.183686) (xy 138.334109 -436.206731) (xy 138.334496 -436.218838)
			(xy 138.334496 -438.760362) (xy 138.333961 -438.772446) (xy 138.326519 -438.795439) (xy 138.312349 -438.815017)
			(xy 138.292832 -438.82927) (xy 138.26987 -438.836809) (xy 138.257788 -438.837324) (xy 137.317988 -438.837324)
			(xy 137.305881 -438.836894) (xy 137.282857 -438.829395) (xy 137.263286 -438.815136) (xy 137.249091 -438.795518)
			(xy 137.241667 -438.77247) (xy 137.24128 -438.760362) (xy 136.3345 -438.760362) (xy 136.3345 -439.76036)
			(xy 139.241276 -439.76036) (xy 139.241276 -437.218836) (xy 139.241743 -437.206757) (xy 139.249199 -437.183778)
			(xy 139.263391 -437.164228) (xy 139.282931 -437.150023) (xy 139.305905 -437.142551) (xy 139.317984 -437.142128)
			(xy 140.257784 -437.142128) (xy 140.269869 -437.142527) (xy 140.292858 -437.149995) (xy 140.312411 -437.164203)
			(xy 140.326615 -437.18376) (xy 140.334076 -437.20675) (xy 140.334492 -437.218836) (xy 140.334492 -438.760362)
			(xy 142.241016 -438.760362) (xy 142.241016 -436.218838) (xy 142.241492 -436.206719) (xy 142.248971 -436.183665)
			(xy 142.263209 -436.164052) (xy 142.282812 -436.149798) (xy 142.30586 -436.142301) (xy 142.317978 -436.141876)
			(xy 143.257778 -436.141876) (xy 143.269903 -436.142279) (xy 143.292968 -436.14977) (xy 143.307623 -436.160418)
			(xy 144.241012 -436.160418) (xy 144.241012 -433.618894) (xy 144.241506 -433.606782) (xy 144.248992 -433.583743)
			(xy 144.263229 -433.564143) (xy 144.282825 -433.549901) (xy 144.305862 -433.54241) (xy 144.317974 -433.541932)
			(xy 145.257774 -433.541932) (xy 145.269895 -433.542382) (xy 145.292952 -433.549866) (xy 145.312567 -433.56411)
			(xy 145.326819 -433.58372) (xy 145.334313 -433.606773) (xy 145.334736 -433.618894) (xy 145.334736 -435.16042)
			(xy 146.241008 -435.16042) (xy 146.241008 -432.618896) (xy 146.241413 -432.606786) (xy 146.248914 -432.583757)
			(xy 146.263179 -432.564184) (xy 146.282803 -432.549989) (xy 146.305859 -432.54257) (xy 146.31797 -432.542188)
			(xy 147.25777 -432.542188) (xy 147.269863 -432.542634) (xy 147.29287 -432.550088) (xy 147.307207 -432.560476)
			(xy 148.241512 -432.560476) (xy 148.241512 -430.018952) (xy 148.241924 -430.006873) (xy 148.249402 -429.983901)
			(xy 148.263611 -429.964363) (xy 148.283162 -429.950171) (xy 148.306141 -429.942713) (xy 148.31822 -429.942244)
			(xy 149.25802 -429.942244) (xy 149.270091 -429.942747) (xy 149.29305 -429.950209) (xy 149.312583 -429.964397)
			(xy 149.326778 -429.983924) (xy 149.334249 -430.006881) (xy 149.334728 -430.018952) (xy 149.334728 -431.560478)
			(xy 150.241508 -431.560478) (xy 150.241508 -429.018954) (xy 150.241968 -429.006865) (xy 150.249433 -428.983868)
			(xy 150.263623 -428.964292) (xy 150.283155 -428.950042) (xy 150.306129 -428.942505) (xy 150.318216 -428.941992)
			(xy 151.258016 -428.941992) (xy 151.270125 -428.942402) (xy 151.293151 -428.949905) (xy 151.307388 -428.96028)
			(xy 152.241504 -428.96028) (xy 152.241504 -428.233332) (xy 152.241734 -428.224511) (xy 152.245714 -428.207323)
			(xy 152.249378 -428.199296) (xy 152.482804 -427.723046) (xy 152.487531 -427.712539) (xy 152.491012 -427.689775)
			(xy 152.487516 -427.667012) (xy 152.482804 -427.656498) (xy 152.249378 -427.180248) (xy 152.245707 -427.172222)
			(xy 152.241723 -427.155034) (xy 152.241504 -427.146212) (xy 152.241504 -426.418756) (xy 152.241927 -426.406678)
			(xy 152.249403 -426.383707) (xy 152.26361 -426.36417) (xy 152.283157 -426.349977) (xy 152.306134 -426.342518)
			(xy 152.318212 -426.342048) (xy 153.258012 -426.342048) (xy 153.270083 -426.342553) (xy 153.293043 -426.350014)
			(xy 153.312576 -426.364201) (xy 153.326772 -426.383728) (xy 153.334242 -426.406685) (xy 153.33472 -426.418756)
			(xy 153.33472 -427.960536) (xy 154.2415 -427.960536) (xy 154.2415 -427.233588) (xy 154.241749 -427.224768)
			(xy 154.245716 -427.207581) (xy 154.249374 -427.199552) (xy 154.4828 -426.723302) (xy 154.487488 -426.71278)
			(xy 154.490983 -426.690025) (xy 154.487503 -426.667268) (xy 154.4828 -426.656754) (xy 154.249374 -426.180504)
			(xy 154.245689 -426.172484) (xy 154.241714 -426.155292) (xy 154.2415 -426.146468) (xy 154.2415 -425.419012)
			(xy 154.241923 -425.406929) (xy 154.249388 -425.383946) (xy 154.263592 -425.364394) (xy 154.283142 -425.35019)
			(xy 154.306125 -425.342724) (xy 154.318208 -425.342304) (xy 155.258008 -425.342304) (xy 155.270092 -425.342706)
			(xy 155.293077 -425.350177) (xy 155.312629 -425.364386) (xy 155.326832 -425.383941) (xy 155.334297 -425.406928)
			(xy 155.334716 -425.419012) (xy 155.334716 -427.960536) (xy 155.334267 -427.972612) (xy 155.326795 -427.995579)
			(xy 155.312595 -428.015115) (xy 155.293054 -428.029308) (xy 155.270084 -428.036771) (xy 155.258008 -428.037244)
			(xy 154.318208 -428.037244) (xy 154.306137 -428.03673) (xy 154.283177 -428.029274) (xy 154.263643 -428.015089)
			(xy 154.249447 -427.995563) (xy 154.241977 -427.972606) (xy 154.2415 -427.960536) (xy 153.33472 -427.960536)
			(xy 153.33472 -428.96028) (xy 153.33427 -428.97236) (xy 153.32681 -428.99534) (xy 153.312613 -429.01489)
			(xy 153.293069 -429.029095) (xy 153.270092 -429.036565) (xy 153.258012 -429.036988) (xy 152.318212 -429.036988)
			(xy 152.306128 -429.036577) (xy 152.283142 -429.02911) (xy 152.26359 -429.014904) (xy 152.249386 -428.995351)
			(xy 152.241922 -428.972364) (xy 152.241504 -428.96028) (xy 151.307388 -428.96028) (xy 151.312724 -428.964169)
			(xy 151.326918 -428.983791) (xy 151.33434 -429.006844) (xy 151.334724 -429.018954) (xy 151.334724 -431.560478)
			(xy 151.334273 -431.57257) (xy 151.326818 -431.595576) (xy 151.312629 -431.615159) (xy 151.293089 -431.629409)
			(xy 151.270106 -431.636935) (xy 151.258016 -431.63744) (xy 150.318216 -431.63744) (xy 150.306112 -431.63697)
			(xy 150.283092 -431.62948) (xy 150.263522 -431.615231) (xy 150.249326 -431.595623) (xy 150.241897 -431.572583)
			(xy 150.241508 -431.560478) (xy 149.334728 -431.560478) (xy 149.334728 -432.560476) (xy 149.334267 -432.572555)
			(xy 149.326809 -432.595534) (xy 149.312614 -432.615083) (xy 149.293073 -432.629288) (xy 149.270099 -432.63676)
			(xy 149.25802 -432.637184) (xy 148.31822 -432.637184) (xy 148.306136 -432.63677) (xy 148.28315 -432.629305)
			(xy 148.263597 -432.6151) (xy 148.249393 -432.595547) (xy 148.24193 -432.57256) (xy 148.241512 -432.560476)
			(xy 147.307207 -432.560476) (xy 147.312455 -432.564278) (xy 147.326705 -432.58382) (xy 147.334229 -432.606805)
			(xy 147.334732 -432.618896) (xy 147.334732 -435.16042) (xy 147.334301 -435.172527) (xy 147.3268 -435.195549)
			(xy 147.312541 -435.215119) (xy 147.292925 -435.229314) (xy 147.269878 -435.23674) (xy 147.25777 -435.237128)
			(xy 146.31797 -435.237128) (xy 146.305876 -435.236718) (xy 146.282869 -435.229249) (xy 146.263286 -435.215049)
			(xy 146.249038 -435.195502) (xy 146.241512 -435.172513) (xy 146.241008 -435.16042) (xy 145.334736 -435.16042)
			(xy 145.334736 -436.160418) (xy 145.334355 -436.172544) (xy 145.326854 -436.195608) (xy 145.312594 -436.215225)
			(xy 145.292969 -436.229474) (xy 145.2699 -436.236962) (xy 145.257774 -436.23738) (xy 144.317974 -436.23738)
			(xy 144.30586 -436.236911) (xy 144.282819 -436.229419) (xy 144.263219 -436.215175) (xy 144.248978 -436.195574)
			(xy 144.241488 -436.172532) (xy 144.241012 -436.160418) (xy 143.307623 -436.160418) (xy 143.312587 -436.164025)
			(xy 143.326837 -436.183646) (xy 143.334323 -436.206713) (xy 143.33474 -436.218838) (xy 143.33474 -438.760362)
			(xy 143.334307 -438.772485) (xy 143.326823 -438.795546) (xy 143.312575 -438.815164) (xy 143.292961 -438.829416)
			(xy 143.269901 -438.836905) (xy 143.257778 -438.837324) (xy 142.317978 -438.837324) (xy 142.30585 -438.836958)
			(xy 142.282784 -438.829455) (xy 142.263167 -438.815191) (xy 142.248918 -438.795562) (xy 142.241433 -438.77249)
			(xy 142.241016 -438.760362) (xy 140.334492 -438.760362) (xy 140.334492 -439.76036) (xy 144.241012 -439.76036)
			(xy 144.241012 -437.218836) (xy 144.241447 -437.206728) (xy 144.248938 -437.1837) (xy 144.263194 -437.164125)
			(xy 144.282813 -437.14993) (xy 144.305865 -437.14251) (xy 144.317974 -437.142128) (xy 145.257774 -437.142128)
			(xy 145.269861 -437.142629) (xy 145.292859 -437.150077) (xy 145.312438 -437.164256) (xy 145.32669 -437.183781)
			(xy 145.334225 -437.206751) (xy 145.334736 -437.218836) (xy 145.334736 -438.760362) (xy 146.241008 -438.760362)
			(xy 146.241008 -436.218838) (xy 146.241492 -436.20672) (xy 146.24897 -436.183668) (xy 146.263206 -436.164055)
			(xy 146.282807 -436.149801) (xy 146.305853 -436.142302) (xy 146.31797 -436.141876) (xy 147.25777 -436.141876)
			(xy 147.269895 -436.142286) (xy 147.292959 -436.149775) (xy 147.307609 -436.160418) (xy 148.241004 -436.160418)
			(xy 148.241004 -433.618894) (xy 148.241506 -433.606783) (xy 148.248991 -433.583745) (xy 148.263226 -433.564146)
			(xy 148.28282 -433.549904) (xy 148.305855 -433.542411) (xy 148.317966 -433.541932) (xy 149.257766 -433.541932)
			(xy 149.269886 -433.542389) (xy 149.292943 -433.549871) (xy 149.312558 -433.564113) (xy 149.326811 -433.583721)
			(xy 149.334305 -433.606774) (xy 149.334728 -433.618894) (xy 149.334728 -435.16042) (xy 150.241 -435.16042)
			(xy 150.241 -432.618896) (xy 150.241413 -432.606787) (xy 150.248913 -432.583759) (xy 150.263176 -432.564186)
			(xy 150.282798 -432.549992) (xy 150.305852 -432.542571) (xy 150.317962 -432.542188) (xy 151.257762 -432.542188)
			(xy 151.269854 -432.542641) (xy 151.292862 -432.550093) (xy 151.307195 -432.560476) (xy 152.241504 -432.560476)
			(xy 152.241504 -430.018952) (xy 152.241923 -430.006874) (xy 152.249401 -429.983903) (xy 152.263608 -429.964366)
			(xy 152.283157 -429.950173) (xy 152.306133 -429.942714) (xy 152.318212 -429.942244) (xy 153.258012 -429.942244)
			(xy 153.270082 -429.942753) (xy 153.293042 -429.950213) (xy 153.312574 -429.9644) (xy 153.32677 -429.983926)
			(xy 153.334241 -430.006882) (xy 153.33472 -430.018952) (xy 153.33472 -431.560478) (xy 154.2415 -431.560478)
			(xy 154.2415 -429.018954) (xy 154.241967 -429.006866) (xy 154.249432 -428.983871) (xy 154.26362 -428.964295)
			(xy 154.28315 -428.950044) (xy 154.306122 -428.942507) (xy 154.318208 -428.941992) (xy 155.258008 -428.941992)
			(xy 155.270117 -428.942409) (xy 155.293143 -428.94991) (xy 155.307374 -428.96028) (xy 156.241496 -428.96028)
			(xy 156.241496 -428.233332) (xy 156.241727 -428.224511) (xy 156.245706 -428.207324) (xy 156.24937 -428.199296)
			(xy 156.482796 -427.723046) (xy 156.487523 -427.712539) (xy 156.491005 -427.689775) (xy 156.487508 -427.667012)
			(xy 156.482796 -427.656498) (xy 156.24937 -427.180248) (xy 156.245699 -427.172222) (xy 156.241715 -427.155035)
			(xy 156.241496 -427.146212) (xy 156.241496 -426.418756) (xy 156.241927 -426.406679) (xy 156.249402 -426.383709)
			(xy 156.263607 -426.364173) (xy 156.283152 -426.34998) (xy 156.306126 -426.342519) (xy 156.318204 -426.342048)
			(xy 157.258004 -426.342048) (xy 157.270074 -426.34256) (xy 157.293034 -426.350018) (xy 157.312567 -426.364204)
			(xy 157.326763 -426.38373) (xy 157.334233 -426.406686) (xy 157.334712 -426.418756) (xy 157.334712 -428.96028)
			(xy 157.33427 -428.972361) (xy 157.326809 -428.995343) (xy 157.31261 -429.014893) (xy 157.293064 -429.029098)
			(xy 157.270085 -429.036566) (xy 157.258004 -429.036988) (xy 156.318204 -429.036988) (xy 156.306119 -429.036584)
			(xy 156.283133 -429.029115) (xy 156.263581 -429.014907) (xy 156.249378 -428.995352) (xy 156.241914 -428.972365)
			(xy 156.241496 -428.96028) (xy 155.307374 -428.96028) (xy 155.312715 -428.964172) (xy 155.32691 -428.983792)
			(xy 155.334332 -429.006844) (xy 155.334716 -429.018954) (xy 155.334716 -431.560478) (xy 155.334273 -431.572571)
			(xy 155.326817 -431.595578) (xy 155.312626 -431.615162) (xy 155.293084 -431.629412) (xy 155.270099 -431.636937)
			(xy 155.258008 -431.63744) (xy 154.318208 -431.63744) (xy 154.306104 -431.636978) (xy 154.283083 -431.629485)
			(xy 154.263513 -431.615234) (xy 154.249317 -431.595625) (xy 154.241889 -431.572584) (xy 154.2415 -431.560478)
			(xy 153.33472 -431.560478) (xy 153.33472 -432.560476) (xy 153.334267 -432.572556) (xy 153.326807 -432.595536)
			(xy 153.312611 -432.615086) (xy 153.293068 -432.629291) (xy 153.270092 -432.636761) (xy 153.258012 -432.637184)
			(xy 152.318212 -432.637184) (xy 152.306128 -432.636777) (xy 152.283141 -432.629309) (xy 152.263589 -432.615103)
			(xy 152.249385 -432.595548) (xy 152.241922 -432.572561) (xy 152.241504 -432.560476) (xy 151.307195 -432.560476)
			(xy 151.312447 -432.564281) (xy 151.326697 -432.583821) (xy 151.334221 -432.606805) (xy 151.334724 -432.618896)
			(xy 151.334724 -435.16042) (xy 151.334301 -435.172528) (xy 151.326799 -435.195551) (xy 151.312538 -435.215122)
			(xy 151.29292 -435.229317) (xy 151.269871 -435.236741) (xy 151.257762 -435.237128) (xy 150.317962 -435.237128)
			(xy 150.305867 -435.236724) (xy 150.28286 -435.229253) (xy 150.263278 -435.215052) (xy 150.24903 -435.195503)
			(xy 150.241504 -435.172514) (xy 150.241 -435.16042) (xy 149.334728 -435.16042) (xy 149.334728 -436.160418)
			(xy 149.334355 -436.172545) (xy 149.326853 -436.19561) (xy 149.312591 -436.215228) (xy 149.292964 -436.229477)
			(xy 149.269893 -436.236963) (xy 149.257766 -436.23738) (xy 148.317966 -436.23738) (xy 148.305851 -436.236918)
			(xy 148.28281 -436.229423) (xy 148.26321 -436.215178) (xy 148.248969 -436.195576) (xy 148.24148 -436.172533)
			(xy 148.241004 -436.160418) (xy 147.307609 -436.160418) (xy 147.312578 -436.164028) (xy 147.326829 -436.183648)
			(xy 147.334315 -436.206713) (xy 147.334732 -436.218838) (xy 147.334732 -438.760362) (xy 147.334307 -438.772486)
			(xy 147.326822 -438.795549) (xy 147.312573 -438.815167) (xy 147.292956 -438.829418) (xy 147.269894 -438.836906)
			(xy 147.25777 -438.837324) (xy 146.31797 -438.837324) (xy 146.305842 -438.836965) (xy 146.282776 -438.82946)
			(xy 146.263158 -438.815194) (xy 146.248909 -438.795563) (xy 146.241424 -438.772491) (xy 146.241008 -438.760362)
			(xy 145.334736 -438.760362) (xy 145.334736 -439.76036) (xy 148.241004 -439.76036) (xy 148.241004 -437.218836)
			(xy 148.241447 -437.206729) (xy 148.248937 -437.183702) (xy 148.263192 -437.164128) (xy 148.282808 -437.149932)
			(xy 148.305857 -437.142511) (xy 148.317966 -437.142128) (xy 149.257766 -437.142128) (xy 149.269853 -437.142636)
			(xy 149.29285 -437.150082) (xy 149.31243 -437.164258) (xy 149.326682 -437.183783) (xy 149.334217 -437.206751)
			(xy 149.334728 -437.218836) (xy 149.334728 -438.760362) (xy 150.241 -438.760362) (xy 150.241 -436.218838)
			(xy 150.241543 -436.206729) (xy 150.249016 -436.183694) (xy 150.26324 -436.164094) (xy 150.282825 -436.14985)
			(xy 150.305854 -436.142355) (xy 150.317962 -436.141876) (xy 151.257762 -436.141876) (xy 151.269887 -436.142293)
			(xy 151.292951 -436.149779) (xy 151.307597 -436.160418) (xy 152.240996 -436.160418) (xy 152.240996 -433.618894)
			(xy 152.241506 -433.606783) (xy 152.24899 -433.583747) (xy 152.263224 -433.564149) (xy 152.282815 -433.549906)
			(xy 152.305848 -433.542412) (xy 152.317958 -433.541932) (xy 153.257758 -433.541932) (xy 153.269878 -433.542396)
			(xy 153.292934 -433.549876) (xy 153.31255 -433.564116) (xy 153.326803 -433.583722) (xy 153.334297 -433.606774)
			(xy 153.33472 -433.618894) (xy 153.33472 -435.16042) (xy 154.240992 -435.16042) (xy 154.240992 -432.618896)
			(xy 154.241413 -432.606788) (xy 154.248912 -432.583762) (xy 154.263173 -432.564189) (xy 154.282793 -432.549994)
			(xy 154.305844 -432.542572) (xy 154.317954 -432.542188) (xy 155.257754 -432.542188) (xy 155.269846 -432.542647)
			(xy 155.292853 -432.550097) (xy 155.307181 -432.560476) (xy 156.241496 -432.560476) (xy 156.241496 -430.018952)
			(xy 156.241923 -430.006875) (xy 156.249399 -429.983905) (xy 156.263605 -429.964368) (xy 156.283152 -429.950176)
			(xy 156.306126 -429.942715) (xy 156.318204 -429.942244) (xy 157.258004 -429.942244) (xy 157.270074 -429.94276)
			(xy 157.293033 -429.950218) (xy 157.312566 -429.964403) (xy 157.326762 -429.983927) (xy 157.334233 -430.006882)
			(xy 157.334712 -430.018952) (xy 157.334712 -432.560476) (xy 157.334267 -432.572557) (xy 157.326806 -432.595538)
			(xy 157.312609 -432.615089) (xy 157.293063 -432.629294) (xy 157.270085 -432.636762) (xy 157.258004 -432.637184)
			(xy 156.318204 -432.637184) (xy 156.306119 -432.636784) (xy 156.283132 -432.629314) (xy 156.26358 -432.615106)
			(xy 156.249376 -432.59555) (xy 156.241913 -432.572561) (xy 156.241496 -432.560476) (xy 155.307181 -432.560476)
			(xy 155.312438 -432.564284) (xy 155.326688 -432.583823) (xy 155.334213 -432.606806) (xy 155.334716 -432.618896)
			(xy 155.334716 -435.16042) (xy 155.334301 -435.172528) (xy 155.326798 -435.195554) (xy 155.312536 -435.215125)
			(xy 155.292915 -435.229319) (xy 155.269864 -435.236743) (xy 155.257754 -435.237128) (xy 154.317954 -435.237128)
			(xy 154.305859 -435.236731) (xy 154.282851 -435.229258) (xy 154.263269 -435.215054) (xy 154.249022 -435.195505)
			(xy 154.241496 -435.172514) (xy 154.240992 -435.16042) (xy 153.33472 -435.16042) (xy 153.33472 -436.160418)
			(xy 153.334354 -436.172546) (xy 153.326852 -436.195612) (xy 153.312588 -436.215231) (xy 153.292958 -436.22948)
			(xy 153.269886 -436.236964) (xy 153.257758 -436.23738) (xy 152.317958 -436.23738) (xy 152.305843 -436.236924)
			(xy 152.282801 -436.229428) (xy 152.263202 -436.215181) (xy 152.248961 -436.195577) (xy 152.241472 -436.172533)
			(xy 152.240996 -436.160418) (xy 151.307597 -436.160418) (xy 151.31257 -436.16403) (xy 151.326821 -436.183649)
			(xy 151.334307 -436.206713) (xy 151.334724 -436.218838) (xy 151.334724 -438.760362) (xy 151.334307 -438.772487)
			(xy 151.326821 -438.795551) (xy 151.31257 -438.81517) (xy 151.292951 -438.829421) (xy 151.269887 -438.836907)
			(xy 151.257762 -438.837324) (xy 150.317962 -438.837324) (xy 150.305842 -438.83692) (xy 150.282791 -438.829418)
			(xy 150.263186 -438.81516) (xy 150.248947 -438.795541) (xy 150.241468 -438.772483) (xy 150.241 -438.760362)
			(xy 149.334728 -438.760362) (xy 149.334728 -439.76036) (xy 152.240996 -439.76036) (xy 152.240996 -437.218836)
			(xy 152.241447 -437.206729) (xy 152.248936 -437.183704) (xy 152.263189 -437.164131) (xy 152.282803 -437.149935)
			(xy 152.30585 -437.142512) (xy 152.317958 -437.142128) (xy 153.257758 -437.142128) (xy 153.269844 -437.142643)
			(xy 153.292841 -437.150087) (xy 153.312421 -437.164261) (xy 153.326673 -437.183784) (xy 153.334209 -437.206752)
			(xy 153.33472 -437.218836) (xy 153.33472 -438.760362) (xy 154.240992 -438.760362) (xy 154.240992 -436.218838)
			(xy 154.241543 -436.20673) (xy 154.249015 -436.183696) (xy 154.263238 -436.164097) (xy 154.28282 -436.149853)
			(xy 154.305847 -436.142357) (xy 154.317954 -436.141876) (xy 155.257754 -436.141876) (xy 155.269878 -436.1423)
			(xy 155.292942 -436.149784) (xy 155.307584 -436.160418) (xy 156.240988 -436.160418) (xy 156.240988 -433.618894)
			(xy 156.241506 -433.606784) (xy 156.248989 -433.583749) (xy 156.263221 -433.564152) (xy 156.28281 -433.549909)
			(xy 156.30584 -433.542413) (xy 156.31795 -433.541932) (xy 157.25775 -433.541932) (xy 157.269867 -433.542369)
			(xy 157.29291 -433.549869) (xy 157.312511 -433.564121) (xy 157.326751 -433.583729) (xy 157.334238 -433.606777)
			(xy 157.334712 -433.618894) (xy 157.334712 -436.160418) (xy 157.334205 -436.172529) (xy 157.326718 -436.195564)
			(xy 157.312484 -436.215161) (xy 157.292893 -436.229404) (xy 157.26986 -436.2369) (xy 157.25775 -436.23738)
			(xy 156.31795 -436.23738) (xy 156.305835 -436.236931) (xy 156.282793 -436.229432) (xy 156.263193 -436.215184)
			(xy 156.248953 -436.195578) (xy 156.241464 -436.172534) (xy 156.240988 -436.160418) (xy 155.307584 -436.160418)
			(xy 155.312561 -436.164033) (xy 155.326813 -436.183651) (xy 155.334299 -436.206714) (xy 155.334716 -436.218838)
			(xy 155.334716 -438.760362) (xy 155.334307 -438.772487) (xy 155.32682 -438.795553) (xy 155.312567 -438.815173)
			(xy 155.292946 -438.829423) (xy 155.269879 -438.836908) (xy 155.257754 -438.837324) (xy 154.317954 -438.837324)
			(xy 154.305833 -438.836927) (xy 154.282782 -438.829422) (xy 154.263178 -438.815162) (xy 154.248939 -438.795543)
			(xy 154.24146 -438.772483) (xy 154.240992 -438.760362) (xy 153.33472 -438.760362) (xy 153.33472 -439.76036)
			(xy 156.240988 -439.76036) (xy 156.240988 -437.218836) (xy 156.241447 -437.20673) (xy 156.248935 -437.183706)
			(xy 156.263186 -437.164134) (xy 156.282798 -437.149937) (xy 156.305843 -437.142514) (xy 156.31795 -437.142128)
			(xy 157.25775 -437.142128) (xy 157.269836 -437.14265) (xy 157.292833 -437.150091) (xy 157.312413 -437.164264)
			(xy 157.326665 -437.183786) (xy 157.334201 -437.206752) (xy 157.334712 -437.218836) (xy 157.334712 -438.760616)
			(xy 314.141104 -438.760616) (xy 314.141104 -436.219092) (xy 314.141509 -436.206982) (xy 314.149012 -436.183954)
			(xy 314.163276 -436.164381) (xy 314.1829 -436.150186) (xy 314.205955 -436.142767) (xy 314.218066 -436.142384)
			(xy 315.157866 -436.142384) (xy 315.169958 -436.142837) (xy 315.192965 -436.15029) (xy 315.207295 -436.160672)
			(xy 316.1411 -436.160672) (xy 316.1411 -433.619148) (xy 316.141557 -433.607042) (xy 316.149043 -433.584016)
			(xy 316.163294 -433.564442) (xy 316.182908 -433.550246) (xy 316.205955 -433.542824) (xy 316.218062 -433.54244)
			(xy 317.157862 -433.54244) (xy 317.16995 -433.54294) (xy 317.192949 -433.550386) (xy 317.21253 -433.564564)
			(xy 317.226781 -433.584091) (xy 317.234314 -433.607062) (xy 317.234824 -433.619148) (xy 317.234824 -435.160674)
			(xy 318.141096 -435.160674) (xy 318.141096 -432.61915) (xy 318.141568 -432.607037) (xy 318.149064 -432.583999)
			(xy 318.163308 -432.564402) (xy 318.182906 -432.550161) (xy 318.205945 -432.542667) (xy 318.218058 -432.542188)
			(xy 319.157858 -432.542188) (xy 319.169965 -432.542747) (xy 319.192999 -432.550216) (xy 319.207487 -432.56073)
			(xy 320.141092 -432.56073) (xy 320.141092 -430.019206) (xy 320.141616 -430.007096) (xy 320.149096 -429.984061)
			(xy 320.163326 -429.964463) (xy 320.182915 -429.95022) (xy 320.205945 -429.942724) (xy 320.218054 -429.942244)
			(xy 321.157854 -429.942244) (xy 321.169975 -429.942699) (xy 321.193033 -429.950179) (xy 321.21265 -429.964422)
			(xy 321.226902 -429.984031) (xy 321.234395 -430.007085) (xy 321.234816 -430.019206) (xy 321.234816 -431.560732)
			(xy 322.141088 -431.560732) (xy 322.141088 -429.019208) (xy 322.141523 -429.007101) (xy 322.149019 -428.984076)
			(xy 322.163276 -428.964503) (xy 322.182893 -428.950308) (xy 322.205941 -428.942885) (xy 322.21805 -428.9425)
			(xy 323.15785 -428.9425) (xy 323.169933 -428.943049) (xy 323.192925 -428.950487) (xy 323.206809 -428.960534)
			(xy 324.141084 -428.960534) (xy 324.141084 -428.233586) (xy 324.141367 -428.224751) (xy 324.145481 -428.207564)
			(xy 324.149212 -428.19955) (xy 324.382638 -427.7233) (xy 324.387326 -427.712778) (xy 324.390818 -427.690023)
			(xy 324.38734 -427.667267) (xy 324.382638 -427.656752) (xy 324.149212 -427.180502) (xy 324.145457 -427.172496)
			(xy 324.14134 -427.155304) (xy 324.141084 -427.146466) (xy 324.141084 -426.41901) (xy 324.141469 -426.406883)
			(xy 324.148964 -426.383817) (xy 324.163223 -426.364198) (xy 324.182849 -426.349948) (xy 324.205919 -426.342464)
			(xy 324.218046 -426.342048) (xy 325.157846 -426.342048) (xy 325.169964 -426.342473) (xy 325.19301 -426.349974)
			(xy 325.212612 -426.364228) (xy 325.226852 -426.38384) (xy 325.234336 -426.406892) (xy 325.234808 -426.41901)
			(xy 325.234808 -427.960536) (xy 326.14108 -427.960536) (xy 326.14108 -427.233588) (xy 326.141364 -427.224753)
			(xy 326.145477 -427.207566) (xy 326.149208 -427.199552) (xy 326.382634 -426.723302) (xy 326.38732 -426.71278)
			(xy 326.390814 -426.690025) (xy 326.387336 -426.667268) (xy 326.382634 -426.656754) (xy 326.149208 -426.180504)
			(xy 326.145453 -426.172498) (xy 326.141336 -426.155306) (xy 326.14108 -426.146468) (xy 326.14108 -425.419012)
			(xy 326.141527 -425.406906) (xy 326.14902 -425.383882) (xy 326.163275 -425.364311) (xy 326.182889 -425.350115)
			(xy 326.205935 -425.342691) (xy 326.218042 -425.342304) (xy 327.157842 -425.342304) (xy 327.16993 -425.342771)
			(xy 327.192926 -425.350235) (xy 327.212502 -425.364423) (xy 327.226753 -425.383953) (xy 327.23429 -425.406925)
			(xy 327.234804 -425.419012) (xy 327.234804 -427.960536) (xy 327.234414 -427.972646) (xy 327.226906 -427.995674)
			(xy 327.212637 -428.015246) (xy 327.19301 -428.02944) (xy 327.169954 -428.03686) (xy 327.157842 -428.037244)
			(xy 326.218042 -428.037244) (xy 326.205953 -428.036757) (xy 326.182951 -428.029309) (xy 326.163369 -428.015129)
			(xy 326.149118 -427.995598) (xy 326.141587 -427.972623) (xy 326.14108 -427.960536) (xy 325.234808 -427.960536)
			(xy 325.234808 -428.960534) (xy 325.234318 -428.972646) (xy 325.226827 -428.995682) (xy 325.212588 -429.01528)
			(xy 325.192993 -429.029522) (xy 325.169958 -429.037016) (xy 325.157846 -429.037496) (xy 324.218046 -429.037496)
			(xy 324.205929 -429.037002) (xy 324.182877 -429.029526) (xy 324.163264 -429.015292) (xy 324.149011 -428.995694)
			(xy 324.141511 -428.972651) (xy 324.141084 -428.960534) (xy 323.206809 -428.960534) (xy 323.212503 -428.964654)
			(xy 323.226756 -428.984168) (xy 323.234297 -429.007127) (xy 323.234812 -429.019208) (xy 323.234812 -431.560732)
			(xy 323.234411 -431.572841) (xy 323.226904 -431.595868) (xy 323.212638 -431.615439) (xy 323.193015 -431.629633)
			(xy 323.169961 -431.637055) (xy 323.15785 -431.63744) (xy 322.21805 -431.63744) (xy 322.205961 -431.63695)
			(xy 322.182959 -431.629504) (xy 322.163376 -431.615325) (xy 322.149125 -431.595794) (xy 322.141595 -431.572819)
			(xy 322.141088 -431.560732) (xy 321.234816 -431.560732) (xy 321.234816 -432.56073) (xy 321.234465 -432.572859)
			(xy 321.226959 -432.595927) (xy 321.212691 -432.615545) (xy 321.193058 -432.629794) (xy 321.169983 -432.637277)
			(xy 321.157854 -432.637692) (xy 320.218054 -432.637692) (xy 320.20594 -432.637228) (xy 320.1829 -432.629732)
			(xy 320.163302 -432.615487) (xy 320.149061 -432.595885) (xy 320.14157 -432.572844) (xy 320.141092 -432.56073)
			(xy 319.207487 -432.56073) (xy 319.212597 -432.564438) (xy 319.226842 -432.584019) (xy 319.234339 -432.607043)
			(xy 319.23482 -432.61915) (xy 319.23482 -435.160674) (xy 319.234417 -435.1728) (xy 319.226927 -435.195865)
			(xy 319.212672 -435.215484) (xy 319.19305 -435.229734) (xy 319.169984 -435.23722) (xy 319.157858 -435.237636)
			(xy 318.218058 -435.237636) (xy 318.205939 -435.237224) (xy 318.18289 -435.229722) (xy 318.163286 -435.215465)
			(xy 318.149047 -435.195849) (xy 318.141566 -435.172794) (xy 318.141096 -435.160674) (xy 317.234824 -435.160674)
			(xy 317.234824 -436.160672) (xy 317.23436 -436.172777) (xy 317.226871 -436.195799) (xy 317.212621 -436.215371)
			(xy 317.193011 -436.229567) (xy 317.169968 -436.236993) (xy 317.157862 -436.23738) (xy 316.218062 -436.23738)
			(xy 316.205972 -436.236925) (xy 316.182974 -436.229461) (xy 316.163396 -436.21527) (xy 316.149146 -436.195736)
			(xy 316.141612 -436.17276) (xy 316.1411 -436.160672) (xy 315.207295 -436.160672) (xy 315.212549 -436.164478)
			(xy 315.2268 -436.184018) (xy 315.234325 -436.207001) (xy 315.234828 -436.219092) (xy 315.234828 -438.760616)
			(xy 315.234398 -438.772723) (xy 315.226897 -438.795746) (xy 315.212638 -438.815316) (xy 315.193022 -438.829511)
			(xy 315.169974 -438.836937) (xy 315.157866 -438.837324) (xy 314.218066 -438.837324) (xy 314.205971 -438.836921)
			(xy 314.182963 -438.829451) (xy 314.163381 -438.815249) (xy 314.149133 -438.7957) (xy 314.141608 -438.77271)
			(xy 314.141104 -438.760616) (xy 157.334712 -438.760616) (xy 157.334712 -439.76036) (xy 157.334702 -439.760614)
			(xy 316.1411 -439.760614) (xy 316.1411 -437.21909) (xy 316.141603 -437.206979) (xy 316.149088 -437.183942)
			(xy 316.163324 -437.164343) (xy 316.182917 -437.150101) (xy 316.205951 -437.142607) (xy 316.218062 -437.142128)
			(xy 317.157862 -437.142128) (xy 317.169982 -437.142592) (xy 317.193038 -437.150073) (xy 317.212653 -437.164313)
			(xy 317.226905 -437.183919) (xy 317.2344 -437.20697) (xy 317.234824 -437.21909) (xy 317.234824 -438.760616)
			(xy 318.141096 -438.760616) (xy 318.141096 -436.219092) (xy 318.141509 -436.206983) (xy 318.14901 -436.183956)
			(xy 318.163273 -436.164384) (xy 318.182895 -436.150189) (xy 318.205948 -436.142768) (xy 318.218058 -436.142384)
			(xy 319.157858 -436.142384) (xy 319.16995 -436.142844) (xy 319.192956 -436.150294) (xy 319.207283 -436.160672)
			(xy 320.141092 -436.160672) (xy 320.141092 -433.619148) (xy 320.141557 -433.607042) (xy 320.149042 -433.584018)
			(xy 320.163292 -433.564445) (xy 320.182903 -433.550248) (xy 320.205947 -433.542825) (xy 320.218054 -433.54244)
			(xy 321.157854 -433.54244) (xy 321.169941 -433.542947) (xy 321.19294 -433.550391) (xy 321.212521 -433.564567)
			(xy 321.226773 -433.584093) (xy 321.234306 -433.607063) (xy 321.234816 -433.619148) (xy 321.234816 -435.160674)
			(xy 322.141088 -435.160674) (xy 322.141088 -432.61915) (xy 322.141568 -432.607038) (xy 322.149063 -432.584001)
			(xy 322.163305 -432.564405) (xy 322.182901 -432.550163) (xy 322.205938 -432.542668) (xy 322.21805 -432.542188)
			(xy 323.15785 -432.542188) (xy 323.169962 -432.542668) (xy 323.192999 -432.550163) (xy 323.207538 -432.56073)
			(xy 324.141084 -432.56073) (xy 324.141084 -430.019206) (xy 324.141466 -430.007079) (xy 324.148962 -429.984013)
			(xy 324.163222 -429.964393) (xy 324.182848 -429.950144) (xy 324.205919 -429.94266) (xy 324.218046 -429.942244)
			(xy 325.157846 -429.942244) (xy 325.169964 -429.942673) (xy 325.193009 -429.950173) (xy 325.212611 -429.964426)
			(xy 325.226851 -429.984037) (xy 325.234336 -430.007088) (xy 325.234808 -430.019206) (xy 325.234808 -431.560732)
			(xy 326.14108 -431.560732) (xy 326.14108 -429.019208) (xy 326.141523 -429.007102) (xy 326.149017 -428.984078)
			(xy 326.163273 -428.964506) (xy 326.182888 -428.950311) (xy 326.205934 -428.942886) (xy 326.218042 -428.9425)
			(xy 327.157842 -428.9425) (xy 327.16993 -428.942971) (xy 327.192925 -428.950434) (xy 327.206862 -428.960534)
			(xy 328.141076 -428.960534) (xy 328.141076 -428.233586) (xy 328.14136 -428.224751) (xy 328.145472 -428.207564)
			(xy 328.149204 -428.19955) (xy 328.38263 -427.7233) (xy 328.387318 -427.712778) (xy 328.390811 -427.690023)
			(xy 328.387332 -427.667266) (xy 328.38263 -427.656752) (xy 328.149204 -427.180502) (xy 328.145448 -427.172497)
			(xy 328.141332 -427.155304) (xy 328.141076 -427.146466) (xy 328.141076 -426.41901) (xy 328.141469 -426.406884)
			(xy 328.148963 -426.383819) (xy 328.16322 -426.364201) (xy 328.182844 -426.34995) (xy 328.205912 -426.342465)
			(xy 328.218038 -426.342048) (xy 329.157838 -426.342048) (xy 329.169956 -426.342479) (xy 329.193002 -426.349978)
			(xy 329.212604 -426.36423) (xy 329.226844 -426.383841) (xy 329.234328 -426.406892) (xy 329.2348 -426.41901)
			(xy 329.2348 -427.960536) (xy 331.141324 -427.960536) (xy 331.141324 -427.233588) (xy 331.14157 -427.224768)
			(xy 331.145538 -427.20758) (xy 331.149198 -427.199552) (xy 331.382624 -426.723302) (xy 331.387311 -426.71278)
			(xy 331.390805 -426.690025) (xy 331.387326 -426.667268) (xy 331.382624 -426.656754) (xy 331.149198 -426.180504)
			(xy 331.145515 -426.172483) (xy 331.141538 -426.155292) (xy 331.141324 -426.146468) (xy 331.141324 -425.419012)
			(xy 331.141724 -425.406927) (xy 331.149192 -425.383939) (xy 331.1634 -425.364386) (xy 331.182957 -425.350183)
			(xy 331.205947 -425.34272) (xy 331.218032 -425.342304) (xy 332.157832 -425.342304) (xy 332.169909 -425.342737)
			(xy 332.19288 -425.35021) (xy 332.212417 -425.364414) (xy 332.22661 -425.38396) (xy 332.23407 -425.406934)
			(xy 332.23454 -425.419012) (xy 332.23454 -427.960536) (xy 332.234067 -427.972609) (xy 332.226599 -427.995572)
			(xy 332.212403 -428.015106) (xy 332.192869 -428.0293) (xy 332.169905 -428.036768) (xy 332.157832 -428.037244)
			(xy 331.218032 -428.037244) (xy 331.205963 -428.036709) (xy 331.183003 -428.02926) (xy 331.163468 -428.01508)
			(xy 331.149271 -427.995558) (xy 331.141801 -427.972605) (xy 331.141324 -427.960536) (xy 329.2348 -427.960536)
			(xy 329.2348 -428.960534) (xy 329.234318 -428.972647) (xy 329.226826 -428.995684) (xy 329.212585 -429.015282)
			(xy 329.192988 -429.029524) (xy 329.169951 -429.037017) (xy 329.157838 -429.037496) (xy 328.218038 -429.037496)
			(xy 328.205921 -429.037008) (xy 328.182869 -429.029531) (xy 328.163256 -429.015295) (xy 328.149002 -428.995696)
			(xy 328.141503 -428.972651) (xy 328.141076 -428.960534) (xy 327.206862 -428.960534) (xy 327.212501 -428.964621)
			(xy 327.226751 -428.984151) (xy 327.234289 -429.007122) (xy 327.234804 -429.019208) (xy 327.234804 -431.560732)
			(xy 327.234411 -431.572842) (xy 327.226903 -431.59587) (xy 327.212635 -431.615442) (xy 327.19301 -431.629636)
			(xy 327.169954 -431.637056) (xy 327.157842 -431.63744) (xy 326.218042 -431.63744) (xy 326.205953 -431.636957)
			(xy 326.18295 -431.629509) (xy 326.163368 -431.615327) (xy 326.149116 -431.595796) (xy 326.141587 -431.57282)
			(xy 326.14108 -431.560732) (xy 325.234808 -431.560732) (xy 325.234808 -432.56073) (xy 325.234315 -432.572842)
			(xy 325.226825 -432.595878) (xy 325.212587 -432.615475) (xy 325.192992 -432.629717) (xy 325.169957 -432.637212)
			(xy 325.157846 -432.637692) (xy 324.218046 -432.637692) (xy 324.205929 -432.637201) (xy 324.182876 -432.629725)
			(xy 324.163263 -432.615491) (xy 324.149009 -432.595892) (xy 324.14151 -432.572847) (xy 324.141084 -432.56073)
			(xy 323.207538 -432.56073) (xy 323.212595 -432.564405) (xy 323.226837 -432.584001) (xy 323.234332 -432.607038)
			(xy 323.234812 -432.61915) (xy 323.234812 -435.160674) (xy 323.234267 -435.172782) (xy 323.226793 -435.195816)
			(xy 323.212568 -435.215414) (xy 323.192984 -435.229658) (xy 323.169958 -435.237155) (xy 323.15785 -435.237636)
			(xy 322.21805 -435.237636) (xy 322.20593 -435.23723) (xy 322.182881 -435.229726) (xy 322.163278 -435.215468)
			(xy 322.149039 -435.195851) (xy 322.141558 -435.172794) (xy 322.141088 -435.160674) (xy 321.234816 -435.160674)
			(xy 321.234816 -436.160672) (xy 321.23436 -436.172778) (xy 321.22687 -436.195801) (xy 321.212618 -436.215374)
			(xy 321.193006 -436.22957) (xy 321.169961 -436.236994) (xy 321.157854 -436.23738) (xy 320.218054 -436.23738)
			(xy 320.205964 -436.236932) (xy 320.182965 -436.229465) (xy 320.163388 -436.215273) (xy 320.149138 -436.195737)
			(xy 320.141604 -436.172761) (xy 320.141092 -436.160672) (xy 319.207283 -436.160672) (xy 319.212541 -436.164481)
			(xy 319.226791 -436.184019) (xy 319.234316 -436.207002) (xy 319.23482 -436.219092) (xy 319.23482 -438.760616)
			(xy 319.234398 -438.772724) (xy 319.226896 -438.795748) (xy 319.212636 -438.815319) (xy 319.193017 -438.829514)
			(xy 319.169967 -438.836938) (xy 319.157858 -438.837324) (xy 318.218058 -438.837324) (xy 318.205963 -438.836928)
			(xy 318.182955 -438.829455) (xy 318.163372 -438.815252) (xy 318.149124 -438.795701) (xy 318.1416 -438.77271)
			(xy 318.141096 -438.760616) (xy 317.234824 -438.760616) (xy 317.234824 -439.760614) (xy 320.141092 -439.760614)
			(xy 320.141092 -437.21909) (xy 320.141603 -437.20698) (xy 320.149087 -437.183944) (xy 320.163321 -437.164346)
			(xy 320.182912 -437.150104) (xy 320.205944 -437.142608) (xy 320.218054 -437.142128) (xy 321.157854 -437.142128)
			(xy 321.169973 -437.142599) (xy 321.193029 -437.150077) (xy 321.212644 -437.164316) (xy 321.226897 -437.183921)
			(xy 321.234392 -437.206971) (xy 321.234816 -437.21909) (xy 321.234816 -438.760616) (xy 322.141088 -438.760616)
			(xy 322.141088 -436.219092) (xy 322.141509 -436.206984) (xy 322.149009 -436.183958) (xy 322.16327 -436.164386)
			(xy 322.18289 -436.150192) (xy 322.205941 -436.142769) (xy 322.21805 -436.142384) (xy 323.15785 -436.142384)
			(xy 323.169941 -436.142851) (xy 323.192948 -436.150299) (xy 323.207269 -436.160672) (xy 324.141084 -436.160672)
			(xy 324.141084 -433.619148) (xy 324.141557 -433.607043) (xy 324.149041 -433.58402) (xy 324.163289 -433.564448)
			(xy 324.182898 -433.550251) (xy 324.20594 -433.542826) (xy 324.218046 -433.54244) (xy 325.157846 -433.54244)
			(xy 325.169938 -433.542868) (xy 325.19294 -433.550338) (xy 325.212519 -433.564534) (xy 325.226768 -433.584075)
			(xy 325.234299 -433.607057) (xy 325.234808 -433.619148) (xy 325.234808 -435.160674) (xy 326.14108 -435.160674)
			(xy 326.14108 -432.61915) (xy 326.14147 -432.607029) (xy 326.148976 -432.583977) (xy 326.163238 -432.564372)
			(xy 326.182859 -432.550134) (xy 326.20592 -432.542655) (xy 326.218042 -432.542188) (xy 327.157842 -432.542188)
			(xy 327.169954 -432.542675) (xy 327.19299 -432.550168) (xy 327.207525 -432.56073) (xy 328.141076 -432.56073)
			(xy 328.141076 -430.019206) (xy 328.141466 -430.00708) (xy 328.148961 -429.984015) (xy 328.163219 -429.964396)
			(xy 328.182843 -429.950146) (xy 328.205912 -429.942661) (xy 328.218038 -429.942244) (xy 329.157838 -429.942244)
			(xy 329.169955 -429.942679) (xy 329.193001 -429.950178) (xy 329.212602 -429.964429) (xy 329.226842 -429.984039)
			(xy 329.234328 -430.007089) (xy 329.2348 -430.019206) (xy 329.2348 -431.560732) (xy 331.141324 -431.560732)
			(xy 331.141324 -429.019208) (xy 331.141723 -429.007097) (xy 331.149223 -428.984066) (xy 331.163488 -428.964491)
			(xy 331.183115 -428.950296) (xy 331.206174 -428.94288) (xy 331.218286 -428.9425) (xy 332.158086 -428.9425)
			(xy 332.170171 -428.943019) (xy 332.193164 -428.950467) (xy 332.207068 -428.960534) (xy 333.14132 -428.960534)
			(xy 333.14132 -428.233586) (xy 333.141566 -428.224766) (xy 333.145534 -428.207578) (xy 333.149194 -428.19955)
			(xy 333.38262 -427.7233) (xy 333.387309 -427.712779) (xy 333.390802 -427.690023) (xy 333.387323 -427.667266)
			(xy 333.38262 -427.656752) (xy 333.149194 -427.180502) (xy 333.14551 -427.172481) (xy 333.141534 -427.15529)
			(xy 333.14132 -427.146466) (xy 333.14132 -426.41901) (xy 333.141816 -426.406923) (xy 333.149267 -426.383926)
			(xy 333.163447 -426.364348) (xy 333.182973 -426.350096) (xy 333.205943 -426.34256) (xy 333.218028 -426.342048)
			(xy 334.157828 -426.342048) (xy 334.169933 -426.342492) (xy 334.192952 -426.349993) (xy 334.212521 -426.364249)
			(xy 334.226716 -426.383861) (xy 334.234145 -426.406904) (xy 334.234536 -426.41901) (xy 334.234536 -427.960536)
			(xy 335.141316 -427.960536) (xy 335.141316 -427.233588) (xy 335.141563 -427.224768) (xy 335.145531 -427.20758)
			(xy 335.14919 -427.199552) (xy 335.382616 -426.723302) (xy 335.387303 -426.71278) (xy 335.390797 -426.690025)
			(xy 335.387318 -426.667268) (xy 335.382616 -426.656754) (xy 335.14919 -426.180504) (xy 335.145506 -426.172483)
			(xy 335.14153 -426.155292) (xy 335.141316 -426.146468) (xy 335.141316 -425.419012) (xy 335.141723 -425.406928)
			(xy 335.149191 -425.383941) (xy 335.163397 -425.364389) (xy 335.182952 -425.350185) (xy 335.205939 -425.342722)
			(xy 335.218024 -425.342304) (xy 336.157824 -425.342304) (xy 336.169901 -425.342744) (xy 336.192871 -425.350215)
			(xy 336.212409 -425.364417) (xy 336.226602 -425.383961) (xy 336.234061 -425.406935) (xy 336.234532 -425.419012)
			(xy 336.234532 -427.960536) (xy 336.234067 -427.97261) (xy 336.226598 -427.995574) (xy 336.2124 -428.015109)
			(xy 336.192864 -428.029303) (xy 336.169898 -428.036769) (xy 336.157824 -428.037244) (xy 335.218024 -428.037244)
			(xy 335.205954 -428.036716) (xy 335.182994 -428.029264) (xy 335.16346 -428.015083) (xy 335.149263 -427.99556)
			(xy 335.141793 -427.972605) (xy 335.141316 -427.960536) (xy 334.234536 -427.960536) (xy 334.234536 -428.960534)
			(xy 334.234121 -428.972628) (xy 334.226652 -428.995634) (xy 334.212453 -429.015215) (xy 334.192907 -429.029464)
			(xy 334.16992 -429.03699) (xy 334.157828 -429.037496) (xy 333.218028 -429.037496) (xy 333.20592 -429.03706)
			(xy 333.182893 -429.029567) (xy 333.163319 -429.015311) (xy 333.149124 -428.995693) (xy 333.141703 -428.972643)
			(xy 333.14132 -428.960534) (xy 332.207068 -428.960534) (xy 332.212741 -428.964641) (xy 332.226993 -428.984162)
			(xy 332.234533 -429.007125) (xy 332.235048 -429.019208) (xy 332.235048 -431.560732) (xy 332.234612 -431.572838)
			(xy 332.227109 -431.595858) (xy 332.212851 -431.615426) (xy 332.193237 -431.629622) (xy 332.170193 -431.63705)
			(xy 332.158086 -431.63744) (xy 331.218286 -431.63744) (xy 331.206194 -431.637004) (xy 331.183189 -431.629541)
			(xy 331.163608 -431.615347) (xy 331.149358 -431.595806) (xy 331.14183 -431.572823) (xy 331.141324 -431.560732)
			(xy 329.2348 -431.560732) (xy 329.2348 -432.56073) (xy 329.234315 -432.572842) (xy 329.226824 -432.59588)
			(xy 329.212584 -432.615478) (xy 329.192987 -432.62972) (xy 329.16995 -432.637213) (xy 329.157838 -432.637692)
			(xy 328.218038 -432.637692) (xy 328.20592 -432.637208) (xy 328.182868 -432.62973) (xy 328.163255 -432.615494)
			(xy 328.149001 -432.595893) (xy 328.141502 -432.572847) (xy 328.141076 -432.56073) (xy 327.207525 -432.56073)
			(xy 327.212587 -432.564408) (xy 327.226829 -432.584003) (xy 327.234324 -432.607038) (xy 327.234804 -432.61915)
			(xy 327.234804 -435.160674) (xy 327.234267 -435.172783) (xy 327.226792 -435.195818) (xy 327.212565 -435.215417)
			(xy 327.192979 -435.229661) (xy 327.169951 -435.237156) (xy 327.157842 -435.237636) (xy 326.218042 -435.237636)
			(xy 326.205919 -435.237204) (xy 326.182857 -435.22972) (xy 326.163239 -435.215473) (xy 326.148987 -435.195857)
			(xy 326.141499 -435.172797) (xy 326.14108 -435.160674) (xy 325.234808 -435.160674) (xy 325.234808 -436.160672)
			(xy 325.23436 -436.172779) (xy 325.226869 -436.195804) (xy 325.212615 -436.215376) (xy 325.193001 -436.229572)
			(xy 325.169954 -436.236995) (xy 325.157846 -436.23738) (xy 324.218046 -436.23738) (xy 324.205961 -436.236854)
			(xy 324.182965 -436.229412) (xy 324.163386 -436.21524) (xy 324.149133 -436.19572) (xy 324.141597 -436.172755)
			(xy 324.141084 -436.160672) (xy 323.207269 -436.160672) (xy 323.212532 -436.164484) (xy 323.226783 -436.184021)
			(xy 323.234308 -436.207002) (xy 323.234812 -436.219092) (xy 323.234812 -438.760616) (xy 323.234398 -438.772725)
			(xy 323.226895 -438.79575) (xy 323.212633 -438.815322) (xy 323.193012 -438.829517) (xy 323.16996 -438.836939)
			(xy 323.15785 -438.837324) (xy 322.21805 -438.837324) (xy 322.205959 -438.836849) (xy 322.182954 -438.829402)
			(xy 322.16337 -438.815219) (xy 322.149119 -438.795684) (xy 322.141593 -438.772705) (xy 322.141088 -438.760616)
			(xy 321.234816 -438.760616) (xy 321.234816 -439.760614) (xy 324.141084 -439.760614) (xy 324.141084 -437.21909)
			(xy 324.141452 -437.206962) (xy 324.148953 -437.183895) (xy 324.163216 -437.164276) (xy 324.182845 -437.150027)
			(xy 324.205918 -437.142544) (xy 324.218046 -437.142128) (xy 325.157846 -437.142128) (xy 325.169962 -437.142572)
			(xy 325.193005 -437.150071) (xy 325.212605 -437.164321) (xy 325.226845 -437.183927) (xy 325.234333 -437.206974)
			(xy 325.234808 -437.21909) (xy 325.234808 -438.760616) (xy 326.14108 -438.760616) (xy 326.14108 -436.219092)
			(xy 326.141509 -436.206985) (xy 326.149008 -436.183961) (xy 326.163267 -436.164389) (xy 326.182885 -436.150194)
			(xy 326.205933 -436.14277) (xy 326.218042 -436.142384) (xy 327.157842 -436.142384) (xy 327.169938 -436.142772)
			(xy 327.192948 -436.150246) (xy 327.207321 -436.160672) (xy 328.141076 -436.160672) (xy 328.141076 -433.619148)
			(xy 328.141557 -433.607044) (xy 328.14904 -433.584022) (xy 328.163286 -433.564451) (xy 328.182893 -433.550253)
			(xy 328.205933 -433.542827) (xy 328.218038 -433.54244) (xy 329.157838 -433.54244) (xy 329.16993 -433.542875)
			(xy 329.192931 -433.550342) (xy 329.212511 -433.564537) (xy 329.22676 -433.584077) (xy 329.234291 -433.607058)
			(xy 329.2348 -433.619148) (xy 329.2348 -435.160674) (xy 331.141324 -435.160674) (xy 331.141324 -432.61915)
			(xy 331.14185 -432.607065) (xy 331.149291 -432.584068) (xy 331.163463 -432.564489) (xy 331.182983 -432.550236)
			(xy 331.205949 -432.5427) (xy 331.218032 -432.542188) (xy 332.157832 -432.542188) (xy 332.169941 -432.542589)
			(xy 332.192968 -432.550096) (xy 332.207556 -432.56073) (xy 333.14132 -432.56073) (xy 333.14132 -430.019206)
			(xy 333.141817 -430.007094) (xy 333.1493 -429.984054) (xy 333.163536 -429.964453) (xy 333.183132 -429.950211)
			(xy 333.20617 -429.942721) (xy 333.218282 -429.942244) (xy 334.158082 -429.942244) (xy 334.170204 -429.942675)
			(xy 334.193264 -429.950163) (xy 334.21288 -429.964412) (xy 334.227131 -429.984026) (xy 334.234623 -430.007084)
			(xy 334.235044 -430.019206) (xy 334.235044 -431.560732) (xy 335.141316 -431.560732) (xy 335.141316 -429.019208)
			(xy 335.141723 -429.007098) (xy 335.149222 -428.984068) (xy 335.163486 -428.964493) (xy 335.18311 -428.950299)
			(xy 335.206167 -428.942881) (xy 335.218278 -428.9425) (xy 336.158078 -428.9425) (xy 336.170162 -428.943025)
			(xy 336.193156 -428.950471) (xy 336.207055 -428.960534) (xy 337.141312 -428.960534) (xy 337.141312 -428.233586)
			(xy 337.141559 -428.224766) (xy 337.145527 -428.207578) (xy 337.149186 -428.19955) (xy 337.382612 -427.7233)
			(xy 337.387301 -427.712779) (xy 337.390795 -427.690023) (xy 337.387315 -427.667266) (xy 337.382612 -427.656752)
			(xy 337.149186 -427.180502) (xy 337.145501 -427.172482) (xy 337.141526 -427.15529) (xy 337.141312 -427.146466)
			(xy 337.141312 -426.41901) (xy 337.141815 -426.406924) (xy 337.149266 -426.383928) (xy 337.163444 -426.364351)
			(xy 337.182968 -426.350099) (xy 337.205936 -426.342562) (xy 337.21802 -426.342048) (xy 338.15782 -426.342048)
			(xy 338.169925 -426.342499) (xy 338.192944 -426.349997) (xy 338.212512 -426.364252) (xy 338.226708 -426.383863)
			(xy 338.234137 -426.406904) (xy 338.234528 -426.41901) (xy 338.234528 -427.960536) (xy 339.141308 -427.960536)
			(xy 339.141308 -427.233588) (xy 339.141556 -427.224768) (xy 339.145523 -427.207581) (xy 339.149182 -427.199552)
			(xy 339.382608 -426.723302) (xy 339.387295 -426.71278) (xy 339.39079 -426.690025) (xy 339.387311 -426.667268)
			(xy 339.382608 -426.656754) (xy 339.149182 -426.180504) (xy 339.145498 -426.172483) (xy 339.141522 -426.155292)
			(xy 339.141308 -426.146468) (xy 339.141308 -425.419012) (xy 339.141723 -425.406928) (xy 339.149189 -425.383943)
			(xy 339.163394 -425.364392) (xy 339.182947 -425.350188) (xy 339.205932 -425.342723) (xy 339.218016 -425.342304)
			(xy 340.157816 -425.342304) (xy 340.169893 -425.342751) (xy 340.192862 -425.350219) (xy 340.2124 -425.36442)
			(xy 340.226594 -425.383963) (xy 340.234053 -425.406935) (xy 340.234524 -425.419012) (xy 340.234524 -427.960536)
			(xy 340.234067 -427.972611) (xy 340.226596 -427.995577) (xy 340.212397 -428.015112) (xy 340.192859 -428.029306)
			(xy 340.169891 -428.03677) (xy 340.157816 -428.037244) (xy 339.218016 -428.037244) (xy 339.205946 -428.036723)
			(xy 339.182985 -428.029269) (xy 339.163451 -428.015086) (xy 339.149255 -427.995561) (xy 339.141785 -427.972606)
			(xy 339.141308 -427.960536) (xy 338.234528 -427.960536) (xy 338.234528 -428.960534) (xy 338.234121 -428.972629)
			(xy 338.226651 -428.995636) (xy 338.21245 -429.015218) (xy 338.192902 -429.029466) (xy 338.169913 -429.036992)
			(xy 338.15782 -429.037496) (xy 337.21802 -429.037496) (xy 337.205912 -429.037066) (xy 337.182885 -429.029572)
			(xy 337.163311 -429.015314) (xy 337.149116 -428.995695) (xy 337.141695 -428.972643) (xy 337.141312 -428.960534)
			(xy 336.207055 -428.960534) (xy 336.212732 -428.964644) (xy 336.226985 -428.984163) (xy 336.234525 -429.007126)
			(xy 336.23504 -429.019208) (xy 336.23504 -431.560732) (xy 336.234611 -431.572839) (xy 336.227108 -431.59586)
			(xy 336.212848 -431.615429) (xy 336.193232 -431.629624) (xy 336.170186 -431.637051) (xy 336.158078 -431.63744)
			(xy 335.218278 -431.63744) (xy 335.206185 -431.637011) (xy 335.183181 -431.629546) (xy 335.163599 -431.61535)
			(xy 335.14935 -431.595808) (xy 335.141822 -431.572823) (xy 335.141316 -431.560732) (xy 334.235044 -431.560732)
			(xy 334.235044 -432.56073) (xy 334.234614 -432.572848) (xy 334.227116 -432.595895) (xy 334.212864 -432.615498)
			(xy 334.193252 -432.629738) (xy 334.1702 -432.637221) (xy 334.158082 -432.637692) (xy 333.218282 -432.637692)
			(xy 333.206169 -432.637204) (xy 333.183131 -432.629716) (xy 333.163532 -432.615477) (xy 333.14929 -432.59588)
			(xy 333.141798 -432.572842) (xy 333.14132 -432.56073) (xy 332.207556 -432.56073) (xy 332.212539 -432.564362)
			(xy 332.226733 -432.583985) (xy 332.234155 -432.607039) (xy 332.23454 -432.61915) (xy 332.23454 -435.160674)
			(xy 332.23407 -435.172764) (xy 332.226618 -435.195767) (xy 332.212433 -435.215349) (xy 332.192899 -435.2296)
			(xy 332.169921 -435.237129) (xy 332.157832 -435.237636) (xy 331.218032 -435.237636) (xy 331.205928 -435.237157)
			(xy 331.182908 -435.229671) (xy 331.163338 -435.215424) (xy 331.149141 -435.195818) (xy 331.141713 -435.172779)
			(xy 331.141324 -435.160674) (xy 329.2348 -435.160674) (xy 329.2348 -436.160672) (xy 329.23436 -436.172779)
			(xy 329.226868 -436.195806) (xy 329.212613 -436.215379) (xy 329.192996 -436.229575) (xy 329.169947 -436.236996)
			(xy 329.157838 -436.23738) (xy 328.218038 -436.23738) (xy 328.205952 -436.236861) (xy 328.182956 -436.229417)
			(xy 328.163378 -436.215243) (xy 328.149125 -436.195721) (xy 328.141589 -436.172756) (xy 328.141076 -436.160672)
			(xy 327.207321 -436.160672) (xy 327.212531 -436.164451) (xy 327.226778 -436.184004) (xy 327.234301 -436.206997)
			(xy 327.234804 -436.219092) (xy 327.234804 -438.760616) (xy 327.234397 -438.772725) (xy 327.226894 -438.795752)
			(xy 327.21263 -438.815325) (xy 327.193007 -438.829519) (xy 327.169953 -438.83694) (xy 327.157842 -438.837324)
			(xy 326.218042 -438.837324) (xy 326.205951 -438.836856) (xy 326.182946 -438.829407) (xy 326.163362 -438.815222)
			(xy 326.149111 -438.795686) (xy 326.141585 -438.772705) (xy 326.14108 -438.760616) (xy 325.234808 -438.760616)
			(xy 325.234808 -439.760614) (xy 328.141076 -439.760614) (xy 328.141076 -437.21909) (xy 328.141452 -437.206963)
			(xy 328.148952 -437.183897) (xy 328.163213 -437.164279) (xy 328.18284 -437.15003) (xy 328.205911 -437.142545)
			(xy 328.218038 -437.142128) (xy 329.157838 -437.142128) (xy 329.169954 -437.142579) (xy 329.192996 -437.150076)
			(xy 329.212597 -437.164323) (xy 329.226837 -437.183929) (xy 329.234325 -437.206974) (xy 329.2348 -437.21909)
			(xy 329.2348 -438.760616) (xy 331.141324 -438.760616) (xy 331.141324 -436.219092) (xy 331.141706 -436.207006)
			(xy 331.14918 -436.184017) (xy 331.163393 -436.164464) (xy 331.182953 -436.150262) (xy 331.205945 -436.1428)
			(xy 331.218032 -436.142384) (xy 332.157832 -436.142384) (xy 332.169907 -436.142837) (xy 332.192874 -436.150307)
			(xy 332.207134 -436.160672) (xy 333.14132 -436.160672) (xy 333.14132 -433.619148) (xy 333.141754 -433.607065)
			(xy 333.149212 -433.584079) (xy 333.163411 -433.564526) (xy 333.182961 -433.550321) (xy 333.205945 -433.542857)
			(xy 333.218028 -433.54244) (xy 334.157828 -433.54244) (xy 334.169917 -433.542789) (xy 334.192909 -433.550271)
			(xy 334.212463 -433.564491) (xy 334.226664 -433.584059) (xy 334.234122 -433.607059) (xy 334.234536 -433.619148)
			(xy 334.234536 -435.160674) (xy 335.141316 -435.160674) (xy 335.141316 -432.61915) (xy 335.141849 -432.607065)
			(xy 335.14929 -432.58407) (xy 335.16346 -432.564492) (xy 335.182978 -432.550239) (xy 335.205941 -432.542701)
			(xy 335.218024 -432.542188) (xy 336.157824 -432.542188) (xy 336.169933 -432.542596) (xy 336.192959 -432.5501)
			(xy 336.207544 -432.56073) (xy 337.141312 -432.56073) (xy 337.141312 -430.019206) (xy 337.141817 -430.007094)
			(xy 337.149299 -429.984056) (xy 337.163533 -429.964456) (xy 337.183127 -429.950214) (xy 337.206163 -429.942722)
			(xy 337.218274 -429.942244) (xy 338.158074 -429.942244) (xy 338.170196 -429.942682) (xy 338.193255 -429.950168)
			(xy 338.212871 -429.964415) (xy 338.227123 -429.984027) (xy 338.234615 -430.007084) (xy 338.235036 -430.019206)
			(xy 338.235036 -431.560732) (xy 339.141308 -431.560732) (xy 339.141308 -429.019208) (xy 339.141723 -429.007099)
			(xy 339.149221 -428.98407) (xy 339.163483 -428.964496) (xy 339.183105 -428.950302) (xy 339.206159 -428.942882)
			(xy 339.21827 -428.9425) (xy 340.15807 -428.9425) (xy 340.170154 -428.943032) (xy 340.193147 -428.950476)
			(xy 340.206691 -428.96028) (xy 341.141304 -428.96028) (xy 341.141304 -428.233332) (xy 341.141534 -428.224511)
			(xy 341.145514 -428.207323) (xy 341.149178 -428.199296) (xy 341.382604 -427.723046) (xy 341.387331 -427.712539)
			(xy 341.390812 -427.689775) (xy 341.387316 -427.667012) (xy 341.382604 -427.656498) (xy 341.149178 -427.180248)
			(xy 341.145507 -427.172222) (xy 341.141523 -427.155034) (xy 341.141304 -427.146212) (xy 341.141304 -426.418756)
			(xy 341.141727 -426.406678) (xy 341.149203 -426.383707) (xy 341.16341 -426.36417) (xy 341.182957 -426.349977)
			(xy 341.205934 -426.342518) (xy 341.218012 -426.342048) (xy 342.157812 -426.342048) (xy 342.169883 -426.342553)
			(xy 342.192843 -426.350014) (xy 342.212376 -426.364201) (xy 342.226572 -426.383728) (xy 342.234042 -426.406685)
			(xy 342.23452 -426.418756) (xy 342.23452 -427.960536) (xy 343.1413 -427.960536) (xy 343.1413 -427.233588)
			(xy 343.141549 -427.224768) (xy 343.145516 -427.207581) (xy 343.149174 -427.199552) (xy 343.3826 -426.723302)
			(xy 343.387288 -426.71278) (xy 343.390783 -426.690025) (xy 343.387303 -426.667268) (xy 343.3826 -426.656754)
			(xy 343.149174 -426.180504) (xy 343.145489 -426.172484) (xy 343.141514 -426.155292) (xy 343.1413 -426.146468)
			(xy 343.1413 -425.419012) (xy 343.141723 -425.406929) (xy 343.149188 -425.383946) (xy 343.163392 -425.364394)
			(xy 343.182942 -425.35019) (xy 343.205925 -425.342724) (xy 343.218008 -425.342304) (xy 344.157808 -425.342304)
			(xy 344.169892 -425.342706) (xy 344.192877 -425.350177) (xy 344.212429 -425.364386) (xy 344.226632 -425.383941)
			(xy 344.234097 -425.406928) (xy 344.234516 -425.419012) (xy 344.234516 -427.960536) (xy 344.234067 -427.972612)
			(xy 344.226595 -427.995579) (xy 344.212395 -428.015115) (xy 344.192854 -428.029308) (xy 344.169884 -428.036771)
			(xy 344.157808 -428.037244) (xy 343.218008 -428.037244) (xy 343.205937 -428.03673) (xy 343.182977 -428.029274)
			(xy 343.163443 -428.015089) (xy 343.149247 -427.995563) (xy 343.141777 -427.972606) (xy 343.1413 -427.960536)
			(xy 342.23452 -427.960536) (xy 342.23452 -428.96028) (xy 342.23407 -428.97236) (xy 342.22661 -428.99534)
			(xy 342.212413 -429.01489) (xy 342.192869 -429.029095) (xy 342.169892 -429.036565) (xy 342.157812 -429.036988)
			(xy 341.218012 -429.036988) (xy 341.205928 -429.036577) (xy 341.182942 -429.02911) (xy 341.16339 -429.014904)
			(xy 341.149186 -428.995351) (xy 341.141722 -428.972364) (xy 341.141304 -428.96028) (xy 340.206691 -428.96028)
			(xy 340.212724 -428.964647) (xy 340.226977 -428.984164) (xy 340.234517 -429.007126) (xy 340.235032 -429.019208)
			(xy 340.235032 -431.560732) (xy 340.234611 -431.572839) (xy 340.227107 -431.595862) (xy 340.212845 -431.615432)
			(xy 340.193227 -431.629627) (xy 340.170179 -431.637052) (xy 340.15807 -431.63744) (xy 339.21827 -431.63744)
			(xy 339.206177 -431.637018) (xy 339.183172 -431.629551) (xy 339.163591 -431.615353) (xy 339.149342 -431.595809)
			(xy 339.141814 -431.572824) (xy 339.141308 -431.560732) (xy 338.235036 -431.560732) (xy 338.235036 -432.56073)
			(xy 338.234614 -432.572849) (xy 338.227115 -432.595897) (xy 338.212861 -432.615501) (xy 338.193247 -432.62974)
			(xy 338.170193 -432.637222) (xy 338.158074 -432.637692) (xy 337.218274 -432.637692) (xy 337.206161 -432.637211)
			(xy 337.183122 -432.62972) (xy 337.163523 -432.61548) (xy 337.149282 -432.595882) (xy 337.14179 -432.572843)
			(xy 337.141312 -432.56073) (xy 336.207544 -432.56073) (xy 336.212531 -432.564365) (xy 336.226725 -432.583987)
			(xy 336.234147 -432.60704) (xy 336.234532 -432.61915) (xy 336.234532 -435.160674) (xy 336.23407 -435.172765)
			(xy 336.226617 -435.195769) (xy 336.21243 -435.215352) (xy 336.192894 -435.229603) (xy 336.169913 -435.23713)
			(xy 336.157824 -435.237636) (xy 335.218024 -435.237636) (xy 335.20592 -435.237164) (xy 335.1829 -435.229675)
			(xy 335.163329 -435.215427) (xy 335.149133 -435.195819) (xy 335.141705 -435.172779) (xy 335.141316 -435.160674)
			(xy 334.234536 -435.160674) (xy 334.234536 -436.160672) (xy 334.234012 -436.172742) (xy 334.226561 -436.195704)
			(xy 334.212379 -436.215239) (xy 334.192854 -436.229435) (xy 334.169898 -436.236904) (xy 334.157828 -436.23738)
			(xy 333.218028 -436.23738) (xy 333.205944 -436.236963) (xy 333.182957 -436.2295) (xy 333.163404 -436.215296)
			(xy 333.1492 -436.195743) (xy 333.141737 -436.172756) (xy 333.14132 -436.160672) (xy 332.207134 -436.160672)
			(xy 332.21241 -436.164507) (xy 332.226604 -436.184047) (xy 332.234067 -436.207016) (xy 332.23454 -436.219092)
			(xy 332.23454 -438.760616) (xy 332.23405 -438.772688) (xy 332.226587 -438.79565) (xy 332.212396 -438.815184)
			(xy 332.192865 -438.829379) (xy 332.169904 -438.836847) (xy 332.157832 -438.837324) (xy 331.218032 -438.837324)
			(xy 331.205953 -438.83686) (xy 331.182974 -438.829403) (xy 331.163424 -438.81521) (xy 331.149218 -438.795669)
			(xy 331.141747 -438.772695) (xy 331.141324 -438.760616) (xy 329.2348 -438.760616) (xy 329.2348 -439.760614)
			(xy 333.14132 -439.760614) (xy 333.14132 -437.21909) (xy 333.141799 -437.207002) (xy 333.149256 -437.184004)
			(xy 333.16344 -437.164426) (xy 333.18297 -437.150176) (xy 333.205942 -437.14264) (xy 333.218028 -437.142128)
			(xy 334.157828 -437.142128) (xy 334.169941 -437.142493) (xy 334.192974 -437.150003) (xy 334.212549 -437.164277)
			(xy 334.226742 -437.183911) (xy 334.234157 -437.206975) (xy 334.234536 -437.21909) (xy 334.234536 -438.760616)
			(xy 335.141316 -438.760616) (xy 335.141316 -436.219092) (xy 335.141706 -436.207006) (xy 335.149179 -436.184019)
			(xy 335.16339 -436.164467) (xy 335.182948 -436.150264) (xy 335.205938 -436.142801) (xy 335.218024 -436.142384)
			(xy 336.157824 -436.142384) (xy 336.169899 -436.142844) (xy 336.192866 -436.150312) (xy 336.20712 -436.160672)
			(xy 337.141312 -436.160672) (xy 337.141312 -433.619148) (xy 337.141754 -433.607066) (xy 337.149211 -433.584081)
			(xy 337.163408 -433.564528) (xy 337.182956 -433.550323) (xy 337.205938 -433.542858) (xy 337.21802 -433.54244)
			(xy 338.15782 -433.54244) (xy 338.169909 -433.542796) (xy 338.1929 -433.550275) (xy 338.212454 -433.564494)
			(xy 338.226656 -433.584061) (xy 338.234114 -433.607059) (xy 338.234528 -433.619148) (xy 338.234528 -435.160674)
			(xy 339.141308 -435.160674) (xy 339.141308 -432.61915) (xy 339.141849 -432.607066) (xy 339.149288 -432.584073)
			(xy 339.163457 -432.564495) (xy 339.182973 -432.550241) (xy 339.205934 -432.542702) (xy 339.218016 -432.542188)
			(xy 340.157816 -432.542188) (xy 340.169925 -432.542602) (xy 340.19295 -432.550105) (xy 340.207531 -432.56073)
			(xy 341.141304 -432.56073) (xy 341.141304 -430.019206) (xy 341.141816 -430.007095) (xy 341.149298 -429.984058)
			(xy 341.163531 -429.964459) (xy 341.183122 -429.950216) (xy 341.206155 -429.942723) (xy 341.218266 -429.942244)
			(xy 342.158066 -429.942244) (xy 342.170188 -429.942689) (xy 342.193246 -429.950173) (xy 342.212863 -429.964418)
			(xy 342.227115 -429.984029) (xy 342.234607 -430.007085) (xy 342.235028 -430.019206) (xy 342.235028 -431.560732)
			(xy 343.1413 -431.560732) (xy 343.1413 -429.019208) (xy 343.141723 -429.0071) (xy 343.14922 -428.984072)
			(xy 343.16348 -428.964499) (xy 343.1831 -428.950304) (xy 343.206152 -428.942883) (xy 343.218262 -428.9425)
			(xy 344.158062 -428.9425) (xy 344.170146 -428.943039) (xy 344.193138 -428.95048) (xy 344.207028 -428.960534)
			(xy 345.141296 -428.960534) (xy 345.141296 -428.233586) (xy 345.141544 -428.224766) (xy 345.145511 -428.207579)
			(xy 345.14917 -428.19955) (xy 345.382596 -427.7233) (xy 345.387285 -427.712779) (xy 345.39078 -427.690023)
			(xy 345.387299 -427.667266) (xy 345.382596 -427.656752) (xy 345.14917 -427.180502) (xy 345.145484 -427.172482)
			(xy 345.14151 -427.15529) (xy 345.141296 -427.146466) (xy 345.141296 -426.41901) (xy 345.141815 -426.406925)
			(xy 345.149264 -426.383932) (xy 345.163439 -426.364356) (xy 345.182958 -426.350104) (xy 345.205921 -426.342564)
			(xy 345.218004 -426.342048) (xy 346.157804 -426.342048) (xy 346.169908 -426.342512) (xy 346.192927 -426.350006)
			(xy 346.212495 -426.364257) (xy 346.226691 -426.383866) (xy 346.234121 -426.406905) (xy 346.234512 -426.41901)
			(xy 346.234512 -428.960534) (xy 346.234121 -428.97263) (xy 346.226649 -428.99564) (xy 346.212444 -429.015223)
			(xy 346.192892 -429.029471) (xy 346.169899 -429.036994) (xy 346.157804 -429.037496) (xy 345.218004 -429.037496)
			(xy 345.205895 -429.03708) (xy 345.182867 -429.029582) (xy 345.163293 -429.01532) (xy 345.149099 -428.995698)
			(xy 345.141679 -428.972644) (xy 345.141296 -428.960534) (xy 344.207028 -428.960534) (xy 344.212715 -428.96465)
			(xy 344.226969 -428.984166) (xy 344.234509 -429.007126) (xy 344.235024 -429.019208) (xy 344.235024 -431.560732)
			(xy 344.234611 -431.57284) (xy 344.227106 -431.595864) (xy 344.212843 -431.615435) (xy 344.193222 -431.629629)
			(xy 344.170172 -431.637053) (xy 344.158062 -431.63744) (xy 343.218262 -431.63744) (xy 343.206168 -431.637025)
			(xy 343.183163 -431.629555) (xy 343.163582 -431.615356) (xy 343.149334 -431.595811) (xy 343.141806 -431.572824)
			(xy 343.1413 -431.560732) (xy 342.235028 -431.560732) (xy 342.235028 -432.56073) (xy 342.234665 -432.572858)
			(xy 342.227161 -432.595923) (xy 342.212895 -432.615541) (xy 342.193266 -432.62979) (xy 342.170194 -432.637275)
			(xy 342.158066 -432.637692) (xy 341.218266 -432.637692) (xy 341.206153 -432.637218) (xy 341.183113 -432.629725)
			(xy 341.163515 -432.615482) (xy 341.149273 -432.595883) (xy 341.141782 -432.572843) (xy 341.141304 -432.56073)
			(xy 340.207531 -432.56073) (xy 340.212522 -432.564367) (xy 340.226717 -432.583988) (xy 340.234139 -432.60704)
			(xy 340.234524 -432.61915) (xy 340.234524 -435.160674) (xy 340.23407 -435.172766) (xy 340.226616 -435.195772)
			(xy 340.212427 -435.215355) (xy 340.192889 -435.229605) (xy 340.169906 -435.237131) (xy 340.157816 -435.237636)
			(xy 339.218016 -435.237636) (xy 339.205912 -435.23717) (xy 339.182891 -435.22968) (xy 339.163321 -435.21543)
			(xy 339.149124 -435.195821) (xy 339.141697 -435.172779) (xy 339.141308 -435.160674) (xy 338.234528 -435.160674)
			(xy 338.234528 -436.160672) (xy 338.234064 -436.172751) (xy 338.226606 -436.19573) (xy 338.212413 -436.215279)
			(xy 338.192873 -436.229484) (xy 338.169899 -436.236956) (xy 338.15782 -436.23738) (xy 337.21802 -436.23738)
			(xy 337.205936 -436.23697) (xy 337.182949 -436.229504) (xy 337.163396 -436.215299) (xy 337.149192 -436.195744)
			(xy 337.141729 -436.172756) (xy 337.141312 -436.160672) (xy 336.20712 -436.160672) (xy 336.212401 -436.16451)
			(xy 336.226595 -436.184049) (xy 336.234059 -436.207017) (xy 336.234532 -436.219092) (xy 336.234532 -438.760616)
			(xy 336.23405 -438.772689) (xy 336.226586 -438.795653) (xy 336.212393 -438.815187) (xy 336.19286 -438.829382)
			(xy 336.169897 -438.836848) (xy 336.157824 -438.837324) (xy 335.218024 -438.837324) (xy 335.205944 -438.836867)
			(xy 335.182965 -438.829408) (xy 335.163416 -438.815213) (xy 335.14921 -438.795671) (xy 335.141739 -438.772696)
			(xy 335.141316 -438.760616) (xy 334.234536 -438.760616) (xy 334.234536 -439.760614) (xy 337.141312 -439.760614)
			(xy 337.141312 -437.21909) (xy 337.141799 -437.207003) (xy 337.149255 -437.184007) (xy 337.163437 -437.164429)
			(xy 337.182965 -437.150178) (xy 337.205934 -437.142641) (xy 337.21802 -437.142128) (xy 338.15782 -437.142128)
			(xy 338.169933 -437.1425) (xy 338.192965 -437.150008) (xy 338.212541 -437.16428) (xy 338.226734 -437.183913)
			(xy 338.234149 -437.206976) (xy 338.234528 -437.21909) (xy 338.234528 -438.760616) (xy 339.141308 -438.760616)
			(xy 339.141308 -436.219092) (xy 339.141706 -436.207007) (xy 339.149178 -436.184021) (xy 339.163387 -436.16447)
			(xy 339.182943 -436.150267) (xy 339.205931 -436.142802) (xy 339.218016 -436.142384) (xy 340.157816 -436.142384)
			(xy 340.169891 -436.142851) (xy 340.192857 -436.150317) (xy 340.207107 -436.160672) (xy 341.141304 -436.160672)
			(xy 341.141304 -433.619148) (xy 341.141754 -433.607067) (xy 341.14921 -433.584083) (xy 341.163406 -433.564531)
			(xy 341.182951 -433.550326) (xy 341.205931 -433.542859) (xy 341.218012 -433.54244) (xy 342.157812 -433.54244)
			(xy 342.1699 -433.542803) (xy 342.192891 -433.55028) (xy 342.212446 -433.564497) (xy 342.226648 -433.584062)
			(xy 342.234106 -433.60706) (xy 342.23452 -433.619148) (xy 342.23452 -435.160674) (xy 343.1413 -435.160674)
			(xy 343.1413 -432.61915) (xy 343.141849 -432.607067) (xy 343.149287 -432.584075) (xy 343.163454 -432.564497)
			(xy 343.182968 -432.550244) (xy 343.205927 -432.542703) (xy 343.218008 -432.542188) (xy 344.157808 -432.542188)
			(xy 344.169916 -432.542609) (xy 344.192942 -432.550109) (xy 344.207518 -432.56073) (xy 345.141296 -432.56073)
			(xy 345.141296 -430.019206) (xy 345.141816 -430.007096) (xy 345.149297 -429.98406) (xy 345.163528 -429.964462)
			(xy 345.183117 -429.950219) (xy 345.206148 -429.942724) (xy 345.218258 -429.942244) (xy 346.158058 -429.942244)
			(xy 346.170179 -429.942696) (xy 346.193238 -429.950177) (xy 346.212854 -429.96442) (xy 346.227106 -429.98403)
			(xy 346.234599 -430.007085) (xy 346.23502 -430.019206) (xy 346.23502 -431.360072) (xy 356.154736 -431.360072)
			(xy 356.155234 -431.275192) (xy 356.163191 -431.105619) (xy 356.179087 -430.936605) (xy 356.202888 -430.768522)
			(xy 356.234542 -430.601739) (xy 356.273978 -430.436623) (xy 356.32111 -430.273538) (xy 356.375834 -430.11284)
			(xy 356.438031 -429.954885) (xy 356.507563 -429.800018) (xy 356.584278 -429.648581) (xy 356.668006 -429.500905)
			(xy 356.758564 -429.357317) (xy 356.855753 -429.218131) (xy 356.95936 -429.083654) (xy 357.069155 -428.954181)
			(xy 357.184899 -428.829996) (xy 357.306336 -428.711373) (xy 357.4332 -428.598572) (xy 357.565211 -428.491842)
			(xy 357.702081 -428.391417) (xy 357.843506 -428.297518) (xy 357.989178 -428.21035) (xy 358.138776 -428.130107)
			(xy 358.29197 -428.056963) (xy 358.448424 -427.991081) (xy 358.607794 -427.932604) (xy 358.76973 -427.881662)
			(xy 358.933876 -427.838366) (xy 359.099871 -427.802811) (xy 359.26735 -427.775076) (xy 359.435945 -427.755222)
			(xy 359.605285 -427.743292) (xy 359.774998 -427.739313) (xy 359.944711 -427.743292) (xy 360.114051 -427.755222)
			(xy 360.282646 -427.775076) (xy 360.450125 -427.802811) (xy 360.61612 -427.838366) (xy 360.780266 -427.881662)
			(xy 360.942202 -427.932604) (xy 361.018326 -427.960536) (xy 381.2413 -427.960536) (xy 381.2413 -427.233588)
			(xy 381.241582 -427.224753) (xy 381.245696 -427.207565) (xy 381.249428 -427.199552) (xy 381.482854 -426.723302)
			(xy 381.487539 -426.71278) (xy 381.491032 -426.690025) (xy 381.487554 -426.667269) (xy 381.482854 -426.656754)
			(xy 381.249428 -426.180504) (xy 381.245674 -426.172498) (xy 381.241556 -426.155306) (xy 381.2413 -426.146468)
			(xy 381.2413 -425.419012) (xy 381.241727 -425.406904) (xy 381.249223 -425.383877) (xy 381.263482 -425.364304)
			(xy 381.283101 -425.350109) (xy 381.306152 -425.342688) (xy 381.318262 -425.342304) (xy 382.258062 -425.342304)
			(xy 382.270146 -425.342839) (xy 382.293139 -425.350281) (xy 382.312717 -425.364451) (xy 382.32697 -425.383968)
			(xy 382.334509 -425.40693) (xy 382.335024 -425.419012) (xy 382.335024 -427.960536) (xy 382.334615 -427.972644)
			(xy 382.327108 -427.995669) (xy 382.312844 -428.015239) (xy 382.293223 -428.029433) (xy 382.270172 -428.036857)
			(xy 382.258062 -428.037244) (xy 381.318262 -428.037244) (xy 381.306169 -428.036825) (xy 381.283164 -428.029356)
			(xy 381.263584 -428.015157) (xy 381.249335 -427.995613) (xy 381.241807 -427.972628) (xy 381.2413 -427.960536)
			(xy 361.018326 -427.960536) (xy 361.101572 -427.991081) (xy 361.258026 -428.056963) (xy 361.41122 -428.130107)
			(xy 361.560818 -428.21035) (xy 361.70649 -428.297518) (xy 361.847915 -428.391417) (xy 361.984785 -428.491842)
			(xy 362.116796 -428.598572) (xy 362.24366 -428.711373) (xy 362.365097 -428.829996) (xy 362.480841 -428.954181)
			(xy 362.590636 -429.083654) (xy 362.694243 -429.218131) (xy 362.791432 -429.357317) (xy 362.88199 -429.500905)
			(xy 362.965718 -429.648581) (xy 363.042433 -429.800018) (xy 363.111965 -429.954885) (xy 363.174162 -430.11284)
			(xy 363.228886 -430.273538) (xy 363.276018 -430.436623) (xy 363.315454 -430.601739) (xy 363.347108 -430.768522)
			(xy 363.370909 -430.936605) (xy 363.386805 -431.105619) (xy 363.394762 -431.275192) (xy 363.39526 -431.360072)
			(xy 363.394788 -431.445675) (xy 363.389347 -431.560732) (xy 381.2413 -431.560732) (xy 381.2413 -429.019208)
			(xy 381.241723 -429.0071) (xy 381.24922 -428.984072) (xy 381.26348 -428.964499) (xy 381.2831 -428.950304)
			(xy 381.306152 -428.942883) (xy 381.318262 -428.9425) (xy 382.258062 -428.9425) (xy 382.270146 -428.943039)
			(xy 382.293138 -428.95048) (xy 382.307028 -428.960534) (xy 383.241296 -428.960534) (xy 383.241296 -428.233586)
			(xy 383.241578 -428.224751) (xy 383.245692 -428.207563) (xy 383.249424 -428.19955) (xy 383.48285 -427.7233)
			(xy 383.487537 -427.712778) (xy 383.491029 -427.690023) (xy 383.487551 -427.667267) (xy 383.48285 -427.656752)
			(xy 383.249424 -427.180502) (xy 383.245669 -427.172496) (xy 383.241552 -427.155304) (xy 383.241296 -427.146466)
			(xy 383.241296 -426.41901) (xy 383.24182 -426.4069) (xy 383.249299 -426.383864) (xy 383.263529 -426.364266)
			(xy 383.283118 -426.350023) (xy 383.306148 -426.342528) (xy 383.318258 -426.342048) (xy 384.258058 -426.342048)
			(xy 384.27018 -426.342496) (xy 384.293239 -426.349978) (xy 384.312855 -426.364222) (xy 384.327108 -426.383833)
			(xy 384.334599 -426.406889) (xy 384.33502 -426.41901) (xy 384.33502 -427.960536) (xy 385.241292 -427.960536)
			(xy 385.241292 -427.233588) (xy 385.241575 -427.224753) (xy 385.245688 -427.207566) (xy 385.24942 -427.199552)
			(xy 385.482846 -426.723302) (xy 385.487532 -426.71278) (xy 385.491025 -426.690025) (xy 385.487547 -426.667269)
			(xy 385.482846 -426.656754) (xy 385.24942 -426.180504) (xy 385.245666 -426.172498) (xy 385.241548 -426.155306)
			(xy 385.241292 -426.146468) (xy 385.241292 -425.419012) (xy 385.241727 -425.406905) (xy 385.249222 -425.383879)
			(xy 385.263479 -425.364307) (xy 385.283096 -425.350111) (xy 385.306145 -425.342689) (xy 385.318254 -425.342304)
			(xy 386.258054 -425.342304) (xy 386.270138 -425.342846) (xy 386.293131 -425.350286) (xy 386.312708 -425.364454)
			(xy 386.326962 -425.38397) (xy 386.334501 -425.40693) (xy 386.335016 -425.419012) (xy 386.335016 -427.960536)
			(xy 386.334615 -427.972645) (xy 386.327107 -427.995671) (xy 386.312841 -428.015242) (xy 386.293218 -428.029436)
			(xy 386.270165 -428.036859) (xy 386.258054 -428.037244) (xy 385.318254 -428.037244) (xy 385.30616 -428.036832)
			(xy 385.283156 -428.02936) (xy 385.263575 -428.01516) (xy 385.249327 -427.995615) (xy 385.241799 -427.972628)
			(xy 385.241292 -427.960536) (xy 384.33502 -427.960536) (xy 384.33502 -428.960534) (xy 384.334669 -428.972663)
			(xy 384.327162 -428.99573) (xy 384.312894 -429.015348) (xy 384.293262 -429.029597) (xy 384.270187 -429.03708)
			(xy 384.258058 -429.037496) (xy 383.318258 -429.037496) (xy 383.306145 -429.037025) (xy 383.283106 -429.02953)
			(xy 383.263508 -429.015287) (xy 383.249266 -428.995687) (xy 383.241774 -428.972647) (xy 383.241296 -428.960534)
			(xy 382.307028 -428.960534) (xy 382.312715 -428.96465) (xy 382.326969 -428.984166) (xy 382.334509 -429.007126)
			(xy 382.335024 -429.019208) (xy 382.335024 -431.560732) (xy 382.334611 -431.57284) (xy 382.327106 -431.595864)
			(xy 382.312843 -431.615435) (xy 382.293222 -431.629629) (xy 382.270172 -431.637053) (xy 382.258062 -431.63744)
			(xy 381.318262 -431.63744) (xy 381.306168 -431.637025) (xy 381.283163 -431.629555) (xy 381.263582 -431.615356)
			(xy 381.249334 -431.595811) (xy 381.241806 -431.572824) (xy 381.2413 -431.560732) (xy 363.389347 -431.560732)
			(xy 363.386701 -431.616689) (xy 363.370537 -431.787129) (xy 363.346334 -431.956615) (xy 363.314145 -432.124767)
			(xy 363.274043 -432.291209) (xy 363.226117 -432.455569) (xy 363.170474 -432.61748) (xy 363.107239 -432.776579)
			(xy 363.036553 -432.932511) (xy 362.958574 -433.084927) (xy 362.873477 -433.233486) (xy 362.781452 -433.377855)
			(xy 362.682704 -433.517713) (xy 362.577455 -433.652746) (xy 362.46594 -433.782652) (xy 362.348408 -433.907141)
			(xy 362.225123 -434.025934) (xy 362.096359 -434.138766) (xy 361.962404 -434.245385) (xy 361.82356 -434.345551)
			(xy 361.680135 -434.439042) (xy 361.53245 -434.525647) (xy 361.380836 -434.605174) (xy 361.225632 -434.677444)
			(xy 361.146598 -434.710332) (xy 361.138713 -434.713995) (xy 361.125816 -434.725637) (xy 361.117551 -434.740919)
			(xy 361.115864 -434.749448) (xy 361.100116 -434.849016) (xy 361.109514 -434.873654) (xy 361.119928 -434.88229)
			(xy 361.169374 -434.924299) (xy 361.263563 -435.013553) (xy 361.352051 -435.108462) (xy 361.395012 -435.160674)
			(xy 381.2413 -435.160674) (xy 381.2413 -432.61915) (xy 381.241769 -432.607037) (xy 381.249265 -432.583998)
			(xy 381.263509 -432.564401) (xy 381.283109 -432.550159) (xy 381.306149 -432.542667) (xy 381.318262 -432.542188)
			(xy 382.258062 -432.542188) (xy 382.27017 -432.542743) (xy 382.293203 -432.550214) (xy 382.307694 -432.56073)
			(xy 383.241296 -432.56073) (xy 383.241296 -430.019206) (xy 383.241816 -430.007096) (xy 383.249297 -429.98406)
			(xy 383.263528 -429.964462) (xy 383.283117 -429.950219) (xy 383.306148 -429.942724) (xy 383.318258 -429.942244)
			(xy 384.258058 -429.942244) (xy 384.270179 -429.942696) (xy 384.293238 -429.950177) (xy 384.312854 -429.96442)
			(xy 384.327106 -429.98403) (xy 384.334599 -430.007085) (xy 384.33502 -430.019206) (xy 384.33502 -431.560732)
			(xy 385.241292 -431.560732) (xy 385.241292 -429.019208) (xy 385.241723 -429.0071) (xy 385.249219 -428.984075)
			(xy 385.263477 -428.964502) (xy 385.283095 -428.950307) (xy 385.306145 -428.942884) (xy 385.318254 -428.9425)
			(xy 386.258054 -428.9425) (xy 386.270137 -428.943046) (xy 386.29313 -428.950485) (xy 386.307015 -428.960534)
			(xy 387.241288 -428.960534) (xy 387.241288 -428.233586) (xy 387.241571 -428.224751) (xy 387.245684 -428.207564)
			(xy 387.249416 -428.19955) (xy 387.482842 -427.7233) (xy 387.487529 -427.712778) (xy 387.491022 -427.690023)
			(xy 387.487543 -427.667267) (xy 387.482842 -427.656752) (xy 387.249416 -427.180502) (xy 387.245661 -427.172496)
			(xy 387.241544 -427.155304) (xy 387.241288 -427.146466) (xy 387.241288 -426.41901) (xy 387.24182 -426.406901)
			(xy 387.249298 -426.383867) (xy 387.263526 -426.364269) (xy 387.283113 -426.350025) (xy 387.306141 -426.342529)
			(xy 387.31825 -426.342048) (xy 388.25805 -426.342048) (xy 388.270168 -426.342469) (xy 388.293215 -426.349972)
			(xy 388.312816 -426.364226) (xy 388.327056 -426.383839) (xy 388.33454 -426.406891) (xy 388.335012 -426.41901)
			(xy 388.335012 -427.960536) (xy 389.241284 -427.960536) (xy 389.241284 -427.233588) (xy 389.241568 -427.224753)
			(xy 389.245681 -427.207566) (xy 389.249412 -427.199552) (xy 389.482838 -426.723302) (xy 389.487524 -426.71278)
			(xy 389.491018 -426.690025) (xy 389.487539 -426.667268) (xy 389.482838 -426.656754) (xy 389.249412 -426.180504)
			(xy 389.245657 -426.172498) (xy 389.24154 -426.155306) (xy 389.241284 -426.146468) (xy 389.241284 -425.419012)
			(xy 389.241727 -425.406905) (xy 389.249221 -425.383881) (xy 389.263476 -425.364309) (xy 389.283091 -425.350114)
			(xy 389.306138 -425.34269) (xy 389.318246 -425.342304) (xy 390.258046 -425.342304) (xy 390.270134 -425.342767)
			(xy 390.29313 -425.350232) (xy 390.312707 -425.364421) (xy 390.326957 -425.383953) (xy 390.334494 -425.406925)
			(xy 390.335008 -425.419012) (xy 390.335008 -427.960536) (xy 390.334614 -427.972646) (xy 390.327106 -427.995673)
			(xy 390.312838 -428.015245) (xy 390.293213 -428.029438) (xy 390.270157 -428.03686) (xy 390.258046 -428.037244)
			(xy 389.318246 -428.037244) (xy 389.306157 -428.036753) (xy 389.283155 -428.029307) (xy 389.263573 -428.015127)
			(xy 389.249322 -427.995597) (xy 389.241791 -427.972623) (xy 389.241284 -427.960536) (xy 388.335012 -427.960536)
			(xy 388.335012 -428.960534) (xy 388.334518 -428.972645) (xy 388.327028 -428.995681) (xy 388.31279 -429.015278)
			(xy 388.293196 -429.02952) (xy 388.270161 -429.037016) (xy 388.25805 -429.037496) (xy 387.31825 -429.037496)
			(xy 387.306136 -429.037031) (xy 387.283097 -429.029535) (xy 387.263499 -429.015289) (xy 387.249258 -428.995689)
			(xy 387.241766 -428.972648) (xy 387.241288 -428.960534) (xy 386.307015 -428.960534) (xy 386.312707 -428.964653)
			(xy 386.32696 -428.984167) (xy 386.334501 -429.007127) (xy 386.335016 -429.019208) (xy 386.335016 -431.560732)
			(xy 386.334611 -431.572841) (xy 386.327105 -431.595867) (xy 386.31284 -431.615438) (xy 386.293217 -431.629632)
			(xy 386.270164 -431.637055) (xy 386.258054 -431.63744) (xy 385.318254 -431.63744) (xy 385.30616 -431.637031)
			(xy 385.283155 -431.62956) (xy 385.263574 -431.615359) (xy 385.249325 -431.595812) (xy 385.241798 -431.572825)
			(xy 385.241292 -431.560732) (xy 384.33502 -431.560732) (xy 384.33502 -432.56073) (xy 384.334665 -432.572859)
			(xy 384.327159 -432.595926) (xy 384.312892 -432.615544) (xy 384.293261 -432.629792) (xy 384.270187 -432.637276)
			(xy 384.258058 -432.637692) (xy 383.318258 -432.637692) (xy 383.306144 -432.637225) (xy 383.283105 -432.629729)
			(xy 383.263506 -432.615485) (xy 383.249265 -432.595885) (xy 383.241774 -432.572844) (xy 383.241296 -432.56073)
			(xy 382.307694 -432.56073) (xy 382.312801 -432.564436) (xy 382.327046 -432.584018) (xy 382.334543 -432.607043)
			(xy 382.335024 -432.61915) (xy 382.335024 -435.160674) (xy 382.334617 -435.172799) (xy 382.327128 -435.195864)
			(xy 382.312874 -435.215482) (xy 382.293253 -435.229733) (xy 382.270187 -435.237219) (xy 382.258062 -435.237636)
			(xy 381.318262 -435.237636) (xy 381.306143 -435.23722) (xy 381.283094 -435.229719) (xy 381.263491 -435.215464)
			(xy 381.249251 -435.195849) (xy 381.24177 -435.172794) (xy 381.2413 -435.160674) (xy 361.395012 -435.160674)
			(xy 361.434498 -435.208663) (xy 361.510589 -435.313772) (xy 361.580032 -435.423387) (xy 361.642562 -435.537087)
			(xy 361.697938 -435.654438) (xy 361.74595 -435.77499) (xy 361.786412 -435.89828) (xy 361.81917 -436.023838)
			(xy 361.844098 -436.151181) (xy 361.861101 -436.279823) (xy 361.870114 -436.40927) (xy 361.871103 -436.539027)
			(xy 361.864062 -436.668596) (xy 361.849021 -436.797482) (xy 361.826035 -436.92519) (xy 361.795194 -437.051232)
			(xy 361.756614 -437.175125) (xy 361.710445 -437.296394) (xy 361.656862 -437.414574) (xy 361.596072 -437.529214)
			(xy 361.528306 -437.639874) (xy 361.453825 -437.74613) (xy 361.372914 -437.847575) (xy 361.285882 -437.943821)
			(xy 361.193064 -438.034499) (xy 361.094814 -438.119261) (xy 360.991508 -438.197784) (xy 360.883543 -438.269766)
			(xy 360.771333 -438.334931) (xy 360.655306 -438.39303) (xy 360.535907 -438.443841) (xy 360.413594 -438.487169)
			(xy 360.288835 -438.522847) (xy 360.162108 -438.550739) (xy 360.033898 -438.570739) (xy 359.904696 -438.58277)
			(xy 359.774998 -438.586785) (xy 359.6453 -438.58277) (xy 359.516098 -438.570739) (xy 359.387888 -438.550739)
			(xy 359.261161 -438.522847) (xy 359.136402 -438.487169) (xy 359.014089 -438.443841) (xy 358.89469 -438.39303)
			(xy 358.778663 -438.334931) (xy 358.666453 -438.269766) (xy 358.558488 -438.197784) (xy 358.455182 -438.119261)
			(xy 358.356932 -438.034499) (xy 358.264114 -437.943821) (xy 358.177082 -437.847575) (xy 358.096171 -437.74613)
			(xy 358.02169 -437.639874) (xy 357.953924 -437.529214) (xy 357.893134 -437.414574) (xy 357.839551 -437.296394)
			(xy 357.793382 -437.175125) (xy 357.754802 -437.051232) (xy 357.723961 -436.92519) (xy 357.700975 -436.797482)
			(xy 357.685934 -436.668596) (xy 357.678893 -436.539027) (xy 357.679882 -436.40927) (xy 357.688895 -436.279823)
			(xy 357.705898 -436.151181) (xy 357.730826 -436.023838) (xy 357.763584 -435.89828) (xy 357.804046 -435.77499)
			(xy 357.852058 -435.654438) (xy 357.907434 -435.537087) (xy 357.969964 -435.423387) (xy 358.039407 -435.313772)
			(xy 358.115498 -435.208663) (xy 358.197945 -435.108462) (xy 358.286433 -435.013553) (xy 358.380622 -434.924299)
			(xy 358.430068 -434.88229) (xy 358.440228 -434.873908) (xy 358.449626 -434.849016) (xy 358.4321 -434.73624)
			(xy 358.415844 -434.715412) (xy 358.403398 -434.710332) (xy 358.325295 -434.677853) (xy 358.1719 -434.606515)
			(xy 358.022004 -434.52809) (xy 357.875935 -434.44275) (xy 357.734012 -434.350681) (xy 357.596544 -434.252083)
			(xy 357.463831 -434.147172) (xy 357.336162 -434.036176) (xy 357.213818 -433.919339) (xy 357.097064 -433.796915)
			(xy 356.986156 -433.669172) (xy 356.881335 -433.536387) (xy 356.782831 -433.398852) (xy 356.690858 -433.256866)
			(xy 356.605617 -433.110739) (xy 356.527295 -432.96079) (xy 356.456061 -432.807346) (xy 356.392073 -432.650743)
			(xy 356.335468 -432.491322) (xy 356.286372 -432.329431) (xy 356.244891 -432.165424) (xy 356.211115 -431.999658)
			(xy 356.185119 -431.832496) (xy 356.166958 -431.664301) (xy 356.156674 -431.495443) (xy 356.15499 -431.410872)
			(xy 356.155244 -431.410872) (xy 356.154736 -431.360072) (xy 346.23502 -431.360072) (xy 346.23502 -432.56073)
			(xy 346.234665 -432.572859) (xy 346.227159 -432.595926) (xy 346.212892 -432.615544) (xy 346.193261 -432.629792)
			(xy 346.170187 -432.637276) (xy 346.158058 -432.637692) (xy 345.218258 -432.637692) (xy 345.206144 -432.637225)
			(xy 345.183105 -432.629729) (xy 345.163506 -432.615485) (xy 345.149265 -432.595885) (xy 345.141774 -432.572844)
			(xy 345.141296 -432.56073) (xy 344.207518 -432.56073) (xy 344.212514 -432.56437) (xy 344.226708 -432.58399)
			(xy 344.234131 -432.607041) (xy 344.234516 -432.61915) (xy 344.234516 -435.160674) (xy 344.23407 -435.172767)
			(xy 344.226615 -435.195774) (xy 344.212424 -435.215358) (xy 344.192883 -435.229608) (xy 344.169899 -435.237133)
			(xy 344.157808 -435.237636) (xy 343.218008 -435.237636) (xy 343.205903 -435.237178) (xy 343.182882 -435.229685)
			(xy 343.163312 -435.215433) (xy 343.149116 -435.195822) (xy 343.141688 -435.17278) (xy 343.1413 -435.160674)
			(xy 342.23452 -435.160674) (xy 342.23452 -436.160672) (xy 342.234064 -436.172752) (xy 342.226605 -436.195732)
			(xy 342.21241 -436.215281) (xy 342.192868 -436.229487) (xy 342.169892 -436.236957) (xy 342.157812 -436.23738)
			(xy 341.218012 -436.23738) (xy 341.205927 -436.236976) (xy 341.18294 -436.229509) (xy 341.163387 -436.215301)
			(xy 341.149184 -436.195746) (xy 341.141721 -436.172757) (xy 341.141304 -436.160672) (xy 340.207107 -436.160672)
			(xy 340.212393 -436.164513) (xy 340.226587 -436.18405) (xy 340.234051 -436.207017) (xy 340.234524 -436.219092)
			(xy 340.234524 -438.760616) (xy 340.23405 -438.77269) (xy 340.226585 -438.795655) (xy 340.21239 -438.81519)
			(xy 340.192855 -438.829385) (xy 340.16989 -438.83685) (xy 340.157816 -438.837324) (xy 339.218016 -438.837324)
			(xy 339.205944 -438.836822) (xy 339.18298 -438.829366) (xy 339.163444 -438.815179) (xy 339.149248 -438.795649)
			(xy 339.141783 -438.772688) (xy 339.141308 -438.760616) (xy 338.234528 -438.760616) (xy 338.234528 -439.760614)
			(xy 341.141304 -439.760614) (xy 341.141304 -437.21909) (xy 341.141798 -437.207004) (xy 341.149253 -437.184009)
			(xy 341.163434 -437.164432) (xy 341.18296 -437.150181) (xy 341.205927 -437.142643) (xy 341.218012 -437.142128)
			(xy 342.157812 -437.142128) (xy 342.169924 -437.142506) (xy 342.192957 -437.150012) (xy 342.212532 -437.164283)
			(xy 342.226725 -437.183914) (xy 342.234141 -437.206976) (xy 342.23452 -437.21909) (xy 342.23452 -438.760616)
			(xy 343.1413 -438.760616) (xy 343.1413 -436.219092) (xy 343.141758 -436.207016) (xy 343.149223 -436.184047)
			(xy 343.163421 -436.16451) (xy 343.182962 -436.150316) (xy 343.205932 -436.142855) (xy 343.218008 -436.142384)
			(xy 344.157808 -436.142384) (xy 344.169882 -436.142857) (xy 344.192848 -436.150321) (xy 344.207094 -436.160672)
			(xy 345.141296 -436.160672) (xy 345.141296 -433.619148) (xy 345.141754 -433.607067) (xy 345.149208 -433.584086)
			(xy 345.163403 -433.564534) (xy 345.182946 -433.550329) (xy 345.205924 -433.542861) (xy 345.218004 -433.54244)
			(xy 346.157804 -433.54244) (xy 346.169892 -433.54281) (xy 346.192883 -433.550284) (xy 346.212437 -433.5645)
			(xy 346.226639 -433.584064) (xy 346.234098 -433.60706) (xy 346.234512 -433.619148) (xy 346.234512 -436.160672)
			(xy 346.234063 -436.172753) (xy 346.226604 -436.195734) (xy 346.212407 -436.215284) (xy 346.192863 -436.229489)
			(xy 346.169885 -436.236958) (xy 346.157804 -436.23738) (xy 345.218004 -436.23738) (xy 345.205919 -436.236984)
			(xy 345.182931 -436.229514) (xy 345.163378 -436.215304) (xy 345.149175 -436.195747) (xy 345.141712 -436.172757)
			(xy 345.141296 -436.160672) (xy 344.207094 -436.160672) (xy 344.212384 -436.164516) (xy 344.226579 -436.184052)
			(xy 344.234043 -436.207018) (xy 344.234516 -436.219092) (xy 344.234516 -438.760616) (xy 344.234049 -438.772691)
			(xy 344.226583 -438.795657) (xy 344.212387 -438.815193) (xy 344.19285 -438.829387) (xy 344.169883 -438.836851)
			(xy 344.157808 -438.837324) (xy 343.218008 -438.837324) (xy 343.205935 -438.836829) (xy 343.182971 -438.829371)
			(xy 343.163435 -438.815182) (xy 343.14924 -438.79565) (xy 343.141775 -438.772688) (xy 343.1413 -438.760616)
			(xy 342.23452 -438.760616) (xy 342.23452 -439.760614) (xy 345.141296 -439.760614) (xy 345.141296 -437.21909)
			(xy 345.141798 -437.207004) (xy 345.149252 -437.184011) (xy 345.163431 -437.164435) (xy 345.182955 -437.150183)
			(xy 345.20592 -437.142644) (xy 345.218004 -437.142128) (xy 346.157804 -437.142128) (xy 346.169916 -437.142513)
			(xy 346.192948 -437.150017) (xy 346.212524 -437.164286) (xy 346.226717 -437.183916) (xy 346.234133 -437.206977)
			(xy 346.234512 -437.21909) (xy 346.234512 -438.760616) (xy 381.2413 -438.760616) (xy 381.2413 -436.219092)
			(xy 381.241709 -436.206983) (xy 381.249211 -436.183955) (xy 381.263474 -436.164382) (xy 381.283097 -436.150188)
			(xy 381.306151 -436.142767) (xy 381.318262 -436.142384) (xy 382.258062 -436.142384) (xy 382.270154 -436.142841)
			(xy 382.293161 -436.150292) (xy 382.307489 -436.160672) (xy 383.241296 -436.160672) (xy 383.241296 -433.619148)
			(xy 383.241757 -433.607042) (xy 383.249243 -433.584017) (xy 383.263493 -433.564443) (xy 383.283105 -433.550247)
			(xy 383.306151 -433.542824) (xy 383.318258 -433.54244) (xy 384.258058 -433.54244) (xy 384.270145 -433.542943)
			(xy 384.293145 -433.550388) (xy 384.312725 -433.564566) (xy 384.326977 -433.584092) (xy 384.33451 -433.607062)
			(xy 384.33502 -433.619148) (xy 384.33502 -435.160674) (xy 385.241292 -435.160674) (xy 385.241292 -432.61915)
			(xy 385.241768 -432.607037) (xy 385.249264 -432.584) (xy 385.263506 -432.564403) (xy 385.283104 -432.550162)
			(xy 385.306141 -432.542668) (xy 385.318254 -432.542188) (xy 386.258054 -432.542188) (xy 386.270161 -432.54275)
			(xy 386.293195 -432.550219) (xy 386.307681 -432.56073) (xy 387.241288 -432.56073) (xy 387.241288 -430.019206)
			(xy 387.241816 -430.007097) (xy 387.249296 -429.984062) (xy 387.263525 -429.964465) (xy 387.283112 -429.950221)
			(xy 387.306141 -429.942725) (xy 387.31825 -429.942244) (xy 388.25805 -429.942244) (xy 388.270168 -429.942669)
			(xy 388.293214 -429.950171) (xy 388.312815 -429.964425) (xy 388.327055 -429.984037) (xy 388.33454 -430.007088)
			(xy 388.335012 -430.019206) (xy 388.335012 -431.560732) (xy 389.241284 -431.560732) (xy 389.241284 -429.019208)
			(xy 389.241723 -429.007101) (xy 389.249218 -428.984077) (xy 389.263474 -428.964505) (xy 389.28309 -428.950309)
			(xy 389.306138 -428.942886) (xy 389.318246 -428.9425) (xy 390.258046 -428.9425) (xy 390.270134 -428.942967)
			(xy 390.293129 -428.950432) (xy 390.307067 -428.960534) (xy 391.24128 -428.960534) (xy 391.24128 -428.233586)
			(xy 391.241564 -428.224751) (xy 391.245677 -428.207564) (xy 391.249408 -428.19955) (xy 391.482834 -427.7233)
			(xy 391.487522 -427.712778) (xy 391.491015 -427.690023) (xy 391.487536 -427.667266) (xy 391.482834 -427.656752)
			(xy 391.249408 -427.180502) (xy 391.245652 -427.172496) (xy 391.241536 -427.155304) (xy 391.24128 -427.146466)
			(xy 391.24128 -426.41901) (xy 391.241669 -426.406884) (xy 391.249164 -426.383818) (xy 391.263422 -426.364199)
			(xy 391.283047 -426.349949) (xy 391.306115 -426.342464) (xy 391.318242 -426.342048) (xy 392.258042 -426.342048)
			(xy 392.27016 -426.342476) (xy 392.293206 -426.349976) (xy 392.312808 -426.364229) (xy 392.327048 -426.383841)
			(xy 392.334532 -426.406892) (xy 392.335004 -426.41901) (xy 392.335004 -427.960536) (xy 393.241276 -427.960536)
			(xy 393.241276 -427.233588) (xy 393.24156 -427.224753) (xy 393.245673 -427.207566) (xy 393.249404 -427.199552)
			(xy 393.48283 -426.723302) (xy 393.487517 -426.71278) (xy 393.49101 -426.690025) (xy 393.487532 -426.667268)
			(xy 393.48283 -426.656754) (xy 393.249404 -426.180504) (xy 393.245649 -426.172498) (xy 393.241532 -426.155306)
			(xy 393.241276 -426.146468) (xy 393.241276 -425.419012) (xy 393.241726 -425.406906) (xy 393.24922 -425.383883)
			(xy 393.263473 -425.364312) (xy 393.283086 -425.350116) (xy 393.306131 -425.342691) (xy 393.318238 -425.342304)
			(xy 394.258038 -425.342304) (xy 394.270126 -425.342774) (xy 394.293122 -425.350237) (xy 394.312698 -425.364424)
			(xy 394.326949 -425.383954) (xy 394.334486 -425.406926) (xy 394.335 -425.419012) (xy 394.335 -427.960536)
			(xy 394.334614 -427.972647) (xy 394.327105 -427.995675) (xy 394.312835 -428.015248) (xy 394.293208 -428.029441)
			(xy 394.27015 -428.036861) (xy 394.258038 -428.037244) (xy 393.318238 -428.037244) (xy 393.306149 -428.03676)
			(xy 393.283147 -428.029312) (xy 393.263565 -428.01513) (xy 393.249314 -427.995599) (xy 393.241783 -427.972623)
			(xy 393.241276 -427.960536) (xy 392.335004 -427.960536) (xy 392.335004 -428.960534) (xy 392.334518 -428.972646)
			(xy 392.327027 -428.995683) (xy 392.312787 -429.015281) (xy 392.293191 -429.029523) (xy 392.270154 -429.037017)
			(xy 392.258042 -429.037496) (xy 391.318242 -429.037496) (xy 391.306125 -429.037005) (xy 391.283073 -429.029528)
			(xy 391.26346 -429.015294) (xy 391.249206 -428.995695) (xy 391.241707 -428.972651) (xy 391.24128 -428.960534)
			(xy 390.307067 -428.960534) (xy 390.312705 -428.96462) (xy 390.326956 -428.98415) (xy 390.334493 -429.007122)
			(xy 390.335008 -429.019208) (xy 390.335008 -431.560732) (xy 390.334611 -431.572842) (xy 390.327104 -431.595869)
			(xy 390.312837 -431.615441) (xy 390.293212 -431.629634) (xy 390.270157 -431.637056) (xy 390.258046 -431.63744)
			(xy 389.318246 -431.63744) (xy 389.306157 -431.636953) (xy 389.283154 -431.629507) (xy 389.263572 -431.615326)
			(xy 389.24932 -431.595795) (xy 389.241791 -431.572819) (xy 389.241284 -431.560732) (xy 388.335012 -431.560732)
			(xy 388.335012 -432.56073) (xy 388.334515 -432.572841) (xy 388.327025 -432.595877) (xy 388.312788 -432.615474)
			(xy 388.293195 -432.629716) (xy 388.270161 -432.637212) (xy 388.25805 -432.637692) (xy 387.31825 -432.637692)
			(xy 387.306136 -432.637231) (xy 387.283096 -432.629734) (xy 387.263498 -432.615488) (xy 387.249257 -432.595886)
			(xy 387.241766 -432.572844) (xy 387.241288 -432.56073) (xy 386.307681 -432.56073) (xy 386.312793 -432.564439)
			(xy 386.327038 -432.584019) (xy 386.334535 -432.607043) (xy 386.335016 -432.61915) (xy 386.335016 -435.160674)
			(xy 386.334617 -435.1728) (xy 386.327127 -435.195866) (xy 386.312871 -435.215485) (xy 386.293248 -435.229736)
			(xy 386.27018 -435.23722) (xy 386.258054 -435.237636) (xy 385.318254 -435.237636) (xy 385.306134 -435.237227)
			(xy 385.283085 -435.229724) (xy 385.263482 -435.215467) (xy 385.249243 -435.19585) (xy 385.241762 -435.172794)
			(xy 385.241292 -435.160674) (xy 384.33502 -435.160674) (xy 384.33502 -436.160672) (xy 384.33456 -436.172777)
			(xy 384.327071 -436.1958) (xy 384.31282 -436.215372) (xy 384.293208 -436.229568) (xy 384.270164 -436.236993)
			(xy 384.258058 -436.23738) (xy 383.318258 -436.23738) (xy 383.306168 -436.236929) (xy 383.28317 -436.229463)
			(xy 383.263592 -436.215272) (xy 383.249342 -436.195737) (xy 383.241808 -436.17276) (xy 383.241296 -436.160672)
			(xy 382.307489 -436.160672) (xy 382.312745 -436.16448) (xy 382.326995 -436.184019) (xy 382.334521 -436.207002)
			(xy 382.335024 -436.219092) (xy 382.335024 -438.760616) (xy 382.334598 -438.772723) (xy 382.327097 -438.795747)
			(xy 382.312837 -438.815318) (xy 382.293219 -438.829513) (xy 382.270171 -438.836937) (xy 382.258062 -438.837324)
			(xy 381.318262 -438.837324) (xy 381.306167 -438.836924) (xy 381.283159 -438.829453) (xy 381.263577 -438.81525)
			(xy 381.249329 -438.795701) (xy 381.241804 -438.77271) (xy 381.2413 -438.760616) (xy 346.234512 -438.760616)
			(xy 346.234512 -439.760614) (xy 383.241296 -439.760614) (xy 383.241296 -437.21909) (xy 383.241803 -437.206979)
			(xy 383.249288 -437.183943) (xy 383.263522 -437.164345) (xy 383.283114 -437.150102) (xy 383.306147 -437.142608)
			(xy 383.318258 -437.142128) (xy 384.258058 -437.142128) (xy 384.270178 -437.142595) (xy 384.293233 -437.150075)
			(xy 384.312848 -437.164315) (xy 384.327101 -437.18392) (xy 384.334596 -437.206971) (xy 384.33502 -437.21909)
			(xy 384.33502 -438.760616) (xy 385.241292 -438.760616) (xy 385.241292 -436.219092) (xy 385.241709 -436.206983)
			(xy 385.24921 -436.183957) (xy 385.263472 -436.164385) (xy 385.283092 -436.15019) (xy 385.306144 -436.142768)
			(xy 385.318254 -436.142384) (xy 386.258054 -436.142384) (xy 386.270146 -436.142847) (xy 386.293152 -436.150297)
			(xy 386.307476 -436.160672) (xy 387.241288 -436.160672) (xy 387.241288 -433.619148) (xy 387.241757 -433.607043)
			(xy 387.249242 -433.584019) (xy 387.26349 -433.564446) (xy 387.2831 -433.55025) (xy 387.306144 -433.542826)
			(xy 387.31825 -433.54244) (xy 388.25805 -433.54244) (xy 388.270137 -433.54295) (xy 388.293136 -433.550393)
			(xy 388.312717 -433.564568) (xy 388.326969 -433.584093) (xy 388.334502 -433.607063) (xy 388.335012 -433.619148)
			(xy 388.335012 -435.160674) (xy 389.241284 -435.160674) (xy 389.241284 -432.61915) (xy 389.24167 -432.607028)
			(xy 389.249176 -432.583976) (xy 389.263439 -432.564371) (xy 389.283062 -432.550133) (xy 389.306124 -432.542655)
			(xy 389.318246 -432.542188) (xy 390.258046 -432.542188) (xy 390.270158 -432.542672) (xy 390.293194 -432.550166)
			(xy 390.307732 -432.56073) (xy 391.24128 -432.56073) (xy 391.24128 -430.019206) (xy 391.241666 -430.007079)
			(xy 391.249162 -429.984014) (xy 391.263421 -429.964395) (xy 391.283046 -429.950145) (xy 391.306115 -429.94266)
			(xy 391.318242 -429.942244) (xy 392.258042 -429.942244) (xy 392.270159 -429.942676) (xy 392.293205 -429.950176)
			(xy 392.312807 -429.964428) (xy 392.327046 -429.984038) (xy 392.334532 -430.007088) (xy 392.335004 -430.019206)
			(xy 392.335004 -431.560732) (xy 393.241276 -431.560732) (xy 393.241276 -429.019208) (xy 393.241723 -429.007102)
			(xy 393.249217 -428.984079) (xy 393.263471 -428.964508) (xy 393.283085 -428.950312) (xy 393.306131 -428.942887)
			(xy 393.318238 -428.9425) (xy 394.258038 -428.9425) (xy 394.270126 -428.942974) (xy 394.293121 -428.950436)
			(xy 394.307055 -428.960534) (xy 395.241272 -428.960534) (xy 395.241272 -428.233586) (xy 395.241556 -428.224751)
			(xy 395.245669 -428.207564) (xy 395.2494 -428.19955) (xy 395.482826 -427.7233) (xy 395.487514 -427.712778)
			(xy 395.491008 -427.690023) (xy 395.487528 -427.667266) (xy 395.482826 -427.656752) (xy 395.2494 -427.180502)
			(xy 395.245644 -427.172497) (xy 395.241528 -427.155304) (xy 395.241272 -427.146466) (xy 395.241272 -426.41901)
			(xy 395.241669 -426.406884) (xy 395.249163 -426.38382) (xy 395.263419 -426.364202) (xy 395.283042 -426.349952)
			(xy 395.306108 -426.342465) (xy 395.318234 -426.342048) (xy 396.258034 -426.342048) (xy 396.270151 -426.342483)
			(xy 396.293197 -426.349981) (xy 396.312799 -426.364232) (xy 396.327039 -426.383842) (xy 396.334524 -426.406892)
			(xy 396.334996 -426.41901) (xy 396.334996 -427.960536) (xy 398.24152 -427.960536) (xy 398.24152 -427.233588)
			(xy 398.241767 -427.224768) (xy 398.245735 -427.20758) (xy 398.249394 -427.199552) (xy 398.48282 -426.723302)
			(xy 398.487507 -426.71278) (xy 398.491001 -426.690025) (xy 398.487522 -426.667268) (xy 398.48282 -426.656754)
			(xy 398.249394 -426.180504) (xy 398.24571 -426.172483) (xy 398.241734 -426.155292) (xy 398.24152 -426.146468)
			(xy 398.24152 -425.419012) (xy 398.241924 -425.406927) (xy 398.249391 -425.38394) (xy 398.263599 -425.364387)
			(xy 398.283154 -425.350184) (xy 398.306143 -425.342721) (xy 398.318228 -425.342304) (xy 399.258028 -425.342304)
			(xy 399.270105 -425.34274) (xy 399.293075 -425.350212) (xy 399.312613 -425.364415) (xy 399.326806 -425.38396)
			(xy 399.334266 -425.406935) (xy 399.334736 -425.419012) (xy 399.334736 -427.960536) (xy 399.334267 -427.97261)
			(xy 399.326798 -427.995573) (xy 399.312602 -428.015107) (xy 399.293066 -428.029302) (xy 399.270102 -428.036768)
			(xy 399.258028 -428.037244) (xy 398.318228 -428.037244) (xy 398.306158 -428.036713) (xy 398.283198 -428.029262)
			(xy 398.263664 -428.015082) (xy 398.249467 -427.995559) (xy 398.241997 -427.972605) (xy 398.24152 -427.960536)
			(xy 396.334996 -427.960536) (xy 396.334996 -428.960534) (xy 396.334518 -428.972647) (xy 396.327025 -428.995686)
			(xy 396.312784 -429.015284) (xy 396.293186 -429.029525) (xy 396.270147 -429.037018) (xy 396.258034 -429.037496)
			(xy 395.318234 -429.037496) (xy 395.306125 -429.03696) (xy 395.283088 -429.029486) (xy 395.263489 -429.01526)
			(xy 395.249245 -428.995673) (xy 395.241751 -428.972643) (xy 395.241272 -428.960534) (xy 394.307055 -428.960534)
			(xy 394.312697 -428.964623) (xy 394.326947 -428.984152) (xy 394.334485 -429.007122) (xy 394.335 -429.019208)
			(xy 394.335 -431.560732) (xy 394.334611 -431.572843) (xy 394.327103 -431.595871) (xy 394.312834 -431.615443)
			(xy 394.293207 -431.629637) (xy 394.27015 -431.637057) (xy 394.258038 -431.63744) (xy 393.318238 -431.63744)
			(xy 393.306148 -431.63696) (xy 393.283146 -431.629511) (xy 393.263563 -431.615329) (xy 393.249312 -431.595796)
			(xy 393.241783 -431.57282) (xy 393.241276 -431.560732) (xy 392.335004 -431.560732) (xy 392.335004 -432.56073)
			(xy 392.334515 -432.572842) (xy 392.327024 -432.595879) (xy 392.312785 -432.615477) (xy 392.29319 -432.629719)
			(xy 392.270154 -432.637213) (xy 392.258042 -432.637692) (xy 391.318242 -432.637692) (xy 391.306124 -432.637205)
			(xy 391.283072 -432.629728) (xy 391.263459 -432.615492) (xy 391.249205 -432.595893) (xy 391.241706 -432.572847)
			(xy 391.24128 -432.56073) (xy 390.307732 -432.56073) (xy 390.312791 -432.564406) (xy 390.327033 -432.584002)
			(xy 390.334528 -432.607038) (xy 390.335008 -432.61915) (xy 390.335008 -435.160674) (xy 390.334467 -435.172783)
			(xy 390.326992 -435.195817) (xy 390.312767 -435.215415) (xy 390.293182 -435.229659) (xy 390.270154 -435.237155)
			(xy 390.258046 -435.237636) (xy 389.318246 -435.237636) (xy 389.306123 -435.237201) (xy 389.283061 -435.229718)
			(xy 389.263443 -435.215471) (xy 389.249191 -435.195857) (xy 389.241703 -435.172797) (xy 389.241284 -435.160674)
			(xy 388.335012 -435.160674) (xy 388.335012 -436.160672) (xy 388.33456 -436.172778) (xy 388.32707 -436.195802)
			(xy 388.312817 -436.215375) (xy 388.293203 -436.229571) (xy 388.270157 -436.236994) (xy 388.25805 -436.23738)
			(xy 387.31825 -436.23738) (xy 387.306165 -436.23685) (xy 387.283169 -436.22941) (xy 387.26359 -436.215239)
			(xy 387.249337 -436.195719) (xy 387.241801 -436.172755) (xy 387.241288 -436.160672) (xy 386.307476 -436.160672)
			(xy 386.312737 -436.164483) (xy 386.326987 -436.18402) (xy 386.334512 -436.207002) (xy 386.335016 -436.219092)
			(xy 386.335016 -438.760616) (xy 386.334598 -438.772724) (xy 386.327096 -438.795749) (xy 386.312834 -438.815321)
			(xy 386.293214 -438.829515) (xy 386.270163 -438.836939) (xy 386.258054 -438.837324) (xy 385.318254 -438.837324)
			(xy 385.306158 -438.836931) (xy 385.28315 -438.829457) (xy 385.263568 -438.815253) (xy 385.24932 -438.795702)
			(xy 385.241796 -438.77271) (xy 385.241292 -438.760616) (xy 384.33502 -438.760616) (xy 384.33502 -439.760614)
			(xy 387.241288 -439.760614) (xy 387.241288 -437.21909) (xy 387.241803 -437.20698) (xy 387.249287 -437.183945)
			(xy 387.263519 -437.164348) (xy 387.283109 -437.150105) (xy 387.30614 -437.142609) (xy 387.31825 -437.142128)
			(xy 388.25805 -437.142128) (xy 388.270166 -437.142569) (xy 388.293209 -437.150069) (xy 388.312809 -437.164319)
			(xy 388.32705 -437.183927) (xy 388.334537 -437.206974) (xy 388.335012 -437.21909) (xy 388.335012 -438.760616)
			(xy 389.241284 -438.760616) (xy 389.241284 -436.219092) (xy 389.241709 -436.206984) (xy 389.249209 -436.183959)
			(xy 389.263469 -436.164388) (xy 389.283087 -436.150193) (xy 389.306137 -436.142769) (xy 389.318246 -436.142384)
			(xy 390.258046 -436.142384) (xy 390.270142 -436.142769) (xy 390.293152 -436.150244) (xy 390.307527 -436.160672)
			(xy 391.24128 -436.160672) (xy 391.24128 -433.619148) (xy 391.241757 -433.607044) (xy 391.249241 -433.584021)
			(xy 391.263487 -433.564449) (xy 391.283095 -433.550252) (xy 391.306137 -433.542827) (xy 391.318242 -433.54244)
			(xy 392.258042 -433.54244) (xy 392.270134 -433.542872) (xy 392.293136 -433.55034) (xy 392.312715 -433.564536)
			(xy 392.326964 -433.584076) (xy 392.334495 -433.607058) (xy 392.335004 -433.619148) (xy 392.335004 -435.160674)
			(xy 393.241276 -435.160674) (xy 393.241276 -432.61915) (xy 393.24167 -432.607029) (xy 393.249175 -432.583978)
			(xy 393.263436 -432.564374) (xy 393.283057 -432.550135) (xy 393.306117 -432.542656) (xy 393.318238 -432.542188)
			(xy 394.258038 -432.542188) (xy 394.27015 -432.542678) (xy 394.293186 -432.55017) (xy 394.307719 -432.56073)
			(xy 395.241272 -432.56073) (xy 395.241272 -430.019206) (xy 395.241666 -430.00708) (xy 395.24916 -429.984016)
			(xy 395.263418 -429.964398) (xy 395.283041 -429.950148) (xy 395.306108 -429.942661) (xy 395.318234 -429.942244)
			(xy 396.258034 -429.942244) (xy 396.270151 -429.942683) (xy 396.293196 -429.95018) (xy 396.312798 -429.96443)
			(xy 396.327038 -429.98404) (xy 396.334524 -430.007089) (xy 396.334996 -430.019206) (xy 396.334996 -431.560732)
			(xy 398.24152 -431.560732) (xy 398.24152 -429.019208) (xy 398.241923 -429.007098) (xy 398.249423 -428.984067)
			(xy 398.263687 -428.964492) (xy 398.283313 -428.950298) (xy 398.30637 -428.94288) (xy 398.318482 -428.9425)
			(xy 399.258282 -428.9425) (xy 399.270367 -428.943022) (xy 399.29336 -428.950469) (xy 399.307262 -428.960534)
			(xy 400.241516 -428.960534) (xy 400.241516 -428.233586) (xy 400.241762 -428.224766) (xy 400.245731 -428.207578)
			(xy 400.24939 -428.19955) (xy 400.482816 -427.7233) (xy 400.487504 -427.712778) (xy 400.490998 -427.690023)
			(xy 400.487518 -427.667266) (xy 400.482816 -427.656752) (xy 400.24939 -427.180502) (xy 400.245705 -427.172482)
			(xy 400.24173 -427.15529) (xy 400.241516 -427.146466) (xy 400.241516 -426.41901) (xy 400.242016 -426.406923)
			(xy 400.249467 -426.383927) (xy 400.263646 -426.364349) (xy 400.283171 -426.350097) (xy 400.306139 -426.342561)
			(xy 400.318224 -426.342048) (xy 401.258024 -426.342048) (xy 401.270129 -426.342495) (xy 401.293148 -426.349995)
			(xy 401.312716 -426.36425) (xy 401.326912 -426.383862) (xy 401.334341 -426.406904) (xy 401.334732 -426.41901)
			(xy 401.334732 -427.960536) (xy 402.241512 -427.960536) (xy 402.241512 -427.233588) (xy 402.24176 -427.224768)
			(xy 402.245727 -427.207581) (xy 402.249386 -427.199552) (xy 402.482812 -426.723302) (xy 402.487499 -426.71278)
			(xy 402.490994 -426.690025) (xy 402.487514 -426.667268) (xy 402.482812 -426.656754) (xy 402.249386 -426.180504)
			(xy 402.245702 -426.172483) (xy 402.241726 -426.155292) (xy 402.241512 -426.146468) (xy 402.241512 -425.419012)
			(xy 402.241923 -425.406928) (xy 402.24939 -425.383942) (xy 402.263596 -425.36439) (xy 402.283149 -425.350186)
			(xy 402.306136 -425.342722) (xy 402.31822 -425.342304) (xy 403.25802 -425.342304) (xy 403.270097 -425.342748)
			(xy 403.293067 -425.350217) (xy 403.312604 -425.364419) (xy 403.326798 -425.383962) (xy 403.334257 -425.406935)
			(xy 403.334728 -425.419012) (xy 403.334728 -427.960536) (xy 403.334267 -427.97261) (xy 403.326797 -427.995576)
			(xy 403.312599 -428.01511) (xy 403.293061 -428.029304) (xy 403.270095 -428.036769) (xy 403.25802 -428.037244)
			(xy 402.31822 -428.037244) (xy 402.30615 -428.036719) (xy 402.28319 -428.029267) (xy 402.263655 -428.015085)
			(xy 402.249459 -427.995561) (xy 402.241989 -427.972606) (xy 402.241512 -427.960536) (xy 401.334732 -427.960536)
			(xy 401.334732 -428.960534) (xy 401.334321 -428.972628) (xy 401.326852 -428.995635) (xy 401.312652 -429.015216)
			(xy 401.293105 -429.029465) (xy 401.270117 -429.036991) (xy 401.258024 -429.037496) (xy 400.318224 -429.037496)
			(xy 400.306116 -429.037063) (xy 400.283089 -429.02957) (xy 400.263515 -429.015313) (xy 400.24932 -428.995694)
			(xy 400.241899 -428.972643) (xy 400.241516 -428.960534) (xy 399.307262 -428.960534) (xy 399.312937 -428.964643)
			(xy 399.327189 -428.984162) (xy 399.334729 -429.007125) (xy 399.335244 -429.019208) (xy 399.335244 -431.560732)
			(xy 399.334811 -431.572838) (xy 399.327309 -431.595859) (xy 399.31305 -431.615428) (xy 399.293435 -431.629623)
			(xy 399.270389 -431.637051) (xy 399.258282 -431.63744) (xy 398.318482 -431.63744) (xy 398.306389 -431.637008)
			(xy 398.283385 -431.629544) (xy 398.263803 -431.615349) (xy 398.249554 -431.595807) (xy 398.242026 -431.572823)
			(xy 398.24152 -431.560732) (xy 396.334996 -431.560732) (xy 396.334996 -432.56073) (xy 396.334514 -432.572843)
			(xy 396.327023 -432.595881) (xy 396.312782 -432.61548) (xy 396.293185 -432.629721) (xy 396.270147 -432.637214)
			(xy 396.258034 -432.637692) (xy 395.318234 -432.637692) (xy 395.306116 -432.637212) (xy 395.283063 -432.629732)
			(xy 395.26345 -432.615495) (xy 395.249197 -432.595894) (xy 395.241698 -432.572848) (xy 395.241272 -432.56073)
			(xy 394.307719 -432.56073) (xy 394.312782 -432.564409) (xy 394.327024 -432.584004) (xy 394.33452 -432.607039)
			(xy 394.335 -432.61915) (xy 394.335 -435.160674) (xy 394.334467 -435.172783) (xy 394.326991 -435.195819)
			(xy 394.312764 -435.215418) (xy 394.293177 -435.229662) (xy 394.270147 -435.237157) (xy 394.258038 -435.237636)
			(xy 393.318238 -435.237636) (xy 393.306115 -435.237207) (xy 393.283053 -435.229722) (xy 393.263435 -435.215474)
			(xy 393.249183 -435.195858) (xy 393.241695 -435.172797) (xy 393.241276 -435.160674) (xy 392.335004 -435.160674)
			(xy 392.335004 -436.160672) (xy 392.33456 -436.172779) (xy 392.327069 -436.195805) (xy 392.312814 -436.215378)
			(xy 392.293198 -436.229574) (xy 392.27015 -436.236996) (xy 392.258042 -436.23738) (xy 391.318242 -436.23738)
			(xy 391.306157 -436.236857) (xy 391.283161 -436.229415) (xy 391.263582 -436.215242) (xy 391.249329 -436.195721)
			(xy 391.241793 -436.172755) (xy 391.24128 -436.160672) (xy 390.307527 -436.160672) (xy 390.312735 -436.16445)
			(xy 390.326982 -436.184003) (xy 390.334505 -436.206997) (xy 390.335008 -436.219092) (xy 390.335008 -438.760616)
			(xy 390.334598 -438.772725) (xy 390.327095 -438.795751) (xy 390.312831 -438.815324) (xy 390.293209 -438.829518)
			(xy 390.270156 -438.83694) (xy 390.258046 -438.837324) (xy 389.318246 -438.837324) (xy 389.306155 -438.836853)
			(xy 389.28315 -438.829404) (xy 389.263566 -438.81522) (xy 389.249315 -438.795685) (xy 389.241789 -438.772705)
			(xy 389.241284 -438.760616) (xy 388.335012 -438.760616) (xy 388.335012 -439.760614) (xy 391.24128 -439.760614)
			(xy 391.24128 -437.21909) (xy 391.241652 -437.206963) (xy 391.249152 -437.183896) (xy 391.263415 -437.164278)
			(xy 391.283043 -437.150029) (xy 391.306114 -437.142544) (xy 391.318242 -437.142128) (xy 392.258042 -437.142128)
			(xy 392.270158 -437.142576) (xy 392.293201 -437.150073) (xy 392.312801 -437.164322) (xy 392.327041 -437.183928)
			(xy 392.334529 -437.206974) (xy 392.335004 -437.21909) (xy 392.335004 -438.760616) (xy 393.241276 -438.760616)
			(xy 393.241276 -436.219092) (xy 393.241709 -436.206985) (xy 393.249208 -436.183962) (xy 393.263466 -436.164391)
			(xy 393.283082 -436.150195) (xy 393.30613 -436.142771) (xy 393.318238 -436.142384) (xy 394.258038 -436.142384)
			(xy 394.270134 -436.142776) (xy 394.293143 -436.150248) (xy 394.307514 -436.160672) (xy 395.241272 -436.160672)
			(xy 395.241272 -433.619148) (xy 395.241757 -433.607044) (xy 395.24924 -433.584023) (xy 395.263484 -433.564452)
			(xy 395.28309 -433.550255) (xy 395.306129 -433.542828) (xy 395.318234 -433.54244) (xy 396.258034 -433.54244)
			(xy 396.270125 -433.542878) (xy 396.293127 -433.550344) (xy 396.312706 -433.564538) (xy 396.326956 -433.584078)
			(xy 396.334487 -433.607058) (xy 396.334996 -433.619148) (xy 396.334996 -435.160674) (xy 398.24152 -435.160674)
			(xy 398.24152 -432.61915) (xy 398.24205 -432.607065) (xy 398.24949 -432.584069) (xy 398.263661 -432.56449)
			(xy 398.283181 -432.550237) (xy 398.306145 -432.542701) (xy 398.318228 -432.542188) (xy 399.258028 -432.542188)
			(xy 399.270137 -432.542592) (xy 399.293163 -432.550098) (xy 399.30775 -432.56073) (xy 400.241516 -432.56073)
			(xy 400.241516 -430.019206) (xy 400.242017 -430.007094) (xy 400.2495 -429.984055) (xy 400.263735 -429.964455)
			(xy 400.28333 -429.950212) (xy 400.306366 -429.942721) (xy 400.318478 -429.942244) (xy 401.258278 -429.942244)
			(xy 401.2704 -429.942679) (xy 401.293459 -429.950166) (xy 401.313075 -429.964413) (xy 401.327327 -429.984026)
			(xy 401.334819 -430.007084) (xy 401.33524 -430.019206) (xy 401.33524 -431.560732) (xy 402.241512 -431.560732)
			(xy 402.241512 -429.019208) (xy 402.241923 -429.007098) (xy 402.249422 -428.984069) (xy 402.263684 -428.964495)
			(xy 402.283308 -428.9503) (xy 402.306363 -428.942882) (xy 402.318474 -428.9425) (xy 403.258274 -428.9425)
			(xy 403.270358 -428.943029) (xy 403.293351 -428.950474) (xy 403.307248 -428.960534) (xy 404.241508 -428.960534)
			(xy 404.241508 -428.233586) (xy 404.241755 -428.224766) (xy 404.245723 -428.207579) (xy 404.249382 -428.19955)
			(xy 404.482808 -427.7233) (xy 404.487497 -427.712779) (xy 404.490991 -427.690023) (xy 404.487511 -427.667266)
			(xy 404.482808 -427.656752) (xy 404.249382 -427.180502) (xy 404.245697 -427.172482) (xy 404.241722 -427.15529)
			(xy 404.241508 -427.146466) (xy 404.241508 -426.41901) (xy 404.242015 -426.406924) (xy 404.249465 -426.383929)
			(xy 404.263643 -426.364352) (xy 404.283166 -426.3501) (xy 404.306132 -426.342562) (xy 404.318216 -426.342048)
			(xy 405.258016 -426.342048) (xy 405.270121 -426.342502) (xy 405.293139 -426.349999) (xy 405.312708 -426.364253)
			(xy 405.326904 -426.383863) (xy 405.334333 -426.406904) (xy 405.334724 -426.41901) (xy 405.334724 -427.960536)
			(xy 406.241504 -427.960536) (xy 406.241504 -427.233588) (xy 406.241752 -427.224768) (xy 406.245719 -427.207581)
			(xy 406.249378 -427.199552) (xy 406.482804 -426.723302) (xy 406.487492 -426.71278) (xy 406.490987 -426.690025)
			(xy 406.487507 -426.667268) (xy 406.482804 -426.656754) (xy 406.249378 -426.180504) (xy 406.245693 -426.172484)
			(xy 406.241718 -426.155292) (xy 406.241504 -426.146468) (xy 406.241504 -425.419012) (xy 406.241923 -425.406929)
			(xy 406.249389 -425.383944) (xy 406.263593 -425.364393) (xy 406.283144 -425.350189) (xy 406.306129 -425.342723)
			(xy 406.318212 -425.342304) (xy 407.258012 -425.342304) (xy 407.270088 -425.342754) (xy 407.293058 -425.350222)
			(xy 407.312596 -425.364421) (xy 407.326789 -425.383964) (xy 407.334249 -425.406935) (xy 407.33472 -425.419012)
			(xy 407.33472 -427.960536) (xy 407.334267 -427.972611) (xy 407.326796 -427.995578) (xy 407.312596 -428.015113)
			(xy 407.293056 -428.029307) (xy 407.270087 -428.036771) (xy 407.258012 -428.037244) (xy 406.318212 -428.037244)
			(xy 406.306142 -428.036726) (xy 406.283181 -428.029271) (xy 406.263647 -428.015087) (xy 406.249451 -427.995562)
			(xy 406.241981 -427.972606) (xy 406.241504 -427.960536) (xy 405.334724 -427.960536) (xy 405.334724 -428.960534)
			(xy 405.334321 -428.972629) (xy 405.326851 -428.995637) (xy 405.312649 -429.015219) (xy 405.2931 -429.029467)
			(xy 405.27011 -429.036992) (xy 405.258016 -429.037496) (xy 404.318216 -429.037496) (xy 404.306108 -429.03707)
			(xy 404.28308 -429.029574) (xy 404.263507 -429.015315) (xy 404.249312 -428.995695) (xy 404.241891 -428.972644)
			(xy 404.241508 -428.960534) (xy 403.307248 -428.960534) (xy 403.312928 -428.964646) (xy 403.327181 -428.984164)
			(xy 403.334721 -429.007126) (xy 403.335236 -429.019208) (xy 403.335236 -431.560732) (xy 403.334811 -431.572839)
			(xy 403.327308 -431.595861) (xy 403.313047 -431.615431) (xy 403.29343 -431.629625) (xy 403.270382 -431.637052)
			(xy 403.258274 -431.63744) (xy 402.318474 -431.63744) (xy 402.306381 -431.637015) (xy 402.283376 -431.629548)
			(xy 402.263795 -431.615352) (xy 402.249546 -431.595808) (xy 402.242018 -431.572824) (xy 402.241512 -431.560732)
			(xy 401.33524 -431.560732) (xy 401.33524 -432.56073) (xy 401.334814 -432.572848) (xy 401.327315 -432.595896)
			(xy 401.313062 -432.615499) (xy 401.29345 -432.629739) (xy 401.270397 -432.637222) (xy 401.258278 -432.637692)
			(xy 400.318478 -432.637692) (xy 400.306365 -432.637208) (xy 400.283326 -432.629718) (xy 400.263728 -432.615478)
			(xy 400.249486 -432.595881) (xy 400.241994 -432.572843) (xy 400.241516 -432.56073) (xy 399.30775 -432.56073)
			(xy 399.312735 -432.564363) (xy 399.326929 -432.583986) (xy 399.334351 -432.607039) (xy 399.334736 -432.61915)
			(xy 399.334736 -435.160674) (xy 399.33427 -435.172765) (xy 399.326818 -435.195768) (xy 399.312632 -435.215351)
			(xy 399.293096 -435.229601) (xy 399.270117 -435.23713) (xy 399.258028 -435.237636) (xy 398.318228 -435.237636)
			(xy 398.306124 -435.23716) (xy 398.283104 -435.229673) (xy 398.263534 -435.215425) (xy 398.249337 -435.195818)
			(xy 398.241909 -435.172779) (xy 398.24152 -435.160674) (xy 396.334996 -435.160674) (xy 396.334996 -436.160672)
			(xy 396.33456 -436.17278) (xy 396.327067 -436.195807) (xy 396.312811 -436.215381) (xy 396.293193 -436.229576)
			(xy 396.270143 -436.236997) (xy 396.258034 -436.23738) (xy 395.318234 -436.23738) (xy 395.306148 -436.236864)
			(xy 395.283152 -436.229419) (xy 395.263573 -436.215244) (xy 395.249321 -436.195722) (xy 395.241785 -436.172756)
			(xy 395.241272 -436.160672) (xy 394.307514 -436.160672) (xy 394.312726 -436.164453) (xy 394.326974 -436.184004)
			(xy 394.334497 -436.206997) (xy 394.335 -436.219092) (xy 394.335 -438.760616) (xy 394.334597 -438.772726)
			(xy 394.327094 -438.795754) (xy 394.312828 -438.815326) (xy 394.293204 -438.82952) (xy 394.270149 -438.836941)
			(xy 394.258038 -438.837324) (xy 393.318238 -438.837324) (xy 393.306147 -438.83686) (xy 393.283141 -438.829409)
			(xy 393.263558 -438.815223) (xy 393.249307 -438.795686) (xy 393.241781 -438.772706) (xy 393.241276 -438.760616)
			(xy 392.335004 -438.760616) (xy 392.335004 -439.760614) (xy 395.241272 -439.760614) (xy 395.241272 -437.21909)
			(xy 395.241652 -437.206963) (xy 395.249151 -437.183898) (xy 395.263412 -437.164281) (xy 395.283038 -437.150031)
			(xy 395.306107 -437.142545) (xy 395.318234 -437.142128) (xy 396.258034 -437.142128) (xy 396.270149 -437.142583)
			(xy 396.293192 -437.150078) (xy 396.312792 -437.164325) (xy 396.327033 -437.18393) (xy 396.334521 -437.206975)
			(xy 396.334996 -437.21909) (xy 396.334996 -438.760616) (xy 398.24152 -438.760616) (xy 398.24152 -436.219092)
			(xy 398.241906 -436.207006) (xy 398.249379 -436.184018) (xy 398.263591 -436.164466) (xy 398.283151 -436.150263)
			(xy 398.306142 -436.1428) (xy 398.318228 -436.142384) (xy 399.258028 -436.142384) (xy 399.270103 -436.14284)
			(xy 399.29307 -436.150309) (xy 399.307328 -436.160672) (xy 400.241516 -436.160672) (xy 400.241516 -433.619148)
			(xy 400.241954 -433.607065) (xy 400.249411 -433.58408) (xy 400.26361 -433.564527) (xy 400.283159 -433.550322)
			(xy 400.306142 -433.542858) (xy 400.318224 -433.54244) (xy 401.258024 -433.54244) (xy 401.270113 -433.542793)
			(xy 401.293104 -433.550273) (xy 401.312658 -433.564493) (xy 401.32686 -433.58406) (xy 401.334318 -433.607059)
			(xy 401.334732 -433.619148) (xy 401.334732 -435.160674) (xy 402.241512 -435.160674) (xy 402.241512 -432.61915)
			(xy 402.242049 -432.607066) (xy 402.249489 -432.584071) (xy 402.263658 -432.564493) (xy 402.283176 -432.55024)
			(xy 402.306138 -432.542702) (xy 402.31822 -432.542188) (xy 403.25802 -432.542188) (xy 403.270129 -432.542599)
			(xy 403.293155 -432.550103) (xy 403.307737 -432.56073) (xy 404.241508 -432.56073) (xy 404.241508 -430.019206)
			(xy 404.242017 -430.007095) (xy 404.249498 -429.984057) (xy 404.263732 -429.964458) (xy 404.283325 -429.950215)
			(xy 404.306359 -429.942722) (xy 404.31847 -429.942244) (xy 405.25827 -429.942244) (xy 405.270392 -429.942686)
			(xy 405.293451 -429.95017) (xy 405.313067 -429.964416) (xy 405.327319 -429.984028) (xy 405.334811 -430.007084)
			(xy 405.335232 -430.019206) (xy 405.335232 -431.560732) (xy 406.241504 -431.560732) (xy 406.241504 -429.019208)
			(xy 406.241923 -429.007099) (xy 406.249421 -428.984071) (xy 406.263681 -428.964498) (xy 406.283303 -428.950303)
			(xy 406.306356 -428.942883) (xy 406.318466 -428.9425) (xy 407.258266 -428.9425) (xy 407.27035 -428.943036)
			(xy 407.293343 -428.950478) (xy 407.306885 -428.96028) (xy 408.2415 -428.96028) (xy 408.2415 -428.233332)
			(xy 408.24173 -428.224511) (xy 408.24571 -428.207323) (xy 408.249374 -428.199296) (xy 408.4828 -427.723046)
			(xy 408.487527 -427.712539) (xy 408.491008 -427.689775) (xy 408.487512 -427.667012) (xy 408.4828 -427.656498)
			(xy 408.249374 -427.180248) (xy 408.245703 -427.172222) (xy 408.241719 -427.155034) (xy 408.2415 -427.146212)
			(xy 408.2415 -426.418756) (xy 408.241927 -426.406678) (xy 408.249402 -426.383708) (xy 408.263608 -426.364171)
			(xy 408.283155 -426.349979) (xy 408.30613 -426.342519) (xy 408.318208 -426.342048) (xy 409.258008 -426.342048)
			(xy 409.270079 -426.342557) (xy 409.293039 -426.350016) (xy 409.312572 -426.364203) (xy 409.326767 -426.383729)
			(xy 409.334238 -426.406686) (xy 409.334716 -426.418756) (xy 409.334716 -427.960536) (xy 410.241496 -427.960536)
			(xy 410.241496 -427.233588) (xy 410.241745 -427.224768) (xy 410.245712 -427.207581) (xy 410.24937 -427.199552)
			(xy 410.482796 -426.723302) (xy 410.487484 -426.71278) (xy 410.490979 -426.690025) (xy 410.487499 -426.667268)
			(xy 410.482796 -426.656754) (xy 410.24937 -426.180504) (xy 410.245685 -426.172484) (xy 410.24171 -426.155292)
			(xy 410.241496 -426.146468) (xy 410.241496 -425.419012) (xy 410.241923 -425.40693) (xy 410.249388 -425.383947)
			(xy 410.26359 -425.364396) (xy 410.283139 -425.350191) (xy 410.306122 -425.342724) (xy 410.318204 -425.342304)
			(xy 411.258004 -425.342304) (xy 411.270088 -425.342709) (xy 411.293073 -425.350179) (xy 411.312624 -425.364387)
			(xy 411.326828 -425.383941) (xy 411.334293 -425.406928) (xy 411.334712 -425.419012) (xy 411.334712 -427.960536)
			(xy 411.334267 -427.972612) (xy 411.326795 -427.99558) (xy 411.312593 -428.015116) (xy 411.293051 -428.029309)
			(xy 411.27008 -428.036772) (xy 411.258004 -428.037244) (xy 410.318204 -428.037244) (xy 410.306133 -428.036733)
			(xy 410.283172 -428.029276) (xy 410.263638 -428.01509) (xy 410.249442 -427.995564) (xy 410.241973 -427.972607)
			(xy 410.241496 -427.960536) (xy 409.334716 -427.960536) (xy 409.334716 -428.96028) (xy 409.33427 -428.972361)
			(xy 409.326809 -428.995342) (xy 409.312611 -429.014891) (xy 409.293067 -429.029096) (xy 409.270089 -429.036566)
			(xy 409.258008 -429.036988) (xy 408.318208 -429.036988) (xy 408.306124 -429.03658) (xy 408.283138 -429.029113)
			(xy 408.263586 -429.014906) (xy 408.249382 -428.995352) (xy 408.241918 -428.972364) (xy 408.2415 -428.96028)
			(xy 407.306885 -428.96028) (xy 407.31292 -428.964648) (xy 407.327173 -428.984165) (xy 407.334713 -429.007126)
			(xy 407.335228 -429.019208) (xy 407.335228 -431.560732) (xy 407.334811 -431.57284) (xy 407.327306 -431.595863)
			(xy 407.313044 -431.615433) (xy 407.293425 -431.629628) (xy 407.270375 -431.637053) (xy 407.258266 -431.63744)
			(xy 406.318466 -431.63744) (xy 406.306373 -431.637021) (xy 406.283368 -431.629553) (xy 406.263786 -431.615354)
			(xy 406.249538 -431.59581) (xy 406.24201 -431.572824) (xy 406.241504 -431.560732) (xy 405.335232 -431.560732)
			(xy 405.335232 -432.56073) (xy 405.334813 -432.572849) (xy 405.327314 -432.595898) (xy 405.31306 -432.615502)
			(xy 405.293445 -432.629742) (xy 405.270389 -432.637223) (xy 405.25827 -432.637692) (xy 404.31847 -432.637692)
			(xy 404.306357 -432.637214) (xy 404.283318 -432.629723) (xy 404.263719 -432.615481) (xy 404.249477 -432.595882)
			(xy 404.241986 -432.572843) (xy 404.241508 -432.56073) (xy 403.307737 -432.56073) (xy 403.312726 -432.564366)
			(xy 403.326921 -432.583988) (xy 403.334343 -432.60704) (xy 403.334728 -432.61915) (xy 403.334728 -435.160674)
			(xy 403.33427 -435.172765) (xy 403.326816 -435.195771) (xy 403.312629 -435.215354) (xy 403.293091 -435.229604)
			(xy 403.27011 -435.237131) (xy 403.25802 -435.237636) (xy 402.31822 -435.237636) (xy 402.306116 -435.237167)
			(xy 402.283095 -435.229677) (xy 402.263525 -435.215428) (xy 402.249329 -435.19582) (xy 402.241901 -435.172779)
			(xy 402.241512 -435.160674) (xy 401.334732 -435.160674) (xy 401.334732 -436.160672) (xy 401.334264 -436.172751)
			(xy 401.326807 -436.195729) (xy 401.312614 -436.215277) (xy 401.293075 -436.229483) (xy 401.270103 -436.236956)
			(xy 401.258024 -436.23738) (xy 400.318224 -436.23738) (xy 400.30614 -436.236966) (xy 400.283153 -436.229502)
			(xy 400.2636 -436.215297) (xy 400.249396 -436.195743) (xy 400.241933 -436.172756) (xy 400.241516 -436.160672)
			(xy 399.307328 -436.160672) (xy 399.312606 -436.164508) (xy 399.3268 -436.184048) (xy 399.334263 -436.207017)
			(xy 399.334736 -436.219092) (xy 399.334736 -438.760616) (xy 399.33425 -438.772689) (xy 399.326786 -438.795651)
			(xy 399.312594 -438.815186) (xy 399.293062 -438.829381) (xy 399.270101 -438.836848) (xy 399.258028 -438.837324)
			(xy 398.318228 -438.837324) (xy 398.306148 -438.836864) (xy 398.283169 -438.829406) (xy 398.26362 -438.815211)
			(xy 398.249414 -438.79567) (xy 398.241943 -438.772695) (xy 398.24152 -438.760616) (xy 396.334996 -438.760616)
			(xy 396.334996 -439.760614) (xy 400.241516 -439.760614) (xy 400.241516 -437.21909) (xy 400.241999 -437.207002)
			(xy 400.249455 -437.184006) (xy 400.263639 -437.164428) (xy 400.283167 -437.150177) (xy 400.306138 -437.142641)
			(xy 400.318224 -437.142128) (xy 401.258024 -437.142128) (xy 401.270137 -437.142496) (xy 401.29317 -437.150006)
			(xy 401.312745 -437.164279) (xy 401.326938 -437.183912) (xy 401.334353 -437.206975) (xy 401.334732 -437.21909)
			(xy 401.334732 -438.760616) (xy 402.241512 -438.760616) (xy 402.241512 -436.219092) (xy 402.241906 -436.207007)
			(xy 402.249378 -436.18402) (xy 402.263588 -436.164469) (xy 402.283146 -436.150265) (xy 402.306135 -436.142802)
			(xy 402.31822 -436.142384) (xy 403.25802 -436.142384) (xy 403.270095 -436.142847) (xy 403.293061 -436.150314)
			(xy 403.307314 -436.160672) (xy 404.241508 -436.160672) (xy 404.241508 -433.619148) (xy 404.241954 -433.607066)
			(xy 404.24941 -433.584082) (xy 404.263607 -433.56453) (xy 404.283154 -433.550325) (xy 404.306134 -433.542859)
			(xy 404.318216 -433.54244) (xy 405.258016 -433.54244) (xy 405.270104 -433.5428) (xy 405.293096 -433.550277)
			(xy 405.31265 -433.564496) (xy 405.326852 -433.584062) (xy 405.33431 -433.607059) (xy 405.334724 -433.619148)
			(xy 405.334724 -435.160674) (xy 406.241504 -435.160674) (xy 406.241504 -432.61915) (xy 406.242049 -432.607067)
			(xy 406.249488 -432.584074) (xy 406.263655 -432.564496) (xy 406.283171 -432.550242) (xy 406.306131 -432.542703)
			(xy 406.318212 -432.542188) (xy 407.258012 -432.542188) (xy 407.27012 -432.542606) (xy 407.293146 -432.550107)
			(xy 407.307724 -432.56073) (xy 408.2415 -432.56073) (xy 408.2415 -430.019206) (xy 408.242016 -430.007096)
			(xy 408.249497 -429.984059) (xy 408.263729 -429.96446) (xy 408.28332 -429.950217) (xy 408.306352 -429.942723)
			(xy 408.318462 -429.942244) (xy 409.258262 -429.942244) (xy 409.270383 -429.942692) (xy 409.293442 -429.950175)
			(xy 409.313058 -429.964419) (xy 409.327311 -429.984029) (xy 409.334803 -430.007085) (xy 409.335224 -430.019206)
			(xy 409.335224 -431.560732) (xy 410.241496 -431.560732) (xy 410.241496 -429.019208) (xy 410.241923 -429.0071)
			(xy 410.24942 -428.984073) (xy 410.263679 -428.964501) (xy 410.283298 -428.950305) (xy 410.306349 -428.942884)
			(xy 410.318458 -428.9425) (xy 411.258258 -428.9425) (xy 411.270341 -428.943042) (xy 411.293334 -428.950483)
			(xy 411.307222 -428.960534) (xy 412.241492 -428.960534) (xy 412.241492 -428.233586) (xy 412.241741 -428.224766)
			(xy 412.245708 -428.207579) (xy 412.249366 -428.19955) (xy 412.482792 -427.7233) (xy 412.487482 -427.712779)
			(xy 412.490977 -427.690023) (xy 412.487496 -427.667266) (xy 412.482792 -427.656752) (xy 412.249366 -427.180502)
			(xy 412.24568 -427.172482) (xy 412.241706 -427.15529) (xy 412.241492 -427.146466) (xy 412.241492 -426.41901)
			(xy 412.242015 -426.406926) (xy 412.249463 -426.383934) (xy 412.263637 -426.364358) (xy 412.283156 -426.350105)
			(xy 412.306118 -426.342564) (xy 412.3182 -426.342048) (xy 413.258 -426.342048) (xy 413.270104 -426.342515)
			(xy 413.293122 -426.350009) (xy 413.312691 -426.364259) (xy 413.326887 -426.383866) (xy 413.334317 -426.406905)
			(xy 413.334708 -426.41901) (xy 413.334708 -428.960534) (xy 413.334223 -428.972621) (xy 413.326762 -428.995614)
			(xy 413.312579 -429.01519) (xy 413.293053 -429.029441) (xy 413.270085 -429.03698) (xy 413.258 -429.037496)
			(xy 412.3182 -429.037496) (xy 412.306091 -429.037084) (xy 412.283063 -429.029584) (xy 412.263489 -429.015321)
			(xy 412.249295 -428.995699) (xy 412.241875 -428.972645) (xy 412.241492 -428.960534) (xy 411.307222 -428.960534)
			(xy 411.312911 -428.964651) (xy 411.327165 -428.984167) (xy 411.334705 -429.007127) (xy 411.33522 -429.019208)
			(xy 411.33522 -431.560732) (xy 411.334811 -431.572841) (xy 411.327305 -431.595865) (xy 411.313041 -431.615436)
			(xy 411.29342 -431.62963) (xy 411.270368 -431.637054) (xy 411.258258 -431.63744) (xy 410.318458 -431.63744)
			(xy 410.306364 -431.637028) (xy 410.283359 -431.629557) (xy 410.263778 -431.615357) (xy 410.249529 -431.595811)
			(xy 410.242002 -431.572825) (xy 410.241496 -431.560732) (xy 409.335224 -431.560732) (xy 409.335224 -432.56073)
			(xy 409.334865 -432.572858) (xy 409.32736 -432.595924) (xy 409.313094 -432.615542) (xy 409.293463 -432.629791)
			(xy 409.270391 -432.637276) (xy 409.258262 -432.637692) (xy 408.318462 -432.637692) (xy 408.306348 -432.637221)
			(xy 408.283309 -432.629727) (xy 408.263711 -432.615484) (xy 408.249469 -432.595884) (xy 408.241978 -432.572844)
			(xy 408.2415 -432.56073) (xy 407.307724 -432.56073) (xy 407.312718 -432.564369) (xy 407.326913 -432.583989)
			(xy 407.334335 -432.60704) (xy 407.33472 -432.61915) (xy 407.33472 -435.160674) (xy 407.33427 -435.172766)
			(xy 407.326815 -435.195773) (xy 407.312626 -435.215356) (xy 407.293086 -435.229606) (xy 407.270103 -435.237132)
			(xy 407.258012 -435.237636) (xy 406.318212 -435.237636) (xy 406.306107 -435.237174) (xy 406.283087 -435.229682)
			(xy 406.263517 -435.215431) (xy 406.24932 -435.195821) (xy 406.241893 -435.17278) (xy 406.241504 -435.160674)
			(xy 405.334724 -435.160674) (xy 405.334724 -436.160672) (xy 405.334264 -436.172752) (xy 405.326806 -436.195731)
			(xy 405.312611 -436.21528) (xy 405.29307 -436.229486) (xy 405.270095 -436.236957) (xy 405.258016 -436.23738)
			(xy 404.318216 -436.23738) (xy 404.306131 -436.236973) (xy 404.283144 -436.229507) (xy 404.263592 -436.2153)
			(xy 404.249388 -436.195745) (xy 404.241925 -436.172757) (xy 404.241508 -436.160672) (xy 403.307314 -436.160672)
			(xy 403.312597 -436.164511) (xy 403.326791 -436.18405) (xy 403.334255 -436.207017) (xy 403.334728 -436.219092)
			(xy 403.334728 -438.760616) (xy 403.33425 -438.772689) (xy 403.326785 -438.795654) (xy 403.312591 -438.815189)
			(xy 403.293057 -438.829383) (xy 403.270093 -438.836849) (xy 403.25802 -438.837324) (xy 402.31822 -438.837324)
			(xy 402.30614 -438.83687) (xy 402.283161 -438.82941) (xy 402.263611 -438.815214) (xy 402.249406 -438.795672)
			(xy 402.241935 -438.772696) (xy 402.241512 -438.760616) (xy 401.334732 -438.760616) (xy 401.334732 -439.760614)
			(xy 404.241508 -439.760614) (xy 404.241508 -437.21909) (xy 404.241998 -437.207003) (xy 404.249454 -437.184008)
			(xy 404.263636 -437.164431) (xy 404.283162 -437.150179) (xy 404.306131 -437.142642) (xy 404.318216 -437.142128)
			(xy 405.258016 -437.142128) (xy 405.270129 -437.142503) (xy 405.293161 -437.15001) (xy 405.312736 -437.164281)
			(xy 405.326929 -437.183914) (xy 405.334345 -437.206976) (xy 405.334724 -437.21909) (xy 405.334724 -438.760616)
			(xy 406.241504 -438.760616) (xy 406.241504 -436.219092) (xy 406.241906 -436.207008) (xy 406.249377 -436.184023)
			(xy 406.263586 -436.164471) (xy 406.283141 -436.150268) (xy 406.306128 -436.142803) (xy 406.318212 -436.142384)
			(xy 407.258012 -436.142384) (xy 407.270086 -436.142854) (xy 407.293053 -436.150319) (xy 407.307301 -436.160672)
			(xy 408.2415 -436.160672) (xy 408.2415 -433.619148) (xy 408.241954 -433.607067) (xy 408.249409 -433.584084)
			(xy 408.263604 -433.564533) (xy 408.283149 -433.550327) (xy 408.306127 -433.54286) (xy 408.318208 -433.54244)
			(xy 409.258008 -433.54244) (xy 409.270096 -433.542806) (xy 409.293087 -433.550282) (xy 409.312641 -433.564498)
			(xy 409.326844 -433.584063) (xy 409.334302 -433.60706) (xy 409.334716 -433.619148) (xy 409.334716 -435.160674)
			(xy 410.241496 -435.160674) (xy 410.241496 -432.61915) (xy 410.242049 -432.607067) (xy 410.249487 -432.584076)
			(xy 410.263653 -432.564499) (xy 410.283166 -432.550245) (xy 410.306124 -432.542704) (xy 410.318204 -432.542188)
			(xy 411.258004 -432.542188) (xy 411.270112 -432.542613) (xy 411.293137 -432.550112) (xy 411.30771 -432.56073)
			(xy 412.241492 -432.56073) (xy 412.241492 -430.019206) (xy 412.242016 -430.007096) (xy 412.249496 -429.984061)
			(xy 412.263726 -429.964463) (xy 412.283315 -429.95022) (xy 412.306345 -429.942724) (xy 412.318454 -429.942244)
			(xy 413.258254 -429.942244) (xy 413.270375 -429.942699) (xy 413.293433 -429.950179) (xy 413.31305 -429.964422)
			(xy 413.327302 -429.984031) (xy 413.334795 -430.007085) (xy 413.335216 -430.019206) (xy 413.335216 -432.56073)
			(xy 413.334865 -432.572859) (xy 413.327359 -432.595927) (xy 413.313091 -432.615545) (xy 413.293458 -432.629794)
			(xy 413.270383 -432.637277) (xy 413.258254 -432.637692) (xy 412.318454 -432.637692) (xy 412.30634 -432.637228)
			(xy 412.2833 -432.629732) (xy 412.263702 -432.615487) (xy 412.249461 -432.595885) (xy 412.24197 -432.572844)
			(xy 412.241492 -432.56073) (xy 411.30771 -432.56073) (xy 411.312709 -432.564372) (xy 411.326904 -432.583991)
			(xy 411.334327 -432.607041) (xy 411.334712 -432.61915) (xy 411.334712 -435.160674) (xy 411.33427 -435.172767)
			(xy 411.326814 -435.195775) (xy 411.312623 -435.215359) (xy 411.293081 -435.229609) (xy 411.270096 -435.237133)
			(xy 411.258004 -435.237636) (xy 410.318204 -435.237636) (xy 410.306099 -435.237181) (xy 410.283078 -435.229687)
			(xy 410.263508 -435.215434) (xy 410.249312 -435.195823) (xy 410.241884 -435.17278) (xy 410.241496 -435.160674)
			(xy 409.334716 -435.160674) (xy 409.334716 -436.160672) (xy 409.334264 -436.172752) (xy 409.326805 -436.195733)
			(xy 409.312609 -436.215283) (xy 409.293065 -436.229488) (xy 409.270088 -436.236958) (xy 409.258008 -436.23738)
			(xy 408.318208 -436.23738) (xy 408.306123 -436.23698) (xy 408.283136 -436.229512) (xy 408.263583 -436.215303)
			(xy 408.249379 -436.195746) (xy 408.241916 -436.172757) (xy 408.2415 -436.160672) (xy 407.307301 -436.160672)
			(xy 407.312589 -436.164514) (xy 407.326783 -436.184051) (xy 407.334247 -436.207018) (xy 407.33472 -436.219092)
			(xy 407.33472 -438.760616) (xy 407.334249 -438.77269) (xy 407.326784 -438.795656) (xy 407.312589 -438.815191)
			(xy 407.293052 -438.829386) (xy 407.270086 -438.83685) (xy 407.258012 -438.837324) (xy 406.318212 -438.837324)
			(xy 406.30614 -438.836826) (xy 406.283176 -438.829369) (xy 406.26364 -438.81518) (xy 406.249444 -438.79565)
			(xy 406.241979 -438.772688) (xy 406.241504 -438.760616) (xy 405.334724 -438.760616) (xy 405.334724 -439.760614)
			(xy 408.2415 -439.760614) (xy 408.2415 -437.21909) (xy 408.241998 -437.207004) (xy 408.249453 -437.18401)
			(xy 408.263633 -437.164434) (xy 408.283157 -437.150182) (xy 408.306124 -437.142643) (xy 408.318208 -437.142128)
			(xy 409.258008 -437.142128) (xy 409.27012 -437.14251) (xy 409.293152 -437.150015) (xy 409.312728 -437.164284)
			(xy 409.326921 -437.183915) (xy 409.334337 -437.206976) (xy 409.334716 -437.21909) (xy 409.334716 -438.760616)
			(xy 410.241496 -438.760616) (xy 410.241496 -436.219092) (xy 410.241958 -436.207017) (xy 410.249423 -436.184049)
			(xy 410.26362 -436.164511) (xy 410.283159 -436.150317) (xy 410.306129 -436.142856) (xy 410.318204 -436.142384)
			(xy 411.258004 -436.142384) (xy 411.270078 -436.142861) (xy 411.293044 -436.150323) (xy 411.307288 -436.160672)
			(xy 412.241492 -436.160672) (xy 412.241492 -433.619148) (xy 412.241954 -433.607068) (xy 412.249408 -433.584087)
			(xy 412.263601 -433.564536) (xy 412.283144 -433.55033) (xy 412.30612 -433.542861) (xy 412.3182 -433.54244)
			(xy 413.258 -433.54244) (xy 413.270088 -433.542813) (xy 413.293078 -433.550287) (xy 413.312633 -433.564501)
			(xy 413.326835 -433.584065) (xy 413.334294 -433.60706) (xy 413.334708 -433.619148) (xy 413.334708 -435.59984)
			(xy 446.741306 -435.59984) (xy 446.745288 -435.471854) (xy 446.75722 -435.344363) (xy 446.777054 -435.21786)
			(xy 446.804715 -435.092835) (xy 446.840095 -434.969772) (xy 446.883057 -434.849146) (xy 446.933435 -434.731425)
			(xy 446.991035 -434.617063) (xy 447.055633 -434.506504) (xy 447.12698 -434.400174) (xy 447.204799 -434.298486)
			(xy 447.288789 -434.201832) (xy 447.378626 -434.110587) (xy 447.473962 -434.025104) (xy 447.574427 -433.945713)
			(xy 447.679635 -433.872721) (xy 447.789176 -433.806412) (xy 447.902628 -433.747041) (xy 448.019552 -433.694837)
			(xy 448.139495 -433.650004) (xy 448.261993 -433.612715) (xy 448.386573 -433.583113) (xy 448.512751 -433.561314)
			(xy 448.640041 -433.547401) (xy 448.76795 -433.541429) (xy 448.895983 -433.54342) (xy 449.023644 -433.553368)
			(xy 449.15044 -433.571232) (xy 449.275879 -433.596945) (xy 449.399478 -433.630407) (xy 449.520757 -433.671488)
			(xy 449.639248 -433.72003) (xy 449.754492 -433.775844) (xy 449.866042 -433.838715) (xy 449.973469 -433.908399)
			(xy 450.076355 -433.984627) (xy 450.174303 -434.067104) (xy 450.266934 -434.155511) (xy 450.35389 -434.249506)
			(xy 450.434834 -434.348725) (xy 450.509453 -434.452784) (xy 450.577458 -434.561281) (xy 450.638586 -434.673796)
			(xy 450.692601 -434.789894) (xy 450.739294 -434.909125) (xy 450.778484 -435.031029) (xy 450.81002 -435.155133)
			(xy 450.833779 -435.280957) (xy 450.849669 -435.408016) (xy 450.85763 -435.535816) (xy 450.858128 -435.59984)
			(xy 450.85763 -435.663864) (xy 450.849669 -435.791664) (xy 450.833779 -435.918723) (xy 450.81002 -436.044547)
			(xy 450.778484 -436.168651) (xy 450.739294 -436.290555) (xy 450.692601 -436.409786) (xy 450.638586 -436.525884)
			(xy 450.577458 -436.638399) (xy 450.509453 -436.746896) (xy 450.434834 -436.850955) (xy 450.35389 -436.950174)
			(xy 450.266934 -437.044169) (xy 450.174303 -437.132576) (xy 450.076355 -437.215053) (xy 449.973469 -437.291281)
			(xy 449.866042 -437.360965) (xy 449.754492 -437.423836) (xy 449.639248 -437.47965) (xy 449.520757 -437.528192)
			(xy 449.399478 -437.569273) (xy 449.275879 -437.602735) (xy 449.15044 -437.628448) (xy 449.023644 -437.646312)
			(xy 448.895983 -437.65626) (xy 448.76795 -437.658251) (xy 448.640041 -437.652279) (xy 448.512751 -437.638366)
			(xy 448.386573 -437.616567) (xy 448.261993 -437.586965) (xy 448.139495 -437.549676) (xy 448.019552 -437.504843)
			(xy 447.902628 -437.452639) (xy 447.789176 -437.393268) (xy 447.679635 -437.326959) (xy 447.574427 -437.253967)
			(xy 447.473962 -437.174576) (xy 447.378626 -437.089093) (xy 447.288789 -436.997848) (xy 447.204799 -436.901194)
			(xy 447.12698 -436.799506) (xy 447.055633 -436.693176) (xy 446.991035 -436.582617) (xy 446.933435 -436.468255)
			(xy 446.883057 -436.350534) (xy 446.840095 -436.229908) (xy 446.804715 -436.106845) (xy 446.777054 -435.98182)
			(xy 446.75722 -435.855317) (xy 446.745288 -435.727826) (xy 446.741306 -435.59984) (xy 413.334708 -435.59984)
			(xy 413.334708 -436.160672) (xy 413.334263 -436.172753) (xy 413.326804 -436.195735) (xy 413.312606 -436.215286)
			(xy 413.29306 -436.229491) (xy 413.270081 -436.236959) (xy 413.258 -436.23738) (xy 412.3182 -436.23738)
			(xy 412.306114 -436.236987) (xy 412.283127 -436.229516) (xy 412.263574 -436.215306) (xy 412.249371 -436.195748)
			(xy 412.241908 -436.172758) (xy 412.241492 -436.160672) (xy 411.307288 -436.160672) (xy 411.31258 -436.164517)
			(xy 411.326775 -436.184053) (xy 411.334239 -436.207018) (xy 411.334712 -436.219092) (xy 411.334712 -438.760616)
			(xy 411.334249 -438.772691) (xy 411.326783 -438.795658) (xy 411.312586 -438.815194) (xy 411.293047 -438.829388)
			(xy 411.270079 -438.836851) (xy 411.258004 -438.837324) (xy 410.318204 -438.837324) (xy 410.306131 -438.836833)
			(xy 410.283167 -438.829373) (xy 410.263631 -438.815183) (xy 410.249436 -438.795651) (xy 410.241971 -438.772689)
			(xy 410.241496 -438.760616) (xy 409.334716 -438.760616) (xy 409.334716 -439.760614) (xy 412.241492 -439.760614)
			(xy 412.241492 -437.21909) (xy 412.241998 -437.207005) (xy 412.249452 -437.184012) (xy 412.26363 -437.164436)
			(xy 412.283152 -437.150184) (xy 412.306117 -437.142644) (xy 412.3182 -437.142128) (xy 413.258 -437.142128)
			(xy 413.270112 -437.142516) (xy 413.293144 -437.150019) (xy 413.312719 -437.164287) (xy 413.326913 -437.183916)
			(xy 413.334329 -437.206977) (xy 413.334708 -437.21909) (xy 413.334708 -439.760614) (xy 413.334206 -439.7727)
			(xy 413.326751 -439.795693) (xy 413.312572 -439.815268) (xy 413.293049 -439.82952) (xy 413.270084 -439.83706)
			(xy 413.258 -439.837576) (xy 412.3182 -439.837576) (xy 412.306089 -439.837184) (xy 412.283057 -439.829681)
			(xy 412.263482 -439.815414) (xy 412.249288 -439.795786) (xy 412.241872 -439.772727) (xy 412.241492 -439.760614)
			(xy 409.334716 -439.760614) (xy 409.334304 -439.772709) (xy 409.326838 -439.795717) (xy 409.312639 -439.815301)
			(xy 409.293091 -439.829549) (xy 409.270101 -439.837073) (xy 409.258008 -439.837576) (xy 408.318208 -439.837576)
			(xy 408.306097 -439.837177) (xy 408.283066 -439.829677) (xy 408.263491 -439.815412) (xy 408.249296 -439.795785)
			(xy 408.24188 -439.772726) (xy 408.2415 -439.760614) (xy 405.334724 -439.760614) (xy 405.334304 -439.772708)
			(xy 405.326839 -439.795715) (xy 405.312642 -439.815298) (xy 405.293096 -439.829547) (xy 405.270109 -439.837072)
			(xy 405.258016 -439.837576) (xy 404.318216 -439.837576) (xy 404.306106 -439.83717) (xy 404.283075 -439.829672)
			(xy 404.263499 -439.815408) (xy 404.249305 -439.795783) (xy 404.241888 -439.772726) (xy 404.241508 -439.760614)
			(xy 401.334732 -439.760614) (xy 401.334304 -439.772707) (xy 401.32684 -439.795713) (xy 401.312645 -439.815295)
			(xy 401.293101 -439.829544) (xy 401.270116 -439.837071) (xy 401.258024 -439.837576) (xy 400.318224 -439.837576)
			(xy 400.306114 -439.837163) (xy 400.283083 -439.829667) (xy 400.263508 -439.815406) (xy 400.249313 -439.795781)
			(xy 400.241896 -439.772725) (xy 400.241516 -439.760614) (xy 396.334996 -439.760614) (xy 396.334501 -439.772726)
			(xy 396.327014 -439.795764) (xy 396.312777 -439.815363) (xy 396.293182 -439.829605) (xy 396.270146 -439.837098)
			(xy 396.258034 -439.837576) (xy 395.318234 -439.837576) (xy 395.306114 -439.837111) (xy 395.283059 -439.82963)
			(xy 395.263445 -439.81539) (xy 395.249192 -439.795784) (xy 395.241696 -439.772733) (xy 395.241272 -439.760614)
			(xy 392.335004 -439.760614) (xy 392.334501 -439.772725) (xy 392.327015 -439.795762) (xy 392.31278 -439.81536)
			(xy 392.293187 -439.829602) (xy 392.270153 -439.837097) (xy 392.258042 -439.837576) (xy 391.318242 -439.837576)
			(xy 391.306123 -439.837105) (xy 391.283068 -439.829626) (xy 391.263453 -439.815387) (xy 391.2492 -439.795783)
			(xy 391.241704 -439.772733) (xy 391.24128 -439.760614) (xy 388.335012 -439.760614) (xy 388.334501 -439.772724)
			(xy 388.327016 -439.79576) (xy 388.312782 -439.815357) (xy 388.293192 -439.8296) (xy 388.27016 -439.837096)
			(xy 388.25805 -439.837576) (xy 387.31825 -439.837576) (xy 387.306134 -439.837131) (xy 387.283092 -439.829632)
			(xy 387.263492 -439.815382) (xy 387.249252 -439.795776) (xy 387.241763 -439.77273) (xy 387.241288 -439.760614)
			(xy 384.33502 -439.760614) (xy 384.334651 -439.772742) (xy 384.32715 -439.795808) (xy 384.312886 -439.815426)
			(xy 384.293258 -439.829675) (xy 384.270186 -439.83716) (xy 384.258058 -439.837576) (xy 383.318258 -439.837576)
			(xy 383.306143 -439.837124) (xy 383.2831 -439.829627) (xy 383.263501 -439.815379) (xy 383.24926 -439.795774)
			(xy 383.241771 -439.77273) (xy 383.241296 -439.760614) (xy 346.234512 -439.760614) (xy 346.234104 -439.772709)
			(xy 346.226638 -439.795718) (xy 346.212437 -439.815302) (xy 346.192889 -439.829551) (xy 346.169898 -439.837074)
			(xy 346.157804 -439.837576) (xy 345.218004 -439.837576) (xy 345.205893 -439.83718) (xy 345.182862 -439.829679)
			(xy 345.163286 -439.815413) (xy 345.149092 -439.795785) (xy 345.141676 -439.772727) (xy 345.141296 -439.760614)
			(xy 342.23452 -439.760614) (xy 342.234104 -439.772708) (xy 342.226639 -439.795716) (xy 342.21244 -439.815299)
			(xy 342.192894 -439.829548) (xy 342.169905 -439.837073) (xy 342.157812 -439.837576) (xy 341.218012 -439.837576)
			(xy 341.205901 -439.837173) (xy 341.18287 -439.829674) (xy 341.163295 -439.81541) (xy 341.149101 -439.795784)
			(xy 341.141684 -439.772726) (xy 341.141304 -439.760614) (xy 338.234528 -439.760614) (xy 338.234104 -439.772708)
			(xy 338.22664 -439.795714) (xy 338.212443 -439.815297) (xy 338.192899 -439.829546) (xy 338.169912 -439.837072)
			(xy 338.15782 -439.837576) (xy 337.21802 -439.837576) (xy 337.20591 -439.837166) (xy 337.182879 -439.829669)
			(xy 337.163304 -439.815407) (xy 337.149109 -439.795782) (xy 337.141692 -439.772726) (xy 337.141312 -439.760614)
			(xy 334.234536 -439.760614) (xy 334.234104 -439.772707) (xy 334.226641 -439.795712) (xy 334.212446 -439.815294)
			(xy 334.192904 -439.829543) (xy 334.169919 -439.83707) (xy 334.157828 -439.837576) (xy 333.218028 -439.837576)
			(xy 333.205918 -439.837159) (xy 333.182888 -439.829665) (xy 333.163312 -439.815404) (xy 333.149117 -439.795781)
			(xy 333.1417 -439.772725) (xy 333.14132 -439.760614) (xy 329.2348 -439.760614) (xy 329.234301 -439.772726)
			(xy 329.226815 -439.795763) (xy 329.212578 -439.815361) (xy 329.192984 -439.829604) (xy 329.169949 -439.837097)
			(xy 329.157838 -439.837576) (xy 328.218038 -439.837576) (xy 328.205919 -439.837108) (xy 328.182863 -439.829628)
			(xy 328.163249 -439.815388) (xy 328.148996 -439.795783) (xy 328.1415 -439.772733) (xy 328.141076 -439.760614)
			(xy 325.234808 -439.760614) (xy 325.234301 -439.772725) (xy 325.226816 -439.795761) (xy 325.212581 -439.815358)
			(xy 325.192989 -439.829601) (xy 325.169957 -439.837096) (xy 325.157846 -439.837576) (xy 324.218046 -439.837576)
			(xy 324.205927 -439.837101) (xy 324.182872 -439.829623) (xy 324.163257 -439.815385) (xy 324.149004 -439.795782)
			(xy 324.141508 -439.772733) (xy 324.141084 -439.760614) (xy 321.234816 -439.760614) (xy 321.234451 -439.772742)
			(xy 321.226949 -439.795809) (xy 321.212685 -439.815428) (xy 321.193055 -439.829677) (xy 321.169982 -439.83716)
			(xy 321.157854 -439.837576) (xy 320.218054 -439.837576) (xy 320.205938 -439.837128) (xy 320.182896 -439.82963)
			(xy 320.163296 -439.815381) (xy 320.149056 -439.795775) (xy 320.141567 -439.77273) (xy 320.141092 -439.760614)
			(xy 317.234824 -439.760614) (xy 317.234451 -439.772741) (xy 317.22695 -439.795807) (xy 317.212688 -439.815425)
			(xy 317.19306 -439.829674) (xy 317.16999 -439.837159) (xy 317.157862 -439.837576) (xy 316.218062 -439.837576)
			(xy 316.205947 -439.837121) (xy 316.182905 -439.829625) (xy 316.163305 -439.815378) (xy 316.149064 -439.795774)
			(xy 316.141575 -439.772729) (xy 316.1411 -439.760614) (xy 157.334702 -439.760614) (xy 157.33425 -439.772466)
			(xy 157.326763 -439.79549) (xy 157.312513 -439.815062) (xy 157.292901 -439.829259) (xy 157.269857 -439.836682)
			(xy 157.25775 -439.837068) (xy 156.31795 -439.837068) (xy 156.305864 -439.83655) (xy 156.282866 -439.829108)
			(xy 156.263286 -439.814935) (xy 156.249033 -439.795412) (xy 156.241499 -439.772444) (xy 156.240988 -439.76036)
			(xy 153.33472 -439.76036) (xy 153.33425 -439.772465) (xy 153.326764 -439.795487) (xy 153.312516 -439.815059)
			(xy 153.292906 -439.829256) (xy 153.269864 -439.836681) (xy 153.257758 -439.837068) (xy 152.317958 -439.837068)
			(xy 152.305867 -439.836629) (xy 152.282866 -439.829161) (xy 152.263288 -439.814967) (xy 152.249038 -439.795429)
			(xy 152.241506 -439.77245) (xy 152.240996 -439.76036) (xy 149.334728 -439.76036) (xy 149.33425 -439.772464)
			(xy 149.326765 -439.795485) (xy 149.312518 -439.815057) (xy 149.292911 -439.829254) (xy 149.269871 -439.83668)
			(xy 149.257766 -439.837068) (xy 148.317966 -439.837068) (xy 148.305875 -439.836622) (xy 148.282875 -439.829157)
			(xy 148.263296 -439.814964) (xy 148.249047 -439.795428) (xy 148.241514 -439.772449) (xy 148.241004 -439.76036)
			(xy 145.334736 -439.76036) (xy 145.33425 -439.772463) (xy 145.326766 -439.795483) (xy 145.312521 -439.815054)
			(xy 145.292916 -439.829251) (xy 145.269878 -439.836679) (xy 145.257774 -439.837068) (xy 144.317974 -439.837068)
			(xy 144.305884 -439.836615) (xy 144.282884 -439.829152) (xy 144.263305 -439.814962) (xy 144.249055 -439.795426)
			(xy 144.241522 -439.772449) (xy 144.241012 -439.76036) (xy 140.334492 -439.76036) (xy 140.334053 -439.772442)
			(xy 140.326595 -439.795426) (xy 140.312396 -439.814979) (xy 140.292848 -439.829184) (xy 140.269866 -439.836649)
			(xy 140.257784 -439.837068) (xy 139.317984 -439.837068) (xy 139.305896 -439.8367) (xy 139.282906 -439.829224)
			(xy 139.263353 -439.815007) (xy 139.249151 -439.795443) (xy 139.241691 -439.772448) (xy 139.241276 -439.76036)
			(xy 136.3345 -439.76036) (xy 136.334053 -439.772441) (xy 136.326596 -439.795424) (xy 136.312399 -439.814976)
			(xy 136.292853 -439.829181) (xy 136.269873 -439.836648) (xy 136.257792 -439.837068) (xy 135.317992 -439.837068)
			(xy 135.305905 -439.836694) (xy 135.282915 -439.829219) (xy 135.263361 -439.815004) (xy 135.249159 -439.795442)
			(xy 135.241699 -439.772447) (xy 135.241284 -439.76036) (xy 132.334508 -439.76036) (xy 132.334053 -439.772441)
			(xy 132.326597 -439.795422) (xy 132.312401 -439.814973) (xy 132.292858 -439.829178) (xy 132.26988 -439.836647)
			(xy 132.2578 -439.837068) (xy 131.318 -439.837068) (xy 131.305913 -439.836687) (xy 131.282924 -439.829215)
			(xy 131.26337 -439.815002) (xy 131.249167 -439.79544) (xy 131.241707 -439.772447) (xy 131.241292 -439.76036)
			(xy 128.334516 -439.76036) (xy 128.334053 -439.77244) (xy 128.326598 -439.79542) (xy 128.312404 -439.81497)
			(xy 128.292863 -439.829176) (xy 128.269888 -439.836646) (xy 128.257808 -439.837068) (xy 127.318008 -439.837068)
			(xy 127.305922 -439.83668) (xy 127.282932 -439.82921) (xy 127.263378 -439.814999) (xy 127.249175 -439.795439)
			(xy 127.241715 -439.772447) (xy 127.2413 -439.76036) (xy 90.234516 -439.76036) (xy 90.234516 -439.760614)
			(xy 90.234104 -439.772709) (xy 90.226638 -439.795717) (xy 90.212439 -439.815301) (xy 90.192891 -439.829549)
			(xy 90.169901 -439.837073) (xy 90.157808 -439.837576) (xy 89.218008 -439.837576) (xy 89.205897 -439.837177)
			(xy 89.182866 -439.829677) (xy 89.163291 -439.815412) (xy 89.149096 -439.795785) (xy 89.14168 -439.772726)
			(xy 89.1413 -439.760614) (xy 86.234524 -439.760614) (xy 86.234104 -439.772708) (xy 86.226639 -439.795715)
			(xy 86.212442 -439.815298) (xy 86.192896 -439.829547) (xy 86.169909 -439.837072) (xy 86.157816 -439.837576)
			(xy 85.218016 -439.837576) (xy 85.205906 -439.83717) (xy 85.182875 -439.829672) (xy 85.163299 -439.815408)
			(xy 85.149105 -439.795783) (xy 85.141688 -439.772726) (xy 85.141308 -439.760614) (xy 82.234532 -439.760614)
			(xy 82.234104 -439.772707) (xy 82.22664 -439.795713) (xy 82.212445 -439.815295) (xy 82.192901 -439.829544)
			(xy 82.169916 -439.837071) (xy 82.157824 -439.837576) (xy 81.218024 -439.837576) (xy 81.205914 -439.837163)
			(xy 81.182883 -439.829667) (xy 81.163308 -439.815406) (xy 81.149113 -439.795781) (xy 81.141696 -439.772725)
			(xy 81.141316 -439.760614) (xy 78.23454 -439.760614) (xy 78.234104 -439.772706) (xy 78.226641 -439.795711)
			(xy 78.212447 -439.815292) (xy 78.192906 -439.829542) (xy 78.169923 -439.83707) (xy 78.157832 -439.837576)
			(xy 77.218032 -439.837576) (xy 77.205922 -439.837156) (xy 77.182892 -439.829663) (xy 77.163316 -439.815403)
			(xy 77.149122 -439.79578) (xy 77.141704 -439.772725) (xy 77.141324 -439.760614) (xy 73.234804 -439.760614)
			(xy 73.234301 -439.772725) (xy 73.226815 -439.795762) (xy 73.21258 -439.81536) (xy 73.192987 -439.829602)
			(xy 73.169953 -439.837097) (xy 73.157842 -439.837576) (xy 72.218042 -439.837576) (xy 72.205923 -439.837105)
			(xy 72.182868 -439.829626) (xy 72.163253 -439.815387) (xy 72.149 -439.795783) (xy 72.141504 -439.772733)
			(xy 72.14108 -439.760614) (xy 69.234812 -439.760614) (xy 69.234301 -439.772724) (xy 69.226816 -439.79576)
			(xy 69.212582 -439.815357) (xy 69.192992 -439.8296) (xy 69.16996 -439.837096) (xy 69.15785 -439.837576)
			(xy 68.21805 -439.837576) (xy 68.205934 -439.837131) (xy 68.182892 -439.829632) (xy 68.163292 -439.815382)
			(xy 68.149052 -439.795776) (xy 68.141563 -439.77273) (xy 68.141088 -439.760614) (xy 65.23482 -439.760614)
			(xy 65.234451 -439.772742) (xy 65.22695 -439.795808) (xy 65.212686 -439.815426) (xy 65.193058 -439.829675)
			(xy 65.169986 -439.83716) (xy 65.157858 -439.837576) (xy 64.218058 -439.837576) (xy 64.205943 -439.837124)
			(xy 64.1829 -439.829627) (xy 64.163301 -439.815379) (xy 64.14906 -439.795774) (xy 64.141571 -439.77273)
			(xy 64.141096 -439.760614) (xy 61.234828 -439.760614) (xy 61.234451 -439.772741) (xy 61.226951 -439.795806)
			(xy 61.212689 -439.815424) (xy 61.193063 -439.829673) (xy 61.169993 -439.837159) (xy 61.157866 -439.837576)
			(xy 60.218066 -439.837576) (xy 60.205951 -439.837118) (xy 60.182909 -439.829623) (xy 60.163309 -439.815377)
			(xy 60.149068 -439.795773) (xy 60.141579 -439.772729) (xy 60.141104 -439.760614) (xy 7.00913 -439.760614)
			(xy 7.00913 -439.989976) (xy 7.009638 -440.045746) (xy 7.017973 -440.156973) (xy 7.034597 -440.267266)
			(xy 7.059417 -440.376009) (xy 7.092293 -440.482593) (xy 7.133043 -440.586422) (xy 7.181438 -440.686915)
			(xy 7.237207 -440.783511) (xy 7.300039 -440.87567) (xy 7.369583 -440.962874) (xy 7.445449 -441.044639)
			(xy 7.527212 -441.120505) (xy 7.614417 -441.190048) (xy 7.706575 -441.252881) (xy 7.803171 -441.30865)
			(xy 7.903664 -441.357045) (xy 8.007493 -441.397795) (xy 8.114077 -441.430672) (xy 8.22282 -441.455492)
			(xy 8.333113 -441.472116) (xy 8.44434 -441.480451) (xy 8.50011 -441.480956)
		)
		(stroke
			(width 0)
			(type solid)
		)
		(fill yes)
		(layer "In5.Cu")
		(net "GND")
	)
	(gr_line
		(start 1.414272 -79.914242)
		(end 0.585724 -79.085694)
		(stroke
			(width 1.016)
			(type default)
		)
		(layer "In5.Cu")
	)
	(gr_line
		(start 1.999996 -403.371558)
		(end 1.999996 -81.328514)
		(stroke
			(width 1.016)
			(type default)
		)
		(layer "In5.Cu")
	)
	(gr_arc
		(start 1.999996 -403.371558)
		(mid 2.152159 -404.136965)
		(end 2.58572 -404.78583)
		(stroke
			(width 1.016)
			(type default)
		)
		(layer "In5.Cu")
	)
	(gr_arc
		(start 1.999996 -81.328514)
		(mid 1.847755 -80.563149)
		(end 1.414272 -79.914242)
		(stroke
			(width 1.016)
			(type default)
		)
		(layer "In5.Cu")
	)
	(gr_arc
		(start 1.999996 -11.780012)
		(mid 0.585785 -12.365797)
		(end 0 -13.780008)
		(stroke
			(width 1.016)
			(type default)
		)
		(layer "In5.Cu")
	)
	(gr_line
		(start 1.999996 -11.780012)
		(end 11.102086 -11.780012)
		(stroke
			(width 1.016)
			(type default)
		)
		(layer "In5.Cu")
	)
	(gr_line
		(start 5.914136 -408.114246)
		(end 2.58572 -404.78583)
		(stroke
			(width 1.016)
			(type default)
		)
		(layer "In5.Cu")
	)
	(gr_line
		(start 6.500114 -439.989976)
		(end 6.500114 -409.528518)
		(stroke
			(width 1.016)
			(type default)
		)
		(layer "In5.Cu")
	)
	(gr_arc
		(start 6.500114 -439.989976)
		(mid 7.085891 -441.404199)
		(end 8.50011 -441.989972)
		(stroke
			(width 1.016)
			(type default)
		)
		(layer "In5.Cu")
	)
	(gr_arc
		(start 6.500114 -409.528518)
		(mid 6.347771 -408.763109)
		(end 5.914136 -408.114246)
		(stroke
			(width 1.016)
			(type default)
		)
		(layer "In5.Cu")
	)
	(gr_arc
		(start 11.102086 -11.780012)
		(mid 12.516297 -11.194227)
		(end 13.102082 -9.780016)
		(stroke
			(width 1.016)
			(type default)
		)
		(layer "In5.Cu")
	)
	(gr_line
		(start 13.102082 -9.780016)
		(end 13.102082 -0.500126)
		(stroke
			(width 1.016)
			(type default)
		)
		(layer "In5.Cu")
	)
	(gr_arc
		(start 13.601954 0)
		(mid 13.24848 -0.146572)
		(end 13.102082 -0.500126)
		(stroke
			(width 1.016)
			(type default)
		)
		(layer "In5.Cu")
	)
	(gr_line
		(start 13.601954 0)
		(end 81.202022 0)
		(stroke
			(width 1.016)
			(type default)
		)
		(layer "In5.Cu")
	)
	(gr_circle
		(center 25.82545 -40.816276)
		(end 26.71445 -40.816276)
		(stroke
			(width 0.2)
			(type default)
		)
		(fill no)
		(layer "In5.Cu")
	)
	(gr_circle
		(center 29.291534 -348.709488)
		(end 30.171644 -348.709488)
		(stroke
			(width 0.2)
			(type default)
		)
		(fill no)
		(layer "In5.Cu")
	)
	(gr_circle
		(center 29.908754 -348.709488)
		(end 30.788864 -348.709488)
		(stroke
			(width 0.2)
			(type default)
		)
		(fill no)
		(layer "In5.Cu")
	)
	(gr_circle
		(center 30.525974 -348.709488)
		(end 31.406084 -348.709488)
		(stroke
			(width 0.2)
			(type default)
		)
		(fill no)
		(layer "In5.Cu")
	)
	(gr_circle
		(center 30.795214 -347.966538)
		(end 31.684214 -347.966538)
		(stroke
			(width 0.2)
			(type default)
		)
		(fill no)
		(layer "In5.Cu")
	)
	(gr_circle
		(center 30.795214 -347.229938)
		(end 31.684214 -347.229938)
		(stroke
			(width 0.2)
			(type default)
		)
		(fill no)
		(layer "In5.Cu")
	)
	(gr_circle
		(center 31.22803 -350.318578)
		(end 32.11703 -350.318578)
		(stroke
			(width 0.2)
			(type default)
		)
		(fill no)
		(layer "In5.Cu")
	)
	(gr_circle
		(center 31.22803 -349.581978)
		(end 32.11703 -349.581978)
		(stroke
			(width 0.2)
			(type default)
		)
		(fill no)
		(layer "In5.Cu")
	)
	(gr_circle
		(center 31.752794 -349.142558)
		(end 32.641794 -349.142558)
		(stroke
			(width 0.2)
			(type default)
		)
		(fill no)
		(layer "In5.Cu")
	)
	(gr_circle
		(center 31.778194 -349.904558)
		(end 32.667194 -349.904558)
		(stroke
			(width 0.2)
			(type default)
		)
		(fill no)
		(layer "In5.Cu")
	)
	(gr_circle
		(center 32.311594 -350.260158)
		(end 33.200594 -350.260158)
		(stroke
			(width 0.2)
			(type default)
		)
		(fill no)
		(layer "In5.Cu")
	)
	(gr_circle
		(center 32.311594 -349.523558)
		(end 33.200594 -349.523558)
		(stroke
			(width 0.2)
			(type default)
		)
		(fill no)
		(layer "In5.Cu")
	)
	(gr_circle
		(center 32.311594 -348.786958)
		(end 33.200594 -348.786958)
		(stroke
			(width 0.2)
			(type default)
		)
		(fill no)
		(layer "In5.Cu")
	)
	(gr_circle
		(center 37.571934 -348.709488)
		(end 38.452044 -348.709488)
		(stroke
			(width 0.2)
			(type default)
		)
		(fill no)
		(layer "In5.Cu")
	)
	(gr_circle
		(center 38.189154 -348.709488)
		(end 39.069264 -348.709488)
		(stroke
			(width 0.2)
			(type default)
		)
		(fill no)
		(layer "In5.Cu")
	)
	(gr_circle
		(center 38.806374 -348.709488)
		(end 39.686484 -348.709488)
		(stroke
			(width 0.2)
			(type default)
		)
		(fill no)
		(layer "In5.Cu")
	)
	(gr_circle
		(center 39.050214 -347.974158)
		(end 39.939214 -347.974158)
		(stroke
			(width 0.2)
			(type default)
		)
		(fill no)
		(layer "In5.Cu")
	)
	(gr_circle
		(center 39.050214 -347.237558)
		(end 39.939214 -347.237558)
		(stroke
			(width 0.2)
			(type default)
		)
		(fill no)
		(layer "In5.Cu")
	)
	(gr_circle
		(center 39.50843 -350.318578)
		(end 40.39743 -350.318578)
		(stroke
			(width 0.2)
			(type default)
		)
		(fill no)
		(layer "In5.Cu")
	)
	(gr_circle
		(center 39.50843 -349.581978)
		(end 40.39743 -349.581978)
		(stroke
			(width 0.2)
			(type default)
		)
		(fill no)
		(layer "In5.Cu")
	)
	(gr_circle
		(center 40.033194 -349.142558)
		(end 40.922194 -349.142558)
		(stroke
			(width 0.2)
			(type default)
		)
		(fill no)
		(layer "In5.Cu")
	)
	(gr_circle
		(center 40.058594 -349.904558)
		(end 40.947594 -349.904558)
		(stroke
			(width 0.2)
			(type default)
		)
		(fill no)
		(layer "In5.Cu")
	)
	(gr_circle
		(center 40.591994 -350.260158)
		(end 41.480994 -350.260158)
		(stroke
			(width 0.2)
			(type default)
		)
		(fill no)
		(layer "In5.Cu")
	)
	(gr_circle
		(center 40.591994 -349.523558)
		(end 41.480994 -349.523558)
		(stroke
			(width 0.2)
			(type default)
		)
		(fill no)
		(layer "In5.Cu")
	)
	(gr_circle
		(center 40.591994 -348.786958)
		(end 41.480994 -348.786958)
		(stroke
			(width 0.2)
			(type default)
		)
		(fill no)
		(layer "In5.Cu")
	)
	(gr_circle
		(center 41.369742 -358.549194)
		(end 42.258742 -358.549194)
		(stroke
			(width 0.2)
			(type default)
		)
		(fill no)
		(layer "In5.Cu")
	)
	(gr_circle
		(center 41.417494 -357.898192)
		(end 42.306494 -357.898192)
		(stroke
			(width 0.2)
			(type default)
		)
		(fill no)
		(layer "In5.Cu")
	)
	(gr_circle
		(center 41.417494 -357.263192)
		(end 42.306494 -357.263192)
		(stroke
			(width 0.2)
			(type default)
		)
		(fill no)
		(layer "In5.Cu")
	)
	(gr_circle
		(center 41.427146 -359.2576)
		(end 42.316146 -359.2576)
		(stroke
			(width 0.2)
			(type default)
		)
		(fill no)
		(layer "In5.Cu")
	)
	(gr_circle
		(center 43.935904 -358.51084)
		(end 44.824904 -358.51084)
		(stroke
			(width 0.2)
			(type default)
		)
		(fill no)
		(layer "In5.Cu")
	)
	(gr_circle
		(center 43.983656 -357.859838)
		(end 44.872656 -357.859838)
		(stroke
			(width 0.2)
			(type default)
		)
		(fill no)
		(layer "In5.Cu")
	)
	(gr_circle
		(center 43.983656 -357.224838)
		(end 44.872656 -357.224838)
		(stroke
			(width 0.2)
			(type default)
		)
		(fill no)
		(layer "In5.Cu")
	)
	(gr_circle
		(center 43.993308 -359.219246)
		(end 44.882308 -359.219246)
		(stroke
			(width 0.2)
			(type default)
		)
		(fill no)
		(layer "In5.Cu")
	)
	(gr_circle
		(center 45.877734 -348.709488)
		(end 46.757844 -348.709488)
		(stroke
			(width 0.2)
			(type default)
		)
		(fill no)
		(layer "In5.Cu")
	)
	(gr_circle
		(center 46.494954 -348.709488)
		(end 47.375064 -348.709488)
		(stroke
			(width 0.2)
			(type default)
		)
		(fill no)
		(layer "In5.Cu")
	)
	(gr_circle
		(center 47.112174 -348.709488)
		(end 47.992284 -348.709488)
		(stroke
			(width 0.2)
			(type default)
		)
		(fill no)
		(layer "In5.Cu")
	)
	(gr_circle
		(center 47.366174 -348.017338)
		(end 48.255174 -348.017338)
		(stroke
			(width 0.2)
			(type default)
		)
		(fill no)
		(layer "In5.Cu")
	)
	(gr_circle
		(center 47.366174 -347.280738)
		(end 48.255174 -347.280738)
		(stroke
			(width 0.2)
			(type default)
		)
		(fill no)
		(layer "In5.Cu")
	)
	(gr_circle
		(center 47.81423 -350.318578)
		(end 48.70323 -350.318578)
		(stroke
			(width 0.2)
			(type default)
		)
		(fill no)
		(layer "In5.Cu")
	)
	(gr_circle
		(center 47.81423 -349.581978)
		(end 48.70323 -349.581978)
		(stroke
			(width 0.2)
			(type default)
		)
		(fill no)
		(layer "In5.Cu")
	)
	(gr_circle
		(center 47.880778 -358.108504)
		(end 48.769778 -358.108504)
		(stroke
			(width 0.2)
			(type default)
		)
		(fill no)
		(layer "In5.Cu")
	)
	(gr_circle
		(center 47.92853 -357.457502)
		(end 48.81753 -357.457502)
		(stroke
			(width 0.2)
			(type default)
		)
		(fill no)
		(layer "In5.Cu")
	)
	(gr_circle
		(center 47.92853 -356.822502)
		(end 48.81753 -356.822502)
		(stroke
			(width 0.2)
			(type default)
		)
		(fill no)
		(layer "In5.Cu")
	)
	(gr_circle
		(center 48.338994 -349.142558)
		(end 49.227994 -349.142558)
		(stroke
			(width 0.2)
			(type default)
		)
		(fill no)
		(layer "In5.Cu")
	)
	(gr_circle
		(center 48.364394 -349.904558)
		(end 49.253394 -349.904558)
		(stroke
			(width 0.2)
			(type default)
		)
		(fill no)
		(layer "In5.Cu")
	)
	(gr_circle
		(center 48.718978 -358.108504)
		(end 49.607978 -358.108504)
		(stroke
			(width 0.2)
			(type default)
		)
		(fill no)
		(layer "In5.Cu")
	)
	(gr_circle
		(center 48.76673 -357.457502)
		(end 49.65573 -357.457502)
		(stroke
			(width 0.2)
			(type default)
		)
		(fill no)
		(layer "In5.Cu")
	)
	(gr_circle
		(center 48.76673 -356.822502)
		(end 49.65573 -356.822502)
		(stroke
			(width 0.2)
			(type default)
		)
		(fill no)
		(layer "In5.Cu")
	)
	(gr_circle
		(center 48.897794 -350.260158)
		(end 49.786794 -350.260158)
		(stroke
			(width 0.2)
			(type default)
		)
		(fill no)
		(layer "In5.Cu")
	)
	(gr_circle
		(center 48.897794 -349.523558)
		(end 49.786794 -349.523558)
		(stroke
			(width 0.2)
			(type default)
		)
		(fill no)
		(layer "In5.Cu")
	)
	(gr_circle
		(center 48.897794 -348.786958)
		(end 49.786794 -348.786958)
		(stroke
			(width 0.2)
			(type default)
		)
		(fill no)
		(layer "In5.Cu")
	)
	(gr_circle
		(center 49.353978 -358.108504)
		(end 50.242978 -358.108504)
		(stroke
			(width 0.2)
			(type default)
		)
		(fill no)
		(layer "In5.Cu")
	)
	(gr_circle
		(center 49.40173 -357.457502)
		(end 50.29073 -357.457502)
		(stroke
			(width 0.2)
			(type default)
		)
		(fill no)
		(layer "In5.Cu")
	)
	(gr_circle
		(center 49.40173 -356.822502)
		(end 50.29073 -356.822502)
		(stroke
			(width 0.2)
			(type default)
		)
		(fill no)
		(layer "In5.Cu")
	)
	(gr_circle
		(center 49.988978 -358.108504)
		(end 50.877978 -358.108504)
		(stroke
			(width 0.2)
			(type default)
		)
		(fill no)
		(layer "In5.Cu")
	)
	(gr_circle
		(center 50.03673 -357.457502)
		(end 50.92573 -357.457502)
		(stroke
			(width 0.2)
			(type default)
		)
		(fill no)
		(layer "In5.Cu")
	)
	(gr_circle
		(center 50.03673 -356.822502)
		(end 50.92573 -356.822502)
		(stroke
			(width 0.2)
			(type default)
		)
		(fill no)
		(layer "In5.Cu")
	)
	(gr_circle
		(center 50.623978 -358.108504)
		(end 51.512978 -358.108504)
		(stroke
			(width 0.2)
			(type default)
		)
		(fill no)
		(layer "In5.Cu")
	)
	(gr_circle
		(center 50.67173 -357.457502)
		(end 51.56073 -357.457502)
		(stroke
			(width 0.2)
			(type default)
		)
		(fill no)
		(layer "In5.Cu")
	)
	(gr_circle
		(center 50.67173 -356.822502)
		(end 51.56073 -356.822502)
		(stroke
			(width 0.2)
			(type default)
		)
		(fill no)
		(layer "In5.Cu")
	)
	(gr_circle
		(center 54.234334 -348.709488)
		(end 55.114444 -348.709488)
		(stroke
			(width 0.2)
			(type default)
		)
		(fill no)
		(layer "In5.Cu")
	)
	(gr_circle
		(center 54.851554 -348.709488)
		(end 55.731664 -348.709488)
		(stroke
			(width 0.2)
			(type default)
		)
		(fill no)
		(layer "In5.Cu")
	)
	(gr_circle
		(center 55.468774 -348.709488)
		(end 56.348884 -348.709488)
		(stroke
			(width 0.2)
			(type default)
		)
		(fill no)
		(layer "In5.Cu")
	)
	(gr_circle
		(center 55.727854 -347.997018)
		(end 56.616854 -347.997018)
		(stroke
			(width 0.2)
			(type default)
		)
		(fill no)
		(layer "In5.Cu")
	)
	(gr_circle
		(center 55.727854 -347.260418)
		(end 56.616854 -347.260418)
		(stroke
			(width 0.2)
			(type default)
		)
		(fill no)
		(layer "In5.Cu")
	)
	(gr_circle
		(center 56.17083 -350.318578)
		(end 57.05983 -350.318578)
		(stroke
			(width 0.2)
			(type default)
		)
		(fill no)
		(layer "In5.Cu")
	)
	(gr_circle
		(center 56.17083 -349.581978)
		(end 57.05983 -349.581978)
		(stroke
			(width 0.2)
			(type default)
		)
		(fill no)
		(layer "In5.Cu")
	)
	(gr_circle
		(center 56.695594 -349.142558)
		(end 57.584594 -349.142558)
		(stroke
			(width 0.2)
			(type default)
		)
		(fill no)
		(layer "In5.Cu")
	)
	(gr_circle
		(center 56.720994 -349.904558)
		(end 57.609994 -349.904558)
		(stroke
			(width 0.2)
			(type default)
		)
		(fill no)
		(layer "In5.Cu")
	)
	(gr_circle
		(center 57.254394 -350.260158)
		(end 58.143394 -350.260158)
		(stroke
			(width 0.2)
			(type default)
		)
		(fill no)
		(layer "In5.Cu")
	)
	(gr_circle
		(center 57.254394 -349.523558)
		(end 58.143394 -349.523558)
		(stroke
			(width 0.2)
			(type default)
		)
		(fill no)
		(layer "In5.Cu")
	)
	(gr_circle
		(center 57.254394 -348.786958)
		(end 58.143394 -348.786958)
		(stroke
			(width 0.2)
			(type default)
		)
		(fill no)
		(layer "In5.Cu")
	)
	(gr_circle
		(center 61.93663 -166.86276)
		(end 62.82563 -166.86276)
		(stroke
			(width 0.2)
			(type default)
		)
		(fill no)
		(layer "In5.Cu")
	)
	(gr_circle
		(center 61.93663 -166.12616)
		(end 62.82563 -166.12616)
		(stroke
			(width 0.2)
			(type default)
		)
		(fill no)
		(layer "In5.Cu")
	)
	(gr_circle
		(center 61.93663 -165.38956)
		(end 62.82563 -165.38956)
		(stroke
			(width 0.2)
			(type default)
		)
		(fill no)
		(layer "In5.Cu")
	)
	(gr_circle
		(center 62.47003 -165.74516)
		(end 63.35903 -165.74516)
		(stroke
			(width 0.2)
			(type default)
		)
		(fill no)
		(layer "In5.Cu")
	)
	(gr_circle
		(center 62.49543 -166.50716)
		(end 63.38443 -166.50716)
		(stroke
			(width 0.2)
			(type default)
		)
		(fill no)
		(layer "In5.Cu")
	)
	(gr_circle
		(center 62.565534 -348.709488)
		(end 63.445644 -348.709488)
		(stroke
			(width 0.2)
			(type default)
		)
		(fill no)
		(layer "In5.Cu")
	)
	(gr_circle
		(center 63.020194 -166.06774)
		(end 63.909194 -166.06774)
		(stroke
			(width 0.2)
			(type default)
		)
		(fill no)
		(layer "In5.Cu")
	)
	(gr_circle
		(center 63.020194 -165.33114)
		(end 63.909194 -165.33114)
		(stroke
			(width 0.2)
			(type default)
		)
		(fill no)
		(layer "In5.Cu")
	)
	(gr_circle
		(center 63.182754 -348.709488)
		(end 64.062864 -348.709488)
		(stroke
			(width 0.2)
			(type default)
		)
		(fill no)
		(layer "In5.Cu")
	)
	(gr_circle
		(center 63.199264 -12.43711)
		(end 64.088264 -12.43711)
		(stroke
			(width 0.2)
			(type default)
		)
		(fill no)
		(layer "In5.Cu")
	)
	(gr_circle
		(center 63.579248 -168.42232)
		(end 64.468248 -168.42232)
		(stroke
			(width 0.2)
			(type default)
		)
		(fill no)
		(layer "In5.Cu")
	)
	(gr_circle
		(center 63.579248 -167.68572)
		(end 64.468248 -167.68572)
		(stroke
			(width 0.2)
			(type default)
		)
		(fill no)
		(layer "In5.Cu")
	)
	(gr_circle
		(center 63.631064 -13.09751)
		(end 64.520064 -13.09751)
		(stroke
			(width 0.2)
			(type default)
		)
		(fill no)
		(layer "In5.Cu")
	)
	(gr_circle
		(center 63.72225 -166.94023)
		(end 64.60236 -166.94023)
		(stroke
			(width 0.2)
			(type default)
		)
		(fill no)
		(layer "In5.Cu")
	)
	(gr_circle
		(center 63.799974 -348.709488)
		(end 64.680084 -348.709488)
		(stroke
			(width 0.2)
			(type default)
		)
		(fill no)
		(layer "In5.Cu")
	)
	(gr_circle
		(center 64.061594 -348.038928)
		(end 64.941704 -348.038928)
		(stroke
			(width 0.2)
			(type default)
		)
		(fill no)
		(layer "In5.Cu")
	)
	(gr_circle
		(center 64.061594 -347.302328)
		(end 64.941704 -347.302328)
		(stroke
			(width 0.2)
			(type default)
		)
		(fill no)
		(layer "In5.Cu")
	)
	(gr_circle
		(center 64.088264 -12.43711)
		(end 64.977264 -12.43711)
		(stroke
			(width 0.2)
			(type default)
		)
		(fill no)
		(layer "In5.Cu")
	)
	(gr_circle
		(center 64.33947 -166.94023)
		(end 65.21958 -166.94023)
		(stroke
			(width 0.2)
			(type default)
		)
		(fill no)
		(layer "In5.Cu")
	)
	(gr_circle
		(center 64.50203 -350.318578)
		(end 65.39103 -350.318578)
		(stroke
			(width 0.2)
			(type default)
		)
		(fill no)
		(layer "In5.Cu")
	)
	(gr_circle
		(center 64.50203 -349.581978)
		(end 65.39103 -349.581978)
		(stroke
			(width 0.2)
			(type default)
		)
		(fill no)
		(layer "In5.Cu")
	)
	(gr_circle
		(center 64.520064 -13.09751)
		(end 65.409064 -13.09751)
		(stroke
			(width 0.2)
			(type default)
		)
		(fill no)
		(layer "In5.Cu")
	)
	(gr_circle
		(center 64.95669 -166.94023)
		(end 65.8368 -166.94023)
		(stroke
			(width 0.2)
			(type default)
		)
		(fill no)
		(layer "In5.Cu")
	)
	(gr_circle
		(center 64.977264 -12.43711)
		(end 65.866264 -12.43711)
		(stroke
			(width 0.2)
			(type default)
		)
		(fill no)
		(layer "In5.Cu")
	)
	(gr_circle
		(center 65.026794 -349.142558)
		(end 65.915794 -349.142558)
		(stroke
			(width 0.2)
			(type default)
		)
		(fill no)
		(layer "In5.Cu")
	)
	(gr_circle
		(center 65.052194 -349.904558)
		(end 65.941194 -349.904558)
		(stroke
			(width 0.2)
			(type default)
		)
		(fill no)
		(layer "In5.Cu")
	)
	(gr_circle
		(center 65.409064 -13.09751)
		(end 66.298064 -13.09751)
		(stroke
			(width 0.2)
			(type default)
		)
		(fill no)
		(layer "In5.Cu")
	)
	(gr_circle
		(center 65.585594 -350.260158)
		(end 66.474594 -350.260158)
		(stroke
			(width 0.2)
			(type default)
		)
		(fill no)
		(layer "In5.Cu")
	)
	(gr_circle
		(center 65.585594 -349.523558)
		(end 66.474594 -349.523558)
		(stroke
			(width 0.2)
			(type default)
		)
		(fill no)
		(layer "In5.Cu")
	)
	(gr_circle
		(center 65.585594 -348.786958)
		(end 66.474594 -348.786958)
		(stroke
			(width 0.2)
			(type default)
		)
		(fill no)
		(layer "In5.Cu")
	)
	(gr_circle
		(center 65.866264 -12.43711)
		(end 66.755264 -12.43711)
		(stroke
			(width 0.2)
			(type default)
		)
		(fill no)
		(layer "In5.Cu")
	)
	(gr_circle
		(center 66.298064 -13.09751)
		(end 67.187064 -13.09751)
		(stroke
			(width 0.2)
			(type default)
		)
		(fill no)
		(layer "In5.Cu")
	)
	(gr_circle
		(center 66.399664 -25.56891)
		(end 67.288664 -25.56891)
		(stroke
			(width 0.2)
			(type default)
		)
		(fill no)
		(layer "In5.Cu")
	)
	(gr_circle
		(center 66.501264 -12.43711)
		(end 67.390264 -12.43711)
		(stroke
			(width 0.2)
			(type default)
		)
		(fill no)
		(layer "In5.Cu")
	)
	(gr_circle
		(center 66.774822 -20.327366)
		(end 67.663822 -20.327366)
		(stroke
			(width 0.2)
			(type default)
		)
		(fill no)
		(layer "In5.Cu")
	)
	(gr_circle
		(center 66.774822 -19.692366)
		(end 67.663822 -19.692366)
		(stroke
			(width 0.2)
			(type default)
		)
		(fill no)
		(layer "In5.Cu")
	)
	(gr_circle
		(center 66.780664 -24.88311)
		(end 67.669664 -24.88311)
		(stroke
			(width 0.2)
			(type default)
		)
		(fill no)
		(layer "In5.Cu")
	)
	(gr_circle
		(center 66.848228 -18.642584)
		(end 67.737228 -18.642584)
		(stroke
			(width 0.2)
			(type default)
		)
		(fill no)
		(layer "In5.Cu")
	)
	(gr_circle
		(center 66.882264 -22.26691)
		(end 67.771264 -22.26691)
		(stroke
			(width 0.2)
			(type default)
		)
		(fill no)
		(layer "In5.Cu")
	)
	(gr_circle
		(center 66.933064 -13.09751)
		(end 67.822064 -13.09751)
		(stroke
			(width 0.2)
			(type default)
		)
		(fill no)
		(layer "In5.Cu")
	)
	(gr_circle
		(center 67.288664 -25.56891)
		(end 68.177664 -25.56891)
		(stroke
			(width 0.2)
			(type default)
		)
		(fill no)
		(layer "In5.Cu")
	)
	(gr_circle
		(center 67.40271 -12.489434)
		(end 68.29171 -12.489434)
		(stroke
			(width 0.2)
			(type default)
		)
		(fill no)
		(layer "In5.Cu")
	)
	(gr_circle
		(center 67.669664 -24.88311)
		(end 68.558664 -24.88311)
		(stroke
			(width 0.2)
			(type default)
		)
		(fill no)
		(layer "In5.Cu")
	)
	(gr_circle
		(center 68.177664 -25.56891)
		(end 69.066664 -25.56891)
		(stroke
			(width 0.2)
			(type default)
		)
		(fill no)
		(layer "In5.Cu")
	)
	(gr_circle
		(center 68.54444 -18.476214)
		(end 69.43344 -18.476214)
		(stroke
			(width 0.2)
			(type default)
		)
		(fill no)
		(layer "In5.Cu")
	)
	(gr_circle
		(center 68.558664 -24.88311)
		(end 69.447664 -24.88311)
		(stroke
			(width 0.2)
			(type default)
		)
		(fill no)
		(layer "In5.Cu")
	)
	(gr_circle
		(center 69.498464 -24.55291)
		(end 70.387464 -24.55291)
		(stroke
			(width 0.2)
			(type default)
		)
		(fill no)
		(layer "In5.Cu")
	)
	(gr_circle
		(center 70.25005 -175.559974)
		(end 71.13905 -175.559974)
		(stroke
			(width 0.2)
			(type default)
		)
		(fill no)
		(layer "In5.Cu")
	)
	(gr_circle
		(center 70.25005 -174.823374)
		(end 71.13905 -174.823374)
		(stroke
			(width 0.2)
			(type default)
		)
		(fill no)
		(layer "In5.Cu")
	)
	(gr_circle
		(center 70.25005 -174.086774)
		(end 71.13905 -174.086774)
		(stroke
			(width 0.2)
			(type default)
		)
		(fill no)
		(layer "In5.Cu")
	)
	(gr_circle
		(center 70.78345 -174.442374)
		(end 71.67245 -174.442374)
		(stroke
			(width 0.2)
			(type default)
		)
		(fill no)
		(layer "In5.Cu")
	)
	(gr_circle
		(center 70.80885 -175.204374)
		(end 71.69785 -175.204374)
		(stroke
			(width 0.2)
			(type default)
		)
		(fill no)
		(layer "In5.Cu")
	)
	(gr_circle
		(center 71.099934 -336.988404)
		(end 71.980044 -336.988404)
		(stroke
			(width 0.2)
			(type default)
		)
		(fill no)
		(layer "In5.Cu")
	)
	(gr_circle
		(center 71.333614 -174.764954)
		(end 72.222614 -174.764954)
		(stroke
			(width 0.2)
			(type default)
		)
		(fill no)
		(layer "In5.Cu")
	)
	(gr_circle
		(center 71.333614 -174.028354)
		(end 72.222614 -174.028354)
		(stroke
			(width 0.2)
			(type default)
		)
		(fill no)
		(layer "In5.Cu")
	)
	(gr_circle
		(center 71.717154 -336.988404)
		(end 72.597264 -336.988404)
		(stroke
			(width 0.2)
			(type default)
		)
		(fill no)
		(layer "In5.Cu")
	)
	(gr_circle
		(center 71.892668 -177.10912)
		(end 72.781668 -177.10912)
		(stroke
			(width 0.2)
			(type default)
		)
		(fill no)
		(layer "In5.Cu")
	)
	(gr_circle
		(center 71.892668 -176.37252)
		(end 72.781668 -176.37252)
		(stroke
			(width 0.2)
			(type default)
		)
		(fill no)
		(layer "In5.Cu")
	)
	(gr_circle
		(center 72.03567 -175.639222)
		(end 72.91578 -175.639222)
		(stroke
			(width 0.2)
			(type default)
		)
		(fill no)
		(layer "In5.Cu")
	)
	(gr_circle
		(center 72.334374 -336.988404)
		(end 73.214484 -336.988404)
		(stroke
			(width 0.2)
			(type default)
		)
		(fill no)
		(layer "In5.Cu")
	)
	(gr_circle
		(center 72.616314 -336.255868)
		(end 73.496424 -336.255868)
		(stroke
			(width 0.2)
			(type default)
		)
		(fill no)
		(layer "In5.Cu")
	)
	(gr_circle
		(center 72.616314 -335.519268)
		(end 73.496424 -335.519268)
		(stroke
			(width 0.2)
			(type default)
		)
		(fill no)
		(layer "In5.Cu")
	)
	(gr_circle
		(center 72.65289 -175.639222)
		(end 73.533 -175.639222)
		(stroke
			(width 0.2)
			(type default)
		)
		(fill no)
		(layer "In5.Cu")
	)
	(gr_circle
		(center 73.03643 -338.597494)
		(end 73.92543 -338.597494)
		(stroke
			(width 0.2)
			(type default)
		)
		(fill no)
		(layer "In5.Cu")
	)
	(gr_circle
		(center 73.03643 -337.860894)
		(end 73.92543 -337.860894)
		(stroke
			(width 0.2)
			(type default)
		)
		(fill no)
		(layer "In5.Cu")
	)
	(gr_circle
		(center 73.27011 -175.639222)
		(end 74.15022 -175.639222)
		(stroke
			(width 0.2)
			(type default)
		)
		(fill no)
		(layer "In5.Cu")
	)
	(gr_circle
		(center 73.561194 -337.421474)
		(end 74.450194 -337.421474)
		(stroke
			(width 0.2)
			(type default)
		)
		(fill no)
		(layer "In5.Cu")
	)
	(gr_circle
		(center 73.586594 -338.183474)
		(end 74.475594 -338.183474)
		(stroke
			(width 0.2)
			(type default)
		)
		(fill no)
		(layer "In5.Cu")
	)
	(gr_circle
		(center 74.119994 -338.539074)
		(end 75.008994 -338.539074)
		(stroke
			(width 0.2)
			(type default)
		)
		(fill no)
		(layer "In5.Cu")
	)
	(gr_circle
		(center 74.119994 -337.802474)
		(end 75.008994 -337.802474)
		(stroke
			(width 0.2)
			(type default)
		)
		(fill no)
		(layer "In5.Cu")
	)
	(gr_circle
		(center 74.119994 -337.065874)
		(end 75.008994 -337.065874)
		(stroke
			(width 0.2)
			(type default)
		)
		(fill no)
		(layer "In5.Cu")
	)
	(gr_circle
		(center 74.811382 -351.637854)
		(end 75.700382 -351.637854)
		(stroke
			(width 0.2)
			(type default)
		)
		(fill no)
		(layer "In5.Cu")
	)
	(gr_circle
		(center 74.849482 -353.131374)
		(end 75.738482 -353.131374)
		(stroke
			(width 0.2)
			(type default)
		)
		(fill no)
		(layer "In5.Cu")
	)
	(gr_circle
		(center 74.849736 -352.30816)
		(end 75.738736 -352.30816)
		(stroke
			(width 0.2)
			(type default)
		)
		(fill no)
		(layer "In5.Cu")
	)
	(gr_circle
		(center 74.86015 -350.929448)
		(end 75.74915 -350.929448)
		(stroke
			(width 0.2)
			(type default)
		)
		(fill no)
		(layer "In5.Cu")
	)
	(gr_circle
		(center 77.178408 -16.520668)
		(end 78.067408 -16.520668)
		(stroke
			(width 0.2)
			(type default)
		)
		(fill no)
		(layer "In5.Cu")
	)
	(gr_circle
		(center 77.473048 -351.5995)
		(end 78.362048 -351.5995)
		(stroke
			(width 0.2)
			(type default)
		)
		(fill no)
		(layer "In5.Cu")
	)
	(gr_circle
		(center 77.511402 -352.978212)
		(end 78.400402 -352.978212)
		(stroke
			(width 0.2)
			(type default)
		)
		(fill no)
		(layer "In5.Cu")
	)
	(gr_circle
		(center 77.511402 -352.269806)
		(end 78.400402 -352.269806)
		(stroke
			(width 0.2)
			(type default)
		)
		(fill no)
		(layer "In5.Cu")
	)
	(gr_circle
		(center 77.521816 -350.891094)
		(end 78.410816 -350.891094)
		(stroke
			(width 0.2)
			(type default)
		)
		(fill no)
		(layer "In5.Cu")
	)
	(gr_circle
		(center 77.84338 -16.55064)
		(end 78.73238 -16.55064)
		(stroke
			(width 0.2)
			(type default)
		)
		(fill no)
		(layer "In5.Cu")
	)
	(gr_circle
		(center 78.85303 -178.798474)
		(end 79.74203 -178.798474)
		(stroke
			(width 0.2)
			(type default)
		)
		(fill no)
		(layer "In5.Cu")
	)
	(gr_circle
		(center 78.85303 -178.036474)
		(end 79.74203 -178.036474)
		(stroke
			(width 0.2)
			(type default)
		)
		(fill no)
		(layer "In5.Cu")
	)
	(gr_circle
		(center 79.10703 -179.560474)
		(end 79.99603 -179.560474)
		(stroke
			(width 0.2)
			(type default)
		)
		(fill no)
		(layer "In5.Cu")
	)
	(gr_circle
		(center 79.13243 -180.322474)
		(end 80.02143 -180.322474)
		(stroke
			(width 0.2)
			(type default)
		)
		(fill no)
		(layer "In5.Cu")
	)
	(gr_circle
		(center 79.403194 -178.384454)
		(end 80.292194 -178.384454)
		(stroke
			(width 0.2)
			(type default)
		)
		(fill no)
		(layer "In5.Cu")
	)
	(gr_circle
		(center 79.455518 -336.981292)
		(end 80.335628 -336.981292)
		(stroke
			(width 0.2)
			(type default)
		)
		(fill no)
		(layer "In5.Cu")
	)
	(gr_circle
		(center 79.657194 -179.883054)
		(end 80.546194 -179.883054)
		(stroke
			(width 0.2)
			(type default)
		)
		(fill no)
		(layer "In5.Cu")
	)
	(gr_circle
		(center 79.657194 -179.146454)
		(end 80.546194 -179.146454)
		(stroke
			(width 0.2)
			(type default)
		)
		(fill no)
		(layer "In5.Cu")
	)
	(gr_circle
		(center 79.921862 -18.238724)
		(end 80.810862 -18.238724)
		(stroke
			(width 0.2)
			(type default)
		)
		(fill no)
		(layer "In5.Cu")
	)
	(gr_circle
		(center 79.921862 -17.502124)
		(end 80.810862 -17.502124)
		(stroke
			(width 0.2)
			(type default)
		)
		(fill no)
		(layer "In5.Cu")
	)
	(gr_circle
		(center 80.072738 -336.981292)
		(end 80.952848 -336.981292)
		(stroke
			(width 0.2)
			(type default)
		)
		(fill no)
		(layer "In5.Cu")
	)
	(gr_circle
		(center 80.241648 -182.2196)
		(end 81.130648 -182.2196)
		(stroke
			(width 0.2)
			(type default)
		)
		(fill no)
		(layer "In5.Cu")
	)
	(gr_circle
		(center 80.241648 -181.483)
		(end 81.130648 -181.483)
		(stroke
			(width 0.2)
			(type default)
		)
		(fill no)
		(layer "In5.Cu")
	)
	(gr_circle
		(center 80.35925 -180.755544)
		(end 81.23936 -180.755544)
		(stroke
			(width 0.2)
			(type default)
		)
		(fill no)
		(layer "In5.Cu")
	)
	(gr_circle
		(center 80.689958 -336.981292)
		(end 81.570068 -336.981292)
		(stroke
			(width 0.2)
			(type default)
		)
		(fill no)
		(layer "In5.Cu")
	)
	(gr_circle
		(center 80.97647 -180.755544)
		(end 81.85658 -180.755544)
		(stroke
			(width 0.2)
			(type default)
		)
		(fill no)
		(layer "In5.Cu")
	)
	(gr_circle
		(center 80.977994 -336.245708)
		(end 81.858104 -336.245708)
		(stroke
			(width 0.2)
			(type default)
		)
		(fill no)
		(layer "In5.Cu")
	)
	(gr_circle
		(center 80.977994 -335.509108)
		(end 81.858104 -335.509108)
		(stroke
			(width 0.2)
			(type default)
		)
		(fill no)
		(layer "In5.Cu")
	)
	(gr_circle
		(center 81.392014 -338.590382)
		(end 82.281014 -338.590382)
		(stroke
			(width 0.2)
			(type default)
		)
		(fill no)
		(layer "In5.Cu")
	)
	(gr_circle
		(center 81.392014 -337.853782)
		(end 82.281014 -337.853782)
		(stroke
			(width 0.2)
			(type default)
		)
		(fill no)
		(layer "In5.Cu")
	)
	(gr_circle
		(center 81.59369 -180.755544)
		(end 82.4738 -180.755544)
		(stroke
			(width 0.2)
			(type default)
		)
		(fill no)
		(layer "In5.Cu")
	)
	(gr_arc
		(start 81.701894 -9.780016)
		(mid 82.287679 -11.194227)
		(end 83.70189 -11.780012)
		(stroke
			(width 1.016)
			(type default)
		)
		(layer "In5.Cu")
	)
	(gr_arc
		(start 81.701894 -0.500126)
		(mid 81.555625 -0.146451)
		(end 81.202022 0)
		(stroke
			(width 1.016)
			(type default)
		)
		(layer "In5.Cu")
	)
	(gr_line
		(start 81.701894 -0.500126)
		(end 81.701894 -9.780016)
		(stroke
			(width 1.016)
			(type default)
		)
		(layer "In5.Cu")
	)
	(gr_circle
		(center 81.916778 -337.414362)
		(end 82.805778 -337.414362)
		(stroke
			(width 0.2)
			(type default)
		)
		(fill no)
		(layer "In5.Cu")
	)
	(gr_circle
		(center 81.942178 -338.176362)
		(end 82.831178 -338.176362)
		(stroke
			(width 0.2)
			(type default)
		)
		(fill no)
		(layer "In5.Cu")
	)
	(gr_circle
		(center 82.183986 -348.89948)
		(end 83.072986 -348.89948)
		(stroke
			(width 0.2)
			(type default)
		)
		(fill no)
		(layer "In5.Cu")
	)
	(gr_circle
		(center 82.222086 -350.393)
		(end 83.111086 -350.393)
		(stroke
			(width 0.2)
			(type default)
		)
		(fill no)
		(layer "In5.Cu")
	)
	(gr_circle
		(center 82.22234 -349.569786)
		(end 83.11134 -349.569786)
		(stroke
			(width 0.2)
			(type default)
		)
		(fill no)
		(layer "In5.Cu")
	)
	(gr_circle
		(center 82.232754 -348.191074)
		(end 83.121754 -348.191074)
		(stroke
			(width 0.2)
			(type default)
		)
		(fill no)
		(layer "In5.Cu")
	)
	(gr_circle
		(center 82.475578 -338.531962)
		(end 83.364578 -338.531962)
		(stroke
			(width 0.2)
			(type default)
		)
		(fill no)
		(layer "In5.Cu")
	)
	(gr_circle
		(center 82.475578 -337.795362)
		(end 83.364578 -337.795362)
		(stroke
			(width 0.2)
			(type default)
		)
		(fill no)
		(layer "In5.Cu")
	)
	(gr_circle
		(center 82.475578 -337.058762)
		(end 83.364578 -337.058762)
		(stroke
			(width 0.2)
			(type default)
		)
		(fill no)
		(layer "In5.Cu")
	)
	(gr_circle
		(center 82.989674 -165.962076)
		(end 84.386674 -165.962076)
		(stroke
			(width 0.2)
			(type default)
		)
		(fill no)
		(layer "In5.Cu")
	)
	(gr_line
		(start 83.70189 -11.780012)
		(end 124.102114 -11.780012)
		(stroke
			(width 1.016)
			(type default)
		)
		(layer "In5.Cu")
	)
	(gr_circle
		(center 84.845652 -348.861126)
		(end 85.734652 -348.861126)
		(stroke
			(width 0.2)
			(type default)
		)
		(fill no)
		(layer "In5.Cu")
	)
	(gr_circle
		(center 84.884006 -350.239838)
		(end 85.773006 -350.239838)
		(stroke
			(width 0.2)
			(type default)
		)
		(fill no)
		(layer "In5.Cu")
	)
	(gr_circle
		(center 84.884006 -349.531432)
		(end 85.773006 -349.531432)
		(stroke
			(width 0.2)
			(type default)
		)
		(fill no)
		(layer "In5.Cu")
	)
	(gr_circle
		(center 84.89442 -348.15272)
		(end 85.78342 -348.15272)
		(stroke
			(width 0.2)
			(type default)
		)
		(fill no)
		(layer "In5.Cu")
	)
	(gr_circle
		(center 86.97087 -180.610002)
		(end 87.85987 -180.610002)
		(stroke
			(width 0.2)
			(type default)
		)
		(fill no)
		(layer "In5.Cu")
	)
	(gr_circle
		(center 86.97087 -179.873402)
		(end 87.85987 -179.873402)
		(stroke
			(width 0.2)
			(type default)
		)
		(fill no)
		(layer "In5.Cu")
	)
	(gr_circle
		(center 86.97087 -179.136802)
		(end 87.85987 -179.136802)
		(stroke
			(width 0.2)
			(type default)
		)
		(fill no)
		(layer "In5.Cu")
	)
	(gr_circle
		(center 87.01913 -164.097716)
		(end 87.90813 -164.097716)
		(stroke
			(width 0.2)
			(type default)
		)
		(fill no)
		(layer "In5.Cu")
	)
	(gr_circle
		(center 87.03945 -163.447476)
		(end 87.92845 -163.447476)
		(stroke
			(width 0.2)
			(type default)
		)
		(fill no)
		(layer "In5.Cu")
	)
	(gr_circle
		(center 87.03945 -162.812476)
		(end 87.92845 -162.812476)
		(stroke
			(width 0.2)
			(type default)
		)
		(fill no)
		(layer "In5.Cu")
	)
	(gr_circle
		(center 87.50427 -179.492402)
		(end 88.39327 -179.492402)
		(stroke
			(width 0.2)
			(type default)
		)
		(fill no)
		(layer "In5.Cu")
	)
	(gr_circle
		(center 87.52967 -180.254402)
		(end 88.41867 -180.254402)
		(stroke
			(width 0.2)
			(type default)
		)
		(fill no)
		(layer "In5.Cu")
	)
	(gr_circle
		(center 87.65413 -164.097716)
		(end 88.54313 -164.097716)
		(stroke
			(width 0.2)
			(type default)
		)
		(fill no)
		(layer "In5.Cu")
	)
	(gr_circle
		(center 87.67445 -163.447476)
		(end 88.56345 -163.447476)
		(stroke
			(width 0.2)
			(type default)
		)
		(fill no)
		(layer "In5.Cu")
	)
	(gr_circle
		(center 87.67445 -162.812476)
		(end 88.56345 -162.812476)
		(stroke
			(width 0.2)
			(type default)
		)
		(fill no)
		(layer "In5.Cu")
	)
	(gr_circle
		(center 87.813134 -336.966814)
		(end 88.693244 -336.966814)
		(stroke
			(width 0.2)
			(type default)
		)
		(fill no)
		(layer "In5.Cu")
	)
	(gr_circle
		(center 88.054434 -179.814982)
		(end 88.943434 -179.814982)
		(stroke
			(width 0.2)
			(type default)
		)
		(fill no)
		(layer "In5.Cu")
	)
	(gr_circle
		(center 88.054434 -179.078382)
		(end 88.943434 -179.078382)
		(stroke
			(width 0.2)
			(type default)
		)
		(fill no)
		(layer "In5.Cu")
	)
	(gr_circle
		(center 88.28913 -164.097716)
		(end 89.17813 -164.097716)
		(stroke
			(width 0.2)
			(type default)
		)
		(fill no)
		(layer "In5.Cu")
	)
	(gr_circle
		(center 88.30945 -163.447476)
		(end 89.19845 -163.447476)
		(stroke
			(width 0.2)
			(type default)
		)
		(fill no)
		(layer "In5.Cu")
	)
	(gr_circle
		(center 88.30945 -162.812476)
		(end 89.19845 -162.812476)
		(stroke
			(width 0.2)
			(type default)
		)
		(fill no)
		(layer "In5.Cu")
	)
	(gr_circle
		(center 88.430354 -336.966814)
		(end 89.310464 -336.966814)
		(stroke
			(width 0.2)
			(type default)
		)
		(fill no)
		(layer "In5.Cu")
	)
	(gr_circle
		(center 88.49233 -182.13324)
		(end 89.38133 -182.13324)
		(stroke
			(width 0.2)
			(type default)
		)
		(fill no)
		(layer "In5.Cu")
	)
	(gr_circle
		(center 88.49233 -181.39664)
		(end 89.38133 -181.39664)
		(stroke
			(width 0.2)
			(type default)
		)
		(fill no)
		(layer "In5.Cu")
	)
	(gr_circle
		(center 88.75649 -180.687472)
		(end 89.6366 -180.687472)
		(stroke
			(width 0.2)
			(type default)
		)
		(fill no)
		(layer "In5.Cu")
	)
	(gr_circle
		(center 88.92413 -164.097716)
		(end 89.81313 -164.097716)
		(stroke
			(width 0.2)
			(type default)
		)
		(fill no)
		(layer "In5.Cu")
	)
	(gr_circle
		(center 88.94445 -163.447476)
		(end 89.83345 -163.447476)
		(stroke
			(width 0.2)
			(type default)
		)
		(fill no)
		(layer "In5.Cu")
	)
	(gr_circle
		(center 88.94445 -162.812476)
		(end 89.83345 -162.812476)
		(stroke
			(width 0.2)
			(type default)
		)
		(fill no)
		(layer "In5.Cu")
	)
	(gr_circle
		(center 89.047574 -336.966814)
		(end 89.927684 -336.966814)
		(stroke
			(width 0.2)
			(type default)
		)
		(fill no)
		(layer "In5.Cu")
	)
	(gr_circle
		(center 89.314528 -345.237562)
		(end 90.203528 -345.237562)
		(stroke
			(width 0.2)
			(type default)
		)
		(fill no)
		(layer "In5.Cu")
	)
	(gr_circle
		(center 89.319354 -336.255868)
		(end 90.199464 -336.255868)
		(stroke
			(width 0.2)
			(type default)
		)
		(fill no)
		(layer "In5.Cu")
	)
	(gr_circle
		(center 89.319354 -335.519268)
		(end 90.199464 -335.519268)
		(stroke
			(width 0.2)
			(type default)
		)
		(fill no)
		(layer "In5.Cu")
	)
	(gr_circle
		(center 89.350088 -345.96959)
		(end 90.239088 -345.96959)
		(stroke
			(width 0.2)
			(type default)
		)
		(fill no)
		(layer "In5.Cu")
	)
	(gr_circle
		(center 89.37371 -180.687472)
		(end 90.25382 -180.687472)
		(stroke
			(width 0.2)
			(type default)
		)
		(fill no)
		(layer "In5.Cu")
	)
	(gr_circle
		(center 89.388442 -346.639896)
		(end 90.277442 -346.639896)
		(stroke
			(width 0.2)
			(type default)
		)
		(fill no)
		(layer "In5.Cu")
	)
	(gr_circle
		(center 89.55913 -164.097716)
		(end 90.44813 -164.097716)
		(stroke
			(width 0.2)
			(type default)
		)
		(fill no)
		(layer "In5.Cu")
	)
	(gr_circle
		(center 89.57945 -163.447476)
		(end 90.46845 -163.447476)
		(stroke
			(width 0.2)
			(type default)
		)
		(fill no)
		(layer "In5.Cu")
	)
	(gr_circle
		(center 89.57945 -162.812476)
		(end 90.46845 -162.812476)
		(stroke
			(width 0.2)
			(type default)
		)
		(fill no)
		(layer "In5.Cu")
	)
	(gr_circle
		(center 89.74963 -338.575904)
		(end 90.63863 -338.575904)
		(stroke
			(width 0.2)
			(type default)
		)
		(fill no)
		(layer "In5.Cu")
	)
	(gr_circle
		(center 89.74963 -337.839304)
		(end 90.63863 -337.839304)
		(stroke
			(width 0.2)
			(type default)
		)
		(fill no)
		(layer "In5.Cu")
	)
	(gr_circle
		(center 89.983056 -345.261184)
		(end 90.872056 -345.261184)
		(stroke
			(width 0.2)
			(type default)
		)
		(fill no)
		(layer "In5.Cu")
	)
	(gr_circle
		(center 89.985088 -345.96959)
		(end 90.874088 -345.96959)
		(stroke
			(width 0.2)
			(type default)
		)
		(fill no)
		(layer "In5.Cu")
	)
	(gr_circle
		(center 89.99093 -180.687472)
		(end 90.87104 -180.687472)
		(stroke
			(width 0.2)
			(type default)
		)
		(fill no)
		(layer "In5.Cu")
	)
	(gr_circle
		(center 90.023442 -346.639896)
		(end 90.912442 -346.639896)
		(stroke
			(width 0.2)
			(type default)
		)
		(fill no)
		(layer "In5.Cu")
	)
	(gr_circle
		(center 90.21953 -164.107876)
		(end 91.10853 -164.107876)
		(stroke
			(width 0.2)
			(type default)
		)
		(fill no)
		(layer "In5.Cu")
	)
	(gr_circle
		(center 90.23985 -163.457636)
		(end 91.12885 -163.457636)
		(stroke
			(width 0.2)
			(type default)
		)
		(fill no)
		(layer "In5.Cu")
	)
	(gr_circle
		(center 90.23985 -162.822636)
		(end 91.12885 -162.822636)
		(stroke
			(width 0.2)
			(type default)
		)
		(fill no)
		(layer "In5.Cu")
	)
	(gr_circle
		(center 90.274394 -337.399884)
		(end 91.163394 -337.399884)
		(stroke
			(width 0.2)
			(type default)
		)
		(fill no)
		(layer "In5.Cu")
	)
	(gr_circle
		(center 90.299794 -338.161884)
		(end 91.188794 -338.161884)
		(stroke
			(width 0.2)
			(type default)
		)
		(fill no)
		(layer "In5.Cu")
	)
	(gr_circle
		(center 90.618056 -345.261184)
		(end 91.507056 -345.261184)
		(stroke
			(width 0.2)
			(type default)
		)
		(fill no)
		(layer "In5.Cu")
	)
	(gr_circle
		(center 90.620088 -345.96959)
		(end 91.509088 -345.96959)
		(stroke
			(width 0.2)
			(type default)
		)
		(fill no)
		(layer "In5.Cu")
	)
	(gr_circle
		(center 90.658442 -346.639896)
		(end 91.547442 -346.639896)
		(stroke
			(width 0.2)
			(type default)
		)
		(fill no)
		(layer "In5.Cu")
	)
	(gr_circle
		(center 90.833194 -338.517484)
		(end 91.722194 -338.517484)
		(stroke
			(width 0.2)
			(type default)
		)
		(fill no)
		(layer "In5.Cu")
	)
	(gr_circle
		(center 90.833194 -337.780884)
		(end 91.722194 -337.780884)
		(stroke
			(width 0.2)
			(type default)
		)
		(fill no)
		(layer "In5.Cu")
	)
	(gr_circle
		(center 90.833194 -337.044284)
		(end 91.722194 -337.044284)
		(stroke
			(width 0.2)
			(type default)
		)
		(fill no)
		(layer "In5.Cu")
	)
	(gr_circle
		(center 91.255088 -345.96959)
		(end 92.144088 -345.96959)
		(stroke
			(width 0.2)
			(type default)
		)
		(fill no)
		(layer "In5.Cu")
	)
	(gr_circle
		(center 91.293442 -346.639896)
		(end 92.182442 -346.639896)
		(stroke
			(width 0.2)
			(type default)
		)
		(fill no)
		(layer "In5.Cu")
	)
	(gr_circle
		(center 91.380056 -345.261184)
		(end 92.269056 -345.261184)
		(stroke
			(width 0.2)
			(type default)
		)
		(fill no)
		(layer "In5.Cu")
	)
	(gr_circle
		(center 91.966288 -345.96959)
		(end 92.855288 -345.96959)
		(stroke
			(width 0.2)
			(type default)
		)
		(fill no)
		(layer "In5.Cu")
	)
	(gr_circle
		(center 92.004642 -346.639896)
		(end 92.893642 -346.639896)
		(stroke
			(width 0.2)
			(type default)
		)
		(fill no)
		(layer "In5.Cu")
	)
	(gr_circle
		(center 92.015056 -345.261184)
		(end 92.904056 -345.261184)
		(stroke
			(width 0.2)
			(type default)
		)
		(fill no)
		(layer "In5.Cu")
	)
	(gr_circle
		(center 92.387674 -165.962076)
		(end 93.784674 -165.962076)
		(stroke
			(width 0.2)
			(type default)
		)
		(fill no)
		(layer "In5.Cu")
	)
	(gr_circle
		(center 92.601288 -345.96959)
		(end 93.490288 -345.96959)
		(stroke
			(width 0.2)
			(type default)
		)
		(fill no)
		(layer "In5.Cu")
	)
	(gr_circle
		(center 92.639642 -346.639896)
		(end 93.528642 -346.639896)
		(stroke
			(width 0.2)
			(type default)
		)
		(fill no)
		(layer "In5.Cu")
	)
	(gr_circle
		(center 92.650056 -345.261184)
		(end 93.539056 -345.261184)
		(stroke
			(width 0.2)
			(type default)
		)
		(fill no)
		(layer "In5.Cu")
	)
	(gr_circle
		(center 95.36303 -180.627274)
		(end 96.25203 -180.627274)
		(stroke
			(width 0.2)
			(type default)
		)
		(fill no)
		(layer "In5.Cu")
	)
	(gr_circle
		(center 95.36303 -179.890674)
		(end 96.25203 -179.890674)
		(stroke
			(width 0.2)
			(type default)
		)
		(fill no)
		(layer "In5.Cu")
	)
	(gr_circle
		(center 95.36303 -179.154074)
		(end 96.25203 -179.154074)
		(stroke
			(width 0.2)
			(type default)
		)
		(fill no)
		(layer "In5.Cu")
	)
	(gr_circle
		(center 95.89643 -179.509674)
		(end 96.78543 -179.509674)
		(stroke
			(width 0.2)
			(type default)
		)
		(fill no)
		(layer "In5.Cu")
	)
	(gr_circle
		(center 95.92183 -180.271674)
		(end 96.81083 -180.271674)
		(stroke
			(width 0.2)
			(type default)
		)
		(fill no)
		(layer "In5.Cu")
	)
	(gr_circle
		(center 96.144334 -337.017614)
		(end 97.024444 -337.017614)
		(stroke
			(width 0.2)
			(type default)
		)
		(fill no)
		(layer "In5.Cu")
	)
	(gr_circle
		(center 96.446594 -179.832254)
		(end 97.335594 -179.832254)
		(stroke
			(width 0.2)
			(type default)
		)
		(fill no)
		(layer "In5.Cu")
	)
	(gr_circle
		(center 96.446594 -179.095654)
		(end 97.335594 -179.095654)
		(stroke
			(width 0.2)
			(type default)
		)
		(fill no)
		(layer "In5.Cu")
	)
	(gr_circle
		(center 96.761554 -337.017614)
		(end 97.641664 -337.017614)
		(stroke
			(width 0.2)
			(type default)
		)
		(fill no)
		(layer "In5.Cu")
	)
	(gr_circle
		(center 96.980248 -182.13324)
		(end 97.869248 -182.13324)
		(stroke
			(width 0.2)
			(type default)
		)
		(fill no)
		(layer "In5.Cu")
	)
	(gr_circle
		(center 96.980248 -181.39664)
		(end 97.869248 -181.39664)
		(stroke
			(width 0.2)
			(type default)
		)
		(fill no)
		(layer "In5.Cu")
	)
	(gr_circle
		(center 97.14865 -180.704744)
		(end 98.02876 -180.704744)
		(stroke
			(width 0.2)
			(type default)
		)
		(fill no)
		(layer "In5.Cu")
	)
	(gr_circle
		(center 97.378774 -337.017614)
		(end 98.258884 -337.017614)
		(stroke
			(width 0.2)
			(type default)
		)
		(fill no)
		(layer "In5.Cu")
	)
	(gr_circle
		(center 97.658174 -336.319368)
		(end 98.538284 -336.319368)
		(stroke
			(width 0.2)
			(type default)
		)
		(fill no)
		(layer "In5.Cu")
	)
	(gr_circle
		(center 97.658174 -335.582768)
		(end 98.538284 -335.582768)
		(stroke
			(width 0.2)
			(type default)
		)
		(fill no)
		(layer "In5.Cu")
	)
	(gr_circle
		(center 97.76587 -180.704744)
		(end 98.64598 -180.704744)
		(stroke
			(width 0.2)
			(type default)
		)
		(fill no)
		(layer "In5.Cu")
	)
	(gr_circle
		(center 98.08083 -338.626704)
		(end 98.96983 -338.626704)
		(stroke
			(width 0.2)
			(type default)
		)
		(fill no)
		(layer "In5.Cu")
	)
	(gr_circle
		(center 98.08083 -337.890104)
		(end 98.96983 -337.890104)
		(stroke
			(width 0.2)
			(type default)
		)
		(fill no)
		(layer "In5.Cu")
	)
	(gr_circle
		(center 98.199194 -339.358224)
		(end 99.088194 -339.358224)
		(stroke
			(width 0.2)
			(type default)
		)
		(fill no)
		(layer "In5.Cu")
	)
	(gr_circle
		(center 98.38309 -180.704744)
		(end 99.2632 -180.704744)
		(stroke
			(width 0.2)
			(type default)
		)
		(fill no)
		(layer "In5.Cu")
	)
	(gr_circle
		(center 98.605594 -337.450684)
		(end 99.494594 -337.450684)
		(stroke
			(width 0.2)
			(type default)
		)
		(fill no)
		(layer "In5.Cu")
	)
	(gr_circle
		(center 98.630994 -338.212684)
		(end 99.519994 -338.212684)
		(stroke
			(width 0.2)
			(type default)
		)
		(fill no)
		(layer "In5.Cu")
	)
	(gr_circle
		(center 98.747834 -339.736684)
		(end 99.636834 -339.736684)
		(stroke
			(width 0.2)
			(type default)
		)
		(fill no)
		(layer "In5.Cu")
	)
	(gr_circle
		(center 98.747834 -338.974684)
		(end 99.636834 -338.974684)
		(stroke
			(width 0.2)
			(type default)
		)
		(fill no)
		(layer "In5.Cu")
	)
	(gr_circle
		(center 103.74503 -176.106074)
		(end 104.63403 -176.106074)
		(stroke
			(width 0.2)
			(type default)
		)
		(fill no)
		(layer "In5.Cu")
	)
	(gr_circle
		(center 103.74503 -175.369474)
		(end 104.63403 -175.369474)
		(stroke
			(width 0.2)
			(type default)
		)
		(fill no)
		(layer "In5.Cu")
	)
	(gr_circle
		(center 103.74503 -174.632874)
		(end 104.63403 -174.632874)
		(stroke
			(width 0.2)
			(type default)
		)
		(fill no)
		(layer "In5.Cu")
	)
	(gr_circle
		(center 104.27843 -174.988474)
		(end 105.16743 -174.988474)
		(stroke
			(width 0.2)
			(type default)
		)
		(fill no)
		(layer "In5.Cu")
	)
	(gr_circle
		(center 104.30383 -175.750474)
		(end 105.19283 -175.750474)
		(stroke
			(width 0.2)
			(type default)
		)
		(fill no)
		(layer "In5.Cu")
	)
	(gr_circle
		(center 104.420162 -341.927688)
		(end 105.300272 -341.927688)
		(stroke
			(width 0.2)
			(type default)
		)
		(fill no)
		(layer "In5.Cu")
	)
	(gr_circle
		(center 104.828594 -175.311054)
		(end 105.717594 -175.311054)
		(stroke
			(width 0.2)
			(type default)
		)
		(fill no)
		(layer "In5.Cu")
	)
	(gr_circle
		(center 104.828594 -174.574454)
		(end 105.717594 -174.574454)
		(stroke
			(width 0.2)
			(type default)
		)
		(fill no)
		(layer "In5.Cu")
	)
	(gr_circle
		(center 105.037382 -341.927688)
		(end 105.917492 -341.927688)
		(stroke
			(width 0.2)
			(type default)
		)
		(fill no)
		(layer "In5.Cu")
	)
	(gr_circle
		(center 105.336848 -177.65776)
		(end 106.225848 -177.65776)
		(stroke
			(width 0.2)
			(type default)
		)
		(fill no)
		(layer "In5.Cu")
	)
	(gr_circle
		(center 105.336848 -176.92116)
		(end 106.225848 -176.92116)
		(stroke
			(width 0.2)
			(type default)
		)
		(fill no)
		(layer "In5.Cu")
	)
	(gr_circle
		(center 105.53065 -176.183544)
		(end 106.41076 -176.183544)
		(stroke
			(width 0.2)
			(type default)
		)
		(fill no)
		(layer "In5.Cu")
	)
	(gr_circle
		(center 105.654602 -341.927688)
		(end 106.534712 -341.927688)
		(stroke
			(width 0.2)
			(type default)
		)
		(fill no)
		(layer "In5.Cu")
	)
	(gr_circle
		(center 105.934002 -341.229442)
		(end 106.814112 -341.229442)
		(stroke
			(width 0.2)
			(type default)
		)
		(fill no)
		(layer "In5.Cu")
	)
	(gr_circle
		(center 105.934002 -340.492842)
		(end 106.814112 -340.492842)
		(stroke
			(width 0.2)
			(type default)
		)
		(fill no)
		(layer "In5.Cu")
	)
	(gr_circle
		(center 106.14787 -176.183544)
		(end 107.02798 -176.183544)
		(stroke
			(width 0.2)
			(type default)
		)
		(fill no)
		(layer "In5.Cu")
	)
	(gr_circle
		(center 106.34345 -343.450164)
		(end 107.23245 -343.450164)
		(stroke
			(width 0.2)
			(type default)
		)
		(fill no)
		(layer "In5.Cu")
	)
	(gr_circle
		(center 106.34345 -342.713564)
		(end 107.23245 -342.713564)
		(stroke
			(width 0.2)
			(type default)
		)
		(fill no)
		(layer "In5.Cu")
	)
	(gr_circle
		(center 106.76509 -176.183544)
		(end 107.6452 -176.183544)
		(stroke
			(width 0.2)
			(type default)
		)
		(fill no)
		(layer "In5.Cu")
	)
	(gr_circle
		(center 106.98607 -342.540844)
		(end 107.87507 -342.540844)
		(stroke
			(width 0.2)
			(type default)
		)
		(fill no)
		(layer "In5.Cu")
	)
	(gr_circle
		(center 106.98607 -341.804244)
		(end 107.87507 -341.804244)
		(stroke
			(width 0.2)
			(type default)
		)
		(fill no)
		(layer "In5.Cu")
	)
	(gr_circle
		(center 107.01401 -343.986104)
		(end 107.90301 -343.986104)
		(stroke
			(width 0.2)
			(type default)
		)
		(fill no)
		(layer "In5.Cu")
	)
	(gr_circle
		(center 107.01401 -343.249504)
		(end 107.90301 -343.249504)
		(stroke
			(width 0.2)
			(type default)
		)
		(fill no)
		(layer "In5.Cu")
	)
	(gr_circle
		(center 110.140496 -150.941786)
		(end 111.537496 -150.941786)
		(stroke
			(width 0.2)
			(type default)
		)
		(fill no)
		(layer "In5.Cu")
	)
	(gr_circle
		(center 111.97463 -169.857674)
		(end 112.86363 -169.857674)
		(stroke
			(width 0.2)
			(type default)
		)
		(fill no)
		(layer "In5.Cu")
	)
	(gr_circle
		(center 111.97463 -169.121074)
		(end 112.86363 -169.121074)
		(stroke
			(width 0.2)
			(type default)
		)
		(fill no)
		(layer "In5.Cu")
	)
	(gr_circle
		(center 111.97463 -168.384474)
		(end 112.86363 -168.384474)
		(stroke
			(width 0.2)
			(type default)
		)
		(fill no)
		(layer "In5.Cu")
	)
	(gr_circle
		(center 112.50803 -168.740074)
		(end 113.39703 -168.740074)
		(stroke
			(width 0.2)
			(type default)
		)
		(fill no)
		(layer "In5.Cu")
	)
	(gr_circle
		(center 112.53343 -169.502074)
		(end 113.42243 -169.502074)
		(stroke
			(width 0.2)
			(type default)
		)
		(fill no)
		(layer "In5.Cu")
	)
	(gr_circle
		(center 113.058194 -169.062654)
		(end 113.947194 -169.062654)
		(stroke
			(width 0.2)
			(type default)
		)
		(fill no)
		(layer "In5.Cu")
	)
	(gr_circle
		(center 113.058194 -168.326054)
		(end 113.947194 -168.326054)
		(stroke
			(width 0.2)
			(type default)
		)
		(fill no)
		(layer "In5.Cu")
	)
	(gr_circle
		(center 113.591848 -171.33316)
		(end 114.480848 -171.33316)
		(stroke
			(width 0.2)
			(type default)
		)
		(fill no)
		(layer "In5.Cu")
	)
	(gr_circle
		(center 113.591848 -170.59656)
		(end 114.480848 -170.59656)
		(stroke
			(width 0.2)
			(type default)
		)
		(fill no)
		(layer "In5.Cu")
	)
	(gr_circle
		(center 113.76025 -169.935144)
		(end 114.64036 -169.935144)
		(stroke
			(width 0.2)
			(type default)
		)
		(fill no)
		(layer "In5.Cu")
	)
	(gr_circle
		(center 114.37747 -169.935144)
		(end 115.25758 -169.935144)
		(stroke
			(width 0.2)
			(type default)
		)
		(fill no)
		(layer "In5.Cu")
	)
	(gr_circle
		(center 114.99469 -169.935144)
		(end 115.8748 -169.935144)
		(stroke
			(width 0.2)
			(type default)
		)
		(fill no)
		(layer "In5.Cu")
	)
	(gr_circle
		(center 116.258594 -152.657556)
		(end 117.147594 -152.657556)
		(stroke
			(width 0.2)
			(type default)
		)
		(fill no)
		(layer "In5.Cu")
	)
	(gr_circle
		(center 116.258594 -152.022556)
		(end 117.147594 -152.022556)
		(stroke
			(width 0.2)
			(type default)
		)
		(fill no)
		(layer "In5.Cu")
	)
	(gr_circle
		(center 116.893594 -152.657556)
		(end 117.782594 -152.657556)
		(stroke
			(width 0.2)
			(type default)
		)
		(fill no)
		(layer "In5.Cu")
	)
	(gr_circle
		(center 116.893594 -152.022556)
		(end 117.782594 -152.022556)
		(stroke
			(width 0.2)
			(type default)
		)
		(fill no)
		(layer "In5.Cu")
	)
	(gr_circle
		(center 117.559074 -152.657556)
		(end 118.448074 -152.657556)
		(stroke
			(width 0.2)
			(type default)
		)
		(fill no)
		(layer "In5.Cu")
	)
	(gr_circle
		(center 117.559074 -152.022556)
		(end 118.448074 -152.022556)
		(stroke
			(width 0.2)
			(type default)
		)
		(fill no)
		(layer "In5.Cu")
	)
	(gr_circle
		(center 118.194074 -152.657556)
		(end 119.083074 -152.657556)
		(stroke
			(width 0.2)
			(type default)
		)
		(fill no)
		(layer "In5.Cu")
	)
	(gr_circle
		(center 118.194074 -152.022556)
		(end 119.083074 -152.022556)
		(stroke
			(width 0.2)
			(type default)
		)
		(fill no)
		(layer "In5.Cu")
	)
	(gr_circle
		(center 118.829074 -152.657556)
		(end 119.718074 -152.657556)
		(stroke
			(width 0.2)
			(type default)
		)
		(fill no)
		(layer "In5.Cu")
	)
	(gr_circle
		(center 118.829074 -152.022556)
		(end 119.718074 -152.022556)
		(stroke
			(width 0.2)
			(type default)
		)
		(fill no)
		(layer "In5.Cu")
	)
	(gr_circle
		(center 119.464074 -152.657556)
		(end 120.353074 -152.657556)
		(stroke
			(width 0.2)
			(type default)
		)
		(fill no)
		(layer "In5.Cu")
	)
	(gr_circle
		(center 119.464074 -152.022556)
		(end 120.353074 -152.022556)
		(stroke
			(width 0.2)
			(type default)
		)
		(fill no)
		(layer "In5.Cu")
	)
	(gr_circle
		(center 120.25503 -163.126674)
		(end 121.14403 -163.126674)
		(stroke
			(width 0.2)
			(type default)
		)
		(fill no)
		(layer "In5.Cu")
	)
	(gr_circle
		(center 120.25503 -162.390074)
		(end 121.14403 -162.390074)
		(stroke
			(width 0.2)
			(type default)
		)
		(fill no)
		(layer "In5.Cu")
	)
	(gr_circle
		(center 120.25503 -161.653474)
		(end 121.14403 -161.653474)
		(stroke
			(width 0.2)
			(type default)
		)
		(fill no)
		(layer "In5.Cu")
	)
	(gr_circle
		(center 120.78843 -162.009074)
		(end 121.67743 -162.009074)
		(stroke
			(width 0.2)
			(type default)
		)
		(fill no)
		(layer "In5.Cu")
	)
	(gr_circle
		(center 120.81383 -162.771074)
		(end 121.70283 -162.771074)
		(stroke
			(width 0.2)
			(type default)
		)
		(fill no)
		(layer "In5.Cu")
	)
	(gr_circle
		(center 121.338594 -162.331654)
		(end 122.227594 -162.331654)
		(stroke
			(width 0.2)
			(type default)
		)
		(fill no)
		(layer "In5.Cu")
	)
	(gr_circle
		(center 121.338594 -161.595054)
		(end 122.227594 -161.595054)
		(stroke
			(width 0.2)
			(type default)
		)
		(fill no)
		(layer "In5.Cu")
	)
	(gr_circle
		(center 121.872248 -164.62756)
		(end 122.761248 -164.62756)
		(stroke
			(width 0.2)
			(type default)
		)
		(fill no)
		(layer "In5.Cu")
	)
	(gr_circle
		(center 121.872248 -163.89096)
		(end 122.761248 -163.89096)
		(stroke
			(width 0.2)
			(type default)
		)
		(fill no)
		(layer "In5.Cu")
	)
	(gr_circle
		(center 122.04065 -163.204144)
		(end 122.92076 -163.204144)
		(stroke
			(width 0.2)
			(type default)
		)
		(fill no)
		(layer "In5.Cu")
	)
	(gr_circle
		(center 122.65787 -163.204144)
		(end 123.53798 -163.204144)
		(stroke
			(width 0.2)
			(type default)
		)
		(fill no)
		(layer "In5.Cu")
	)
	(gr_circle
		(center 123.27509 -163.204144)
		(end 124.1552 -163.204144)
		(stroke
			(width 0.2)
			(type default)
		)
		(fill no)
		(layer "In5.Cu")
	)
	(gr_arc
		(start 124.102114 -11.780012)
		(mid 125.516325 -11.194227)
		(end 126.10211 -9.780016)
		(stroke
			(width 1.016)
			(type default)
		)
		(layer "In5.Cu")
	)
	(gr_line
		(start 126.10211 -9.780016)
		(end 126.10211 -5.780024)
		(stroke
			(width 1.016)
			(type default)
		)
		(layer "In5.Cu")
	)
	(gr_arc
		(start 126.601982 -5.279898)
		(mid 126.248489 -5.42646)
		(end 126.10211 -5.780024)
		(stroke
			(width 1.016)
			(type default)
		)
		(layer "In5.Cu")
	)
	(gr_line
		(start 126.601982 -5.279898)
		(end 194.20205 -5.279898)
		(stroke
			(width 1.016)
			(type default)
		)
		(layer "In5.Cu")
	)
	(gr_circle
		(center 128.71323 -154.465274)
		(end 129.60223 -154.465274)
		(stroke
			(width 0.2)
			(type default)
		)
		(fill no)
		(layer "In5.Cu")
	)
	(gr_circle
		(center 128.71323 -153.728674)
		(end 129.60223 -153.728674)
		(stroke
			(width 0.2)
			(type default)
		)
		(fill no)
		(layer "In5.Cu")
	)
	(gr_circle
		(center 128.71323 -152.992074)
		(end 129.60223 -152.992074)
		(stroke
			(width 0.2)
			(type default)
		)
		(fill no)
		(layer "In5.Cu")
	)
	(gr_circle
		(center 129.24663 -153.347674)
		(end 130.13563 -153.347674)
		(stroke
			(width 0.2)
			(type default)
		)
		(fill no)
		(layer "In5.Cu")
	)
	(gr_circle
		(center 129.27203 -154.109674)
		(end 130.16103 -154.109674)
		(stroke
			(width 0.2)
			(type default)
		)
		(fill no)
		(layer "In5.Cu")
	)
	(gr_circle
		(center 129.796794 -153.670254)
		(end 130.685794 -153.670254)
		(stroke
			(width 0.2)
			(type default)
		)
		(fill no)
		(layer "In5.Cu")
	)
	(gr_circle
		(center 129.796794 -152.933654)
		(end 130.685794 -152.933654)
		(stroke
			(width 0.2)
			(type default)
		)
		(fill no)
		(layer "In5.Cu")
	)
	(gr_circle
		(center 130.305048 -155.94076)
		(end 131.194048 -155.94076)
		(stroke
			(width 0.2)
			(type default)
		)
		(fill no)
		(layer "In5.Cu")
	)
	(gr_circle
		(center 130.305048 -155.20416)
		(end 131.194048 -155.20416)
		(stroke
			(width 0.2)
			(type default)
		)
		(fill no)
		(layer "In5.Cu")
	)
	(gr_circle
		(center 130.49885 -154.542744)
		(end 131.37896 -154.542744)
		(stroke
			(width 0.2)
			(type default)
		)
		(fill no)
		(layer "In5.Cu")
	)
	(gr_circle
		(center 131.11607 -154.542744)
		(end 131.99618 -154.542744)
		(stroke
			(width 0.2)
			(type default)
		)
		(fill no)
		(layer "In5.Cu")
	)
	(gr_circle
		(center 131.73329 -154.542744)
		(end 132.6134 -154.542744)
		(stroke
			(width 0.2)
			(type default)
		)
		(fill no)
		(layer "In5.Cu")
	)
	(gr_circle
		(center 176.332134 -26.634948)
		(end 177.221134 -26.634948)
		(stroke
			(width 0.2)
			(type default)
		)
		(fill no)
		(layer "In5.Cu")
	)
	(gr_circle
		(center 176.713134 -25.949148)
		(end 177.602134 -25.949148)
		(stroke
			(width 0.2)
			(type default)
		)
		(fill no)
		(layer "In5.Cu")
	)
	(gr_circle
		(center 176.878234 -19.942048)
		(end 177.767234 -19.942048)
		(stroke
			(width 0.2)
			(type default)
		)
		(fill no)
		(layer "In5.Cu")
	)
	(gr_circle
		(center 176.968912 -21.349208)
		(end 177.857912 -21.349208)
		(stroke
			(width 0.2)
			(type default)
		)
		(fill no)
		(layer "In5.Cu")
	)
	(gr_circle
		(center 176.968912 -20.714208)
		(end 177.857912 -20.714208)
		(stroke
			(width 0.2)
			(type default)
		)
		(fill no)
		(layer "In5.Cu")
	)
	(gr_circle
		(center 177.221134 -26.634948)
		(end 178.110134 -26.634948)
		(stroke
			(width 0.2)
			(type default)
		)
		(fill no)
		(layer "In5.Cu")
	)
	(gr_circle
		(center 177.472594 -21.85289)
		(end 178.361594 -21.85289)
		(stroke
			(width 0.2)
			(type default)
		)
		(fill no)
		(layer "In5.Cu")
	)
	(gr_circle
		(center 177.602134 -25.949148)
		(end 178.491134 -25.949148)
		(stroke
			(width 0.2)
			(type default)
		)
		(fill no)
		(layer "In5.Cu")
	)
	(gr_circle
		(center 178.110134 -26.634948)
		(end 178.999134 -26.634948)
		(stroke
			(width 0.2)
			(type default)
		)
		(fill no)
		(layer "In5.Cu")
	)
	(gr_circle
		(center 178.491134 -25.949148)
		(end 179.380134 -25.949148)
		(stroke
			(width 0.2)
			(type default)
		)
		(fill no)
		(layer "In5.Cu")
	)
	(gr_circle
		(center 179.507134 -25.517348)
		(end 180.396134 -25.517348)
		(stroke
			(width 0.2)
			(type default)
		)
		(fill no)
		(layer "In5.Cu")
	)
	(gr_circle
		(center 180.921914 -27.107388)
		(end 181.810914 -27.107388)
		(stroke
			(width 0.2)
			(type default)
		)
		(fill no)
		(layer "In5.Cu")
	)
	(gr_circle
		(center 183.610758 -353.283774)
		(end 184.490868 -353.283774)
		(stroke
			(width 0.2)
			(type default)
		)
		(fill no)
		(layer "In5.Cu")
	)
	(gr_circle
		(center 184.227978 -353.283774)
		(end 185.108088 -353.283774)
		(stroke
			(width 0.2)
			(type default)
		)
		(fill no)
		(layer "In5.Cu")
	)
	(gr_circle
		(center 184.845198 -353.283774)
		(end 185.725308 -353.283774)
		(stroke
			(width 0.2)
			(type default)
		)
		(fill no)
		(layer "In5.Cu")
	)
	(gr_circle
		(center 184.85612 -403.222714)
		(end 185.74512 -403.222714)
		(stroke
			(width 0.2)
			(type default)
		)
		(fill no)
		(layer "In5.Cu")
	)
	(gr_circle
		(center 184.85612 -401.919694)
		(end 185.74512 -401.919694)
		(stroke
			(width 0.2)
			(type default)
		)
		(fill no)
		(layer "In5.Cu")
	)
	(gr_circle
		(center 184.85612 -400.616674)
		(end 185.74512 -400.616674)
		(stroke
			(width 0.2)
			(type default)
		)
		(fill no)
		(layer "In5.Cu")
	)
	(gr_circle
		(center 184.962292 -352.558604)
		(end 185.851292 -352.558604)
		(stroke
			(width 0.2)
			(type default)
		)
		(fill no)
		(layer "In5.Cu")
	)
	(gr_circle
		(center 184.962292 -351.822004)
		(end 185.851292 -351.822004)
		(stroke
			(width 0.2)
			(type default)
		)
		(fill no)
		(layer "In5.Cu")
	)
	(gr_circle
		(center 185.547254 -354.892864)
		(end 186.436254 -354.892864)
		(stroke
			(width 0.2)
			(type default)
		)
		(fill no)
		(layer "In5.Cu")
	)
	(gr_circle
		(center 185.547254 -354.156264)
		(end 186.436254 -354.156264)
		(stroke
			(width 0.2)
			(type default)
		)
		(fill no)
		(layer "In5.Cu")
	)
	(gr_circle
		(center 185.673492 -408.092402)
		(end 186.562492 -408.092402)
		(stroke
			(width 0.2)
			(type default)
		)
		(fill no)
		(layer "In5.Cu")
	)
	(gr_circle
		(center 185.673492 -407.330402)
		(end 186.562492 -407.330402)
		(stroke
			(width 0.2)
			(type default)
		)
		(fill no)
		(layer "In5.Cu")
	)
	(gr_circle
		(center 185.673492 -406.517602)
		(end 186.562492 -406.517602)
		(stroke
			(width 0.2)
			(type default)
		)
		(fill no)
		(layer "In5.Cu")
	)
	(gr_circle
		(center 185.673492 -405.755602)
		(end 186.562492 -405.755602)
		(stroke
			(width 0.2)
			(type default)
		)
		(fill no)
		(layer "In5.Cu")
	)
	(gr_circle
		(center 185.673492 -404.993602)
		(end 186.562492 -404.993602)
		(stroke
			(width 0.2)
			(type default)
		)
		(fill no)
		(layer "In5.Cu")
	)
	(gr_circle
		(center 186.034172 -362.234988)
		(end 186.923172 -362.234988)
		(stroke
			(width 0.2)
			(type default)
		)
		(fill no)
		(layer "In5.Cu")
	)
	(gr_circle
		(center 186.034172 -361.472988)
		(end 186.923172 -361.472988)
		(stroke
			(width 0.2)
			(type default)
		)
		(fill no)
		(layer "In5.Cu")
	)
	(gr_circle
		(center 186.034172 -360.710988)
		(end 186.923172 -360.710988)
		(stroke
			(width 0.2)
			(type default)
		)
		(fill no)
		(layer "In5.Cu")
	)
	(gr_circle
		(center 186.072018 -353.716844)
		(end 186.961018 -353.716844)
		(stroke
			(width 0.2)
			(type default)
		)
		(fill no)
		(layer "In5.Cu")
	)
	(gr_circle
		(center 186.097418 -354.478844)
		(end 186.986418 -354.478844)
		(stroke
			(width 0.2)
			(type default)
		)
		(fill no)
		(layer "In5.Cu")
	)
	(gr_circle
		(center 186.27852 -403.222714)
		(end 187.16752 -403.222714)
		(stroke
			(width 0.2)
			(type default)
		)
		(fill no)
		(layer "In5.Cu")
	)
	(gr_circle
		(center 186.27852 -400.616674)
		(end 187.16752 -400.616674)
		(stroke
			(width 0.2)
			(type default)
		)
		(fill no)
		(layer "In5.Cu")
	)
	(gr_circle
		(center 186.435492 -408.092402)
		(end 187.324492 -408.092402)
		(stroke
			(width 0.2)
			(type default)
		)
		(fill no)
		(layer "In5.Cu")
	)
	(gr_circle
		(center 186.435492 -407.330402)
		(end 187.324492 -407.330402)
		(stroke
			(width 0.2)
			(type default)
		)
		(fill no)
		(layer "In5.Cu")
	)
	(gr_circle
		(center 186.435492 -406.517602)
		(end 187.324492 -406.517602)
		(stroke
			(width 0.2)
			(type default)
		)
		(fill no)
		(layer "In5.Cu")
	)
	(gr_circle
		(center 186.435492 -405.755602)
		(end 187.324492 -405.755602)
		(stroke
			(width 0.2)
			(type default)
		)
		(fill no)
		(layer "In5.Cu")
	)
	(gr_circle
		(center 186.435492 -404.993602)
		(end 187.324492 -404.993602)
		(stroke
			(width 0.2)
			(type default)
		)
		(fill no)
		(layer "In5.Cu")
	)
	(gr_circle
		(center 186.630818 -354.834444)
		(end 187.519818 -354.834444)
		(stroke
			(width 0.2)
			(type default)
		)
		(fill no)
		(layer "In5.Cu")
	)
	(gr_circle
		(center 186.630818 -354.097844)
		(end 187.519818 -354.097844)
		(stroke
			(width 0.2)
			(type default)
		)
		(fill no)
		(layer "In5.Cu")
	)
	(gr_circle
		(center 186.630818 -353.361244)
		(end 187.519818 -353.361244)
		(stroke
			(width 0.2)
			(type default)
		)
		(fill no)
		(layer "In5.Cu")
	)
	(gr_circle
		(center 186.796172 -362.234988)
		(end 187.685172 -362.234988)
		(stroke
			(width 0.2)
			(type default)
		)
		(fill no)
		(layer "In5.Cu")
	)
	(gr_circle
		(center 186.796172 -361.472988)
		(end 187.685172 -361.472988)
		(stroke
			(width 0.2)
			(type default)
		)
		(fill no)
		(layer "In5.Cu")
	)
	(gr_circle
		(center 186.796172 -360.710988)
		(end 187.685172 -360.710988)
		(stroke
			(width 0.2)
			(type default)
		)
		(fill no)
		(layer "In5.Cu")
	)
	(gr_circle
		(center 187.197492 -408.092402)
		(end 188.086492 -408.092402)
		(stroke
			(width 0.2)
			(type default)
		)
		(fill no)
		(layer "In5.Cu")
	)
	(gr_circle
		(center 187.197492 -407.330402)
		(end 188.086492 -407.330402)
		(stroke
			(width 0.2)
			(type default)
		)
		(fill no)
		(layer "In5.Cu")
	)
	(gr_circle
		(center 187.197492 -406.517602)
		(end 188.086492 -406.517602)
		(stroke
			(width 0.2)
			(type default)
		)
		(fill no)
		(layer "In5.Cu")
	)
	(gr_circle
		(center 187.197492 -405.755602)
		(end 188.086492 -405.755602)
		(stroke
			(width 0.2)
			(type default)
		)
		(fill no)
		(layer "In5.Cu")
	)
	(gr_circle
		(center 187.197492 -404.993602)
		(end 188.086492 -404.993602)
		(stroke
			(width 0.2)
			(type default)
		)
		(fill no)
		(layer "In5.Cu")
	)
	(gr_circle
		(center 187.67552 -403.222714)
		(end 188.56452 -403.222714)
		(stroke
			(width 0.2)
			(type default)
		)
		(fill no)
		(layer "In5.Cu")
	)
	(gr_circle
		(center 187.67552 -401.919694)
		(end 188.56452 -401.919694)
		(stroke
			(width 0.2)
			(type default)
		)
		(fill no)
		(layer "In5.Cu")
	)
	(gr_circle
		(center 187.67552 -400.616674)
		(end 188.56452 -400.616674)
		(stroke
			(width 0.2)
			(type default)
		)
		(fill no)
		(layer "In5.Cu")
	)
	(gr_circle
		(center 187.959492 -408.092402)
		(end 188.848492 -408.092402)
		(stroke
			(width 0.2)
			(type default)
		)
		(fill no)
		(layer "In5.Cu")
	)
	(gr_circle
		(center 187.959492 -407.330402)
		(end 188.848492 -407.330402)
		(stroke
			(width 0.2)
			(type default)
		)
		(fill no)
		(layer "In5.Cu")
	)
	(gr_circle
		(center 187.959492 -406.517602)
		(end 188.848492 -406.517602)
		(stroke
			(width 0.2)
			(type default)
		)
		(fill no)
		(layer "In5.Cu")
	)
	(gr_circle
		(center 187.959492 -405.755602)
		(end 188.848492 -405.755602)
		(stroke
			(width 0.2)
			(type default)
		)
		(fill no)
		(layer "In5.Cu")
	)
	(gr_circle
		(center 187.959492 -404.993602)
		(end 188.848492 -404.993602)
		(stroke
			(width 0.2)
			(type default)
		)
		(fill no)
		(layer "In5.Cu")
	)
	(gr_circle
		(center 188.721492 -408.092402)
		(end 189.610492 -408.092402)
		(stroke
			(width 0.2)
			(type default)
		)
		(fill no)
		(layer "In5.Cu")
	)
	(gr_circle
		(center 188.721492 -407.330402)
		(end 189.610492 -407.330402)
		(stroke
			(width 0.2)
			(type default)
		)
		(fill no)
		(layer "In5.Cu")
	)
	(gr_circle
		(center 188.721492 -406.517602)
		(end 189.610492 -406.517602)
		(stroke
			(width 0.2)
			(type default)
		)
		(fill no)
		(layer "In5.Cu")
	)
	(gr_circle
		(center 188.721492 -405.755602)
		(end 189.610492 -405.755602)
		(stroke
			(width 0.2)
			(type default)
		)
		(fill no)
		(layer "In5.Cu")
	)
	(gr_circle
		(center 188.721492 -404.993602)
		(end 189.610492 -404.993602)
		(stroke
			(width 0.2)
			(type default)
		)
		(fill no)
		(layer "In5.Cu")
	)
	(gr_circle
		(center 189.483492 -408.092402)
		(end 190.372492 -408.092402)
		(stroke
			(width 0.2)
			(type default)
		)
		(fill no)
		(layer "In5.Cu")
	)
	(gr_circle
		(center 189.483492 -407.330402)
		(end 190.372492 -407.330402)
		(stroke
			(width 0.2)
			(type default)
		)
		(fill no)
		(layer "In5.Cu")
	)
	(gr_circle
		(center 189.483492 -406.517602)
		(end 190.372492 -406.517602)
		(stroke
			(width 0.2)
			(type default)
		)
		(fill no)
		(layer "In5.Cu")
	)
	(gr_circle
		(center 189.483492 -405.755602)
		(end 190.372492 -405.755602)
		(stroke
			(width 0.2)
			(type default)
		)
		(fill no)
		(layer "In5.Cu")
	)
	(gr_circle
		(center 189.483492 -404.993602)
		(end 190.372492 -404.993602)
		(stroke
			(width 0.2)
			(type default)
		)
		(fill no)
		(layer "In5.Cu")
	)
	(gr_circle
		(center 190.508636 -23.593552)
		(end 191.397636 -23.593552)
		(stroke
			(width 0.2)
			(type default)
		)
		(fill no)
		(layer "In5.Cu")
	)
	(gr_circle
		(center 190.508636 -22.856952)
		(end 191.397636 -22.856952)
		(stroke
			(width 0.2)
			(type default)
		)
		(fill no)
		(layer "In5.Cu")
	)
	(gr_circle
		(center 191.67983 -362.430568)
		(end 193.07683 -362.430568)
		(stroke
			(width 0.2)
			(type default)
		)
		(fill no)
		(layer "In5.Cu")
	)
	(gr_circle
		(center 191.927734 -13.106908)
		(end 192.816734 -13.106908)
		(stroke
			(width 0.2)
			(type default)
		)
		(fill no)
		(layer "In5.Cu")
	)
	(gr_circle
		(center 191.937386 -353.309174)
		(end 192.817496 -353.309174)
		(stroke
			(width 0.2)
			(type default)
		)
		(fill no)
		(layer "In5.Cu")
	)
	(gr_circle
		(center 192.461134 -16.416528)
		(end 193.350134 -16.416528)
		(stroke
			(width 0.2)
			(type default)
		)
		(fill no)
		(layer "In5.Cu")
	)
	(gr_circle
		(center 192.461134 -15.781528)
		(end 193.350134 -15.781528)
		(stroke
			(width 0.2)
			(type default)
		)
		(fill no)
		(layer "In5.Cu")
	)
	(gr_circle
		(center 192.554606 -353.309174)
		(end 193.434716 -353.309174)
		(stroke
			(width 0.2)
			(type default)
		)
		(fill no)
		(layer "In5.Cu")
	)
	(gr_circle
		(center 192.689734 -13.106908)
		(end 193.578734 -13.106908)
		(stroke
			(width 0.2)
			(type default)
		)
		(fill no)
		(layer "In5.Cu")
	)
	(gr_circle
		(center 193.096134 -16.416528)
		(end 193.985134 -16.416528)
		(stroke
			(width 0.2)
			(type default)
		)
		(fill no)
		(layer "In5.Cu")
	)
	(gr_circle
		(center 193.096134 -15.781528)
		(end 193.985134 -15.781528)
		(stroke
			(width 0.2)
			(type default)
		)
		(fill no)
		(layer "In5.Cu")
	)
	(gr_circle
		(center 193.171826 -353.309174)
		(end 194.051936 -353.309174)
		(stroke
			(width 0.2)
			(type default)
		)
		(fill no)
		(layer "In5.Cu")
	)
	(gr_circle
		(center 193.28892 -352.563684)
		(end 194.17792 -352.563684)
		(stroke
			(width 0.2)
			(type default)
		)
		(fill no)
		(layer "In5.Cu")
	)
	(gr_circle
		(center 193.28892 -351.827084)
		(end 194.17792 -351.827084)
		(stroke
			(width 0.2)
			(type default)
		)
		(fill no)
		(layer "In5.Cu")
	)
	(gr_circle
		(center 193.731134 -15.781528)
		(end 194.620134 -15.781528)
		(stroke
			(width 0.2)
			(type default)
		)
		(fill no)
		(layer "In5.Cu")
	)
	(gr_circle
		(center 193.858134 -16.543528)
		(end 194.747134 -16.543528)
		(stroke
			(width 0.2)
			(type default)
		)
		(fill no)
		(layer "In5.Cu")
	)
	(gr_circle
		(center 193.873882 -354.918264)
		(end 194.762882 -354.918264)
		(stroke
			(width 0.2)
			(type default)
		)
		(fill no)
		(layer "In5.Cu")
	)
	(gr_circle
		(center 193.873882 -354.181664)
		(end 194.762882 -354.181664)
		(stroke
			(width 0.2)
			(type default)
		)
		(fill no)
		(layer "In5.Cu")
	)
	(gr_circle
		(center 194.398646 -353.742244)
		(end 195.287646 -353.742244)
		(stroke
			(width 0.2)
			(type default)
		)
		(fill no)
		(layer "In5.Cu")
	)
	(gr_circle
		(center 194.424046 -354.504244)
		(end 195.313046 -354.504244)
		(stroke
			(width 0.2)
			(type default)
		)
		(fill no)
		(layer "In5.Cu")
	)
	(gr_line
		(start 194.505072 -441.989972)
		(end 8.50011 -441.989972)
		(stroke
			(width 1.016)
			(type default)
		)
		(layer "In5.Cu")
	)
	(gr_arc
		(start 194.505072 -441.989972)
		(mid 194.858553 -441.843573)
		(end 195.004944 -441.4901)
		(stroke
			(width 1.016)
			(type default)
		)
		(layer "In5.Cu")
	)
	(gr_arc
		(start 194.701922 -9.780016)
		(mid 195.287707 -11.194227)
		(end 196.701918 -11.780012)
		(stroke
			(width 1.016)
			(type default)
		)
		(layer "In5.Cu")
	)
	(gr_arc
		(start 194.701922 -5.780024)
		(mid 194.555654 -5.42634)
		(end 194.20205 -5.279898)
		(stroke
			(width 1.016)
			(type default)
		)
		(layer "In5.Cu")
	)
	(gr_line
		(start 194.701922 -5.780024)
		(end 194.701922 -9.780016)
		(stroke
			(width 1.016)
			(type default)
		)
		(layer "In5.Cu")
	)
	(gr_line
		(start 194.9069 -420.700454)
		(end 194.9069 -413.816038)
		(stroke
			(width 0.635)
			(type default)
		)
		(layer "In5.Cu")
	)
	(gr_arc
		(start 194.9069 -420.700454)
		(mid 194.935087 -420.841508)
		(end 195.015104 -420.961058)
		(stroke
			(width 0.635)
			(type default)
		)
		(layer "In5.Cu")
	)
	(gr_line
		(start 194.9069 -413.816038)
		(end 195.79209 -412.930848)
		(stroke
			(width 0.635)
			(type default)
		)
		(layer "In5.Cu")
	)
	(gr_circle
		(center 194.957446 -354.859844)
		(end 195.846446 -354.859844)
		(stroke
			(width 0.2)
			(type default)
		)
		(fill no)
		(layer "In5.Cu")
	)
	(gr_circle
		(center 194.957446 -354.123244)
		(end 195.846446 -354.123244)
		(stroke
			(width 0.2)
			(type default)
		)
		(fill no)
		(layer "In5.Cu")
	)
	(gr_circle
		(center 194.957446 -353.386644)
		(end 195.846446 -353.386644)
		(stroke
			(width 0.2)
			(type default)
		)
		(fill no)
		(layer "In5.Cu")
	)
	(gr_line
		(start 195.004944 -441.17006)
		(end 195.004944 -441.4901)
		(stroke
			(width 1.016)
			(type default)
		)
		(layer "In5.Cu")
	)
	(gr_line
		(start 195.015104 -420.961058)
		(end 205.73746 -431.683414)
		(stroke
			(width 0.635)
			(type default)
		)
		(layer "In5.Cu")
	)
	(gr_arc
		(start 195.50507 -440.669934)
		(mid 195.151428 -440.816418)
		(end 195.004944 -441.17006)
		(stroke
			(width 1.016)
			(type default)
		)
		(layer "In5.Cu")
	)
	(gr_line
		(start 195.79209 -412.930848)
		(end 226.92741 -412.930848)
		(stroke
			(width 0.635)
			(type default)
		)
		(layer "In5.Cu")
	)
	(gr_line
		(start 196.701918 -11.780012)
		(end 221.30004 -11.780012)
		(stroke
			(width 1.016)
			(type default)
		)
		(layer "In5.Cu")
	)
	(gr_circle
		(center 197.2437 -408.059382)
		(end 198.1327 -408.059382)
		(stroke
			(width 0.2)
			(type default)
		)
		(fill no)
		(layer "In5.Cu")
	)
	(gr_circle
		(center 197.2437 -407.297382)
		(end 198.1327 -407.297382)
		(stroke
			(width 0.2)
			(type default)
		)
		(fill no)
		(layer "In5.Cu")
	)
	(gr_circle
		(center 197.2437 -406.535382)
		(end 198.1327 -406.535382)
		(stroke
			(width 0.2)
			(type default)
		)
		(fill no)
		(layer "In5.Cu")
	)
	(gr_circle
		(center 197.2437 -405.773382)
		(end 198.1327 -405.773382)
		(stroke
			(width 0.2)
			(type default)
		)
		(fill no)
		(layer "In5.Cu")
	)
	(gr_circle
		(center 197.2437 -405.011382)
		(end 198.1327 -405.011382)
		(stroke
			(width 0.2)
			(type default)
		)
		(fill no)
		(layer "In5.Cu")
	)
	(gr_circle
		(center 198.0057 -408.059382)
		(end 198.8947 -408.059382)
		(stroke
			(width 0.2)
			(type default)
		)
		(fill no)
		(layer "In5.Cu")
	)
	(gr_circle
		(center 198.0057 -407.297382)
		(end 198.8947 -407.297382)
		(stroke
			(width 0.2)
			(type default)
		)
		(fill no)
		(layer "In5.Cu")
	)
	(gr_circle
		(center 198.0057 -406.535382)
		(end 198.8947 -406.535382)
		(stroke
			(width 0.2)
			(type default)
		)
		(fill no)
		(layer "In5.Cu")
	)
	(gr_circle
		(center 198.0057 -405.773382)
		(end 198.8947 -405.773382)
		(stroke
			(width 0.2)
			(type default)
		)
		(fill no)
		(layer "In5.Cu")
	)
	(gr_circle
		(center 198.0057 -405.011382)
		(end 198.8947 -405.011382)
		(stroke
			(width 0.2)
			(type default)
		)
		(fill no)
		(layer "In5.Cu")
	)
	(gr_circle
		(center 198.114158 -403.223222)
		(end 199.003158 -403.223222)
		(stroke
			(width 0.2)
			(type default)
		)
		(fill no)
		(layer "In5.Cu")
	)
	(gr_circle
		(center 198.114158 -401.920202)
		(end 199.003158 -401.920202)
		(stroke
			(width 0.2)
			(type default)
		)
		(fill no)
		(layer "In5.Cu")
	)
	(gr_circle
		(center 198.114158 -400.617182)
		(end 199.003158 -400.617182)
		(stroke
			(width 0.2)
			(type default)
		)
		(fill no)
		(layer "In5.Cu")
	)
	(gr_circle
		(center 198.160386 -37.328094)
		(end 199.049386 -37.328094)
		(stroke
			(width 0.2)
			(type default)
		)
		(fill no)
		(layer "In5.Cu")
	)
	(gr_circle
		(center 198.486014 -30.133798)
		(end 199.375014 -30.133798)
		(stroke
			(width 0.2)
			(type default)
		)
		(fill no)
		(layer "In5.Cu")
	)
	(gr_circle
		(center 198.7677 -408.059382)
		(end 199.6567 -408.059382)
		(stroke
			(width 0.2)
			(type default)
		)
		(fill no)
		(layer "In5.Cu")
	)
	(gr_circle
		(center 198.7677 -407.297382)
		(end 199.6567 -407.297382)
		(stroke
			(width 0.2)
			(type default)
		)
		(fill no)
		(layer "In5.Cu")
	)
	(gr_circle
		(center 198.7677 -406.535382)
		(end 199.6567 -406.535382)
		(stroke
			(width 0.2)
			(type default)
		)
		(fill no)
		(layer "In5.Cu")
	)
	(gr_circle
		(center 198.7677 -405.773382)
		(end 199.6567 -405.773382)
		(stroke
			(width 0.2)
			(type default)
		)
		(fill no)
		(layer "In5.Cu")
	)
	(gr_circle
		(center 198.7677 -405.011382)
		(end 199.6567 -405.011382)
		(stroke
			(width 0.2)
			(type default)
		)
		(fill no)
		(layer "In5.Cu")
	)
	(gr_circle
		(center 198.836026 -37.965634)
		(end 199.725026 -37.965634)
		(stroke
			(width 0.2)
			(type default)
		)
		(fill no)
		(layer "In5.Cu")
	)
	(gr_circle
		(center 199.121014 -30.133798)
		(end 200.010014 -30.133798)
		(stroke
			(width 0.2)
			(type default)
		)
		(fill no)
		(layer "In5.Cu")
	)
	(gr_circle
		(center 199.435974 -30.720538)
		(end 200.324974 -30.720538)
		(stroke
			(width 0.2)
			(type default)
		)
		(fill no)
		(layer "In5.Cu")
	)
	(gr_circle
		(center 199.5297 -408.059382)
		(end 200.4187 -408.059382)
		(stroke
			(width 0.2)
			(type default)
		)
		(fill no)
		(layer "In5.Cu")
	)
	(gr_circle
		(center 199.5297 -407.297382)
		(end 200.4187 -407.297382)
		(stroke
			(width 0.2)
			(type default)
		)
		(fill no)
		(layer "In5.Cu")
	)
	(gr_circle
		(center 199.5297 -406.535382)
		(end 200.4187 -406.535382)
		(stroke
			(width 0.2)
			(type default)
		)
		(fill no)
		(layer "In5.Cu")
	)
	(gr_circle
		(center 199.5297 -405.773382)
		(end 200.4187 -405.773382)
		(stroke
			(width 0.2)
			(type default)
		)
		(fill no)
		(layer "In5.Cu")
	)
	(gr_circle
		(center 199.5297 -405.011382)
		(end 200.4187 -405.011382)
		(stroke
			(width 0.2)
			(type default)
		)
		(fill no)
		(layer "In5.Cu")
	)
	(gr_circle
		(center 199.536558 -403.223222)
		(end 200.425558 -403.223222)
		(stroke
			(width 0.2)
			(type default)
		)
		(fill no)
		(layer "In5.Cu")
	)
	(gr_circle
		(center 199.536558 -400.617182)
		(end 200.425558 -400.617182)
		(stroke
			(width 0.2)
			(type default)
		)
		(fill no)
		(layer "In5.Cu")
	)
	(gr_circle
		(center 199.756014 -30.133798)
		(end 200.645014 -30.133798)
		(stroke
			(width 0.2)
			(type default)
		)
		(fill no)
		(layer "In5.Cu")
	)
	(gr_circle
		(center 200.070974 -30.720538)
		(end 200.959974 -30.720538)
		(stroke
			(width 0.2)
			(type default)
		)
		(fill no)
		(layer "In5.Cu")
	)
	(gr_circle
		(center 200.2917 -408.059382)
		(end 201.1807 -408.059382)
		(stroke
			(width 0.2)
			(type default)
		)
		(fill no)
		(layer "In5.Cu")
	)
	(gr_circle
		(center 200.2917 -407.297382)
		(end 201.1807 -407.297382)
		(stroke
			(width 0.2)
			(type default)
		)
		(fill no)
		(layer "In5.Cu")
	)
	(gr_circle
		(center 200.2917 -406.535382)
		(end 201.1807 -406.535382)
		(stroke
			(width 0.2)
			(type default)
		)
		(fill no)
		(layer "In5.Cu")
	)
	(gr_circle
		(center 200.2917 -405.773382)
		(end 201.1807 -405.773382)
		(stroke
			(width 0.2)
			(type default)
		)
		(fill no)
		(layer "In5.Cu")
	)
	(gr_circle
		(center 200.2917 -405.011382)
		(end 201.1807 -405.011382)
		(stroke
			(width 0.2)
			(type default)
		)
		(fill no)
		(layer "In5.Cu")
	)
	(gr_circle
		(center 200.33234 -378.160534)
		(end 201.22134 -378.160534)
		(stroke
			(width 0.2)
			(type default)
		)
		(fill no)
		(layer "In5.Cu")
	)
	(gr_circle
		(center 200.391014 -30.133798)
		(end 201.280014 -30.133798)
		(stroke
			(width 0.2)
			(type default)
		)
		(fill no)
		(layer "In5.Cu")
	)
	(gr_circle
		(center 200.705974 -30.720538)
		(end 201.594974 -30.720538)
		(stroke
			(width 0.2)
			(type default)
		)
		(fill no)
		(layer "In5.Cu")
	)
	(gr_circle
		(center 200.933558 -403.223222)
		(end 201.822558 -403.223222)
		(stroke
			(width 0.2)
			(type default)
		)
		(fill no)
		(layer "In5.Cu")
	)
	(gr_circle
		(center 200.933558 -401.920202)
		(end 201.822558 -401.920202)
		(stroke
			(width 0.2)
			(type default)
		)
		(fill no)
		(layer "In5.Cu")
	)
	(gr_circle
		(center 200.933558 -400.617182)
		(end 201.822558 -400.617182)
		(stroke
			(width 0.2)
			(type default)
		)
		(fill no)
		(layer "In5.Cu")
	)
	(gr_circle
		(center 201.0537 -408.059382)
		(end 201.9427 -408.059382)
		(stroke
			(width 0.2)
			(type default)
		)
		(fill no)
		(layer "In5.Cu")
	)
	(gr_circle
		(center 201.0537 -407.297382)
		(end 201.9427 -407.297382)
		(stroke
			(width 0.2)
			(type default)
		)
		(fill no)
		(layer "In5.Cu")
	)
	(gr_circle
		(center 201.0537 -406.535382)
		(end 201.9427 -406.535382)
		(stroke
			(width 0.2)
			(type default)
		)
		(fill no)
		(layer "In5.Cu")
	)
	(gr_circle
		(center 201.0537 -405.773382)
		(end 201.9427 -405.773382)
		(stroke
			(width 0.2)
			(type default)
		)
		(fill no)
		(layer "In5.Cu")
	)
	(gr_circle
		(center 201.0537 -405.011382)
		(end 201.9427 -405.011382)
		(stroke
			(width 0.2)
			(type default)
		)
		(fill no)
		(layer "In5.Cu")
	)
	(gr_circle
		(center 201.340974 -30.720538)
		(end 202.229974 -30.720538)
		(stroke
			(width 0.2)
			(type default)
		)
		(fill no)
		(layer "In5.Cu")
	)
	(gr_circle
		(center 201.745342 -346.583)
		(end 202.634342 -346.583)
		(stroke
			(width 0.2)
			(type default)
		)
		(fill no)
		(layer "In5.Cu")
	)
	(gr_circle
		(center 201.745342 -345.821)
		(end 202.634342 -345.821)
		(stroke
			(width 0.2)
			(type default)
		)
		(fill no)
		(layer "In5.Cu")
	)
	(gr_circle
		(center 201.745342 -344.8304)
		(end 202.634342 -344.8304)
		(stroke
			(width 0.2)
			(type default)
		)
		(fill no)
		(layer "In5.Cu")
	)
	(gr_circle
		(center 201.745342 -344.0684)
		(end 202.634342 -344.0684)
		(stroke
			(width 0.2)
			(type default)
		)
		(fill no)
		(layer "In5.Cu")
	)
	(gr_line
		(start 205.73746 -435.231032)
		(end 207.302608 -436.79618)
		(stroke
			(width 0.635)
			(type default)
		)
		(layer "In5.Cu")
	)
	(gr_line
		(start 205.73746 -431.683414)
		(end 205.73746 -435.231032)
		(stroke
			(width 0.635)
			(type default)
		)
		(layer "In5.Cu")
	)
	(gr_circle
		(center 207.1497 -408.059382)
		(end 208.0387 -408.059382)
		(stroke
			(width 0.2)
			(type default)
		)
		(fill no)
		(layer "In5.Cu")
	)
	(gr_line
		(start 207.302608 -436.79618)
		(end 229.074472 -436.79618)
		(stroke
			(width 0.635)
			(type default)
		)
		(layer "In5.Cu")
	)
	(gr_circle
		(center 207.9117 -408.059382)
		(end 208.8007 -408.059382)
		(stroke
			(width 0.2)
			(type default)
		)
		(fill no)
		(layer "In5.Cu")
	)
	(gr_circle
		(center 207.9117 -407.297382)
		(end 208.8007 -407.297382)
		(stroke
			(width 0.2)
			(type default)
		)
		(fill no)
		(layer "In5.Cu")
	)
	(gr_circle
		(center 208.508854 -37.366448)
		(end 209.397854 -37.366448)
		(stroke
			(width 0.2)
			(type default)
		)
		(fill no)
		(layer "In5.Cu")
	)
	(gr_circle
		(center 208.6737 -408.059382)
		(end 209.5627 -408.059382)
		(stroke
			(width 0.2)
			(type default)
		)
		(fill no)
		(layer "In5.Cu")
	)
	(gr_circle
		(center 208.6737 -407.297382)
		(end 209.5627 -407.297382)
		(stroke
			(width 0.2)
			(type default)
		)
		(fill no)
		(layer "In5.Cu")
	)
	(gr_circle
		(center 208.6737 -406.535382)
		(end 209.5627 -406.535382)
		(stroke
			(width 0.2)
			(type default)
		)
		(fill no)
		(layer "In5.Cu")
	)
	(gr_circle
		(center 208.6737 -405.773382)
		(end 209.5627 -405.773382)
		(stroke
			(width 0.2)
			(type default)
		)
		(fill no)
		(layer "In5.Cu")
	)
	(gr_circle
		(center 208.6737 -405.011382)
		(end 209.5627 -405.011382)
		(stroke
			(width 0.2)
			(type default)
		)
		(fill no)
		(layer "In5.Cu")
	)
	(gr_circle
		(center 208.782158 -403.223222)
		(end 209.671158 -403.223222)
		(stroke
			(width 0.2)
			(type default)
		)
		(fill no)
		(layer "In5.Cu")
	)
	(gr_circle
		(center 208.782158 -401.920202)
		(end 209.671158 -401.920202)
		(stroke
			(width 0.2)
			(type default)
		)
		(fill no)
		(layer "In5.Cu")
	)
	(gr_circle
		(center 208.782158 -400.617182)
		(end 209.671158 -400.617182)
		(stroke
			(width 0.2)
			(type default)
		)
		(fill no)
		(layer "In5.Cu")
	)
	(gr_circle
		(center 209.4357 -408.059382)
		(end 210.3247 -408.059382)
		(stroke
			(width 0.2)
			(type default)
		)
		(fill no)
		(layer "In5.Cu")
	)
	(gr_circle
		(center 209.4357 -407.297382)
		(end 210.3247 -407.297382)
		(stroke
			(width 0.2)
			(type default)
		)
		(fill no)
		(layer "In5.Cu")
	)
	(gr_circle
		(center 209.4357 -406.535382)
		(end 210.3247 -406.535382)
		(stroke
			(width 0.2)
			(type default)
		)
		(fill no)
		(layer "In5.Cu")
	)
	(gr_circle
		(center 209.4357 -405.773382)
		(end 210.3247 -405.773382)
		(stroke
			(width 0.2)
			(type default)
		)
		(fill no)
		(layer "In5.Cu")
	)
	(gr_circle
		(center 209.4357 -405.011382)
		(end 210.3247 -405.011382)
		(stroke
			(width 0.2)
			(type default)
		)
		(fill no)
		(layer "In5.Cu")
	)
	(gr_circle
		(center 210.1977 -408.059382)
		(end 211.0867 -408.059382)
		(stroke
			(width 0.2)
			(type default)
		)
		(fill no)
		(layer "In5.Cu")
	)
	(gr_circle
		(center 210.1977 -407.297382)
		(end 211.0867 -407.297382)
		(stroke
			(width 0.2)
			(type default)
		)
		(fill no)
		(layer "In5.Cu")
	)
	(gr_circle
		(center 210.1977 -406.535382)
		(end 211.0867 -406.535382)
		(stroke
			(width 0.2)
			(type default)
		)
		(fill no)
		(layer "In5.Cu")
	)
	(gr_circle
		(center 210.1977 -405.773382)
		(end 211.0867 -405.773382)
		(stroke
			(width 0.2)
			(type default)
		)
		(fill no)
		(layer "In5.Cu")
	)
	(gr_circle
		(center 210.1977 -405.011382)
		(end 211.0867 -405.011382)
		(stroke
			(width 0.2)
			(type default)
		)
		(fill no)
		(layer "In5.Cu")
	)
	(gr_circle
		(center 210.204558 -403.223222)
		(end 211.093558 -403.223222)
		(stroke
			(width 0.2)
			(type default)
		)
		(fill no)
		(layer "In5.Cu")
	)
	(gr_circle
		(center 210.204558 -400.617182)
		(end 211.093558 -400.617182)
		(stroke
			(width 0.2)
			(type default)
		)
		(fill no)
		(layer "In5.Cu")
	)
	(gr_circle
		(center 210.9597 -408.059382)
		(end 211.8487 -408.059382)
		(stroke
			(width 0.2)
			(type default)
		)
		(fill no)
		(layer "In5.Cu")
	)
	(gr_circle
		(center 210.9597 -407.297382)
		(end 211.8487 -407.297382)
		(stroke
			(width 0.2)
			(type default)
		)
		(fill no)
		(layer "In5.Cu")
	)
	(gr_circle
		(center 210.9597 -406.535382)
		(end 211.8487 -406.535382)
		(stroke
			(width 0.2)
			(type default)
		)
		(fill no)
		(layer "In5.Cu")
	)
	(gr_circle
		(center 210.9597 -405.773382)
		(end 211.8487 -405.773382)
		(stroke
			(width 0.2)
			(type default)
		)
		(fill no)
		(layer "In5.Cu")
	)
	(gr_circle
		(center 210.9597 -405.011382)
		(end 211.8487 -405.011382)
		(stroke
			(width 0.2)
			(type default)
		)
		(fill no)
		(layer "In5.Cu")
	)
	(gr_circle
		(center 211.601558 -403.223222)
		(end 212.490558 -403.223222)
		(stroke
			(width 0.2)
			(type default)
		)
		(fill no)
		(layer "In5.Cu")
	)
	(gr_circle
		(center 211.601558 -401.920202)
		(end 212.490558 -401.920202)
		(stroke
			(width 0.2)
			(type default)
		)
		(fill no)
		(layer "In5.Cu")
	)
	(gr_circle
		(center 211.601558 -400.617182)
		(end 212.490558 -400.617182)
		(stroke
			(width 0.2)
			(type default)
		)
		(fill no)
		(layer "In5.Cu")
	)
	(gr_circle
		(center 211.7217 -408.059382)
		(end 212.6107 -408.059382)
		(stroke
			(width 0.2)
			(type default)
		)
		(fill no)
		(layer "In5.Cu")
	)
	(gr_circle
		(center 211.7217 -407.297382)
		(end 212.6107 -407.297382)
		(stroke
			(width 0.2)
			(type default)
		)
		(fill no)
		(layer "In5.Cu")
	)
	(gr_circle
		(center 211.7217 -406.535382)
		(end 212.6107 -406.535382)
		(stroke
			(width 0.2)
			(type default)
		)
		(fill no)
		(layer "In5.Cu")
	)
	(gr_circle
		(center 211.7217 -405.773382)
		(end 212.6107 -405.773382)
		(stroke
			(width 0.2)
			(type default)
		)
		(fill no)
		(layer "In5.Cu")
	)
	(gr_circle
		(center 211.7217 -405.011382)
		(end 212.6107 -405.011382)
		(stroke
			(width 0.2)
			(type default)
		)
		(fill no)
		(layer "In5.Cu")
	)
	(gr_circle
		(center 212.4837 -408.059382)
		(end 213.3727 -408.059382)
		(stroke
			(width 0.2)
			(type default)
		)
		(fill no)
		(layer "In5.Cu")
	)
	(gr_circle
		(center 212.4837 -407.297382)
		(end 213.3727 -407.297382)
		(stroke
			(width 0.2)
			(type default)
		)
		(fill no)
		(layer "In5.Cu")
	)
	(gr_circle
		(center 217.8177 -408.059382)
		(end 218.7067 -408.059382)
		(stroke
			(width 0.2)
			(type default)
		)
		(fill no)
		(layer "In5.Cu")
	)
	(gr_circle
		(center 218.5797 -408.059382)
		(end 219.4687 -408.059382)
		(stroke
			(width 0.2)
			(type default)
		)
		(fill no)
		(layer "In5.Cu")
	)
	(gr_circle
		(center 218.5797 -407.297382)
		(end 219.4687 -407.297382)
		(stroke
			(width 0.2)
			(type default)
		)
		(fill no)
		(layer "In5.Cu")
	)
	(gr_circle
		(center 219.3417 -408.059382)
		(end 220.2307 -408.059382)
		(stroke
			(width 0.2)
			(type default)
		)
		(fill no)
		(layer "In5.Cu")
	)
	(gr_circle
		(center 219.3417 -407.297382)
		(end 220.2307 -407.297382)
		(stroke
			(width 0.2)
			(type default)
		)
		(fill no)
		(layer "In5.Cu")
	)
	(gr_circle
		(center 219.3417 -406.535382)
		(end 220.2307 -406.535382)
		(stroke
			(width 0.2)
			(type default)
		)
		(fill no)
		(layer "In5.Cu")
	)
	(gr_circle
		(center 219.3417 -405.773382)
		(end 220.2307 -405.773382)
		(stroke
			(width 0.2)
			(type default)
		)
		(fill no)
		(layer "In5.Cu")
	)
	(gr_circle
		(center 219.3417 -405.011382)
		(end 220.2307 -405.011382)
		(stroke
			(width 0.2)
			(type default)
		)
		(fill no)
		(layer "In5.Cu")
	)
	(gr_circle
		(center 219.450158 -403.223222)
		(end 220.339158 -403.223222)
		(stroke
			(width 0.2)
			(type default)
		)
		(fill no)
		(layer "In5.Cu")
	)
	(gr_circle
		(center 219.450158 -401.920202)
		(end 220.339158 -401.920202)
		(stroke
			(width 0.2)
			(type default)
		)
		(fill no)
		(layer "In5.Cu")
	)
	(gr_circle
		(center 219.450158 -400.617182)
		(end 220.339158 -400.617182)
		(stroke
			(width 0.2)
			(type default)
		)
		(fill no)
		(layer "In5.Cu")
	)
	(gr_circle
		(center 220.1037 -408.059382)
		(end 220.9927 -408.059382)
		(stroke
			(width 0.2)
			(type default)
		)
		(fill no)
		(layer "In5.Cu")
	)
	(gr_circle
		(center 220.1037 -407.297382)
		(end 220.9927 -407.297382)
		(stroke
			(width 0.2)
			(type default)
		)
		(fill no)
		(layer "In5.Cu")
	)
	(gr_circle
		(center 220.1037 -406.535382)
		(end 220.9927 -406.535382)
		(stroke
			(width 0.2)
			(type default)
		)
		(fill no)
		(layer "In5.Cu")
	)
	(gr_circle
		(center 220.1037 -405.773382)
		(end 220.9927 -405.773382)
		(stroke
			(width 0.2)
			(type default)
		)
		(fill no)
		(layer "In5.Cu")
	)
	(gr_circle
		(center 220.1037 -405.011382)
		(end 220.9927 -405.011382)
		(stroke
			(width 0.2)
			(type default)
		)
		(fill no)
		(layer "In5.Cu")
	)
	(gr_circle
		(center 220.8657 -408.059382)
		(end 221.7547 -408.059382)
		(stroke
			(width 0.2)
			(type default)
		)
		(fill no)
		(layer "In5.Cu")
	)
	(gr_circle
		(center 220.8657 -407.297382)
		(end 221.7547 -407.297382)
		(stroke
			(width 0.2)
			(type default)
		)
		(fill no)
		(layer "In5.Cu")
	)
	(gr_circle
		(center 220.8657 -406.535382)
		(end 221.7547 -406.535382)
		(stroke
			(width 0.2)
			(type default)
		)
		(fill no)
		(layer "In5.Cu")
	)
	(gr_circle
		(center 220.8657 -405.773382)
		(end 221.7547 -405.773382)
		(stroke
			(width 0.2)
			(type default)
		)
		(fill no)
		(layer "In5.Cu")
	)
	(gr_circle
		(center 220.8657 -405.011382)
		(end 221.7547 -405.011382)
		(stroke
			(width 0.2)
			(type default)
		)
		(fill no)
		(layer "In5.Cu")
	)
	(gr_circle
		(center 220.872558 -403.223222)
		(end 221.761558 -403.223222)
		(stroke
			(width 0.2)
			(type default)
		)
		(fill no)
		(layer "In5.Cu")
	)
	(gr_circle
		(center 220.872558 -400.617182)
		(end 221.761558 -400.617182)
		(stroke
			(width 0.2)
			(type default)
		)
		(fill no)
		(layer "In5.Cu")
	)
	(gr_circle
		(center 221.6277 -408.059382)
		(end 222.5167 -408.059382)
		(stroke
			(width 0.2)
			(type default)
		)
		(fill no)
		(layer "In5.Cu")
	)
	(gr_circle
		(center 221.6277 -407.297382)
		(end 222.5167 -407.297382)
		(stroke
			(width 0.2)
			(type default)
		)
		(fill no)
		(layer "In5.Cu")
	)
	(gr_circle
		(center 221.6277 -406.535382)
		(end 222.5167 -406.535382)
		(stroke
			(width 0.2)
			(type default)
		)
		(fill no)
		(layer "In5.Cu")
	)
	(gr_circle
		(center 221.6277 -405.773382)
		(end 222.5167 -405.773382)
		(stroke
			(width 0.2)
			(type default)
		)
		(fill no)
		(layer "In5.Cu")
	)
	(gr_circle
		(center 221.6277 -405.011382)
		(end 222.5167 -405.011382)
		(stroke
			(width 0.2)
			(type default)
		)
		(fill no)
		(layer "In5.Cu")
	)
	(gr_circle
		(center 222.269558 -403.223222)
		(end 223.158558 -403.223222)
		(stroke
			(width 0.2)
			(type default)
		)
		(fill no)
		(layer "In5.Cu")
	)
	(gr_circle
		(center 222.269558 -401.920202)
		(end 223.158558 -401.920202)
		(stroke
			(width 0.2)
			(type default)
		)
		(fill no)
		(layer "In5.Cu")
	)
	(gr_circle
		(center 222.269558 -400.617182)
		(end 223.158558 -400.617182)
		(stroke
			(width 0.2)
			(type default)
		)
		(fill no)
		(layer "In5.Cu")
	)
	(gr_circle
		(center 222.3897 -408.059382)
		(end 223.2787 -408.059382)
		(stroke
			(width 0.2)
			(type default)
		)
		(fill no)
		(layer "In5.Cu")
	)
	(gr_circle
		(center 222.3897 -407.297382)
		(end 223.2787 -407.297382)
		(stroke
			(width 0.2)
			(type default)
		)
		(fill no)
		(layer "In5.Cu")
	)
	(gr_circle
		(center 222.3897 -406.535382)
		(end 223.2787 -406.535382)
		(stroke
			(width 0.2)
			(type default)
		)
		(fill no)
		(layer "In5.Cu")
	)
	(gr_circle
		(center 222.3897 -405.773382)
		(end 223.2787 -405.773382)
		(stroke
			(width 0.2)
			(type default)
		)
		(fill no)
		(layer "In5.Cu")
	)
	(gr_circle
		(center 222.3897 -405.011382)
		(end 223.2787 -405.011382)
		(stroke
			(width 0.2)
			(type default)
		)
		(fill no)
		(layer "In5.Cu")
	)
	(gr_circle
		(center 223.1517 -408.059382)
		(end 224.0407 -408.059382)
		(stroke
			(width 0.2)
			(type default)
		)
		(fill no)
		(layer "In5.Cu")
	)
	(gr_circle
		(center 223.1517 -407.297382)
		(end 224.0407 -407.297382)
		(stroke
			(width 0.2)
			(type default)
		)
		(fill no)
		(layer "In5.Cu")
	)
	(gr_arc
		(start 223.300036 -34.120074)
		(mid 223.885821 -35.534285)
		(end 225.300032 -36.12007)
		(stroke
			(width 1.016)
			(type default)
		)
		(layer "In5.Cu")
	)
	(gr_arc
		(start 223.300036 -13.780008)
		(mid 222.714256 -12.365778)
		(end 221.30004 -11.780012)
		(stroke
			(width 1.016)
			(type default)
		)
		(layer "In5.Cu")
	)
	(gr_line
		(start 223.300036 -13.780008)
		(end 223.300036 -34.120074)
		(stroke
			(width 1.016)
			(type default)
		)
		(layer "In5.Cu")
	)
	(gr_line
		(start 225.300032 -36.12007)
		(end 256.800096 -36.12007)
		(stroke
			(width 1.016)
			(type default)
		)
		(layer "In5.Cu")
	)
	(gr_line
		(start 226.92741 -412.930848)
		(end 229.545642 -410.312616)
		(stroke
			(width 0.635)
			(type default)
		)
		(layer "In5.Cu")
	)
	(gr_circle
		(center 228.4857 -408.059382)
		(end 229.3747 -408.059382)
		(stroke
			(width 0.2)
			(type default)
		)
		(fill no)
		(layer "In5.Cu")
	)
	(gr_line
		(start 229.074472 -436.79618)
		(end 229.997 -435.873652)
		(stroke
			(width 0.635)
			(type default)
		)
		(layer "In5.Cu")
	)
	(gr_circle
		(center 229.2477 -408.059382)
		(end 230.1367 -408.059382)
		(stroke
			(width 0.2)
			(type default)
		)
		(fill no)
		(layer "In5.Cu")
	)
	(gr_circle
		(center 229.2477 -407.297382)
		(end 230.1367 -407.297382)
		(stroke
			(width 0.2)
			(type default)
		)
		(fill no)
		(layer "In5.Cu")
	)
	(gr_line
		(start 229.545642 -410.312616)
		(end 234.715558 -410.312616)
		(stroke
			(width 0.635)
			(type default)
		)
		(layer "In5.Cu")
	)
	(gr_line
		(start 229.997 -435.873652)
		(end 229.997 -422.180766)
		(stroke
			(width 0.635)
			(type default)
		)
		(layer "In5.Cu")
	)
	(gr_circle
		(center 230.0097 -408.059382)
		(end 230.8987 -408.059382)
		(stroke
			(width 0.2)
			(type default)
		)
		(fill no)
		(layer "In5.Cu")
	)
	(gr_circle
		(center 230.0097 -407.297382)
		(end 230.8987 -407.297382)
		(stroke
			(width 0.2)
			(type default)
		)
		(fill no)
		(layer "In5.Cu")
	)
	(gr_circle
		(center 230.0097 -406.535382)
		(end 230.8987 -406.535382)
		(stroke
			(width 0.2)
			(type default)
		)
		(fill no)
		(layer "In5.Cu")
	)
	(gr_circle
		(center 230.0097 -405.773382)
		(end 230.8987 -405.773382)
		(stroke
			(width 0.2)
			(type default)
		)
		(fill no)
		(layer "In5.Cu")
	)
	(gr_circle
		(center 230.0097 -405.011382)
		(end 230.8987 -405.011382)
		(stroke
			(width 0.2)
			(type default)
		)
		(fill no)
		(layer "In5.Cu")
	)
	(gr_circle
		(center 230.118158 -403.223222)
		(end 231.007158 -403.223222)
		(stroke
			(width 0.2)
			(type default)
		)
		(fill no)
		(layer "In5.Cu")
	)
	(gr_circle
		(center 230.118158 -401.920202)
		(end 231.007158 -401.920202)
		(stroke
			(width 0.2)
			(type default)
		)
		(fill no)
		(layer "In5.Cu")
	)
	(gr_circle
		(center 230.118158 -400.617182)
		(end 231.007158 -400.617182)
		(stroke
			(width 0.2)
			(type default)
		)
		(fill no)
		(layer "In5.Cu")
	)
	(gr_circle
		(center 230.7717 -408.059382)
		(end 231.6607 -408.059382)
		(stroke
			(width 0.2)
			(type default)
		)
		(fill no)
		(layer "In5.Cu")
	)
	(gr_circle
		(center 230.7717 -407.297382)
		(end 231.6607 -407.297382)
		(stroke
			(width 0.2)
			(type default)
		)
		(fill no)
		(layer "In5.Cu")
	)
	(gr_circle
		(center 230.7717 -406.535382)
		(end 231.6607 -406.535382)
		(stroke
			(width 0.2)
			(type default)
		)
		(fill no)
		(layer "In5.Cu")
	)
	(gr_circle
		(center 230.7717 -405.773382)
		(end 231.6607 -405.773382)
		(stroke
			(width 0.2)
			(type default)
		)
		(fill no)
		(layer "In5.Cu")
	)
	(gr_circle
		(center 230.7717 -405.011382)
		(end 231.6607 -405.011382)
		(stroke
			(width 0.2)
			(type default)
		)
		(fill no)
		(layer "In5.Cu")
	)
	(gr_circle
		(center 231.5337 -408.059382)
		(end 232.4227 -408.059382)
		(stroke
			(width 0.2)
			(type default)
		)
		(fill no)
		(layer "In5.Cu")
	)
	(gr_circle
		(center 231.5337 -407.297382)
		(end 232.4227 -407.297382)
		(stroke
			(width 0.2)
			(type default)
		)
		(fill no)
		(layer "In5.Cu")
	)
	(gr_circle
		(center 231.5337 -406.535382)
		(end 232.4227 -406.535382)
		(stroke
			(width 0.2)
			(type default)
		)
		(fill no)
		(layer "In5.Cu")
	)
	(gr_circle
		(center 231.5337 -405.773382)
		(end 232.4227 -405.773382)
		(stroke
			(width 0.2)
			(type default)
		)
		(fill no)
		(layer "In5.Cu")
	)
	(gr_circle
		(center 231.5337 -405.011382)
		(end 232.4227 -405.011382)
		(stroke
			(width 0.2)
			(type default)
		)
		(fill no)
		(layer "In5.Cu")
	)
	(gr_circle
		(center 231.540558 -403.223222)
		(end 232.429558 -403.223222)
		(stroke
			(width 0.2)
			(type default)
		)
		(fill no)
		(layer "In5.Cu")
	)
	(gr_circle
		(center 231.540558 -400.617182)
		(end 232.429558 -400.617182)
		(stroke
			(width 0.2)
			(type default)
		)
		(fill no)
		(layer "In5.Cu")
	)
	(gr_circle
		(center 232.2957 -408.059382)
		(end 233.1847 -408.059382)
		(stroke
			(width 0.2)
			(type default)
		)
		(fill no)
		(layer "In5.Cu")
	)
	(gr_circle
		(center 232.2957 -407.297382)
		(end 233.1847 -407.297382)
		(stroke
			(width 0.2)
			(type default)
		)
		(fill no)
		(layer "In5.Cu")
	)
	(gr_circle
		(center 232.2957 -406.535382)
		(end 233.1847 -406.535382)
		(stroke
			(width 0.2)
			(type default)
		)
		(fill no)
		(layer "In5.Cu")
	)
	(gr_circle
		(center 232.2957 -405.773382)
		(end 233.1847 -405.773382)
		(stroke
			(width 0.2)
			(type default)
		)
		(fill no)
		(layer "In5.Cu")
	)
	(gr_circle
		(center 232.2957 -405.011382)
		(end 233.1847 -405.011382)
		(stroke
			(width 0.2)
			(type default)
		)
		(fill no)
		(layer "In5.Cu")
	)
	(gr_circle
		(center 232.937558 -403.223222)
		(end 233.826558 -403.223222)
		(stroke
			(width 0.2)
			(type default)
		)
		(fill no)
		(layer "In5.Cu")
	)
	(gr_circle
		(center 232.937558 -401.920202)
		(end 233.826558 -401.920202)
		(stroke
			(width 0.2)
			(type default)
		)
		(fill no)
		(layer "In5.Cu")
	)
	(gr_circle
		(center 232.937558 -400.617182)
		(end 233.826558 -400.617182)
		(stroke
			(width 0.2)
			(type default)
		)
		(fill no)
		(layer "In5.Cu")
	)
	(gr_circle
		(center 233.0577 -408.059382)
		(end 233.9467 -408.059382)
		(stroke
			(width 0.2)
			(type default)
		)
		(fill no)
		(layer "In5.Cu")
	)
	(gr_circle
		(center 233.0577 -407.297382)
		(end 233.9467 -407.297382)
		(stroke
			(width 0.2)
			(type default)
		)
		(fill no)
		(layer "In5.Cu")
	)
	(gr_circle
		(center 233.0577 -406.535382)
		(end 233.9467 -406.535382)
		(stroke
			(width 0.2)
			(type default)
		)
		(fill no)
		(layer "In5.Cu")
	)
	(gr_circle
		(center 233.0577 -405.773382)
		(end 233.9467 -405.773382)
		(stroke
			(width 0.2)
			(type default)
		)
		(fill no)
		(layer "In5.Cu")
	)
	(gr_circle
		(center 233.0577 -405.011382)
		(end 233.9467 -405.011382)
		(stroke
			(width 0.2)
			(type default)
		)
		(fill no)
		(layer "In5.Cu")
	)
	(gr_circle
		(center 233.8197 -408.059382)
		(end 234.7087 -408.059382)
		(stroke
			(width 0.2)
			(type default)
		)
		(fill no)
		(layer "In5.Cu")
	)
	(gr_circle
		(center 233.8197 -407.297382)
		(end 234.7087 -407.297382)
		(stroke
			(width 0.2)
			(type default)
		)
		(fill no)
		(layer "In5.Cu")
	)
	(gr_line
		(start 234.715558 -410.312616)
		(end 238.882682 -406.145492)
		(stroke
			(width 0.635)
			(type default)
		)
		(layer "In5.Cu")
	)
	(gr_line
		(start 234.897676 -417.28009)
		(end 229.997 -422.180766)
		(stroke
			(width 0.635)
			(type default)
		)
		(layer "In5.Cu")
	)
	(gr_circle
		(center 237.629954 -44.025566)
		(end 238.518954 -44.025566)
		(stroke
			(width 0.2)
			(type default)
		)
		(fill no)
		(layer "In5.Cu")
	)
	(gr_circle
		(center 237.640114 -44.716446)
		(end 238.529114 -44.716446)
		(stroke
			(width 0.2)
			(type default)
		)
		(fill no)
		(layer "In5.Cu")
	)
	(gr_circle
		(center 238.292894 -44.802806)
		(end 239.181894 -44.802806)
		(stroke
			(width 0.2)
			(type default)
		)
		(fill no)
		(layer "In5.Cu")
	)
	(gr_circle
		(center 238.292894 -44.040806)
		(end 239.181894 -44.040806)
		(stroke
			(width 0.2)
			(type default)
		)
		(fill no)
		(layer "In5.Cu")
	)
	(gr_line
		(start 238.882682 -406.145492)
		(end 238.882682 -397.97228)
		(stroke
			(width 0.635)
			(type default)
		)
		(layer "In5.Cu")
	)
	(gr_line
		(start 238.882682 -397.97228)
		(end 239.389412 -397.46555)
		(stroke
			(width 0.635)
			(type default)
		)
		(layer "In5.Cu")
	)
	(gr_circle
		(center 238.943134 -44.802806)
		(end 239.832134 -44.802806)
		(stroke
			(width 0.2)
			(type default)
		)
		(fill no)
		(layer "In5.Cu")
	)
	(gr_circle
		(center 238.943134 -44.040806)
		(end 239.832134 -44.040806)
		(stroke
			(width 0.2)
			(type default)
		)
		(fill no)
		(layer "In5.Cu")
	)
	(gr_line
		(start 239.389412 -397.46555)
		(end 279.416002 -397.46555)
		(stroke
			(width 0.635)
			(type default)
		)
		(layer "In5.Cu")
	)
	(gr_circle
		(center 239.578134 -44.802806)
		(end 240.467134 -44.802806)
		(stroke
			(width 0.2)
			(type default)
		)
		(fill no)
		(layer "In5.Cu")
	)
	(gr_circle
		(center 239.578134 -44.040806)
		(end 240.467134 -44.040806)
		(stroke
			(width 0.2)
			(type default)
		)
		(fill no)
		(layer "In5.Cu")
	)
	(gr_circle
		(center 239.879124 -389.328914)
		(end 240.768124 -389.328914)
		(stroke
			(width 0.2)
			(type default)
		)
		(fill no)
		(layer "In5.Cu")
	)
	(gr_circle
		(center 240.213134 -44.802806)
		(end 241.102134 -44.802806)
		(stroke
			(width 0.2)
			(type default)
		)
		(fill no)
		(layer "In5.Cu")
	)
	(gr_circle
		(center 240.213134 -44.040806)
		(end 241.102134 -44.040806)
		(stroke
			(width 0.2)
			(type default)
		)
		(fill no)
		(layer "In5.Cu")
	)
	(gr_circle
		(center 240.893854 -44.830746)
		(end 241.782854 -44.830746)
		(stroke
			(width 0.2)
			(type default)
		)
		(fill no)
		(layer "In5.Cu")
	)
	(gr_circle
		(center 242.6589 -389.32104)
		(end 243.5479 -389.32104)
		(stroke
			(width 0.2)
			(type default)
		)
		(fill no)
		(layer "In5.Cu")
	)
	(gr_circle
		(center 243.4209 -389.32104)
		(end 244.3099 -389.32104)
		(stroke
			(width 0.2)
			(type default)
		)
		(fill no)
		(layer "In5.Cu")
	)
	(gr_circle
		(center 244.1829 -389.32104)
		(end 245.0719 -389.32104)
		(stroke
			(width 0.2)
			(type default)
		)
		(fill no)
		(layer "In5.Cu")
	)
	(gr_circle
		(center 244.518942 -43.246802)
		(end 245.407942 -43.246802)
		(stroke
			(width 0.2)
			(type default)
		)
		(fill no)
		(layer "In5.Cu")
	)
	(gr_circle
		(center 244.518942 -42.611802)
		(end 245.407942 -42.611802)
		(stroke
			(width 0.2)
			(type default)
		)
		(fill no)
		(layer "In5.Cu")
	)
	(gr_circle
		(center 244.63248 -387.62432)
		(end 245.52148 -387.62432)
		(stroke
			(width 0.2)
			(type default)
		)
		(fill no)
		(layer "In5.Cu")
	)
	(gr_circle
		(center 244.63248 -386.86232)
		(end 245.52148 -386.86232)
		(stroke
			(width 0.2)
			(type default)
		)
		(fill no)
		(layer "In5.Cu")
	)
	(gr_circle
		(center 244.63248 -386.10032)
		(end 245.52148 -386.10032)
		(stroke
			(width 0.2)
			(type default)
		)
		(fill no)
		(layer "In5.Cu")
	)
	(gr_circle
		(center 244.9449 -389.32104)
		(end 245.8339 -389.32104)
		(stroke
			(width 0.2)
			(type default)
		)
		(fill no)
		(layer "In5.Cu")
	)
	(gr_circle
		(center 245.7069 -389.32104)
		(end 246.5959 -389.32104)
		(stroke
			(width 0.2)
			(type default)
		)
		(fill no)
		(layer "In5.Cu")
	)
	(gr_circle
		(center 245.857522 -52.022502)
		(end 246.746522 -52.022502)
		(stroke
			(width 0.2)
			(type default)
		)
		(fill no)
		(layer "In5.Cu")
	)
	(gr_circle
		(center 246.873522 -52.022502)
		(end 247.762522 -52.022502)
		(stroke
			(width 0.2)
			(type default)
		)
		(fill no)
		(layer "In5.Cu")
	)
	(gr_circle
		(center 247.825514 -40.94988)
		(end 248.714514 -40.94988)
		(stroke
			(width 0.2)
			(type default)
		)
		(fill no)
		(layer "In5.Cu")
	)
	(gr_circle
		(center 247.840246 -51.320446)
		(end 248.729246 -51.320446)
		(stroke
			(width 0.2)
			(type default)
		)
		(fill no)
		(layer "In5.Cu")
	)
	(gr_circle
		(center 248.214134 -52.171346)
		(end 249.103134 -52.171346)
		(stroke
			(width 0.2)
			(type default)
		)
		(fill no)
		(layer "In5.Cu")
	)
	(gr_circle
		(center 248.881646 -51.320446)
		(end 249.770646 -51.320446)
		(stroke
			(width 0.2)
			(type default)
		)
		(fill no)
		(layer "In5.Cu")
	)
	(gr_circle
		(center 249.202448 -40.945816)
		(end 250.091448 -40.945816)
		(stroke
			(width 0.2)
			(type default)
		)
		(fill no)
		(layer "In5.Cu")
	)
	(gr_circle
		(center 249.905266 -51.349148)
		(end 250.794266 -51.349148)
		(stroke
			(width 0.2)
			(type default)
		)
		(fill no)
		(layer "In5.Cu")
	)
	(gr_circle
		(center 250.449334 -49.555146)
		(end 251.338334 -49.555146)
		(stroke
			(width 0.2)
			(type default)
		)
		(fill no)
		(layer "In5.Cu")
	)
	(gr_circle
		(center 250.567444 -387.62432)
		(end 251.456444 -387.62432)
		(stroke
			(width 0.2)
			(type default)
		)
		(fill no)
		(layer "In5.Cu")
	)
	(gr_circle
		(center 250.567444 -386.86232)
		(end 251.456444 -386.86232)
		(stroke
			(width 0.2)
			(type default)
		)
		(fill no)
		(layer "In5.Cu")
	)
	(gr_circle
		(center 250.567444 -386.10032)
		(end 251.456444 -386.10032)
		(stroke
			(width 0.2)
			(type default)
		)
		(fill no)
		(layer "In5.Cu")
	)
	(gr_circle
		(center 250.779534 -52.222146)
		(end 251.668534 -52.222146)
		(stroke
			(width 0.2)
			(type default)
		)
		(fill no)
		(layer "In5.Cu")
	)
	(gr_circle
		(center 250.779534 -51.333146)
		(end 251.668534 -51.333146)
		(stroke
			(width 0.2)
			(type default)
		)
		(fill no)
		(layer "In5.Cu")
	)
	(gr_circle
		(center 250.779534 -50.444146)
		(end 251.668534 -50.444146)
		(stroke
			(width 0.2)
			(type default)
		)
		(fill no)
		(layer "In5.Cu")
	)
	(gr_circle
		(center 251.02312 -389.32104)
		(end 251.91212 -389.32104)
		(stroke
			(width 0.2)
			(type default)
		)
		(fill no)
		(layer "In5.Cu")
	)
	(gr_circle
		(center 251.516134 -52.501546)
		(end 252.405134 -52.501546)
		(stroke
			(width 0.2)
			(type default)
		)
		(fill no)
		(layer "In5.Cu")
	)
	(gr_circle
		(center 251.516134 -51.612546)
		(end 252.405134 -51.612546)
		(stroke
			(width 0.2)
			(type default)
		)
		(fill no)
		(layer "In5.Cu")
	)
	(gr_circle
		(center 251.516134 -50.723546)
		(end 252.405134 -50.723546)
		(stroke
			(width 0.2)
			(type default)
		)
		(fill no)
		(layer "In5.Cu")
	)
	(gr_circle
		(center 251.78512 -389.32104)
		(end 252.67412 -389.32104)
		(stroke
			(width 0.2)
			(type default)
		)
		(fill no)
		(layer "In5.Cu")
	)
	(gr_circle
		(center 252.54712 -389.32104)
		(end 253.43612 -389.32104)
		(stroke
			(width 0.2)
			(type default)
		)
		(fill no)
		(layer "In5.Cu")
	)
	(gr_circle
		(center 253.30912 -389.32104)
		(end 254.19812 -389.32104)
		(stroke
			(width 0.2)
			(type default)
		)
		(fill no)
		(layer "In5.Cu")
	)
	(gr_circle
		(center 254.07112 -389.32104)
		(end 254.96012 -389.32104)
		(stroke
			(width 0.2)
			(type default)
		)
		(fill no)
		(layer "In5.Cu")
	)
	(gr_circle
		(center 255.347978 -39.380922)
		(end 256.236978 -39.380922)
		(stroke
			(width 0.2)
			(type default)
		)
		(fill no)
		(layer "In5.Cu")
	)
	(gr_circle
		(center 256.502408 -387.62432)
		(end 257.391408 -387.62432)
		(stroke
			(width 0.2)
			(type default)
		)
		(fill no)
		(layer "In5.Cu")
	)
	(gr_circle
		(center 256.502408 -386.86232)
		(end 257.391408 -386.86232)
		(stroke
			(width 0.2)
			(type default)
		)
		(fill no)
		(layer "In5.Cu")
	)
	(gr_circle
		(center 256.502408 -386.10032)
		(end 257.391408 -386.10032)
		(stroke
			(width 0.2)
			(type default)
		)
		(fill no)
		(layer "In5.Cu")
	)
	(gr_arc
		(start 256.800096 -36.12007)
		(mid 258.214307 -35.534285)
		(end 258.800092 -34.120074)
		(stroke
			(width 1.016)
			(type default)
		)
		(layer "In5.Cu")
	)
	(gr_line
		(start 258.800092 -34.120074)
		(end 258.800092 -13.780008)
		(stroke
			(width 1.016)
			(type default)
		)
		(layer "In5.Cu")
	)
	(gr_circle
		(center 258.93776 -389.36422)
		(end 259.82676 -389.36422)
		(stroke
			(width 0.2)
			(type default)
		)
		(fill no)
		(layer "In5.Cu")
	)
	(gr_circle
		(center 259.69976 -389.36422)
		(end 260.58876 -389.36422)
		(stroke
			(width 0.2)
			(type default)
		)
		(fill no)
		(layer "In5.Cu")
	)
	(gr_circle
		(center 260.46176 -389.36422)
		(end 261.35076 -389.36422)
		(stroke
			(width 0.2)
			(type default)
		)
		(fill no)
		(layer "In5.Cu")
	)
	(gr_arc
		(start 260.800088 -11.780012)
		(mid 259.385888 -12.365802)
		(end 258.800092 -13.780008)
		(stroke
			(width 1.016)
			(type default)
		)
		(layer "In5.Cu")
	)
	(gr_line
		(start 260.800088 -11.780012)
		(end 385.601972 -11.780012)
		(stroke
			(width 1.016)
			(type default)
		)
		(layer "In5.Cu")
	)
	(gr_circle
		(center 261.22376 -389.36422)
		(end 262.11276 -389.36422)
		(stroke
			(width 0.2)
			(type default)
		)
		(fill no)
		(layer "In5.Cu")
	)
	(gr_circle
		(center 261.98576 -389.36422)
		(end 262.87476 -389.36422)
		(stroke
			(width 0.2)
			(type default)
		)
		(fill no)
		(layer "In5.Cu")
	)
	(gr_circle
		(center 262.437372 -387.62432)
		(end 263.326372 -387.62432)
		(stroke
			(width 0.2)
			(type default)
		)
		(fill no)
		(layer "In5.Cu")
	)
	(gr_circle
		(center 262.437372 -386.86232)
		(end 263.326372 -386.86232)
		(stroke
			(width 0.2)
			(type default)
		)
		(fill no)
		(layer "In5.Cu")
	)
	(gr_circle
		(center 262.437372 -386.10032)
		(end 263.326372 -386.10032)
		(stroke
			(width 0.2)
			(type default)
		)
		(fill no)
		(layer "In5.Cu")
	)
	(gr_circle
		(center 266.98194 -389.3439)
		(end 267.87094 -389.3439)
		(stroke
			(width 0.2)
			(type default)
		)
		(fill no)
		(layer "In5.Cu")
	)
	(gr_circle
		(center 267.74394 -389.3439)
		(end 268.63294 -389.3439)
		(stroke
			(width 0.2)
			(type default)
		)
		(fill no)
		(layer "In5.Cu")
	)
	(gr_circle
		(center 268.372336 -387.62432)
		(end 269.261336 -387.62432)
		(stroke
			(width 0.2)
			(type default)
		)
		(fill no)
		(layer "In5.Cu")
	)
	(gr_circle
		(center 268.372336 -386.86232)
		(end 269.261336 -386.86232)
		(stroke
			(width 0.2)
			(type default)
		)
		(fill no)
		(layer "In5.Cu")
	)
	(gr_circle
		(center 268.372336 -386.10032)
		(end 269.261336 -386.10032)
		(stroke
			(width 0.2)
			(type default)
		)
		(fill no)
		(layer "In5.Cu")
	)
	(gr_circle
		(center 268.50594 -389.3439)
		(end 269.39494 -389.3439)
		(stroke
			(width 0.2)
			(type default)
		)
		(fill no)
		(layer "In5.Cu")
	)
	(gr_circle
		(center 269.26794 -389.3439)
		(end 270.15694 -389.3439)
		(stroke
			(width 0.2)
			(type default)
		)
		(fill no)
		(layer "In5.Cu")
	)
	(gr_circle
		(center 270.02994 -389.3439)
		(end 270.91894 -389.3439)
		(stroke
			(width 0.2)
			(type default)
		)
		(fill no)
		(layer "In5.Cu")
	)
	(gr_line
		(start 272.19021 -417.28009)
		(end 234.897676 -417.28009)
		(stroke
			(width 0.635)
			(type default)
		)
		(layer "In5.Cu")
	)
	(gr_circle
		(center 276.112986 -348.704662)
		(end 276.993096 -348.704662)
		(stroke
			(width 0.2)
			(type default)
		)
		(fill no)
		(layer "In5.Cu")
	)
	(gr_circle
		(center 276.1742 -389.29564)
		(end 277.0632 -389.29564)
		(stroke
			(width 0.2)
			(type default)
		)
		(fill no)
		(layer "In5.Cu")
	)
	(gr_line
		(start 276.314916 -440.669934)
		(end 195.50507 -440.669934)
		(stroke
			(width 1.016)
			(type default)
		)
		(layer "In5.Cu")
	)
	(gr_circle
		(center 276.730206 -348.704662)
		(end 277.610316 -348.704662)
		(stroke
			(width 0.2)
			(type default)
		)
		(fill no)
		(layer "In5.Cu")
	)
	(gr_line
		(start 276.815042 -441.4901)
		(end 276.815042 -441.17006)
		(stroke
			(width 1.016)
			(type default)
		)
		(layer "In5.Cu")
	)
	(gr_arc
		(start 276.815042 -441.4901)
		(mid 276.961452 -441.843558)
		(end 277.314914 -441.989972)
		(stroke
			(width 1.016)
			(type default)
		)
		(layer "In5.Cu")
	)
	(gr_arc
		(start 276.815042 -441.17006)
		(mid 276.668558 -440.816418)
		(end 276.314916 -440.669934)
		(stroke
			(width 1.016)
			(type default)
		)
		(layer "In5.Cu")
	)
	(gr_circle
		(center 276.9362 -389.29564)
		(end 277.8252 -389.29564)
		(stroke
			(width 0.2)
			(type default)
		)
		(fill no)
		(layer "In5.Cu")
	)
	(gr_circle
		(center 277.347426 -348.704662)
		(end 278.227536 -348.704662)
		(stroke
			(width 0.2)
			(type default)
		)
		(fill no)
		(layer "In5.Cu")
	)
	(gr_circle
		(center 277.593806 -348.025212)
		(end 278.482806 -348.025212)
		(stroke
			(width 0.2)
			(type default)
		)
		(fill no)
		(layer "In5.Cu")
	)
	(gr_circle
		(center 277.593806 -347.288612)
		(end 278.482806 -347.288612)
		(stroke
			(width 0.2)
			(type default)
		)
		(fill no)
		(layer "In5.Cu")
	)
	(gr_circle
		(center 277.6982 -389.29564)
		(end 278.5872 -389.29564)
		(stroke
			(width 0.2)
			(type default)
		)
		(fill no)
		(layer "In5.Cu")
	)
	(gr_circle
		(center 278.049482 -350.313752)
		(end 278.938482 -350.313752)
		(stroke
			(width 0.2)
			(type default)
		)
		(fill no)
		(layer "In5.Cu")
	)
	(gr_circle
		(center 278.049482 -349.577152)
		(end 278.938482 -349.577152)
		(stroke
			(width 0.2)
			(type default)
		)
		(fill no)
		(layer "In5.Cu")
	)
	(gr_circle
		(center 278.4602 -389.29564)
		(end 279.3492 -389.29564)
		(stroke
			(width 0.2)
			(type default)
		)
		(fill no)
		(layer "In5.Cu")
	)
	(gr_circle
		(center 278.574246 -349.137732)
		(end 279.463246 -349.137732)
		(stroke
			(width 0.2)
			(type default)
		)
		(fill no)
		(layer "In5.Cu")
	)
	(gr_circle
		(center 278.599646 -349.899732)
		(end 279.488646 -349.899732)
		(stroke
			(width 0.2)
			(type default)
		)
		(fill no)
		(layer "In5.Cu")
	)
	(gr_circle
		(center 279.133046 -350.255332)
		(end 280.022046 -350.255332)
		(stroke
			(width 0.2)
			(type default)
		)
		(fill no)
		(layer "In5.Cu")
	)
	(gr_circle
		(center 279.133046 -349.518732)
		(end 280.022046 -349.518732)
		(stroke
			(width 0.2)
			(type default)
		)
		(fill no)
		(layer "In5.Cu")
	)
	(gr_circle
		(center 279.133046 -348.782132)
		(end 280.022046 -348.782132)
		(stroke
			(width 0.2)
			(type default)
		)
		(fill no)
		(layer "In5.Cu")
	)
	(gr_line
		(start 279.416002 -397.46555)
		(end 280.36774 -398.417288)
		(stroke
			(width 0.635)
			(type default)
		)
		(layer "In5.Cu")
	)
	(gr_line
		(start 280.36774 -409.10256)
		(end 272.19021 -417.28009)
		(stroke
			(width 0.635)
			(type default)
		)
		(layer "In5.Cu")
	)
	(gr_line
		(start 280.36774 -398.417288)
		(end 280.36774 -409.10256)
		(stroke
			(width 0.635)
			(type default)
		)
		(layer "In5.Cu")
	)
	(gr_circle
		(center 284.393386 -348.704662)
		(end 285.273496 -348.704662)
		(stroke
			(width 0.2)
			(type default)
		)
		(fill no)
		(layer "In5.Cu")
	)
	(gr_circle
		(center 285.010606 -348.704662)
		(end 285.890716 -348.704662)
		(stroke
			(width 0.2)
			(type default)
		)
		(fill no)
		(layer "In5.Cu")
	)
	(gr_circle
		(center 285.627826 -348.704662)
		(end 286.507936 -348.704662)
		(stroke
			(width 0.2)
			(type default)
		)
		(fill no)
		(layer "In5.Cu")
	)
	(gr_circle
		(center 285.869126 -347.982032)
		(end 286.758126 -347.982032)
		(stroke
			(width 0.2)
			(type default)
		)
		(fill no)
		(layer "In5.Cu")
	)
	(gr_circle
		(center 285.869126 -347.245432)
		(end 286.758126 -347.245432)
		(stroke
			(width 0.2)
			(type default)
		)
		(fill no)
		(layer "In5.Cu")
	)
	(gr_circle
		(center 286.329882 -350.313752)
		(end 287.218882 -350.313752)
		(stroke
			(width 0.2)
			(type default)
		)
		(fill no)
		(layer "In5.Cu")
	)
	(gr_circle
		(center 286.329882 -349.577152)
		(end 287.218882 -349.577152)
		(stroke
			(width 0.2)
			(type default)
		)
		(fill no)
		(layer "In5.Cu")
	)
	(gr_circle
		(center 286.36595 -355.279198)
		(end 287.25495 -355.279198)
		(stroke
			(width 0.2)
			(type default)
		)
		(fill no)
		(layer "In5.Cu")
	)
	(gr_circle
		(center 286.37611 -356.584758)
		(end 287.26511 -356.584758)
		(stroke
			(width 0.2)
			(type default)
		)
		(fill no)
		(layer "In5.Cu")
	)
	(gr_circle
		(center 286.37611 -355.949758)
		(end 287.26511 -355.949758)
		(stroke
			(width 0.2)
			(type default)
		)
		(fill no)
		(layer "In5.Cu")
	)
	(gr_circle
		(center 286.854646 -349.137732)
		(end 287.743646 -349.137732)
		(stroke
			(width 0.2)
			(type default)
		)
		(fill no)
		(layer "In5.Cu")
	)
	(gr_circle
		(center 286.880046 -349.899732)
		(end 287.769046 -349.899732)
		(stroke
			(width 0.2)
			(type default)
		)
		(fill no)
		(layer "In5.Cu")
	)
	(gr_circle
		(center 287.00095 -355.279198)
		(end 287.88995 -355.279198)
		(stroke
			(width 0.2)
			(type default)
		)
		(fill no)
		(layer "In5.Cu")
	)
	(gr_circle
		(center 287.01111 -356.584758)
		(end 287.90011 -356.584758)
		(stroke
			(width 0.2)
			(type default)
		)
		(fill no)
		(layer "In5.Cu")
	)
	(gr_circle
		(center 287.01111 -355.949758)
		(end 287.90011 -355.949758)
		(stroke
			(width 0.2)
			(type default)
		)
		(fill no)
		(layer "In5.Cu")
	)
	(gr_circle
		(center 287.413446 -350.255332)
		(end 288.302446 -350.255332)
		(stroke
			(width 0.2)
			(type default)
		)
		(fill no)
		(layer "In5.Cu")
	)
	(gr_circle
		(center 287.413446 -349.518732)
		(end 288.302446 -349.518732)
		(stroke
			(width 0.2)
			(type default)
		)
		(fill no)
		(layer "In5.Cu")
	)
	(gr_circle
		(center 287.413446 -348.782132)
		(end 288.302446 -348.782132)
		(stroke
			(width 0.2)
			(type default)
		)
		(fill no)
		(layer "In5.Cu")
	)
	(gr_circle
		(center 287.63595 -355.279198)
		(end 288.52495 -355.279198)
		(stroke
			(width 0.2)
			(type default)
		)
		(fill no)
		(layer "In5.Cu")
	)
	(gr_circle
		(center 287.64611 -356.584758)
		(end 288.53511 -356.584758)
		(stroke
			(width 0.2)
			(type default)
		)
		(fill no)
		(layer "In5.Cu")
	)
	(gr_circle
		(center 287.64611 -355.949758)
		(end 288.53511 -355.949758)
		(stroke
			(width 0.2)
			(type default)
		)
		(fill no)
		(layer "In5.Cu")
	)
	(gr_circle
		(center 288.27095 -355.279198)
		(end 289.15995 -355.279198)
		(stroke
			(width 0.2)
			(type default)
		)
		(fill no)
		(layer "In5.Cu")
	)
	(gr_circle
		(center 288.28111 -356.584758)
		(end 289.17011 -356.584758)
		(stroke
			(width 0.2)
			(type default)
		)
		(fill no)
		(layer "In5.Cu")
	)
	(gr_circle
		(center 288.28111 -355.949758)
		(end 289.17011 -355.949758)
		(stroke
			(width 0.2)
			(type default)
		)
		(fill no)
		(layer "In5.Cu")
	)
	(gr_circle
		(center 288.90595 -355.279198)
		(end 289.79495 -355.279198)
		(stroke
			(width 0.2)
			(type default)
		)
		(fill no)
		(layer "In5.Cu")
	)
	(gr_circle
		(center 288.91611 -356.584758)
		(end 289.80511 -356.584758)
		(stroke
			(width 0.2)
			(type default)
		)
		(fill no)
		(layer "In5.Cu")
	)
	(gr_circle
		(center 288.91611 -355.949758)
		(end 289.80511 -355.949758)
		(stroke
			(width 0.2)
			(type default)
		)
		(fill no)
		(layer "In5.Cu")
	)
	(gr_circle
		(center 292.699186 -348.704662)
		(end 293.579296 -348.704662)
		(stroke
			(width 0.2)
			(type default)
		)
		(fill no)
		(layer "In5.Cu")
	)
	(gr_circle
		(center 293.316406 -348.704662)
		(end 294.196516 -348.704662)
		(stroke
			(width 0.2)
			(type default)
		)
		(fill no)
		(layer "In5.Cu")
	)
	(gr_circle
		(center 293.933626 -348.704662)
		(end 294.813736 -348.704662)
		(stroke
			(width 0.2)
			(type default)
		)
		(fill no)
		(layer "In5.Cu")
	)
	(gr_circle
		(center 294.146986 -347.959172)
		(end 295.035986 -347.959172)
		(stroke
			(width 0.2)
			(type default)
		)
		(fill no)
		(layer "In5.Cu")
	)
	(gr_circle
		(center 294.146986 -347.222572)
		(end 295.035986 -347.222572)
		(stroke
			(width 0.2)
			(type default)
		)
		(fill no)
		(layer "In5.Cu")
	)
	(gr_circle
		(center 294.635682 -350.313752)
		(end 295.524682 -350.313752)
		(stroke
			(width 0.2)
			(type default)
		)
		(fill no)
		(layer "In5.Cu")
	)
	(gr_circle
		(center 294.635682 -349.577152)
		(end 295.524682 -349.577152)
		(stroke
			(width 0.2)
			(type default)
		)
		(fill no)
		(layer "In5.Cu")
	)
	(gr_circle
		(center 295.160446 -349.137732)
		(end 296.049446 -349.137732)
		(stroke
			(width 0.2)
			(type default)
		)
		(fill no)
		(layer "In5.Cu")
	)
	(gr_circle
		(center 295.185846 -349.899732)
		(end 296.074846 -349.899732)
		(stroke
			(width 0.2)
			(type default)
		)
		(fill no)
		(layer "In5.Cu")
	)
	(gr_circle
		(center 295.719246 -350.255332)
		(end 296.608246 -350.255332)
		(stroke
			(width 0.2)
			(type default)
		)
		(fill no)
		(layer "In5.Cu")
	)
	(gr_circle
		(center 295.719246 -349.518732)
		(end 296.608246 -349.518732)
		(stroke
			(width 0.2)
			(type default)
		)
		(fill no)
		(layer "In5.Cu")
	)
	(gr_circle
		(center 295.719246 -348.782132)
		(end 296.608246 -348.782132)
		(stroke
			(width 0.2)
			(type default)
		)
		(fill no)
		(layer "In5.Cu")
	)
	(gr_circle
		(center 296.29989 -358.769666)
		(end 297.69689 -358.769666)
		(stroke
			(width 0.2)
			(type default)
		)
		(fill no)
		(layer "In5.Cu")
	)
	(gr_circle
		(center 301.055786 -348.704662)
		(end 301.935896 -348.704662)
		(stroke
			(width 0.2)
			(type default)
		)
		(fill no)
		(layer "In5.Cu")
	)
	(gr_circle
		(center 301.673006 -348.704662)
		(end 302.553116 -348.704662)
		(stroke
			(width 0.2)
			(type default)
		)
		(fill no)
		(layer "In5.Cu")
	)
	(gr_circle
		(center 302.290226 -348.704662)
		(end 303.170336 -348.704662)
		(stroke
			(width 0.2)
			(type default)
		)
		(fill no)
		(layer "In5.Cu")
	)
	(gr_circle
		(center 302.526446 -348.002352)
		(end 303.415446 -348.002352)
		(stroke
			(width 0.2)
			(type default)
		)
		(fill no)
		(layer "In5.Cu")
	)
	(gr_circle
		(center 302.526446 -347.265752)
		(end 303.415446 -347.265752)
		(stroke
			(width 0.2)
			(type default)
		)
		(fill no)
		(layer "In5.Cu")
	)
	(gr_circle
		(center 302.992282 -350.313752)
		(end 303.881282 -350.313752)
		(stroke
			(width 0.2)
			(type default)
		)
		(fill no)
		(layer "In5.Cu")
	)
	(gr_circle
		(center 302.992282 -349.577152)
		(end 303.881282 -349.577152)
		(stroke
			(width 0.2)
			(type default)
		)
		(fill no)
		(layer "In5.Cu")
	)
	(gr_circle
		(center 303.517046 -349.137732)
		(end 304.406046 -349.137732)
		(stroke
			(width 0.2)
			(type default)
		)
		(fill no)
		(layer "In5.Cu")
	)
	(gr_circle
		(center 303.542446 -349.899732)
		(end 304.431446 -349.899732)
		(stroke
			(width 0.2)
			(type default)
		)
		(fill no)
		(layer "In5.Cu")
	)
	(gr_circle
		(center 304.075846 -350.255332)
		(end 304.964846 -350.255332)
		(stroke
			(width 0.2)
			(type default)
		)
		(fill no)
		(layer "In5.Cu")
	)
	(gr_circle
		(center 304.075846 -349.518732)
		(end 304.964846 -349.518732)
		(stroke
			(width 0.2)
			(type default)
		)
		(fill no)
		(layer "In5.Cu")
	)
	(gr_circle
		(center 304.075846 -348.782132)
		(end 304.964846 -348.782132)
		(stroke
			(width 0.2)
			(type default)
		)
		(fill no)
		(layer "In5.Cu")
	)
	(gr_circle
		(center 309.386986 -348.704662)
		(end 310.267096 -348.704662)
		(stroke
			(width 0.2)
			(type default)
		)
		(fill no)
		(layer "In5.Cu")
	)
	(gr_circle
		(center 310.004206 -348.704662)
		(end 310.884316 -348.704662)
		(stroke
			(width 0.2)
			(type default)
		)
		(fill no)
		(layer "In5.Cu")
	)
	(gr_circle
		(center 310.621426 -348.704662)
		(end 311.501536 -348.704662)
		(stroke
			(width 0.2)
			(type default)
		)
		(fill no)
		(layer "In5.Cu")
	)
	(gr_circle
		(center 310.867806 -348.002352)
		(end 311.756806 -348.002352)
		(stroke
			(width 0.2)
			(type default)
		)
		(fill no)
		(layer "In5.Cu")
	)
	(gr_circle
		(center 310.867806 -347.265752)
		(end 311.756806 -347.265752)
		(stroke
			(width 0.2)
			(type default)
		)
		(fill no)
		(layer "In5.Cu")
	)
	(gr_circle
		(center 311.323482 -350.313752)
		(end 312.212482 -350.313752)
		(stroke
			(width 0.2)
			(type default)
		)
		(fill no)
		(layer "In5.Cu")
	)
	(gr_circle
		(center 311.323482 -349.577152)
		(end 312.212482 -349.577152)
		(stroke
			(width 0.2)
			(type default)
		)
		(fill no)
		(layer "In5.Cu")
	)
	(gr_circle
		(center 311.848246 -349.137732)
		(end 312.737246 -349.137732)
		(stroke
			(width 0.2)
			(type default)
		)
		(fill no)
		(layer "In5.Cu")
	)
	(gr_circle
		(center 311.873646 -349.899732)
		(end 312.762646 -349.899732)
		(stroke
			(width 0.2)
			(type default)
		)
		(fill no)
		(layer "In5.Cu")
	)
	(gr_circle
		(center 312.407046 -350.255332)
		(end 313.296046 -350.255332)
		(stroke
			(width 0.2)
			(type default)
		)
		(fill no)
		(layer "In5.Cu")
	)
	(gr_circle
		(center 312.407046 -349.518732)
		(end 313.296046 -349.518732)
		(stroke
			(width 0.2)
			(type default)
		)
		(fill no)
		(layer "In5.Cu")
	)
	(gr_circle
		(center 312.407046 -348.782132)
		(end 313.296046 -348.782132)
		(stroke
			(width 0.2)
			(type default)
		)
		(fill no)
		(layer "In5.Cu")
	)
	(gr_circle
		(center 319.0367 -336.983578)
		(end 319.91681 -336.983578)
		(stroke
			(width 0.2)
			(type default)
		)
		(fill no)
		(layer "In5.Cu")
	)
	(gr_circle
		(center 319.65392 -336.983578)
		(end 320.53403 -336.983578)
		(stroke
			(width 0.2)
			(type default)
		)
		(fill no)
		(layer "In5.Cu")
	)
	(gr_circle
		(center 320.27114 -336.983578)
		(end 321.15125 -336.983578)
		(stroke
			(width 0.2)
			(type default)
		)
		(fill no)
		(layer "In5.Cu")
	)
	(gr_circle
		(center 320.5607 -336.239612)
		(end 321.4497 -336.239612)
		(stroke
			(width 0.2)
			(type default)
		)
		(fill no)
		(layer "In5.Cu")
	)
	(gr_circle
		(center 320.5607 -335.503012)
		(end 321.4497 -335.503012)
		(stroke
			(width 0.2)
			(type default)
		)
		(fill no)
		(layer "In5.Cu")
	)
	(gr_circle
		(center 320.973196 -338.592668)
		(end 321.862196 -338.592668)
		(stroke
			(width 0.2)
			(type default)
		)
		(fill no)
		(layer "In5.Cu")
	)
	(gr_circle
		(center 320.973196 -337.856068)
		(end 321.862196 -337.856068)
		(stroke
			(width 0.2)
			(type default)
		)
		(fill no)
		(layer "In5.Cu")
	)
	(gr_circle
		(center 321.49796 -337.416648)
		(end 322.38696 -337.416648)
		(stroke
			(width 0.2)
			(type default)
		)
		(fill no)
		(layer "In5.Cu")
	)
	(gr_circle
		(center 321.52336 -338.178648)
		(end 322.41236 -338.178648)
		(stroke
			(width 0.2)
			(type default)
		)
		(fill no)
		(layer "In5.Cu")
	)
	(gr_circle
		(center 322.05676 -338.534248)
		(end 322.94576 -338.534248)
		(stroke
			(width 0.2)
			(type default)
		)
		(fill no)
		(layer "In5.Cu")
	)
	(gr_circle
		(center 322.05676 -337.797648)
		(end 322.94576 -337.797648)
		(stroke
			(width 0.2)
			(type default)
		)
		(fill no)
		(layer "In5.Cu")
	)
	(gr_circle
		(center 322.05676 -337.061048)
		(end 322.94576 -337.061048)
		(stroke
			(width 0.2)
			(type default)
		)
		(fill no)
		(layer "In5.Cu")
	)
	(gr_circle
		(center 327.392284 -336.976466)
		(end 328.272394 -336.976466)
		(stroke
			(width 0.2)
			(type default)
		)
		(fill no)
		(layer "In5.Cu")
	)
	(gr_circle
		(center 327.692258 -104.30129)
		(end 328.581258 -104.30129)
		(stroke
			(width 0.2)
			(type default)
		)
		(fill no)
		(layer "In5.Cu")
	)
	(gr_circle
		(center 327.951084 -349.43161)
		(end 329.348084 -349.43161)
		(stroke
			(width 0.2)
			(type default)
		)
		(fill no)
		(layer "In5.Cu")
	)
	(gr_circle
		(center 328.009504 -336.976466)
		(end 328.889614 -336.976466)
		(stroke
			(width 0.2)
			(type default)
		)
		(fill no)
		(layer "In5.Cu")
	)
	(gr_circle
		(center 328.626724 -336.976466)
		(end 329.506834 -336.976466)
		(stroke
			(width 0.2)
			(type default)
		)
		(fill no)
		(layer "In5.Cu")
	)
	(gr_circle
		(center 328.918824 -336.253836)
		(end 329.807824 -336.253836)
		(stroke
			(width 0.2)
			(type default)
		)
		(fill no)
		(layer "In5.Cu")
	)
	(gr_circle
		(center 328.918824 -335.517236)
		(end 329.807824 -335.517236)
		(stroke
			(width 0.2)
			(type default)
		)
		(fill no)
		(layer "In5.Cu")
	)
	(gr_circle
		(center 329.32878 -338.585556)
		(end 330.21778 -338.585556)
		(stroke
			(width 0.2)
			(type default)
		)
		(fill no)
		(layer "In5.Cu")
	)
	(gr_circle
		(center 329.32878 -337.848956)
		(end 330.21778 -337.848956)
		(stroke
			(width 0.2)
			(type default)
		)
		(fill no)
		(layer "In5.Cu")
	)
	(gr_circle
		(center 329.853544 -337.409536)
		(end 330.742544 -337.409536)
		(stroke
			(width 0.2)
			(type default)
		)
		(fill no)
		(layer "In5.Cu")
	)
	(gr_circle
		(center 329.878944 -338.171536)
		(end 330.767944 -338.171536)
		(stroke
			(width 0.2)
			(type default)
		)
		(fill no)
		(layer "In5.Cu")
	)
	(gr_circle
		(center 330.412344 -338.527136)
		(end 331.301344 -338.527136)
		(stroke
			(width 0.2)
			(type default)
		)
		(fill no)
		(layer "In5.Cu")
	)
	(gr_circle
		(center 330.412344 -337.790536)
		(end 331.301344 -337.790536)
		(stroke
			(width 0.2)
			(type default)
		)
		(fill no)
		(layer "In5.Cu")
	)
	(gr_circle
		(center 330.412344 -337.053936)
		(end 331.301344 -337.053936)
		(stroke
			(width 0.2)
			(type default)
		)
		(fill no)
		(layer "In5.Cu")
	)
	(gr_circle
		(center 335.411064 -349.43161)
		(end 336.808064 -349.43161)
		(stroke
			(width 0.2)
			(type default)
		)
		(fill no)
		(layer "In5.Cu")
	)
	(gr_circle
		(center 335.7499 -336.961988)
		(end 336.63001 -336.961988)
		(stroke
			(width 0.2)
			(type default)
		)
		(fill no)
		(layer "In5.Cu")
	)
	(gr_circle
		(center 336.36712 -336.961988)
		(end 337.24723 -336.961988)
		(stroke
			(width 0.2)
			(type default)
		)
		(fill no)
		(layer "In5.Cu")
	)
	(gr_circle
		(center 336.98434 -336.961988)
		(end 337.86445 -336.961988)
		(stroke
			(width 0.2)
			(type default)
		)
		(fill no)
		(layer "In5.Cu")
	)
	(gr_circle
		(center 337.280504 -336.253836)
		(end 338.169504 -336.253836)
		(stroke
			(width 0.2)
			(type default)
		)
		(fill no)
		(layer "In5.Cu")
	)
	(gr_circle
		(center 337.280504 -335.517236)
		(end 338.169504 -335.517236)
		(stroke
			(width 0.2)
			(type default)
		)
		(fill no)
		(layer "In5.Cu")
	)
	(gr_circle
		(center 337.686396 -338.571078)
		(end 338.575396 -338.571078)
		(stroke
			(width 0.2)
			(type default)
		)
		(fill no)
		(layer "In5.Cu")
	)
	(gr_circle
		(center 337.686396 -337.834478)
		(end 338.575396 -337.834478)
		(stroke
			(width 0.2)
			(type default)
		)
		(fill no)
		(layer "In5.Cu")
	)
	(gr_circle
		(center 338.21116 -337.395058)
		(end 339.10016 -337.395058)
		(stroke
			(width 0.2)
			(type default)
		)
		(fill no)
		(layer "In5.Cu")
	)
	(gr_circle
		(center 338.23656 -338.157058)
		(end 339.12556 -338.157058)
		(stroke
			(width 0.2)
			(type default)
		)
		(fill no)
		(layer "In5.Cu")
	)
	(gr_circle
		(center 338.76996 -338.512658)
		(end 339.65896 -338.512658)
		(stroke
			(width 0.2)
			(type default)
		)
		(fill no)
		(layer "In5.Cu")
	)
	(gr_circle
		(center 338.76996 -337.776058)
		(end 339.65896 -337.776058)
		(stroke
			(width 0.2)
			(type default)
		)
		(fill no)
		(layer "In5.Cu")
	)
	(gr_circle
		(center 338.76996 -337.039458)
		(end 339.65896 -337.039458)
		(stroke
			(width 0.2)
			(type default)
		)
		(fill no)
		(layer "In5.Cu")
	)
	(gr_circle
		(center 339.73897 -352.973132)
		(end 340.62797 -352.973132)
		(stroke
			(width 0.2)
			(type default)
		)
		(fill no)
		(layer "In5.Cu")
	)
	(gr_circle
		(center 339.739224 -352.215196)
		(end 340.628224 -352.215196)
		(stroke
			(width 0.2)
			(type default)
		)
		(fill no)
		(layer "In5.Cu")
	)
	(gr_circle
		(center 339.739224 -351.453196)
		(end 340.628224 -351.453196)
		(stroke
			(width 0.2)
			(type default)
		)
		(fill no)
		(layer "In5.Cu")
	)
	(gr_circle
		(center 340.501224 -352.215196)
		(end 341.390224 -352.215196)
		(stroke
			(width 0.2)
			(type default)
		)
		(fill no)
		(layer "In5.Cu")
	)
	(gr_circle
		(center 340.501224 -351.453196)
		(end 341.390224 -351.453196)
		(stroke
			(width 0.2)
			(type default)
		)
		(fill no)
		(layer "In5.Cu")
	)
	(gr_circle
		(center 340.667848 -353.010216)
		(end 341.556848 -353.010216)
		(stroke
			(width 0.2)
			(type default)
		)
		(fill no)
		(layer "In5.Cu")
	)
	(gr_circle
		(center 341.263224 -352.215196)
		(end 342.152224 -352.215196)
		(stroke
			(width 0.2)
			(type default)
		)
		(fill no)
		(layer "In5.Cu")
	)
	(gr_circle
		(center 341.263224 -351.453196)
		(end 342.152224 -351.453196)
		(stroke
			(width 0.2)
			(type default)
		)
		(fill no)
		(layer "In5.Cu")
	)
	(gr_circle
		(center 341.302848 -353.010216)
		(end 342.191848 -353.010216)
		(stroke
			(width 0.2)
			(type default)
		)
		(fill no)
		(layer "In5.Cu")
	)
	(gr_circle
		(center 341.937848 -353.010216)
		(end 342.826848 -353.010216)
		(stroke
			(width 0.2)
			(type default)
		)
		(fill no)
		(layer "In5.Cu")
	)
	(gr_circle
		(center 342.025224 -352.215196)
		(end 342.914224 -352.215196)
		(stroke
			(width 0.2)
			(type default)
		)
		(fill no)
		(layer "In5.Cu")
	)
	(gr_circle
		(center 342.025224 -351.453196)
		(end 342.914224 -351.453196)
		(stroke
			(width 0.2)
			(type default)
		)
		(fill no)
		(layer "In5.Cu")
	)
	(gr_circle
		(center 342.572848 -353.010216)
		(end 343.461848 -353.010216)
		(stroke
			(width 0.2)
			(type default)
		)
		(fill no)
		(layer "In5.Cu")
	)
	(gr_circle
		(center 342.787224 -352.215196)
		(end 343.676224 -352.215196)
		(stroke
			(width 0.2)
			(type default)
		)
		(fill no)
		(layer "In5.Cu")
	)
	(gr_circle
		(center 342.787224 -351.453196)
		(end 343.676224 -351.453196)
		(stroke
			(width 0.2)
			(type default)
		)
		(fill no)
		(layer "In5.Cu")
	)
	(gr_circle
		(center 343.46515 -353.006152)
		(end 344.35415 -353.006152)
		(stroke
			(width 0.2)
			(type default)
		)
		(fill no)
		(layer "In5.Cu")
	)
	(gr_circle
		(center 343.465404 -352.248216)
		(end 344.354404 -352.248216)
		(stroke
			(width 0.2)
			(type default)
		)
		(fill no)
		(layer "In5.Cu")
	)
	(gr_circle
		(center 343.465404 -351.486216)
		(end 344.354404 -351.486216)
		(stroke
			(width 0.2)
			(type default)
		)
		(fill no)
		(layer "In5.Cu")
	)
	(gr_circle
		(center 344.016838 -159.073596)
		(end 344.905838 -159.073596)
		(stroke
			(width 0.2)
			(type default)
		)
		(fill no)
		(layer "In5.Cu")
	)
	(gr_circle
		(center 344.016838 -158.336996)
		(end 344.905838 -158.336996)
		(stroke
			(width 0.2)
			(type default)
		)
		(fill no)
		(layer "In5.Cu")
	)
	(gr_circle
		(center 344.016838 -157.600396)
		(end 344.905838 -157.600396)
		(stroke
			(width 0.2)
			(type default)
		)
		(fill no)
		(layer "In5.Cu")
	)
	(gr_circle
		(center 344.0811 -337.012788)
		(end 344.96121 -337.012788)
		(stroke
			(width 0.2)
			(type default)
		)
		(fill no)
		(layer "In5.Cu")
	)
	(gr_circle
		(center 344.550238 -157.955996)
		(end 345.439238 -157.955996)
		(stroke
			(width 0.2)
			(type default)
		)
		(fill no)
		(layer "In5.Cu")
	)
	(gr_circle
		(center 344.575638 -158.717996)
		(end 345.464638 -158.717996)
		(stroke
			(width 0.2)
			(type default)
		)
		(fill no)
		(layer "In5.Cu")
	)
	(gr_circle
		(center 344.69832 -337.012788)
		(end 345.57843 -337.012788)
		(stroke
			(width 0.2)
			(type default)
		)
		(fill no)
		(layer "In5.Cu")
	)
	(gr_circle
		(center 345.100402 -158.278576)
		(end 345.989402 -158.278576)
		(stroke
			(width 0.2)
			(type default)
		)
		(fill no)
		(layer "In5.Cu")
	)
	(gr_circle
		(center 345.100402 -157.541976)
		(end 345.989402 -157.541976)
		(stroke
			(width 0.2)
			(type default)
		)
		(fill no)
		(layer "In5.Cu")
	)
	(gr_circle
		(center 345.31554 -337.012788)
		(end 346.19565 -337.012788)
		(stroke
			(width 0.2)
			(type default)
		)
		(fill no)
		(layer "In5.Cu")
	)
	(gr_circle
		(center 345.623896 -336.317336)
		(end 346.512896 -336.317336)
		(stroke
			(width 0.2)
			(type default)
		)
		(fill no)
		(layer "In5.Cu")
	)
	(gr_circle
		(center 345.623896 -335.580736)
		(end 346.512896 -335.580736)
		(stroke
			(width 0.2)
			(type default)
		)
		(fill no)
		(layer "In5.Cu")
	)
	(gr_circle
		(center 345.684856 -160.633156)
		(end 346.573856 -160.633156)
		(stroke
			(width 0.2)
			(type default)
		)
		(fill no)
		(layer "In5.Cu")
	)
	(gr_circle
		(center 345.684856 -159.896556)
		(end 346.573856 -159.896556)
		(stroke
			(width 0.2)
			(type default)
		)
		(fill no)
		(layer "In5.Cu")
	)
	(gr_circle
		(center 345.802458 -159.151066)
		(end 346.682568 -159.151066)
		(stroke
			(width 0.2)
			(type default)
		)
		(fill no)
		(layer "In5.Cu")
	)
	(gr_circle
		(center 346.017596 -339.358478)
		(end 346.906596 -339.358478)
		(stroke
			(width 0.2)
			(type default)
		)
		(fill no)
		(layer "In5.Cu")
	)
	(gr_circle
		(center 346.017596 -338.621878)
		(end 346.906596 -338.621878)
		(stroke
			(width 0.2)
			(type default)
		)
		(fill no)
		(layer "In5.Cu")
	)
	(gr_circle
		(center 346.017596 -337.885278)
		(end 346.906596 -337.885278)
		(stroke
			(width 0.2)
			(type default)
		)
		(fill no)
		(layer "In5.Cu")
	)
	(gr_circle
		(center 346.419678 -159.151066)
		(end 347.299788 -159.151066)
		(stroke
			(width 0.2)
			(type default)
		)
		(fill no)
		(layer "In5.Cu")
	)
	(gr_circle
		(center 346.54236 -337.445858)
		(end 347.43136 -337.445858)
		(stroke
			(width 0.2)
			(type default)
		)
		(fill no)
		(layer "In5.Cu")
	)
	(gr_circle
		(center 346.56776 -339.731858)
		(end 347.45676 -339.731858)
		(stroke
			(width 0.2)
			(type default)
		)
		(fill no)
		(layer "In5.Cu")
	)
	(gr_circle
		(center 346.56776 -338.969858)
		(end 347.45676 -338.969858)
		(stroke
			(width 0.2)
			(type default)
		)
		(fill no)
		(layer "In5.Cu")
	)
	(gr_circle
		(center 346.56776 -338.207858)
		(end 347.45676 -338.207858)
		(stroke
			(width 0.2)
			(type default)
		)
		(fill no)
		(layer "In5.Cu")
	)
	(gr_circle
		(center 347.036898 -159.151066)
		(end 347.917008 -159.151066)
		(stroke
			(width 0.2)
			(type default)
		)
		(fill no)
		(layer "In5.Cu")
	)
	(gr_circle
		(center 352.322638 -167.430196)
		(end 353.211638 -167.430196)
		(stroke
			(width 0.2)
			(type default)
		)
		(fill no)
		(layer "In5.Cu")
	)
	(gr_circle
		(center 352.322638 -166.693596)
		(end 353.211638 -166.693596)
		(stroke
			(width 0.2)
			(type default)
		)
		(fill no)
		(layer "In5.Cu")
	)
	(gr_circle
		(center 352.322638 -165.956996)
		(end 353.211638 -165.956996)
		(stroke
			(width 0.2)
			(type default)
		)
		(fill no)
		(layer "In5.Cu")
	)
	(gr_circle
		(center 352.356928 -341.922862)
		(end 353.237038 -341.922862)
		(stroke
			(width 0.2)
			(type default)
		)
		(fill no)
		(layer "In5.Cu")
	)
	(gr_circle
		(center 352.856038 -166.312596)
		(end 353.745038 -166.312596)
		(stroke
			(width 0.2)
			(type default)
		)
		(fill no)
		(layer "In5.Cu")
	)
	(gr_circle
		(center 352.881438 -167.074596)
		(end 353.770438 -167.074596)
		(stroke
			(width 0.2)
			(type default)
		)
		(fill no)
		(layer "In5.Cu")
	)
	(gr_circle
		(center 352.974148 -341.922862)
		(end 353.854258 -341.922862)
		(stroke
			(width 0.2)
			(type default)
		)
		(fill no)
		(layer "In5.Cu")
	)
	(gr_circle
		(center 353.406202 -166.635176)
		(end 354.295202 -166.635176)
		(stroke
			(width 0.2)
			(type default)
		)
		(fill no)
		(layer "In5.Cu")
	)
	(gr_circle
		(center 353.406202 -165.898576)
		(end 354.295202 -165.898576)
		(stroke
			(width 0.2)
			(type default)
		)
		(fill no)
		(layer "In5.Cu")
	)
	(gr_circle
		(center 353.591368 -341.922862)
		(end 354.471478 -341.922862)
		(stroke
			(width 0.2)
			(type default)
		)
		(fill no)
		(layer "In5.Cu")
	)
	(gr_circle
		(center 353.899724 -341.22741)
		(end 354.788724 -341.22741)
		(stroke
			(width 0.2)
			(type default)
		)
		(fill no)
		(layer "In5.Cu")
	)
	(gr_circle
		(center 353.899724 -340.49081)
		(end 354.788724 -340.49081)
		(stroke
			(width 0.2)
			(type default)
		)
		(fill no)
		(layer "In5.Cu")
	)
	(gr_circle
		(center 353.990656 -168.982136)
		(end 354.879656 -168.982136)
		(stroke
			(width 0.2)
			(type default)
		)
		(fill no)
		(layer "In5.Cu")
	)
	(gr_circle
		(center 353.990656 -168.245536)
		(end 354.879656 -168.245536)
		(stroke
			(width 0.2)
			(type default)
		)
		(fill no)
		(layer "In5.Cu")
	)
	(gr_circle
		(center 354.108258 -167.507666)
		(end 354.988368 -167.507666)
		(stroke
			(width 0.2)
			(type default)
		)
		(fill no)
		(layer "In5.Cu")
	)
	(gr_circle
		(center 354.293424 -343.531952)
		(end 355.182424 -343.531952)
		(stroke
			(width 0.2)
			(type default)
		)
		(fill no)
		(layer "In5.Cu")
	)
	(gr_circle
		(center 354.293424 -342.795352)
		(end 355.182424 -342.795352)
		(stroke
			(width 0.2)
			(type default)
		)
		(fill no)
		(layer "In5.Cu")
	)
	(gr_circle
		(center 354.725478 -167.507666)
		(end 355.605588 -167.507666)
		(stroke
			(width 0.2)
			(type default)
		)
		(fill no)
		(layer "In5.Cu")
	)
	(gr_circle
		(center 354.818188 -342.355932)
		(end 355.707188 -342.355932)
		(stroke
			(width 0.2)
			(type default)
		)
		(fill no)
		(layer "In5.Cu")
	)
	(gr_circle
		(center 354.843588 -343.117932)
		(end 355.732588 -343.117932)
		(stroke
			(width 0.2)
			(type default)
		)
		(fill no)
		(layer "In5.Cu")
	)
	(gr_circle
		(center 355.342698 -167.507666)
		(end 356.222808 -167.507666)
		(stroke
			(width 0.2)
			(type default)
		)
		(fill no)
		(layer "In5.Cu")
	)
	(gr_circle
		(center 355.376988 -343.473532)
		(end 356.265988 -343.473532)
		(stroke
			(width 0.2)
			(type default)
		)
		(fill no)
		(layer "In5.Cu")
	)
	(gr_circle
		(center 355.376988 -342.736932)
		(end 356.265988 -342.736932)
		(stroke
			(width 0.2)
			(type default)
		)
		(fill no)
		(layer "In5.Cu")
	)
	(gr_circle
		(center 355.376988 -342.000332)
		(end 356.265988 -342.000332)
		(stroke
			(width 0.2)
			(type default)
		)
		(fill no)
		(layer "In5.Cu")
	)
	(gr_circle
		(center 359.58526 -152.71242)
		(end 360.98226 -152.71242)
		(stroke
			(width 0.2)
			(type default)
		)
		(fill no)
		(layer "In5.Cu")
	)
	(gr_circle
		(center 360.603038 -175.705516)
		(end 361.492038 -175.705516)
		(stroke
			(width 0.2)
			(type default)
		)
		(fill no)
		(layer "In5.Cu")
	)
	(gr_circle
		(center 360.603038 -174.968916)
		(end 361.492038 -174.968916)
		(stroke
			(width 0.2)
			(type default)
		)
		(fill no)
		(layer "In5.Cu")
	)
	(gr_circle
		(center 360.603038 -174.232316)
		(end 361.492038 -174.232316)
		(stroke
			(width 0.2)
			(type default)
		)
		(fill no)
		(layer "In5.Cu")
	)
	(gr_circle
		(center 361.136438 -174.587916)
		(end 362.025438 -174.587916)
		(stroke
			(width 0.2)
			(type default)
		)
		(fill no)
		(layer "In5.Cu")
	)
	(gr_circle
		(center 361.161838 -175.349916)
		(end 362.050838 -175.349916)
		(stroke
			(width 0.2)
			(type default)
		)
		(fill no)
		(layer "In5.Cu")
	)
	(gr_circle
		(center 361.686602 -174.910496)
		(end 362.575602 -174.910496)
		(stroke
			(width 0.2)
			(type default)
		)
		(fill no)
		(layer "In5.Cu")
	)
	(gr_circle
		(center 361.686602 -174.173896)
		(end 362.575602 -174.173896)
		(stroke
			(width 0.2)
			(type default)
		)
		(fill no)
		(layer "In5.Cu")
	)
	(gr_circle
		(center 362.271056 -177.254916)
		(end 363.160056 -177.254916)
		(stroke
			(width 0.2)
			(type default)
		)
		(fill no)
		(layer "In5.Cu")
	)
	(gr_circle
		(center 362.271056 -176.518316)
		(end 363.160056 -176.518316)
		(stroke
			(width 0.2)
			(type default)
		)
		(fill no)
		(layer "In5.Cu")
	)
	(gr_circle
		(center 362.396278 -175.859186)
		(end 363.276388 -175.859186)
		(stroke
			(width 0.2)
			(type default)
		)
		(fill no)
		(layer "In5.Cu")
	)
	(gr_circle
		(center 363.013498 -175.859186)
		(end 363.893608 -175.859186)
		(stroke
			(width 0.2)
			(type default)
		)
		(fill no)
		(layer "In5.Cu")
	)
	(gr_circle
		(center 363.630718 -175.859186)
		(end 364.510828 -175.859186)
		(stroke
			(width 0.2)
			(type default)
		)
		(fill no)
		(layer "In5.Cu")
	)
	(gr_circle
		(center 366.744504 -164.53358)
		(end 367.633504 -164.53358)
		(stroke
			(width 0.2)
			(type default)
		)
		(fill no)
		(layer "In5.Cu")
	)
	(gr_circle
		(center 366.744504 -163.89858)
		(end 367.633504 -163.89858)
		(stroke
			(width 0.2)
			(type default)
		)
		(fill no)
		(layer "In5.Cu")
	)
	(gr_circle
		(center 366.757204 -165.19398)
		(end 367.646204 -165.19398)
		(stroke
			(width 0.2)
			(type default)
		)
		(fill no)
		(layer "In5.Cu")
	)
	(gr_circle
		(center 367.379504 -164.53358)
		(end 368.268504 -164.53358)
		(stroke
			(width 0.2)
			(type default)
		)
		(fill no)
		(layer "In5.Cu")
	)
	(gr_circle
		(center 367.379504 -163.89858)
		(end 368.268504 -163.89858)
		(stroke
			(width 0.2)
			(type default)
		)
		(fill no)
		(layer "In5.Cu")
	)
	(gr_circle
		(center 367.392204 -165.19398)
		(end 368.281204 -165.19398)
		(stroke
			(width 0.2)
			(type default)
		)
		(fill no)
		(layer "In5.Cu")
	)
	(gr_circle
		(center 368.044984 -164.53358)
		(end 368.933984 -164.53358)
		(stroke
			(width 0.2)
			(type default)
		)
		(fill no)
		(layer "In5.Cu")
	)
	(gr_circle
		(center 368.044984 -163.89858)
		(end 368.933984 -163.89858)
		(stroke
			(width 0.2)
			(type default)
		)
		(fill no)
		(layer "In5.Cu")
	)
	(gr_circle
		(center 368.057684 -165.19398)
		(end 368.946684 -165.19398)
		(stroke
			(width 0.2)
			(type default)
		)
		(fill no)
		(layer "In5.Cu")
	)
	(gr_circle
		(center 368.679984 -164.53358)
		(end 369.568984 -164.53358)
		(stroke
			(width 0.2)
			(type default)
		)
		(fill no)
		(layer "In5.Cu")
	)
	(gr_circle
		(center 368.679984 -163.89858)
		(end 369.568984 -163.89858)
		(stroke
			(width 0.2)
			(type default)
		)
		(fill no)
		(layer "In5.Cu")
	)
	(gr_circle
		(center 368.692684 -165.19398)
		(end 369.581684 -165.19398)
		(stroke
			(width 0.2)
			(type default)
		)
		(fill no)
		(layer "In5.Cu")
	)
	(gr_circle
		(center 368.96421 -179.204874)
		(end 369.85321 -179.204874)
		(stroke
			(width 0.2)
			(type default)
		)
		(fill no)
		(layer "In5.Cu")
	)
	(gr_circle
		(center 369.314984 -164.53358)
		(end 370.203984 -164.53358)
		(stroke
			(width 0.2)
			(type default)
		)
		(fill no)
		(layer "In5.Cu")
	)
	(gr_circle
		(center 369.314984 -163.89858)
		(end 370.203984 -163.89858)
		(stroke
			(width 0.2)
			(type default)
		)
		(fill no)
		(layer "In5.Cu")
	)
	(gr_circle
		(center 369.327684 -165.19398)
		(end 370.216684 -165.19398)
		(stroke
			(width 0.2)
			(type default)
		)
		(fill no)
		(layer "In5.Cu")
	)
	(gr_circle
		(center 369.49761 -179.560474)
		(end 370.38661 -179.560474)
		(stroke
			(width 0.2)
			(type default)
		)
		(fill no)
		(layer "In5.Cu")
	)
	(gr_circle
		(center 369.49761 -178.798474)
		(end 370.38661 -178.798474)
		(stroke
			(width 0.2)
			(type default)
		)
		(fill no)
		(layer "In5.Cu")
	)
	(gr_circle
		(center 369.49761 -178.036474)
		(end 370.38661 -178.036474)
		(stroke
			(width 0.2)
			(type default)
		)
		(fill no)
		(layer "In5.Cu")
	)
	(gr_circle
		(center 369.52301 -180.322474)
		(end 370.41201 -180.322474)
		(stroke
			(width 0.2)
			(type default)
		)
		(fill no)
		(layer "In5.Cu")
	)
	(gr_circle
		(center 369.949984 -164.53358)
		(end 370.838984 -164.53358)
		(stroke
			(width 0.2)
			(type default)
		)
		(fill no)
		(layer "In5.Cu")
	)
	(gr_circle
		(center 369.949984 -163.89858)
		(end 370.838984 -163.89858)
		(stroke
			(width 0.2)
			(type default)
		)
		(fill no)
		(layer "In5.Cu")
	)
	(gr_circle
		(center 369.962684 -165.19398)
		(end 370.851684 -165.19398)
		(stroke
			(width 0.2)
			(type default)
		)
		(fill no)
		(layer "In5.Cu")
	)
	(gr_circle
		(center 370.047774 -179.883054)
		(end 370.936774 -179.883054)
		(stroke
			(width 0.2)
			(type default)
		)
		(fill no)
		(layer "In5.Cu")
	)
	(gr_circle
		(center 370.047774 -179.146454)
		(end 370.936774 -179.146454)
		(stroke
			(width 0.2)
			(type default)
		)
		(fill no)
		(layer "In5.Cu")
	)
	(gr_circle
		(center 370.529358 -182.141876)
		(end 371.418358 -182.141876)
		(stroke
			(width 0.2)
			(type default)
		)
		(fill no)
		(layer "In5.Cu")
	)
	(gr_circle
		(center 370.529358 -181.405276)
		(end 371.418358 -181.405276)
		(stroke
			(width 0.2)
			(type default)
		)
		(fill no)
		(layer "In5.Cu")
	)
	(gr_circle
		(center 370.686584 -164.53358)
		(end 371.575584 -164.53358)
		(stroke
			(width 0.2)
			(type default)
		)
		(fill no)
		(layer "In5.Cu")
	)
	(gr_circle
		(center 370.686584 -163.89858)
		(end 371.575584 -163.89858)
		(stroke
			(width 0.2)
			(type default)
		)
		(fill no)
		(layer "In5.Cu")
	)
	(gr_circle
		(center 370.699284 -165.19398)
		(end 371.588284 -165.19398)
		(stroke
			(width 0.2)
			(type default)
		)
		(fill no)
		(layer "In5.Cu")
	)
	(gr_circle
		(center 370.74221 -180.803804)
		(end 371.62232 -180.803804)
		(stroke
			(width 0.2)
			(type default)
		)
		(fill no)
		(layer "In5.Cu")
	)
	(gr_circle
		(center 371.35943 -180.803804)
		(end 372.23954 -180.803804)
		(stroke
			(width 0.2)
			(type default)
		)
		(fill no)
		(layer "In5.Cu")
	)
	(gr_circle
		(center 371.97665 -180.803804)
		(end 372.85676 -180.803804)
		(stroke
			(width 0.2)
			(type default)
		)
		(fill no)
		(layer "In5.Cu")
	)
	(gr_circle
		(center 377.367038 -180.678074)
		(end 378.256038 -180.678074)
		(stroke
			(width 0.2)
			(type default)
		)
		(fill no)
		(layer "In5.Cu")
	)
	(gr_circle
		(center 377.367038 -179.941474)
		(end 378.256038 -179.941474)
		(stroke
			(width 0.2)
			(type default)
		)
		(fill no)
		(layer "In5.Cu")
	)
	(gr_circle
		(center 377.367038 -179.204874)
		(end 378.256038 -179.204874)
		(stroke
			(width 0.2)
			(type default)
		)
		(fill no)
		(layer "In5.Cu")
	)
	(gr_circle
		(center 377.869958 -162.59683)
		(end 379.266958 -162.59683)
		(stroke
			(width 0.2)
			(type default)
		)
		(fill no)
		(layer "In5.Cu")
	)
	(gr_circle
		(center 377.900438 -179.560474)
		(end 378.789438 -179.560474)
		(stroke
			(width 0.2)
			(type default)
		)
		(fill no)
		(layer "In5.Cu")
	)
	(gr_circle
		(center 377.925838 -180.322474)
		(end 378.814838 -180.322474)
		(stroke
			(width 0.2)
			(type default)
		)
		(fill no)
		(layer "In5.Cu")
	)
	(gr_circle
		(center 378.450602 -179.883054)
		(end 379.339602 -179.883054)
		(stroke
			(width 0.2)
			(type default)
		)
		(fill no)
		(layer "In5.Cu")
	)
	(gr_circle
		(center 378.450602 -179.146454)
		(end 379.339602 -179.146454)
		(stroke
			(width 0.2)
			(type default)
		)
		(fill no)
		(layer "In5.Cu")
	)
	(gr_circle
		(center 379.035056 -182.230776)
		(end 379.924056 -182.230776)
		(stroke
			(width 0.2)
			(type default)
		)
		(fill no)
		(layer "In5.Cu")
	)
	(gr_circle
		(center 379.035056 -181.494176)
		(end 379.924056 -181.494176)
		(stroke
			(width 0.2)
			(type default)
		)
		(fill no)
		(layer "In5.Cu")
	)
	(gr_circle
		(center 379.152658 -180.755544)
		(end 380.032768 -180.755544)
		(stroke
			(width 0.2)
			(type default)
		)
		(fill no)
		(layer "In5.Cu")
	)
	(gr_circle
		(center 379.769878 -180.755544)
		(end 380.649988 -180.755544)
		(stroke
			(width 0.2)
			(type default)
		)
		(fill no)
		(layer "In5.Cu")
	)
	(gr_circle
		(center 380.387098 -180.755544)
		(end 381.267208 -180.755544)
		(stroke
			(width 0.2)
			(type default)
		)
		(fill no)
		(layer "In5.Cu")
	)
	(gr_arc
		(start 385.601972 -11.780012)
		(mid 387.016183 -11.194227)
		(end 387.601968 -9.780016)
		(stroke
			(width 1.016)
			(type default)
		)
		(layer "In5.Cu")
	)
	(gr_circle
		(center 385.698238 -180.678074)
		(end 386.587238 -180.678074)
		(stroke
			(width 0.2)
			(type default)
		)
		(fill no)
		(layer "In5.Cu")
	)
	(gr_circle
		(center 385.698238 -179.941474)
		(end 386.587238 -179.941474)
		(stroke
			(width 0.2)
			(type default)
		)
		(fill no)
		(layer "In5.Cu")
	)
	(gr_circle
		(center 385.698238 -179.204874)
		(end 386.587238 -179.204874)
		(stroke
			(width 0.2)
			(type default)
		)
		(fill no)
		(layer "In5.Cu")
	)
	(gr_circle
		(center 386.231638 -179.560474)
		(end 387.120638 -179.560474)
		(stroke
			(width 0.2)
			(type default)
		)
		(fill no)
		(layer "In5.Cu")
	)
	(gr_circle
		(center 386.257038 -180.322474)
		(end 387.146038 -180.322474)
		(stroke
			(width 0.2)
			(type default)
		)
		(fill no)
		(layer "In5.Cu")
	)
	(gr_circle
		(center 386.781802 -179.883054)
		(end 387.670802 -179.883054)
		(stroke
			(width 0.2)
			(type default)
		)
		(fill no)
		(layer "In5.Cu")
	)
	(gr_circle
		(center 386.781802 -179.146454)
		(end 387.670802 -179.146454)
		(stroke
			(width 0.2)
			(type default)
		)
		(fill no)
		(layer "In5.Cu")
	)
	(gr_circle
		(center 387.206998 -162.65271)
		(end 388.603998 -162.65271)
		(stroke
			(width 0.2)
			(type default)
		)
		(fill no)
		(layer "In5.Cu")
	)
	(gr_circle
		(center 387.293358 -157.001972)
		(end 388.182358 -157.001972)
		(stroke
			(width 0.2)
			(type default)
		)
		(fill no)
		(layer "In5.Cu")
	)
	(gr_circle
		(center 387.293358 -156.366972)
		(end 388.182358 -156.366972)
		(stroke
			(width 0.2)
			(type default)
		)
		(fill no)
		(layer "In5.Cu")
	)
	(gr_circle
		(center 387.293358 -155.724352)
		(end 388.182358 -155.724352)
		(stroke
			(width 0.2)
			(type default)
		)
		(fill no)
		(layer "In5.Cu")
	)
	(gr_circle
		(center 387.293358 -155.089352)
		(end 388.182358 -155.089352)
		(stroke
			(width 0.2)
			(type default)
		)
		(fill no)
		(layer "In5.Cu")
	)
	(gr_circle
		(center 387.293358 -154.428952)
		(end 388.182358 -154.428952)
		(stroke
			(width 0.2)
			(type default)
		)
		(fill no)
		(layer "In5.Cu")
	)
	(gr_circle
		(center 387.293358 -153.793952)
		(end 388.182358 -153.793952)
		(stroke
			(width 0.2)
			(type default)
		)
		(fill no)
		(layer "In5.Cu")
	)
	(gr_circle
		(center 387.366256 -182.230776)
		(end 388.255256 -182.230776)
		(stroke
			(width 0.2)
			(type default)
		)
		(fill no)
		(layer "In5.Cu")
	)
	(gr_circle
		(center 387.366256 -181.494176)
		(end 388.255256 -181.494176)
		(stroke
			(width 0.2)
			(type default)
		)
		(fill no)
		(layer "In5.Cu")
	)
	(gr_circle
		(center 387.483858 -180.755544)
		(end 388.363968 -180.755544)
		(stroke
			(width 0.2)
			(type default)
		)
		(fill no)
		(layer "In5.Cu")
	)
	(gr_line
		(start 387.601968 -9.780016)
		(end 387.601968 -0.500126)
		(stroke
			(width 1.016)
			(type default)
		)
		(layer "In5.Cu")
	)
	(gr_circle
		(center 387.928358 -157.001972)
		(end 388.817358 -157.001972)
		(stroke
			(width 0.2)
			(type default)
		)
		(fill no)
		(layer "In5.Cu")
	)
	(gr_circle
		(center 387.928358 -156.366972)
		(end 388.817358 -156.366972)
		(stroke
			(width 0.2)
			(type default)
		)
		(fill no)
		(layer "In5.Cu")
	)
	(gr_circle
		(center 387.928358 -155.724352)
		(end 388.817358 -155.724352)
		(stroke
			(width 0.2)
			(type default)
		)
		(fill no)
		(layer "In5.Cu")
	)
	(gr_circle
		(center 387.928358 -155.089352)
		(end 388.817358 -155.089352)
		(stroke
			(width 0.2)
			(type default)
		)
		(fill no)
		(layer "In5.Cu")
	)
	(gr_circle
		(center 387.928358 -154.428952)
		(end 388.817358 -154.428952)
		(stroke
			(width 0.2)
			(type default)
		)
		(fill no)
		(layer "In5.Cu")
	)
	(gr_circle
		(center 387.928358 -153.793952)
		(end 388.817358 -153.793952)
		(stroke
			(width 0.2)
			(type default)
		)
		(fill no)
		(layer "In5.Cu")
	)
	(gr_circle
		(center 388.101078 -180.755544)
		(end 388.981188 -180.755544)
		(stroke
			(width 0.2)
			(type default)
		)
		(fill no)
		(layer "In5.Cu")
	)
	(gr_arc
		(start 388.102094 0)
		(mid 387.748465 -0.146487)
		(end 387.601968 -0.500126)
		(stroke
			(width 1.016)
			(type default)
		)
		(layer "In5.Cu")
	)
	(gr_line
		(start 388.102094 0)
		(end 455.701908 0)
		(stroke
			(width 1.016)
			(type default)
		)
		(layer "In5.Cu")
	)
	(gr_circle
		(center 388.718298 -180.755544)
		(end 389.598408 -180.755544)
		(stroke
			(width 0.2)
			(type default)
		)
		(fill no)
		(layer "In5.Cu")
	)
	(gr_circle
		(center 394.628878 -173.21911)
		(end 395.517878 -173.21911)
		(stroke
			(width 0.2)
			(type default)
		)
		(fill no)
		(layer "In5.Cu")
	)
	(gr_circle
		(center 394.628878 -172.45711)
		(end 395.517878 -172.45711)
		(stroke
			(width 0.2)
			(type default)
		)
		(fill no)
		(layer "In5.Cu")
	)
	(gr_circle
		(center 394.646658 -173.987714)
		(end 395.535658 -173.987714)
		(stroke
			(width 0.2)
			(type default)
		)
		(fill no)
		(layer "In5.Cu")
	)
	(gr_circle
		(center 394.672058 -174.749714)
		(end 395.561058 -174.749714)
		(stroke
			(width 0.2)
			(type default)
		)
		(fill no)
		(layer "In5.Cu")
	)
	(gr_circle
		(center 395.196822 -174.310294)
		(end 396.085822 -174.310294)
		(stroke
			(width 0.2)
			(type default)
		)
		(fill no)
		(layer "In5.Cu")
	)
	(gr_circle
		(center 395.196822 -173.573694)
		(end 396.085822 -173.573694)
		(stroke
			(width 0.2)
			(type default)
		)
		(fill no)
		(layer "In5.Cu")
	)
	(gr_circle
		(center 395.230858 -172.819314)
		(end 396.119858 -172.819314)
		(stroke
			(width 0.2)
			(type default)
		)
		(fill no)
		(layer "In5.Cu")
	)
	(gr_circle
		(center 395.781276 -176.657254)
		(end 396.670276 -176.657254)
		(stroke
			(width 0.2)
			(type default)
		)
		(fill no)
		(layer "In5.Cu")
	)
	(gr_circle
		(center 395.781276 -175.895254)
		(end 396.670276 -175.895254)
		(stroke
			(width 0.2)
			(type default)
		)
		(fill no)
		(layer "In5.Cu")
	)
	(gr_circle
		(center 395.898878 -175.182784)
		(end 396.778988 -175.182784)
		(stroke
			(width 0.2)
			(type default)
		)
		(fill no)
		(layer "In5.Cu")
	)
	(gr_circle
		(center 396.516098 -175.182784)
		(end 397.396208 -175.182784)
		(stroke
			(width 0.2)
			(type default)
		)
		(fill no)
		(layer "In5.Cu")
	)
	(gr_circle
		(center 397.133318 -175.182784)
		(end 398.013428 -175.182784)
		(stroke
			(width 0.2)
			(type default)
		)
		(fill no)
		(layer "In5.Cu")
	)
	(gr_circle
		(center 399.165064 -81.051146)
		(end 400.054064 -81.051146)
		(stroke
			(width 0.2)
			(type default)
		)
		(fill no)
		(layer "In5.Cu")
	)
	(gr_circle
		(center 402.436838 -166.527988)
		(end 403.325838 -166.527988)
		(stroke
			(width 0.2)
			(type default)
		)
		(fill no)
		(layer "In5.Cu")
	)
	(gr_circle
		(center 402.436838 -165.791388)
		(end 403.325838 -165.791388)
		(stroke
			(width 0.2)
			(type default)
		)
		(fill no)
		(layer "In5.Cu")
	)
	(gr_circle
		(center 402.436838 -165.054788)
		(end 403.325838 -165.054788)
		(stroke
			(width 0.2)
			(type default)
		)
		(fill no)
		(layer "In5.Cu")
	)
	(gr_circle
		(center 402.970238 -165.410388)
		(end 403.859238 -165.410388)
		(stroke
			(width 0.2)
			(type default)
		)
		(fill no)
		(layer "In5.Cu")
	)
	(gr_circle
		(center 402.995638 -166.172388)
		(end 403.884638 -166.172388)
		(stroke
			(width 0.2)
			(type default)
		)
		(fill no)
		(layer "In5.Cu")
	)
	(gr_circle
		(center 403.520402 -165.732968)
		(end 404.409402 -165.732968)
		(stroke
			(width 0.2)
			(type default)
		)
		(fill no)
		(layer "In5.Cu")
	)
	(gr_circle
		(center 403.520402 -164.996368)
		(end 404.409402 -164.996368)
		(stroke
			(width 0.2)
			(type default)
		)
		(fill no)
		(layer "In5.Cu")
	)
	(gr_circle
		(center 404.104856 -168.082214)
		(end 404.993856 -168.082214)
		(stroke
			(width 0.2)
			(type default)
		)
		(fill no)
		(layer "In5.Cu")
	)
	(gr_circle
		(center 404.104856 -167.320214)
		(end 404.993856 -167.320214)
		(stroke
			(width 0.2)
			(type default)
		)
		(fill no)
		(layer "In5.Cu")
	)
	(gr_circle
		(center 404.222458 -166.605458)
		(end 405.102568 -166.605458)
		(stroke
			(width 0.2)
			(type default)
		)
		(fill no)
		(layer "In5.Cu")
	)
	(gr_circle
		(center 404.839678 -166.605458)
		(end 405.719788 -166.605458)
		(stroke
			(width 0.2)
			(type default)
		)
		(fill no)
		(layer "In5.Cu")
	)
	(gr_circle
		(center 405.456898 -166.605458)
		(end 406.337008 -166.605458)
		(stroke
			(width 0.2)
			(type default)
		)
		(fill no)
		(layer "In5.Cu")
	)
	(gr_circle
		(center 410.818838 -161.701988)
		(end 411.707838 -161.701988)
		(stroke
			(width 0.2)
			(type default)
		)
		(fill no)
		(layer "In5.Cu")
	)
	(gr_circle
		(center 410.818838 -160.965388)
		(end 411.707838 -160.965388)
		(stroke
			(width 0.2)
			(type default)
		)
		(fill no)
		(layer "In5.Cu")
	)
	(gr_circle
		(center 410.818838 -160.228788)
		(end 411.707838 -160.228788)
		(stroke
			(width 0.2)
			(type default)
		)
		(fill no)
		(layer "In5.Cu")
	)
	(gr_circle
		(center 411.352238 -160.584388)
		(end 412.241238 -160.584388)
		(stroke
			(width 0.2)
			(type default)
		)
		(fill no)
		(layer "In5.Cu")
	)
	(gr_circle
		(center 411.377638 -161.346388)
		(end 412.266638 -161.346388)
		(stroke
			(width 0.2)
			(type default)
		)
		(fill no)
		(layer "In5.Cu")
	)
	(gr_circle
		(center 411.902402 -160.906968)
		(end 412.791402 -160.906968)
		(stroke
			(width 0.2)
			(type default)
		)
		(fill no)
		(layer "In5.Cu")
	)
	(gr_circle
		(center 411.902402 -160.170368)
		(end 412.791402 -160.170368)
		(stroke
			(width 0.2)
			(type default)
		)
		(fill no)
		(layer "In5.Cu")
	)
	(gr_circle
		(center 412.486856 -163.256214)
		(end 413.375856 -163.256214)
		(stroke
			(width 0.2)
			(type default)
		)
		(fill no)
		(layer "In5.Cu")
	)
	(gr_circle
		(center 412.486856 -162.494214)
		(end 413.375856 -162.494214)
		(stroke
			(width 0.2)
			(type default)
		)
		(fill no)
		(layer "In5.Cu")
	)
	(gr_circle
		(center 412.604458 -161.779458)
		(end 413.484568 -161.779458)
		(stroke
			(width 0.2)
			(type default)
		)
		(fill no)
		(layer "In5.Cu")
	)
	(gr_circle
		(center 413.221678 -161.779458)
		(end 414.101788 -161.779458)
		(stroke
			(width 0.2)
			(type default)
		)
		(fill no)
		(layer "In5.Cu")
	)
	(gr_circle
		(center 413.838898 -161.779458)
		(end 414.719008 -161.779458)
		(stroke
			(width 0.2)
			(type default)
		)
		(fill no)
		(layer "In5.Cu")
	)
	(gr_circle
		(center 424.33494 -353.10318)
		(end 425.21505 -353.10318)
		(stroke
			(width 0.2)
			(type default)
		)
		(fill no)
		(layer "In5.Cu")
	)
	(gr_circle
		(center 424.95216 -353.10318)
		(end 425.83227 -353.10318)
		(stroke
			(width 0.2)
			(type default)
		)
		(fill no)
		(layer "In5.Cu")
	)
	(gr_circle
		(center 425.56938 -353.10318)
		(end 426.44949 -353.10318)
		(stroke
			(width 0.2)
			(type default)
		)
		(fill no)
		(layer "In5.Cu")
	)
	(gr_circle
		(center 425.686474 -352.35769)
		(end 426.575474 -352.35769)
		(stroke
			(width 0.2)
			(type default)
		)
		(fill no)
		(layer "In5.Cu")
	)
	(gr_circle
		(center 425.686474 -351.62109)
		(end 426.575474 -351.62109)
		(stroke
			(width 0.2)
			(type default)
		)
		(fill no)
		(layer "In5.Cu")
	)
	(gr_circle
		(center 426.271436 -354.71227)
		(end 427.160436 -354.71227)
		(stroke
			(width 0.2)
			(type default)
		)
		(fill no)
		(layer "In5.Cu")
	)
	(gr_circle
		(center 426.271436 -353.97567)
		(end 427.160436 -353.97567)
		(stroke
			(width 0.2)
			(type default)
		)
		(fill no)
		(layer "In5.Cu")
	)
	(gr_circle
		(center 426.7962 -353.53625)
		(end 427.6852 -353.53625)
		(stroke
			(width 0.2)
			(type default)
		)
		(fill no)
		(layer "In5.Cu")
	)
	(gr_circle
		(center 426.8216 -354.29825)
		(end 427.7106 -354.29825)
		(stroke
			(width 0.2)
			(type default)
		)
		(fill no)
		(layer "In5.Cu")
	)
	(gr_circle
		(center 427.355 -354.65385)
		(end 428.244 -354.65385)
		(stroke
			(width 0.2)
			(type default)
		)
		(fill no)
		(layer "In5.Cu")
	)
	(gr_circle
		(center 427.355 -353.91725)
		(end 428.244 -353.91725)
		(stroke
			(width 0.2)
			(type default)
		)
		(fill no)
		(layer "In5.Cu")
	)
	(gr_circle
		(center 427.355 -353.18065)
		(end 428.244 -353.18065)
		(stroke
			(width 0.2)
			(type default)
		)
		(fill no)
		(layer "In5.Cu")
	)
	(gr_circle
		(center 432.01336 -361.827826)
		(end 433.41036 -361.827826)
		(stroke
			(width 0.2)
			(type default)
		)
		(fill no)
		(layer "In5.Cu")
	)
	(gr_circle
		(center 432.661568 -353.12858)
		(end 433.541678 -353.12858)
		(stroke
			(width 0.2)
			(type default)
		)
		(fill no)
		(layer "In5.Cu")
	)
	(gr_circle
		(center 433.278788 -353.12858)
		(end 434.158898 -353.12858)
		(stroke
			(width 0.2)
			(type default)
		)
		(fill no)
		(layer "In5.Cu")
	)
	(gr_circle
		(center 433.896008 -353.12858)
		(end 434.776118 -353.12858)
		(stroke
			(width 0.2)
			(type default)
		)
		(fill no)
		(layer "In5.Cu")
	)
	(gr_circle
		(center 434.013102 -352.38309)
		(end 434.902102 -352.38309)
		(stroke
			(width 0.2)
			(type default)
		)
		(fill no)
		(layer "In5.Cu")
	)
	(gr_circle
		(center 434.013102 -351.64649)
		(end 434.902102 -351.64649)
		(stroke
			(width 0.2)
			(type default)
		)
		(fill no)
		(layer "In5.Cu")
	)
	(gr_circle
		(center 434.598064 -354.73767)
		(end 435.487064 -354.73767)
		(stroke
			(width 0.2)
			(type default)
		)
		(fill no)
		(layer "In5.Cu")
	)
	(gr_circle
		(center 434.598064 -354.00107)
		(end 435.487064 -354.00107)
		(stroke
			(width 0.2)
			(type default)
		)
		(fill no)
		(layer "In5.Cu")
	)
	(gr_circle
		(center 435.122828 -353.56165)
		(end 436.011828 -353.56165)
		(stroke
			(width 0.2)
			(type default)
		)
		(fill no)
		(layer "In5.Cu")
	)
	(gr_circle
		(center 435.148228 -354.32365)
		(end 436.037228 -354.32365)
		(stroke
			(width 0.2)
			(type default)
		)
		(fill no)
		(layer "In5.Cu")
	)
	(gr_circle
		(center 435.469538 -361.496102)
		(end 436.358538 -361.496102)
		(stroke
			(width 0.2)
			(type default)
		)
		(fill no)
		(layer "In5.Cu")
	)
	(gr_circle
		(center 435.469538 -360.734102)
		(end 436.358538 -360.734102)
		(stroke
			(width 0.2)
			(type default)
		)
		(fill no)
		(layer "In5.Cu")
	)
	(gr_circle
		(center 435.469538 -359.972102)
		(end 436.358538 -359.972102)
		(stroke
			(width 0.2)
			(type default)
		)
		(fill no)
		(layer "In5.Cu")
	)
	(gr_circle
		(center 435.681628 -354.67925)
		(end 436.570628 -354.67925)
		(stroke
			(width 0.2)
			(type default)
		)
		(fill no)
		(layer "In5.Cu")
	)
	(gr_circle
		(center 435.681628 -353.94265)
		(end 436.570628 -353.94265)
		(stroke
			(width 0.2)
			(type default)
		)
		(fill no)
		(layer "In5.Cu")
	)
	(gr_circle
		(center 435.681628 -353.20605)
		(end 436.570628 -353.20605)
		(stroke
			(width 0.2)
			(type default)
		)
		(fill no)
		(layer "In5.Cu")
	)
	(gr_circle
		(center 436.231538 -361.496102)
		(end 437.120538 -361.496102)
		(stroke
			(width 0.2)
			(type default)
		)
		(fill no)
		(layer "In5.Cu")
	)
	(gr_circle
		(center 436.231538 -360.734102)
		(end 437.120538 -360.734102)
		(stroke
			(width 0.2)
			(type default)
		)
		(fill no)
		(layer "In5.Cu")
	)
	(gr_circle
		(center 436.231538 -359.972102)
		(end 437.120538 -359.972102)
		(stroke
			(width 0.2)
			(type default)
		)
		(fill no)
		(layer "In5.Cu")
	)
	(gr_circle
		(center 437.703214 -12.400788)
		(end 438.592214 -12.400788)
		(stroke
			(width 0.2)
			(type default)
		)
		(fill no)
		(layer "In5.Cu")
	)
	(gr_circle
		(center 438.06999 -13.069316)
		(end 438.95899 -13.069316)
		(stroke
			(width 0.2)
			(type default)
		)
		(fill no)
		(layer "In5.Cu")
	)
	(gr_circle
		(center 438.592214 -12.400788)
		(end 439.481214 -12.400788)
		(stroke
			(width 0.2)
			(type default)
		)
		(fill no)
		(layer "In5.Cu")
	)
	(gr_circle
		(center 438.71515 -13.061696)
		(end 439.60415 -13.061696)
		(stroke
			(width 0.2)
			(type default)
		)
		(fill no)
		(layer "In5.Cu")
	)
	(gr_circle
		(center 439.39333 -13.043916)
		(end 440.28233 -13.043916)
		(stroke
			(width 0.2)
			(type default)
		)
		(fill no)
		(layer "In5.Cu")
	)
	(gr_circle
		(center 439.481214 -12.400788)
		(end 440.370214 -12.400788)
		(stroke
			(width 0.2)
			(type default)
		)
		(fill no)
		(layer "In5.Cu")
	)
	(gr_circle
		(center 440.945524 -11.261852)
		(end 441.834524 -11.261852)
		(stroke
			(width 0.2)
			(type default)
		)
		(fill no)
		(layer "In5.Cu")
	)
	(gr_circle
		(center 440.945524 -10.626852)
		(end 441.834524 -10.626852)
		(stroke
			(width 0.2)
			(type default)
		)
		(fill no)
		(layer "In5.Cu")
	)
	(gr_circle
		(center 441.129674 -25.982422)
		(end 442.018674 -25.982422)
		(stroke
			(width 0.2)
			(type default)
		)
		(fill no)
		(layer "In5.Cu")
	)
	(gr_circle
		(center 441.354718 -20.73656)
		(end 442.243718 -20.73656)
		(stroke
			(width 0.2)
			(type default)
		)
		(fill no)
		(layer "In5.Cu")
	)
	(gr_circle
		(center 441.354718 -20.10156)
		(end 442.243718 -20.10156)
		(stroke
			(width 0.2)
			(type default)
		)
		(fill no)
		(layer "In5.Cu")
	)
	(gr_circle
		(center 441.354718 -19.21256)
		(end 442.243718 -19.21256)
		(stroke
			(width 0.2)
			(type default)
		)
		(fill no)
		(layer "In5.Cu")
	)
	(gr_circle
		(center 441.354718 -18.57756)
		(end 442.243718 -18.57756)
		(stroke
			(width 0.2)
			(type default)
		)
		(fill no)
		(layer "In5.Cu")
	)
	(gr_circle
		(center 441.475622 -14.123162)
		(end 442.364622 -14.123162)
		(stroke
			(width 0.2)
			(type default)
		)
		(fill no)
		(layer "In5.Cu")
	)
	(gr_circle
		(center 441.475622 -13.488162)
		(end 442.364622 -13.488162)
		(stroke
			(width 0.2)
			(type default)
		)
		(fill no)
		(layer "In5.Cu")
	)
	(gr_circle
		(center 441.56249 -25.461976)
		(end 442.45149 -25.461976)
		(stroke
			(width 0.2)
			(type default)
		)
		(fill no)
		(layer "In5.Cu")
	)
	(gr_circle
		(center 442.018674 -25.982422)
		(end 442.907674 -25.982422)
		(stroke
			(width 0.2)
			(type default)
		)
		(fill no)
		(layer "In5.Cu")
	)
	(gr_circle
		(center 442.371734 -20.983702)
		(end 443.260734 -20.983702)
		(stroke
			(width 0.2)
			(type default)
		)
		(fill no)
		(layer "In5.Cu")
	)
	(gr_circle
		(center 442.371734 -20.348702)
		(end 443.260734 -20.348702)
		(stroke
			(width 0.2)
			(type default)
		)
		(fill no)
		(layer "In5.Cu")
	)
	(gr_circle
		(center 442.371734 -19.459702)
		(end 443.260734 -19.459702)
		(stroke
			(width 0.2)
			(type default)
		)
		(fill no)
		(layer "In5.Cu")
	)
	(gr_circle
		(center 442.371734 -18.824702)
		(end 443.260734 -18.824702)
		(stroke
			(width 0.2)
			(type default)
		)
		(fill no)
		(layer "In5.Cu")
	)
	(gr_circle
		(center 442.45149 -25.461976)
		(end 443.34049 -25.461976)
		(stroke
			(width 0.2)
			(type default)
		)
		(fill no)
		(layer "In5.Cu")
	)
	(gr_circle
		(center 442.907674 -25.982422)
		(end 443.796674 -25.982422)
		(stroke
			(width 0.2)
			(type default)
		)
		(fill no)
		(layer "In5.Cu")
	)
	(gr_circle
		(center 443.34049 -25.461976)
		(end 444.22949 -25.461976)
		(stroke
			(width 0.2)
			(type default)
		)
		(fill no)
		(layer "In5.Cu")
	)
	(gr_circle
		(center 444.166244 -24.741632)
		(end 445.055244 -24.741632)
		(stroke
			(width 0.2)
			(type default)
		)
		(fill no)
		(layer "In5.Cu")
	)
	(gr_circle
		(center 450.669914 -14.526514)
		(end 451.558914 -14.526514)
		(stroke
			(width 0.2)
			(type default)
		)
		(fill no)
		(layer "In5.Cu")
	)
	(gr_circle
		(center 450.670676 -16.010382)
		(end 451.559676 -16.010382)
		(stroke
			(width 0.2)
			(type default)
		)
		(fill no)
		(layer "In5.Cu")
	)
	(gr_circle
		(center 450.670676 -15.273782)
		(end 451.559676 -15.273782)
		(stroke
			(width 0.2)
			(type default)
		)
		(fill no)
		(layer "In5.Cu")
	)
	(gr_circle
		(center 452.054976 -18.535142)
		(end 452.943976 -18.535142)
		(stroke
			(width 0.2)
			(type default)
		)
		(fill no)
		(layer "In5.Cu")
	)
	(gr_circle
		(center 452.054976 -17.798542)
		(end 452.943976 -17.798542)
		(stroke
			(width 0.2)
			(type default)
		)
		(fill no)
		(layer "In5.Cu")
	)
	(gr_arc
		(start 456.202034 -9.780016)
		(mid 456.787819 -11.194227)
		(end 458.20203 -11.780012)
		(stroke
			(width 1.016)
			(type default)
		)
		(layer "In5.Cu")
	)
	(gr_arc
		(start 456.202034 -0.500126)
		(mid 456.05556 -0.146464)
		(end 455.701908 0)
		(stroke
			(width 1.016)
			(type default)
		)
		(layer "In5.Cu")
	)
	(gr_line
		(start 456.202034 -0.500126)
		(end 456.202034 -9.780016)
		(stroke
			(width 1.016)
			(type default)
		)
		(layer "In5.Cu")
	)
	(gr_line
		(start 458.20203 -11.780012)
		(end 469.799924 -11.780012)
		(stroke
			(width 1.016)
			(type default)
		)
		(layer "In5.Cu")
	)
	(gr_line
		(start 463.300064 -441.989972)
		(end 277.314914 -441.989972)
		(stroke
			(width 1.016)
			(type default)
		)
		(layer "In5.Cu")
	)
	(gr_arc
		(start 463.300064 -441.989972)
		(mid 464.71429 -441.404198)
		(end 465.30006 -439.989976)
		(stroke
			(width 1.016)
			(type default)
		)
		(layer "In5.Cu")
	)
	(gr_line
		(start 465.30006 -409.528518)
		(end 465.30006 -439.989976)
		(stroke
			(width 1.016)
			(type default)
		)
		(layer "In5.Cu")
	)
	(gr_arc
		(start 465.885784 -408.114246)
		(mid 465.452221 -408.76312)
		(end 465.30006 -409.528518)
		(stroke
			(width 1.016)
			(type default)
		)
		(layer "In5.Cu")
	)
	(gr_line
		(start 467.71433 -406.2857)
		(end 465.885784 -408.114246)
		(stroke
			(width 1.016)
			(type default)
		)
		(layer "In5.Cu")
	)
	(gr_arc
		(start 467.71433 -406.2857)
		(mid 468.147828 -405.636947)
		(end 468.300054 -404.871682)
		(stroke
			(width 1.016)
			(type default)
		)
		(layer "In5.Cu")
	)
	(gr_line
		(start 468.300054 -82.828384)
		(end 468.300054 -404.871682)
		(stroke
			(width 1.016)
			(type default)
		)
		(layer "In5.Cu")
	)
	(gr_arc
		(start 468.885778 -81.414112)
		(mid 468.452215 -82.062986)
		(end 468.300054 -82.828384)
		(stroke
			(width 1.016)
			(type default)
		)
		(layer "In5.Cu")
	)
	(gr_line
		(start 471.214196 -79.085694)
		(end 468.885778 -81.414112)
		(stroke
			(width 1.016)
			(type default)
		)
		(layer "In5.Cu")
	)
	(gr_arc
		(start 471.214196 -79.085694)
		(mid 471.6477 -78.436942)
		(end 471.79992 -77.671676)
		(stroke
			(width 1.016)
			(type default)
		)
		(layer "In5.Cu")
	)
	(gr_arc
		(start 471.79992 -13.780008)
		(mid 471.214139 -12.365784)
		(end 469.799924 -11.780012)
		(stroke
			(width 1.016)
			(type default)
		)
		(layer "In5.Cu")
	)
	(gr_line
		(start 471.79992 -13.780008)
		(end 471.79992 -77.671676)
		(stroke
			(width 1.016)
			(type default)
		)
		(layer "In5.Cu")
	)
	(gr_poly
		(pts
			(xy 77.493114 -223.772476) (xy 77.393292 -223.599248) (xy 77.35189 -223.623124) (xy 77.315314 -223.759522)
			(xy 77.451966 -223.796352)
		)
		(stroke
			(width 0)
			(type solid)
		)
		(fill yes)
		(layer "In6.Cu")
		(net "M_E_CPU1_SA_DQS_DP<5>")
	)
	(gr_poly
		(pts
			(xy 78.040738 -253.595886) (xy 77.940916 -253.49581) (xy 77.84084 -253.595886) (xy 77.84084 -253.640336)
			(xy 78.040738 -253.640336)
		)
		(stroke
			(width 0)
			(type solid)
		)
		(fill yes)
		(layer "In6.Cu")
		(net "M_E_CPU1_SA_CA<2>")
	)
	(gr_poly
		(pts
			(xy 78.040738 -250.355862) (xy 77.940916 -250.255786) (xy 77.84084 -250.355862) (xy 77.84084 -250.400312)
			(xy 78.040738 -250.400312)
		)
		(stroke
			(width 0)
			(type solid)
		)
		(fill yes)
		(layer "In6.Cu")
		(net "M_E_CPU1_ALERT_R_N")
	)
	(gr_poly
		(pts
			(xy 78.060296 -224.035874) (xy 78.096872 -223.899476) (xy 77.96022 -223.8629) (xy 77.919072 -223.886522)
			(xy 78.018894 -224.05975)
		)
		(stroke
			(width 0)
			(type solid)
		)
		(fill yes)
		(layer "In6.Cu")
		(net "M_E_CPU1_SA_DQS_DN<5>")
	)
	(gr_poly
		(pts
			(xy 78.259686 -294.798242) (xy 78.221332 -294.77589) (xy 78.08468 -294.812466) (xy 78.121256 -294.949118)
			(xy 78.159864 -294.97147)
		)
		(stroke
			(width 0)
			(type solid)
		)
		(fill yes)
		(layer "In6.Cu")
		(net "M_E_CPU1_SB_DQ<28>")
	)
	(gr_poly
		(pts
			(xy 78.429866 -224.696274) (xy 78.391258 -224.674176) (xy 78.254606 -224.710752) (xy 78.291436 -224.847404)
			(xy 78.32979 -224.869502)
		)
		(stroke
			(width 0)
			(type solid)
		)
		(fill yes)
		(layer "In6.Cu")
		(net "M_E_CPU1_SA_DQS_DN<0>")
	)
	(gr_poly
		(pts
			(xy 78.43012 -225.39325) (xy 78.330044 -225.220022) (xy 78.29169 -225.242374) (xy 78.255114 -225.379026)
			(xy 78.391512 -225.415602)
		)
		(stroke
			(width 0)
			(type solid)
		)
		(fill yes)
		(layer "In6.Cu")
		(net "M_E_CPU1_SA_DQS_DN<0>")
	)
	(gr_poly
		(pts
			(xy 78.432914 -223.772476) (xy 78.333092 -223.599248) (xy 78.29169 -223.623124) (xy 78.255114 -223.759522)
			(xy 78.391766 -223.796352)
		)
		(stroke
			(width 0)
			(type solid)
		)
		(fill yes)
		(layer "In6.Cu")
		(net "M_E_CPU1_SA_DQS_DN<0>")
	)
	(gr_poly
		(pts
			(xy 78.439518 -232.944924) (xy 78.443836 -232.89768) (xy 78.244446 -232.880154) (xy 78.240382 -232.927652)
			(xy 78.331314 -233.035856)
		)
		(stroke
			(width 0)
			(type solid)
		)
		(fill yes)
		(layer "In6.Cu")
		(net "M_E_CPU1_SA_DQS_DP<6>")
	)
	(gr_poly
		(pts
			(xy 78.518258 -254.00254) (xy 78.518258 -253.95809) (xy 78.31836 -253.95809) (xy 78.31836 -254.00254)
			(xy 78.418436 -254.102616)
		)
		(stroke
			(width 0)
			(type solid)
		)
		(fill yes)
		(layer "In6.Cu")
		(net "M_E_CPU1_SA_CA<3>")
	)
	(gr_poly
		(pts
			(xy 78.518258 -252.382528) (xy 78.518258 -252.338078) (xy 78.31836 -252.338078) (xy 78.31836 -252.382528)
			(xy 78.418436 -252.482604)
		)
		(stroke
			(width 0)
			(type solid)
		)
		(fill yes)
		(layer "In6.Cu")
		(net "M_E_CPU1_SA_CS_N<1>")
	)
	(gr_poly
		(pts
			(xy 78.518258 -239.422432) (xy 78.518258 -239.377982) (xy 78.31836 -239.377982) (xy 78.31836 -239.422432)
			(xy 78.418436 -239.522508)
		)
		(stroke
			(width 0)
			(type solid)
		)
		(fill yes)
		(layer "In6.Cu")
		(net "M_E_CPU1_SA_DQ<23>")
	)
	(gr_poly
		(pts
			(xy 78.518258 -236.182408) (xy 78.518258 -236.137958) (xy 78.31836 -236.137958) (xy 78.31836 -236.182408)
			(xy 78.418436 -236.282484)
		)
		(stroke
			(width 0)
			(type solid)
		)
		(fill yes)
		(layer "In6.Cu")
		(net "M_E_CPU1_SA_DQ<19>")
	)
	(gr_poly
		(pts
			(xy 78.519782 -254.4064) (xy 78.419706 -254.306324) (xy 78.319884 -254.4064) (xy 78.319884 -254.45085)
			(xy 78.519782 -254.45085)
		)
		(stroke
			(width 0)
			(type solid)
		)
		(fill yes)
		(layer "In6.Cu")
		(net "M_E_CPU1_SA_CA<4>")
	)
	(gr_poly
		(pts
			(xy 78.519782 -252.786388) (xy 78.419706 -252.686312) (xy 78.319884 -252.786388) (xy 78.319884 -252.830838)
			(xy 78.519782 -252.830838)
		)
		(stroke
			(width 0)
			(type solid)
		)
		(fill yes)
		(layer "In6.Cu")
		(net "M_E_CPU1_SA_CA<0>")
	)
	(gr_poly
		(pts
			(xy 78.519782 -247.926352) (xy 78.419706 -247.826276) (xy 78.319884 -247.926352) (xy 78.319884 -247.970802)
			(xy 78.519782 -247.970802)
		)
		(stroke
			(width 0)
			(type solid)
		)
		(fill yes)
		(layer "In6.Cu")
		(net "M_E_CPU1_SA_CB<4>")
	)
	(gr_poly
		(pts
			(xy 78.519782 -244.686328) (xy 78.419706 -244.586252) (xy 78.319884 -244.686328) (xy 78.319884 -244.730778)
			(xy 78.519782 -244.730778)
		)
		(stroke
			(width 0)
			(type solid)
		)
		(fill yes)
		(layer "In6.Cu")
		(net "M_E_CPU1_SA_CB<0>")
	)
	(gr_poly
		(pts
			(xy 78.521814 -247.522746) (xy 78.521814 -247.474994) (xy 78.321916 -247.474994) (xy 78.321916 -247.522746)
			(xy 78.421738 -247.622568)
		)
		(stroke
			(width 0)
			(type solid)
		)
		(fill yes)
		(layer "In6.Cu")
		(net "M_E_CPU1_SA_DQS_DP<9>")
	)
	(gr_poly
		(pts
			(xy 78.521814 -242.66271) (xy 78.521814 -242.614958) (xy 78.321916 -242.614958) (xy 78.321916 -242.66271)
			(xy 78.421738 -242.762532)
		)
		(stroke
			(width 0)
			(type solid)
		)
		(fill yes)
		(layer "In6.Cu")
		(net "M_E_CPU1_SA_DQS_DP<8>")
	)
	(gr_poly
		(pts
			(xy 78.529434 -223.22536) (xy 78.56601 -223.088708) (xy 78.429612 -223.052132) (xy 78.38821 -223.076008)
			(xy 78.488286 -223.249236)
		)
		(stroke
			(width 0)
			(type solid)
		)
		(fill yes)
		(layer "In6.Cu")
		(net "M_E_CPU1_SA_DQS_DP<0>")
	)
	(gr_poly
		(pts
			(xy 78.568042 -237.792514) (xy 78.563724 -237.745016) (xy 78.364588 -237.762288) (xy 78.368652 -237.809786)
			(xy 78.47711 -237.900718)
		)
		(stroke
			(width 0)
			(type solid)
		)
		(fill yes)
		(layer "In6.Cu")
		(net "M_E_CPU1_SA_DQS_DP<7>")
	)
	(gr_poly
		(pts
			(xy 78.590902 -241.02695) (xy 78.579472 -240.984024) (xy 78.386178 -241.03584) (xy 78.397862 -241.078766)
			(xy 78.52029 -241.149378)
		)
		(stroke
			(width 0)
			(type solid)
		)
		(fill yes)
		(layer "In6.Cu")
		(net "M_E_CPU1_SA_DQ<27>")
	)
	(gr_poly
		(pts
			(xy 78.740762 -293.969186) (xy 78.702408 -293.946834) (xy 78.565756 -293.98341) (xy 78.602332 -294.120062)
			(xy 78.64094 -294.142414)
		)
		(stroke
			(width 0)
			(type solid)
		)
		(fill yes)
		(layer "In6.Cu")
		(net "M_E_CPU1_SB_DQ<28>")
	)
	(gr_poly
		(pts
			(xy 78.79969 -273.074638) (xy 78.79969 -273.030188) (xy 78.599538 -273.030188) (xy 78.599538 -273.074638)
			(xy 78.699614 -273.174714)
		)
		(stroke
			(width 0)
			(type solid)
		)
		(fill yes)
		(layer "In6.Cu")
		(net "M_E_CPU1_SB_CB<2>")
	)
	(gr_poly
		(pts
			(xy 78.819756 -281.174698) (xy 78.819756 -281.1272) (xy 78.619858 -281.1272) (xy 78.619858 -281.174698)
			(xy 78.71968 -281.274774)
		)
		(stroke
			(width 0)
			(type solid)
		)
		(fill yes)
		(layer "In6.Cu")
		(net "M_E_CPU1_SB_DQS_DN<1>")
	)
	(gr_poly
		(pts
			(xy 78.819756 -279.554432) (xy 78.819756 -279.509982) (xy 78.619858 -279.509982) (xy 78.619858 -279.554432)
			(xy 78.71968 -279.654508)
		)
		(stroke
			(width 0)
			(type solid)
		)
		(fill yes)
		(layer "In6.Cu")
		(net "M_E_CPU1_SB_DQ<10>")
	)
	(gr_poly
		(pts
			(xy 78.819756 -277.93442) (xy 78.819756 -277.88997) (xy 78.619858 -277.88997) (xy 78.619858 -277.93442)
			(xy 78.71968 -278.034496)
		)
		(stroke
			(width 0)
			(type solid)
		)
		(fill yes)
		(layer "In6.Cu")
		(net "M_E_CPU1_SB_DQ<6>")
	)
	(gr_poly
		(pts
			(xy 78.819756 -274.694396) (xy 78.819756 -274.649946) (xy 78.619858 -274.649946) (xy 78.619858 -274.694396)
			(xy 78.71968 -274.794472)
		)
		(stroke
			(width 0)
			(type solid)
		)
		(fill yes)
		(layer "In6.Cu")
		(net "M_E_CPU1_SB_DQ<2>")
	)
	(gr_poly
		(pts
			(xy 78.819756 -269.83436) (xy 78.819756 -269.78991) (xy 78.619858 -269.78991) (xy 78.619858 -269.83436)
			(xy 78.71968 -269.934436)
		)
		(stroke
			(width 0)
			(type solid)
		)
		(fill yes)
		(layer "In6.Cu")
		(net "M_E_CPU1_SB_CB<6>")
	)
	(gr_poly
		(pts
			(xy 78.819756 -264.974324) (xy 78.819756 -264.929874) (xy 78.619858 -264.929874) (xy 78.619858 -264.974324)
			(xy 78.71968 -265.0744)
		)
		(stroke
			(width 0)
			(type solid)
		)
		(fill yes)
		(layer "In6.Cu")
		(net "M_E_CPU1_SB_PAR")
	)
	(gr_poly
		(pts
			(xy 78.827884 -288.058098) (xy 78.727808 -287.958022) (xy 78.627732 -288.058098) (xy 78.627732 -288.102548)
			(xy 78.827884 -288.102548)
		)
		(stroke
			(width 0)
			(type solid)
		)
		(fill yes)
		(layer "In6.Cu")
		(net "M_E_CPU1_SB_DQ<21>")
	)
	(gr_poly
		(pts
			(xy 78.839568 -284.827472) (xy 78.748636 -284.719268) (xy 78.640178 -284.8102) (xy 78.636368 -284.854396)
			(xy 78.835758 -284.871922)
		)
		(stroke
			(width 0)
			(type solid)
		)
		(fill yes)
		(layer "In6.Cu")
		(net "M_E_CPU1_SB_DQ<17>")
	)
	(gr_poly
		(pts
			(xy 78.901798 -222.965264) (xy 78.801722 -222.792036) (xy 78.763368 -222.814388) (xy 78.726792 -222.95104)
			(xy 78.86319 -222.987616)
		)
		(stroke
			(width 0)
			(type solid)
		)
		(fill yes)
		(layer "In6.Cu")
		(net "M_E_CPU1_SA_DQ<3>")
	)
	(gr_poly
		(pts
			(xy 78.903068 -226.202494) (xy 78.803246 -226.029266) (xy 78.761844 -226.053142) (xy 78.725268 -226.18954)
			(xy 78.86192 -226.22637)
		)
		(stroke
			(width 0)
			(type solid)
		)
		(fill yes)
		(layer "In6.Cu")
		(net "M_E_CPU1_SA_DQS_DN<0>")
	)
	(gr_poly
		(pts
			(xy 78.965806 -289.227514) (xy 78.954376 -289.184588) (xy 78.761082 -289.236404) (xy 78.772512 -289.27933)
			(xy 78.895194 -289.349942)
		)
		(stroke
			(width 0)
			(type solid)
		)
		(fill yes)
		(layer "In6.Cu")
		(net "M_E_CPU1_SB_DQ<26>")
	)
	(gr_poly
		(pts
			(xy 78.965806 -287.607756) (xy 78.954376 -287.56483) (xy 78.761082 -287.616392) (xy 78.772766 -287.659572)
			(xy 78.895194 -287.730184)
		)
		(stroke
			(width 0)
			(type solid)
		)
		(fill yes)
		(layer "In6.Cu")
		(net "M_E_CPU1_SB_DQ<22>")
	)
	(gr_poly
		(pts
			(xy 78.972918 -237.396528) (xy 78.872842 -237.296452) (xy 78.772766 -237.396528) (xy 78.772766 -237.444026)
			(xy 78.972918 -237.444026)
		)
		(stroke
			(width 0)
			(type solid)
		)
		(fill yes)
		(layer "In6.Cu")
		(net "M_E_CPU1_SA_DQS_DN<7>")
	)
	(gr_poly
		(pts
			(xy 78.975458 -256.432812) (xy 78.975458 -256.385314) (xy 78.775306 -256.385314) (xy 78.775306 -256.432812)
			(xy 78.875382 -256.532888)
		)
		(stroke
			(width 0)
			(type solid)
		)
		(fill yes)
		(layer "In6.Cu")
		(net "M_E_CPU1_CLK_DN<0>")
	)
	(gr_poly
		(pts
			(xy 78.975458 -255.216406) (xy 78.875636 -255.11633) (xy 78.77556 -255.216406) (xy 78.77556 -255.260856)
			(xy 78.975458 -255.260856)
		)
		(stroke
			(width 0)
			(type solid)
		)
		(fill yes)
		(layer "In6.Cu")
		(net "M_E_CPU1_SA_CA<6>")
	)
	(gr_poly
		(pts
			(xy 78.975458 -254.812546) (xy 78.975458 -254.768096) (xy 78.775306 -254.768096) (xy 78.775306 -254.812546)
			(xy 78.875382 -254.912622)
		)
		(stroke
			(width 0)
			(type solid)
		)
		(fill yes)
		(layer "In6.Cu")
		(net "M_E_CPU1_SA_CA<5>")
	)
	(gr_poly
		(pts
			(xy 78.975458 -253.596394) (xy 78.875636 -253.496318) (xy 78.77556 -253.596394) (xy 78.77556 -253.640844)
			(xy 78.975458 -253.640844)
		)
		(stroke
			(width 0)
			(type solid)
		)
		(fill yes)
		(layer "In6.Cu")
		(net "M_E_CPU1_SA_CA<2>")
	)
	(gr_poly
		(pts
			(xy 78.975458 -253.192534) (xy 78.975458 -253.148084) (xy 78.775306 -253.148084) (xy 78.775306 -253.192534)
			(xy 78.875382 -253.29261)
		)
		(stroke
			(width 0)
			(type solid)
		)
		(fill yes)
		(layer "In6.Cu")
		(net "M_E_CPU1_SA_CA<1>")
	)
	(gr_poly
		(pts
			(xy 78.975458 -251.572522) (xy 78.975458 -251.528072) (xy 78.775306 -251.528072) (xy 78.775306 -251.572522)
			(xy 78.875382 -251.672598)
		)
		(stroke
			(width 0)
			(type solid)
		)
		(fill yes)
		(layer "In6.Cu")
		(net "M_E_CPU1_SA_CS_N<0>")
	)
	(gr_poly
		(pts
			(xy 78.975458 -250.35637) (xy 78.875636 -250.256294) (xy 78.77556 -250.35637) (xy 78.77556 -250.40082)
			(xy 78.975458 -250.40082)
		)
		(stroke
			(width 0)
			(type solid)
		)
		(fill yes)
		(layer "In6.Cu")
		(net "M_E_CPU1_ALERT_R_N")
	)
	(gr_poly
		(pts
			(xy 78.975458 -248.736358) (xy 78.875636 -248.636282) (xy 78.77556 -248.736358) (xy 78.77556 -248.780808)
			(xy 78.975458 -248.780808)
		)
		(stroke
			(width 0)
			(type solid)
		)
		(fill yes)
		(layer "In6.Cu")
		(net "M_E_CPU1_SA_CB<5>")
	)
	(gr_poly
		(pts
			(xy 78.975458 -248.332498) (xy 78.975458 -248.288048) (xy 78.775306 -248.288048) (xy 78.775306 -248.332498)
			(xy 78.875382 -248.432574)
		)
		(stroke
			(width 0)
			(type solid)
		)
		(fill yes)
		(layer "In6.Cu")
		(net "M_E_CPU1_SA_CB<6>")
	)
	(gr_poly
		(pts
			(xy 78.975458 -247.116092) (xy 78.875636 -247.016016) (xy 78.77556 -247.116092) (xy 78.77556 -247.16359)
			(xy 78.975458 -247.16359)
		)
		(stroke
			(width 0)
			(type solid)
		)
		(fill yes)
		(layer "In6.Cu")
		(net "M_E_CPU1_SA_DQS_DN<9>")
	)
	(gr_poly
		(pts
			(xy 78.975458 -246.71274) (xy 78.975458 -246.665242) (xy 78.775306 -246.665242) (xy 78.775306 -246.71274)
			(xy 78.875382 -246.812816)
		)
		(stroke
			(width 0)
			(type solid)
		)
		(fill yes)
		(layer "In6.Cu")
		(net "M_E_CPU1_SA_DQS_DN<4>")
	)
	(gr_poly
		(pts
			(xy 78.975458 -245.496334) (xy 78.875636 -245.396258) (xy 78.77556 -245.496334) (xy 78.77556 -245.540784)
			(xy 78.975458 -245.540784)
		)
		(stroke
			(width 0)
			(type solid)
		)
		(fill yes)
		(layer "In6.Cu")
		(net "M_E_CPU1_SA_CB<1>")
	)
	(gr_poly
		(pts
			(xy 78.975458 -245.092474) (xy 78.975458 -245.048024) (xy 78.775306 -245.048024) (xy 78.775306 -245.092474)
			(xy 78.875382 -245.19255)
		)
		(stroke
			(width 0)
			(type solid)
		)
		(fill yes)
		(layer "In6.Cu")
		(net "M_E_CPU1_SA_CB<2>")
	)
	(gr_poly
		(pts
			(xy 78.975458 -243.876322) (xy 78.875636 -243.776246) (xy 78.77556 -243.876322) (xy 78.77556 -243.920772)
			(xy 78.975458 -243.920772)
		)
		(stroke
			(width 0)
			(type solid)
		)
		(fill yes)
		(layer "In6.Cu")
		(net "M_E_CPU1_SA_DQ<29>")
	)
	(gr_poly
		(pts
			(xy 78.975458 -242.256056) (xy 78.875636 -242.15598) (xy 78.77556 -242.256056) (xy 78.77556 -242.303554)
			(xy 78.975458 -242.303554)
		)
		(stroke
			(width 0)
			(type solid)
		)
		(fill yes)
		(layer "In6.Cu")
		(net "M_E_CPU1_SA_DQS_DN<8>")
	)
	(gr_poly
		(pts
			(xy 78.975458 -241.852704) (xy 78.975458 -241.805206) (xy 78.775306 -241.805206) (xy 78.775306 -241.852704)
			(xy 78.875382 -241.95278)
		)
		(stroke
			(width 0)
			(type solid)
		)
		(fill yes)
		(layer "In6.Cu")
		(net "M_E_CPU1_SA_DQS_DN<3>")
	)
	(gr_poly
		(pts
			(xy 78.975458 -240.636298) (xy 78.875636 -240.536222) (xy 78.77556 -240.636298) (xy 78.77556 -240.680748)
			(xy 78.975458 -240.680748)
		)
		(stroke
			(width 0)
			(type solid)
		)
		(fill yes)
		(layer "In6.Cu")
		(net "M_E_CPU1_SA_DQ<25>")
	)
	(gr_poly
		(pts
			(xy 78.975458 -240.232438) (xy 78.975458 -240.187988) (xy 78.775306 -240.187988) (xy 78.775306 -240.232438)
			(xy 78.875382 -240.332514)
		)
		(stroke
			(width 0)
			(type solid)
		)
		(fill yes)
		(layer "In6.Cu")
		(net "M_E_CPU1_SA_DQ<26>")
	)
	(gr_poly
		(pts
			(xy 78.975458 -239.016286) (xy 78.875636 -238.91621) (xy 78.77556 -239.016286) (xy 78.77556 -239.060736)
			(xy 78.975458 -239.060736)
		)
		(stroke
			(width 0)
			(type solid)
		)
		(fill yes)
		(layer "In6.Cu")
		(net "M_E_CPU1_SA_DQ<21>")
	)
	(gr_poly
		(pts
			(xy 78.975458 -236.992668) (xy 78.975458 -236.94517) (xy 78.775306 -236.94517) (xy 78.775306 -236.992668)
			(xy 78.875382 -237.092744)
		)
		(stroke
			(width 0)
			(type solid)
		)
		(fill yes)
		(layer "In6.Cu")
		(net "M_E_CPU1_SA_DQS_DN<2>")
	)
	(gr_poly
		(pts
			(xy 78.975458 -235.776262) (xy 78.875636 -235.676186) (xy 78.77556 -235.776262) (xy 78.77556 -235.820712)
			(xy 78.975458 -235.820712)
		)
		(stroke
			(width 0)
			(type solid)
		)
		(fill yes)
		(layer "In6.Cu")
		(net "M_E_CPU1_SA_DQ<17>")
	)
	(gr_poly
		(pts
			(xy 78.975458 -234.15625) (xy 78.875636 -234.056174) (xy 78.77556 -234.15625) (xy 78.77556 -234.2007)
			(xy 78.975458 -234.2007)
		)
		(stroke
			(width 0)
			(type solid)
		)
		(fill yes)
		(layer "In6.Cu")
		(net "M_E_CPU1_SA_DQ<13>")
	)
	(gr_poly
		(pts
			(xy 78.975458 -233.75239) (xy 78.975458 -233.70794) (xy 78.775306 -233.70794) (xy 78.775306 -233.75239)
			(xy 78.875382 -233.852466)
		)
		(stroke
			(width 0)
			(type solid)
		)
		(fill yes)
		(layer "In6.Cu")
		(net "M_E_CPU1_SA_DQ<14>")
	)
	(gr_poly
		(pts
			(xy 78.975458 -232.535984) (xy 78.875636 -232.435908) (xy 78.77556 -232.535984) (xy 78.77556 -232.583482)
			(xy 78.975458 -232.583482)
		)
		(stroke
			(width 0)
			(type solid)
		)
		(fill yes)
		(layer "In6.Cu")
		(net "M_E_CPU1_SA_DQS_DN<6>")
	)
	(gr_poly
		(pts
			(xy 78.975458 -232.132632) (xy 78.975458 -232.085134) (xy 78.77556 -232.085134) (xy 78.77556 -232.132632)
			(xy 78.875382 -232.232708)
		)
		(stroke
			(width 0)
			(type solid)
		)
		(fill yes)
		(layer "In6.Cu")
		(net "M_E_CPU1_SA_DQS_DN<1>")
	)
	(gr_poly
		(pts
			(xy 78.98384 -243.472462) (xy 78.98384 -243.428012) (xy 78.783688 -243.428012) (xy 78.783688 -243.472462)
			(xy 78.883764 -243.572538)
		)
		(stroke
			(width 0)
			(type solid)
		)
		(fill yes)
		(layer "In6.Cu")
		(net "M_E_CPU1_SA_DQ<30>")
	)
	(gr_poly
		(pts
			(xy 78.98384 -238.612426) (xy 78.98384 -238.567976) (xy 78.783688 -238.567976) (xy 78.783688 -238.612426)
			(xy 78.883764 -238.712502)
		)
		(stroke
			(width 0)
			(type solid)
		)
		(fill yes)
		(layer "In6.Cu")
		(net "M_E_CPU1_SA_DQ<22>")
	)
	(gr_poly
		(pts
			(xy 78.98384 -235.372402) (xy 78.98384 -235.327952) (xy 78.783688 -235.327952) (xy 78.783688 -235.372402)
			(xy 78.883764 -235.472478)
		)
		(stroke
			(width 0)
			(type solid)
		)
		(fill yes)
		(layer "In6.Cu")
		(net "M_E_CPU1_SA_DQ<18>")
	)
	(gr_poly
		(pts
			(xy 78.999588 -224.035366) (xy 79.036164 -223.898714) (xy 78.899512 -223.862138) (xy 78.860904 -223.884236)
			(xy 78.96098 -224.057464)
		)
		(stroke
			(width 0)
			(type solid)
		)
		(fill yes)
		(layer "In6.Cu")
		(net "M_E_CPU1_SA_DQS_DP<0>")
	)
	(gr_poly
		(pts
			(xy 79.00035 -225.655886) (xy 79.036926 -225.519488) (xy 78.900274 -225.482912) (xy 78.859126 -225.506534)
			(xy 78.958948 -225.679762)
		)
		(stroke
			(width 0)
			(type solid)
		)
		(fill yes)
		(layer "In6.Cu")
		(net "M_E_CPU1_SA_DQS_DP<0>")
	)
	(gr_poly
		(pts
			(xy 79.00035 -222.415862) (xy 79.036926 -222.27921) (xy 78.900274 -222.242634) (xy 78.86192 -222.264986)
			(xy 78.961742 -222.438214)
		)
		(stroke
			(width 0)
			(type solid)
		)
		(fill yes)
		(layer "In6.Cu")
		(net "M_E_CPU1_SA_DQ<1>")
	)
	(gr_poly
		(pts
			(xy 79.036418 -224.569782) (xy 78.999842 -224.43313) (xy 78.961234 -224.410778) (xy 78.861412 -224.584006)
			(xy 78.899766 -224.606358)
		)
		(stroke
			(width 0)
			(type solid)
		)
		(fill yes)
		(layer "In6.Cu")
		(net "M_E_CPU1_SA_DQS_DP<0>")
	)
	(gr_poly
		(pts
			(xy 79.210662 -293.159688) (xy 79.172308 -293.137336) (xy 79.035656 -293.173912) (xy 79.072232 -293.310564)
			(xy 79.11084 -293.332916)
		)
		(stroke
			(width 0)
			(type solid)
		)
		(fill yes)
		(layer "In6.Cu")
		(net "M_E_CPU1_SB_DQ<28>")
	)
	(gr_poly
		(pts
			(xy 79.226156 -227.44557) (xy 79.225902 -227.304092) (xy 79.084424 -227.303838) (xy 79.050642 -227.33762)
			(xy 79.192374 -227.479352)
		)
		(stroke
			(width 0)
			(type solid)
		)
		(fill yes)
		(layer "In6.Cu")
		(net "M_E_CPU1_SA_DQS_DN<5>")
	)
	(gr_poly
		(pts
			(xy 79.2734 -285.628334) (xy 79.173324 -285.528512) (xy 79.073248 -285.628334) (xy 79.073248 -285.676086)
			(xy 79.2734 -285.676086)
		)
		(stroke
			(width 0)
			(type solid)
		)
		(fill yes)
		(layer "In6.Cu")
		(net "M_E_CPU1_SB_DQS_DP<2>")
	)
	(gr_poly
		(pts
			(xy 79.275178 -288.868104) (xy 79.175356 -288.768028) (xy 79.07528 -288.868104) (xy 79.07528 -288.912554)
			(xy 79.275178 -288.912554)
		)
		(stroke
			(width 0)
			(type solid)
		)
		(fill yes)
		(layer "In6.Cu")
		(net "M_E_CPU1_SB_DQ<24>")
	)
	(gr_poly
		(pts
			(xy 79.275178 -287.248092) (xy 79.175356 -287.148016) (xy 79.07528 -287.248092) (xy 79.07528 -287.292542)
			(xy 79.275178 -287.292542)
		)
		(stroke
			(width 0)
			(type solid)
		)
		(fill yes)
		(layer "In6.Cu")
		(net "M_E_CPU1_SB_DQ<20>")
	)
	(gr_poly
		(pts
			(xy 79.275178 -280.768044) (xy 79.175356 -280.667968) (xy 79.07528 -280.768044) (xy 79.07528 -280.815542)
			(xy 79.275178 -280.815542)
		)
		(stroke
			(width 0)
			(type solid)
		)
		(fill yes)
		(layer "In6.Cu")
		(net "M_E_CPU1_SB_DQS_DP<1>")
	)
	(gr_poly
		(pts
			(xy 79.275178 -279.148286) (xy 79.175356 -279.04821) (xy 79.07528 -279.148286) (xy 79.07528 -279.192736)
			(xy 79.275178 -279.192736)
		)
		(stroke
			(width 0)
			(type solid)
		)
		(fill yes)
		(layer "In6.Cu")
		(net "M_E_CPU1_SB_DQ<8>")
	)
	(gr_poly
		(pts
			(xy 79.275178 -277.528274) (xy 79.175356 -277.428198) (xy 79.07528 -277.528274) (xy 79.07528 -277.572724)
			(xy 79.275178 -277.572724)
		)
		(stroke
			(width 0)
			(type solid)
		)
		(fill yes)
		(layer "In6.Cu")
		(net "M_E_CPU1_SB_DQ<4>")
	)
	(gr_poly
		(pts
			(xy 79.275178 -274.28825) (xy 79.175356 -274.188174) (xy 79.07528 -274.28825) (xy 79.07528 -274.3327)
			(xy 79.275178 -274.3327)
		)
		(stroke
			(width 0)
			(type solid)
		)
		(fill yes)
		(layer "In6.Cu")
		(net "M_E_CPU1_SB_DQ<0>")
	)
	(gr_poly
		(pts
			(xy 79.275178 -264.568178) (xy 79.175356 -264.468102) (xy 79.07528 -264.568178) (xy 79.07528 -264.612628)
			(xy 79.275178 -264.612628)
		)
		(stroke
			(width 0)
			(type solid)
		)
		(fill yes)
		(layer "In6.Cu")
		(net "M_E_CPU1_SB_CA<6>")
	)
	(gr_poly
		(pts
			(xy 79.275686 -288.464498) (xy 79.275686 -288.420048) (xy 79.075534 -288.420048) (xy 79.075534 -288.464498)
			(xy 79.17561 -288.564574)
		)
		(stroke
			(width 0)
			(type solid)
		)
		(fill yes)
		(layer "In6.Cu")
		(net "M_E_CPU1_SB_DQ<23>")
	)
	(gr_poly
		(pts
			(xy 79.275686 -285.224474) (xy 79.275686 -285.180024) (xy 79.075534 -285.180024) (xy 79.075534 -285.224474)
			(xy 79.17561 -285.32455)
		)
		(stroke
			(width 0)
			(type solid)
		)
		(fill yes)
		(layer "In6.Cu")
		(net "M_E_CPU1_SB_DQ<19>")
	)
	(gr_poly
		(pts
			(xy 79.275686 -283.604462) (xy 79.275686 -283.560012) (xy 79.075534 -283.560012) (xy 79.075534 -283.604462)
			(xy 79.17561 -283.704538)
		)
		(stroke
			(width 0)
			(type solid)
		)
		(fill yes)
		(layer "In6.Cu")
		(net "M_E_CPU1_SB_DQ<15>")
	)
	(gr_poly
		(pts
			(xy 79.28102 -286.844486) (xy 79.28102 -286.796988) (xy 79.081122 -286.796988) (xy 79.081122 -286.844486)
			(xy 79.181198 -286.944562)
		)
		(stroke
			(width 0)
			(type solid)
		)
		(fill yes)
		(layer "In6.Cu")
		(net "M_E_CPU1_SB_DQS_DP<7>")
	)
	(gr_poly
		(pts
			(xy 79.283814 -284.008322) (xy 79.183738 -283.908246) (xy 79.083662 -284.008322) (xy 79.083662 -284.052772)
			(xy 79.283814 -284.052772)
		)
		(stroke
			(width 0)
			(type solid)
		)
		(fill yes)
		(layer "In6.Cu")
		(net "M_E_CPU1_SB_DQ<16>")
	)
	(gr_poly
		(pts
			(xy 79.283814 -282.38831) (xy 79.183738 -282.288234) (xy 79.083662 -282.38831) (xy 79.083662 -282.43276)
			(xy 79.283814 -282.43276)
		)
		(stroke
			(width 0)
			(type solid)
		)
		(fill yes)
		(layer "In6.Cu")
		(net "M_E_CPU1_SB_DQ<12>")
	)
	(gr_poly
		(pts
			(xy 79.283814 -272.668238) (xy 79.183738 -272.568162) (xy 79.083662 -272.668238) (xy 79.083662 -272.712688)
			(xy 79.283814 -272.712688)
		)
		(stroke
			(width 0)
			(type solid)
		)
		(fill yes)
		(layer "In6.Cu")
		(net "M_E_CPU1_SB_CB<0>")
	)
	(gr_poly
		(pts
			(xy 79.286862 -290.084256) (xy 79.286862 -290.039806) (xy 79.086964 -290.039806) (xy 79.086964 -290.084256)
			(xy 79.18704 -290.184078)
		)
		(stroke
			(width 0)
			(type solid)
		)
		(fill yes)
		(layer "In6.Cu")
		(net "M_E_CPU1_SB_DQ<27>")
	)
	(gr_poly
		(pts
			(xy 79.287116 -267.795502) (xy 79.187294 -267.695426) (xy 79.087218 -267.795502) (xy 79.087218 -267.846302)
			(xy 79.287116 -267.846302)
		)
		(stroke
			(width 0)
			(type solid)
		)
		(fill yes)
		(layer "In6.Cu")
		(net "M_E_CPU1_SB_RSP<0>")
	)
	(gr_poly
		(pts
			(xy 79.290672 -290.488116) (xy 79.19085 -290.38804) (xy 79.090774 -290.488116) (xy 79.090774 -290.535614)
			(xy 79.290672 -290.535614)
		)
		(stroke
			(width 0)
			(type solid)
		)
		(fill yes)
		(layer "In6.Cu")
		(net "M_E_CPU1_SB_DQS_DP<3>")
	)
	(gr_poly
		(pts
			(xy 79.369412 -295.408604) (xy 79.309722 -295.280334) (xy 79.267812 -295.265094) (xy 79.199486 -295.453054)
			(xy 79.241142 -295.468294)
		)
		(stroke
			(width 0)
			(type solid)
		)
		(fill yes)
		(layer "In6.Cu")
		(net "M_E_CPU1_SB_DQ<30>")
	)
	(gr_poly
		(pts
			(xy 79.36992 -224.696274) (xy 79.331312 -224.674176) (xy 79.194914 -224.710752) (xy 79.23149 -224.847404)
			(xy 79.269844 -224.869502)
		)
		(stroke
			(width 0)
			(type solid)
		)
		(fill yes)
		(layer "In6.Cu")
		(net "M_E_CPU1_SA_DQ<3>")
	)
	(gr_poly
		(pts
			(xy 79.36992 -222.152718) (xy 79.269844 -221.97949) (xy 79.23149 -222.001588) (xy 79.194914 -222.13824)
			(xy 79.331312 -222.17507)
		)
		(stroke
			(width 0)
			(type solid)
		)
		(fill yes)
		(layer "In6.Cu")
		(net "M_E_CPU1_SA_DQ<2>")
	)
	(gr_poly
		(pts
			(xy 79.370174 -225.39325) (xy 79.270098 -225.220022) (xy 79.231744 -225.242374) (xy 79.194914 -225.379026)
			(xy 79.331566 -225.415602)
		)
		(stroke
			(width 0)
			(type solid)
		)
		(fill yes)
		(layer "In6.Cu")
		(net "M_E_CPU1_SA_DQ<3>")
	)
	(gr_poly
		(pts
			(xy 79.370428 -223.773238) (xy 79.270352 -223.60001) (xy 79.231998 -223.622362) (xy 79.195422 -223.759014)
			(xy 79.33182 -223.79559)
		)
		(stroke
			(width 0)
			(type solid)
		)
		(fill yes)
		(layer "In6.Cu")
		(net "M_E_CPU1_SA_DQ<3>")
	)
	(gr_poly
		(pts
			(xy 79.372968 -227.0125) (xy 79.273146 -226.839272) (xy 79.231744 -226.863148) (xy 79.195168 -226.999546)
			(xy 79.33182 -227.036376)
		)
		(stroke
			(width 0)
			(type solid)
		)
		(fill yes)
		(layer "In6.Cu")
		(net "M_E_CPU1_SA_DQS_DN<0>")
	)
	(gr_poly
		(pts
			(xy 79.445358 -256.026158) (xy 79.345282 -255.926336) (xy 79.245206 -256.026158) (xy 79.245206 -256.07391)
			(xy 79.445358 -256.07391)
		)
		(stroke
			(width 0)
			(type solid)
		)
		(fill yes)
		(layer "In6.Cu")
		(net "M_E_CPU1_CLK_DP<0>")
	)
	(gr_poly
		(pts
			(xy 79.445358 -255.622552) (xy 79.445358 -255.578102) (xy 79.24546 -255.578102) (xy 79.24546 -255.622552)
			(xy 79.345536 -255.722628)
		)
		(stroke
			(width 0)
			(type solid)
		)
		(fill yes)
		(layer "In6.Cu")
		(net "M_E_CPU1_SA_PAR")
	)
	(gr_poly
		(pts
			(xy 79.445358 -254.4064) (xy 79.345282 -254.306324) (xy 79.245206 -254.4064) (xy 79.245206 -254.45085)
			(xy 79.445358 -254.45085)
		)
		(stroke
			(width 0)
			(type solid)
		)
		(fill yes)
		(layer "In6.Cu")
		(net "M_E_CPU1_SA_CA<4>")
	)
	(gr_poly
		(pts
			(xy 79.445358 -254.00254) (xy 79.445358 -253.95809) (xy 79.24546 -253.95809) (xy 79.24546 -254.00254)
			(xy 79.345536 -254.102616)
		)
		(stroke
			(width 0)
			(type solid)
		)
		(fill yes)
		(layer "In6.Cu")
		(net "M_E_CPU1_SA_CA<3>")
	)
	(gr_poly
		(pts
			(xy 79.445358 -252.786388) (xy 79.345282 -252.686312) (xy 79.245206 -252.786388) (xy 79.245206 -252.830838)
			(xy 79.445358 -252.830838)
		)
		(stroke
			(width 0)
			(type solid)
		)
		(fill yes)
		(layer "In6.Cu")
		(net "M_E_CPU1_SA_CA<0>")
	)
	(gr_poly
		(pts
			(xy 79.445358 -252.382528) (xy 79.445358 -252.338078) (xy 79.24546 -252.338078) (xy 79.24546 -252.382528)
			(xy 79.345536 -252.482604)
		)
		(stroke
			(width 0)
			(type solid)
		)
		(fill yes)
		(layer "In6.Cu")
		(net "M_E_CPU1_SA_CS_N<1>")
	)
	(gr_poly
		(pts
			(xy 79.445358 -250.762516) (xy 79.445358 -250.718066) (xy 79.24546 -250.718066) (xy 79.24546 -250.762516)
			(xy 79.345536 -250.862592)
		)
		(stroke
			(width 0)
			(type solid)
		)
		(fill yes)
		(layer "In6.Cu")
		(net "M_E_CPU1_RESET_N")
	)
	(gr_poly
		(pts
			(xy 79.445358 -249.142504) (xy 79.445358 -249.098054) (xy 79.24546 -249.098054) (xy 79.24546 -249.142504)
			(xy 79.345536 -249.24258)
		)
		(stroke
			(width 0)
			(type solid)
		)
		(fill yes)
		(layer "In6.Cu")
		(net "M_E_CPU1_SA_CB<7>")
	)
	(gr_poly
		(pts
			(xy 79.445358 -247.926352) (xy 79.345282 -247.826276) (xy 79.245206 -247.926352) (xy 79.245206 -247.970802)
			(xy 79.445358 -247.970802)
		)
		(stroke
			(width 0)
			(type solid)
		)
		(fill yes)
		(layer "In6.Cu")
		(net "M_E_CPU1_SA_CB<4>")
	)
	(gr_poly
		(pts
			(xy 79.445358 -247.522746) (xy 79.445358 -247.474994) (xy 79.24546 -247.474994) (xy 79.24546 -247.522746)
			(xy 79.345536 -247.622568)
		)
		(stroke
			(width 0)
			(type solid)
		)
		(fill yes)
		(layer "In6.Cu")
		(net "M_E_CPU1_SA_DQS_DP<9>")
	)
	(gr_poly
		(pts
			(xy 79.445358 -246.306086) (xy 79.345282 -246.206264) (xy 79.245206 -246.306086) (xy 79.245206 -246.353838)
			(xy 79.445358 -246.353838)
		)
		(stroke
			(width 0)
			(type solid)
		)
		(fill yes)
		(layer "In6.Cu")
		(net "M_E_CPU1_SA_DQS_DP<4>")
	)
	(gr_poly
		(pts
			(xy 79.445358 -245.90248) (xy 79.445358 -245.85803) (xy 79.24546 -245.85803) (xy 79.24546 -245.90248)
			(xy 79.345536 -246.002556)
		)
		(stroke
			(width 0)
			(type solid)
		)
		(fill yes)
		(layer "In6.Cu")
		(net "M_E_CPU1_SA_CB<3>")
	)
	(gr_poly
		(pts
			(xy 79.445358 -244.686328) (xy 79.345282 -244.586252) (xy 79.245206 -244.686328) (xy 79.245206 -244.730778)
			(xy 79.445358 -244.730778)
		)
		(stroke
			(width 0)
			(type solid)
		)
		(fill yes)
		(layer "In6.Cu")
		(net "M_E_CPU1_SA_CB<0>")
	)
	(gr_poly
		(pts
			(xy 79.445358 -244.282468) (xy 79.445358 -244.238018) (xy 79.24546 -244.238018) (xy 79.24546 -244.282468)
			(xy 79.345536 -244.382544)
		)
		(stroke
			(width 0)
			(type solid)
		)
		(fill yes)
		(layer "In6.Cu")
		(net "M_E_CPU1_SA_DQ<31>")
	)
	(gr_poly
		(pts
			(xy 79.445358 -242.66271) (xy 79.445358 -242.614958) (xy 79.24546 -242.614958) (xy 79.24546 -242.66271)
			(xy 79.345536 -242.762532)
		)
		(stroke
			(width 0)
			(type solid)
		)
		(fill yes)
		(layer "In6.Cu")
		(net "M_E_CPU1_SA_DQS_DP<8>")
	)
	(gr_poly
		(pts
			(xy 79.445358 -241.44605) (xy 79.345282 -241.346228) (xy 79.245206 -241.44605) (xy 79.245206 -241.493802)
			(xy 79.445358 -241.493802)
		)
		(stroke
			(width 0)
			(type solid)
		)
		(fill yes)
		(layer "In6.Cu")
		(net "M_E_CPU1_SA_DQS_DP<3>")
	)
	(gr_poly
		(pts
			(xy 79.445358 -241.042444) (xy 79.445358 -240.997994) (xy 79.24546 -240.997994) (xy 79.24546 -241.042444)
			(xy 79.345536 -241.14252)
		)
		(stroke
			(width 0)
			(type solid)
		)
		(fill yes)
		(layer "In6.Cu")
		(net "M_E_CPU1_SA_DQ<27>")
	)
	(gr_poly
		(pts
			(xy 79.445358 -239.826292) (xy 79.345282 -239.726216) (xy 79.245206 -239.826292) (xy 79.245206 -239.870742)
			(xy 79.445358 -239.870742)
		)
		(stroke
			(width 0)
			(type solid)
		)
		(fill yes)
		(layer "In6.Cu")
		(net "M_E_CPU1_SA_DQ<24>")
	)
	(gr_poly
		(pts
			(xy 79.445358 -239.422432) (xy 79.445358 -239.377982) (xy 79.24546 -239.377982) (xy 79.24546 -239.422432)
			(xy 79.345536 -239.522508)
		)
		(stroke
			(width 0)
			(type solid)
		)
		(fill yes)
		(layer "In6.Cu")
		(net "M_E_CPU1_SA_DQ<23>")
	)
	(gr_poly
		(pts
			(xy 79.445358 -237.802674) (xy 79.445358 -237.754922) (xy 79.24546 -237.754922) (xy 79.24546 -237.802674)
			(xy 79.345536 -237.902496)
		)
		(stroke
			(width 0)
			(type solid)
		)
		(fill yes)
		(layer "In6.Cu")
		(net "M_E_CPU1_SA_DQS_DP<7>")
	)
	(gr_poly
		(pts
			(xy 79.445358 -236.586014) (xy 79.345282 -236.486192) (xy 79.245206 -236.586014) (xy 79.245206 -236.633766)
			(xy 79.445358 -236.633766)
		)
		(stroke
			(width 0)
			(type solid)
		)
		(fill yes)
		(layer "In6.Cu")
		(net "M_E_CPU1_SA_DQS_DP<2>")
	)
	(gr_poly
		(pts
			(xy 79.445358 -236.182408) (xy 79.445358 -236.137958) (xy 79.24546 -236.137958) (xy 79.24546 -236.182408)
			(xy 79.345536 -236.282484)
		)
		(stroke
			(width 0)
			(type solid)
		)
		(fill yes)
		(layer "In6.Cu")
		(net "M_E_CPU1_SA_DQ<19>")
	)
	(gr_poly
		(pts
			(xy 79.445358 -234.562396) (xy 79.445358 -234.517946) (xy 79.24546 -234.517946) (xy 79.24546 -234.562396)
			(xy 79.345536 -234.662472)
		)
		(stroke
			(width 0)
			(type solid)
		)
		(fill yes)
		(layer "In6.Cu")
		(net "M_E_CPU1_SA_DQ<15>")
	)
	(gr_poly
		(pts
			(xy 79.445358 -233.346244) (xy 79.345282 -233.246168) (xy 79.245206 -233.346244) (xy 79.245206 -233.390694)
			(xy 79.445358 -233.390694)
		)
		(stroke
			(width 0)
			(type solid)
		)
		(fill yes)
		(layer "In6.Cu")
		(net "M_E_CPU1_SA_DQ<12>")
	)
	(gr_poly
		(pts
			(xy 79.445358 -232.942638) (xy 79.445358 -232.894886) (xy 79.24546 -232.894886) (xy 79.24546 -232.942638)
			(xy 79.345536 -233.04246)
		)
		(stroke
			(width 0)
			(type solid)
		)
		(fill yes)
		(layer "In6.Cu")
		(net "M_E_CPU1_SA_DQS_DP<6>")
	)
	(gr_poly
		(pts
			(xy 79.445358 -231.725978) (xy 79.345282 -231.626156) (xy 79.245206 -231.725978) (xy 79.245206 -231.77373)
			(xy 79.445358 -231.77373)
		)
		(stroke
			(width 0)
			(type solid)
		)
		(fill yes)
		(layer "In6.Cu")
		(net "M_E_CPU1_SA_DQS_DP<1>")
	)
	(gr_poly
		(pts
			(xy 79.456534 -243.066316) (xy 79.356458 -242.96624) (xy 79.256382 -243.066316) (xy 79.256382 -243.110766)
			(xy 79.456534 -243.110766)
		)
		(stroke
			(width 0)
			(type solid)
		)
		(fill yes)
		(layer "In6.Cu")
		(net "M_E_CPU1_SA_DQ<28>")
	)
	(gr_poly
		(pts
			(xy 79.456534 -238.20628) (xy 79.356458 -238.106204) (xy 79.256382 -238.20628) (xy 79.256382 -238.25073)
			(xy 79.456534 -238.25073)
		)
		(stroke
			(width 0)
			(type solid)
		)
		(fill yes)
		(layer "In6.Cu")
		(net "M_E_CPU1_SA_DQ<20>")
	)
	(gr_poly
		(pts
			(xy 79.456534 -234.966256) (xy 79.356458 -234.86618) (xy 79.256382 -234.966256) (xy 79.256382 -235.010706)
			(xy 79.456534 -235.010706)
		)
		(stroke
			(width 0)
			(type solid)
		)
		(fill yes)
		(layer "In6.Cu")
		(net "M_E_CPU1_SA_DQ<16>")
	)
	(gr_poly
		(pts
			(xy 79.469996 -223.225868) (xy 79.506572 -223.089216) (xy 79.36992 -223.05264) (xy 79.331566 -223.074992)
			(xy 79.431642 -223.24822)
		)
		(stroke
			(width 0)
			(type solid)
		)
		(fill yes)
		(layer "In6.Cu")
		(net "M_E_CPU1_SA_DQ<1>")
	)
	(gr_poly
		(pts
			(xy 79.47025 -226.465892) (xy 79.506826 -226.329494) (xy 79.370174 -226.292664) (xy 79.329026 -226.31654)
			(xy 79.428848 -226.489768)
		)
		(stroke
			(width 0)
			(type solid)
		)
		(fill yes)
		(layer "In6.Cu")
		(net "M_E_CPU1_SA_DQS_DP<0>")
	)
	(gr_poly
		(pts
			(xy 79.526638 -231.188006) (xy 79.541624 -231.14635) (xy 79.353664 -231.07777) (xy 79.338678 -231.11968)
			(xy 79.398368 -231.247696)
		)
		(stroke
			(width 0)
			(type solid)
		)
		(fill yes)
		(layer "In6.Cu")
		(net "M_E_CPU1_SA_DQ<11>")
	)
	(gr_poly
		(pts
			(xy 79.670402 -295.607486) (xy 79.631794 -295.585134) (xy 79.495142 -295.62171) (xy 79.531972 -295.758362)
			(xy 79.570326 -295.780714)
		)
		(stroke
			(width 0)
			(type solid)
		)
		(fill yes)
		(layer "In6.Cu")
		(net "M_E_CPU1_SB_DQ<29>")
	)
	(gr_poly
		(pts
			(xy 79.680562 -292.349428) (xy 79.642208 -292.327076) (xy 79.505556 -292.363652) (xy 79.542132 -292.500304)
			(xy 79.58074 -292.522656)
		)
		(stroke
			(width 0)
			(type solid)
		)
		(fill yes)
		(layer "In6.Cu")
		(net "M_E_CPU1_SB_DQ<28>")
	)
	(gr_poly
		(pts
			(xy 79.741268 -286.034988) (xy 79.741268 -285.98749) (xy 79.54137 -285.98749) (xy 79.54137 -286.034988)
			(xy 79.641446 -286.135064)
		)
		(stroke
			(width 0)
			(type solid)
		)
		(fill yes)
		(layer "In6.Cu")
		(net "M_E_CPU1_SB_DQS_DN<2>")
	)
	(gr_poly
		(pts
			(xy 79.745078 -289.27425) (xy 79.745078 -289.2298) (xy 79.54518 -289.2298) (xy 79.54518 -289.27425)
			(xy 79.645256 -289.374326)
		)
		(stroke
			(width 0)
			(type solid)
		)
		(fill yes)
		(layer "In6.Cu")
		(net "M_E_CPU1_SB_DQ<26>")
	)
	(gr_poly
		(pts
			(xy 79.745078 -287.654492) (xy 79.745078 -287.610042) (xy 79.54518 -287.610042) (xy 79.54518 -287.654492)
			(xy 79.645256 -287.754568)
		)
		(stroke
			(width 0)
			(type solid)
		)
		(fill yes)
		(layer "In6.Cu")
		(net "M_E_CPU1_SB_DQ<22>")
	)
	(gr_poly
		(pts
			(xy 79.745078 -281.174698) (xy 79.745078 -281.126946) (xy 79.54518 -281.126946) (xy 79.54518 -281.174698)
			(xy 79.645256 -281.27452)
		)
		(stroke
			(width 0)
			(type solid)
		)
		(fill yes)
		(layer "In6.Cu")
		(net "M_E_CPU1_SB_DQS_DN<1>")
	)
	(gr_poly
		(pts
			(xy 79.745078 -279.554432) (xy 79.745078 -279.509982) (xy 79.54518 -279.509982) (xy 79.54518 -279.554432)
			(xy 79.645256 -279.654508)
		)
		(stroke
			(width 0)
			(type solid)
		)
		(fill yes)
		(layer "In6.Cu")
		(net "M_E_CPU1_SB_DQ<10>")
	)
	(gr_poly
		(pts
			(xy 79.745078 -277.93442) (xy 79.745078 -277.88997) (xy 79.54518 -277.88997) (xy 79.54518 -277.93442)
			(xy 79.645256 -278.034496)
		)
		(stroke
			(width 0)
			(type solid)
		)
		(fill yes)
		(layer "In6.Cu")
		(net "M_E_CPU1_SB_DQ<6>")
	)
	(gr_poly
		(pts
			(xy 79.745078 -274.694396) (xy 79.745078 -274.649946) (xy 79.54518 -274.649946) (xy 79.54518 -274.694396)
			(xy 79.645256 -274.794472)
		)
		(stroke
			(width 0)
			(type solid)
		)
		(fill yes)
		(layer "In6.Cu")
		(net "M_E_CPU1_SB_DQ<2>")
	)
	(gr_poly
		(pts
			(xy 79.745078 -264.974324) (xy 79.745078 -264.929874) (xy 79.54518 -264.929874) (xy 79.54518 -264.974324)
			(xy 79.645256 -265.0744)
		)
		(stroke
			(width 0)
			(type solid)
		)
		(fill yes)
		(layer "In6.Cu")
		(net "M_E_CPU1_SB_PAR")
	)
	(gr_poly
		(pts
			(xy 79.745586 -288.058098) (xy 79.64551 -287.958022) (xy 79.545434 -288.058098) (xy 79.545434 -288.102548)
			(xy 79.745586 -288.102548)
		)
		(stroke
			(width 0)
			(type solid)
		)
		(fill yes)
		(layer "In6.Cu")
		(net "M_E_CPU1_SB_DQ<21>")
	)
	(gr_poly
		(pts
			(xy 79.745586 -284.818328) (xy 79.64551 -284.718252) (xy 79.545434 -284.818328) (xy 79.545434 -284.862778)
			(xy 79.745586 -284.862778)
		)
		(stroke
			(width 0)
			(type solid)
		)
		(fill yes)
		(layer "In6.Cu")
		(net "M_E_CPU1_SB_DQ<17>")
	)
	(gr_poly
		(pts
			(xy 79.745586 -283.198316) (xy 79.64551 -283.09824) (xy 79.545434 -283.198316) (xy 79.545434 -283.242766)
			(xy 79.745586 -283.242766)
		)
		(stroke
			(width 0)
			(type solid)
		)
		(fill yes)
		(layer "In6.Cu")
		(net "M_E_CPU1_SB_DQ<13>")
	)
	(gr_poly
		(pts
			(xy 79.751174 -286.438086) (xy 79.651098 -286.33801) (xy 79.551022 -286.438086) (xy 79.551022 -286.485838)
			(xy 79.751174 -286.485838)
		)
		(stroke
			(width 0)
			(type solid)
		)
		(fill yes)
		(layer "In6.Cu")
		(net "M_E_CPU1_SB_DQS_DN<7>")
	)
	(gr_poly
		(pts
			(xy 79.756508 -290.894516) (xy 79.756508 -290.847018) (xy 79.55661 -290.847018) (xy 79.55661 -290.894516)
			(xy 79.656432 -290.994592)
		)
		(stroke
			(width 0)
			(type solid)
		)
		(fill yes)
		(layer "In6.Cu")
		(net "M_E_CPU1_SB_DQS_DN<3>")
	)
	(gr_poly
		(pts
			(xy 79.756508 -284.414468) (xy 79.756508 -284.370018) (xy 79.55661 -284.370018) (xy 79.55661 -284.414468)
			(xy 79.656432 -284.514544)
		)
		(stroke
			(width 0)
			(type solid)
		)
		(fill yes)
		(layer "In6.Cu")
		(net "M_E_CPU1_SB_DQ<18>")
	)
	(gr_poly
		(pts
			(xy 79.756508 -282.794456) (xy 79.756508 -282.750006) (xy 79.55661 -282.750006) (xy 79.55661 -282.794456)
			(xy 79.656432 -282.894532)
		)
		(stroke
			(width 0)
			(type solid)
		)
		(fill yes)
		(layer "In6.Cu")
		(net "M_E_CPU1_SB_DQ<14>")
	)
	(gr_poly
		(pts
			(xy 79.756508 -273.074384) (xy 79.756508 -273.029934) (xy 79.55661 -273.029934) (xy 79.55661 -273.074384)
			(xy 79.656432 -273.17446)
		)
		(stroke
			(width 0)
			(type solid)
		)
		(fill yes)
		(layer "In6.Cu")
		(net "M_E_CPU1_SB_CB<2>")
	)
	(gr_poly
		(pts
			(xy 79.75727 -269.83436) (xy 79.75727 -269.78991) (xy 79.557118 -269.78991) (xy 79.557118 -269.83436)
			(xy 79.657194 -269.934436)
		)
		(stroke
			(width 0)
			(type solid)
		)
		(fill yes)
		(layer "In6.Cu")
		(net "M_E_CPU1_SB_CB<6>")
	)
	(gr_poly
		(pts
			(xy 79.806546 -294.670734) (xy 79.76997 -294.534082) (xy 79.731616 -294.51173) (xy 79.63154 -294.684958)
			(xy 79.670148 -294.70731)
		)
		(stroke
			(width 0)
			(type solid)
		)
		(fill yes)
		(layer "In6.Cu")
		(net "M_E_CPU1_SB_DQ<30>")
	)
	(gr_poly
		(pts
			(xy 79.840328 -226.203256) (xy 79.740252 -226.030028) (xy 79.701898 -226.05238) (xy 79.665322 -226.189032)
			(xy 79.80172 -226.225608)
		)
		(stroke
			(width 0)
			(type solid)
		)
		(fill yes)
		(layer "In6.Cu")
		(net "M_E_CPU1_SA_DQ<3>")
	)
	(gr_poly
		(pts
			(xy 79.841344 -222.964756) (xy 79.741268 -222.791528) (xy 79.70266 -222.813626) (xy 79.666084 -222.950278)
			(xy 79.802736 -222.986854)
		)
		(stroke
			(width 0)
			(type solid)
		)
		(fill yes)
		(layer "In6.Cu")
		(net "M_E_CPU1_SA_DQ<2>")
	)
	(gr_poly
		(pts
			(xy 79.91475 -243.472462) (xy 79.91475 -243.428012) (xy 79.714852 -243.428012) (xy 79.714852 -243.472462)
			(xy 79.814928 -243.572538)
		)
		(stroke
			(width 0)
			(type solid)
		)
		(fill yes)
		(layer "In6.Cu")
		(net "M_E_CPU1_SA_DQ<30>")
	)
	(gr_poly
		(pts
			(xy 79.91475 -238.612426) (xy 79.91475 -238.567976) (xy 79.714852 -238.567976) (xy 79.714852 -238.612426)
			(xy 79.814928 -238.712502)
		)
		(stroke
			(width 0)
			(type solid)
		)
		(fill yes)
		(layer "In6.Cu")
		(net "M_E_CPU1_SA_DQ<22>")
	)
	(gr_poly
		(pts
			(xy 79.91475 -235.372402) (xy 79.91475 -235.327952) (xy 79.714852 -235.327952) (xy 79.714852 -235.372402)
			(xy 79.814928 -235.472478)
		)
		(stroke
			(width 0)
			(type solid)
		)
		(fill yes)
		(layer "In6.Cu")
		(net "M_E_CPU1_SA_DQ<18>")
	)
	(gr_poly
		(pts
			(xy 79.927196 -256.432812) (xy 79.927196 -256.38506) (xy 79.727298 -256.38506) (xy 79.727298 -256.432812)
			(xy 79.82712 -256.532634)
		)
		(stroke
			(width 0)
			(type solid)
		)
		(fill yes)
		(layer "In6.Cu")
		(net "M_E_CPU1_CLK_DN<0>")
	)
	(gr_poly
		(pts
			(xy 79.927196 -255.216406) (xy 79.82712 -255.11633) (xy 79.727298 -255.216406) (xy 79.727298 -255.260856)
			(xy 79.927196 -255.260856)
		)
		(stroke
			(width 0)
			(type solid)
		)
		(fill yes)
		(layer "In6.Cu")
		(net "M_E_CPU1_SA_CA<6>")
	)
	(gr_poly
		(pts
			(xy 79.927196 -254.812546) (xy 79.927196 -254.768096) (xy 79.727298 -254.768096) (xy 79.727298 -254.812546)
			(xy 79.82712 -254.912622)
		)
		(stroke
			(width 0)
			(type solid)
		)
		(fill yes)
		(layer "In6.Cu")
		(net "M_E_CPU1_SA_CA<5>")
	)
	(gr_poly
		(pts
			(xy 79.927196 -253.596394) (xy 79.82712 -253.496318) (xy 79.727298 -253.596394) (xy 79.727298 -253.640844)
			(xy 79.927196 -253.640844)
		)
		(stroke
			(width 0)
			(type solid)
		)
		(fill yes)
		(layer "In6.Cu")
		(net "M_E_CPU1_SA_CA<2>")
	)
	(gr_poly
		(pts
			(xy 79.927196 -253.192534) (xy 79.927196 -253.148084) (xy 79.727298 -253.148084) (xy 79.727298 -253.192534)
			(xy 79.82712 -253.29261)
		)
		(stroke
			(width 0)
			(type solid)
		)
		(fill yes)
		(layer "In6.Cu")
		(net "M_E_CPU1_SA_CA<1>")
	)
	(gr_poly
		(pts
			(xy 79.927196 -251.572522) (xy 79.927196 -251.528072) (xy 79.727298 -251.528072) (xy 79.727298 -251.572522)
			(xy 79.82712 -251.672598)
		)
		(stroke
			(width 0)
			(type solid)
		)
		(fill yes)
		(layer "In6.Cu")
		(net "M_E_CPU1_SA_CS_N<0>")
	)
	(gr_poly
		(pts
			(xy 79.927196 -250.35637) (xy 79.82712 -250.256294) (xy 79.727298 -250.35637) (xy 79.727298 -250.40082)
			(xy 79.927196 -250.40082)
		)
		(stroke
			(width 0)
			(type solid)
		)
		(fill yes)
		(layer "In6.Cu")
		(net "M_E_CPU1_ALERT_R_N")
	)
	(gr_poly
		(pts
			(xy 79.927196 -248.736358) (xy 79.82712 -248.636282) (xy 79.727298 -248.736358) (xy 79.727298 -248.780808)
			(xy 79.927196 -248.780808)
		)
		(stroke
			(width 0)
			(type solid)
		)
		(fill yes)
		(layer "In6.Cu")
		(net "M_E_CPU1_SA_CB<5>")
	)
	(gr_poly
		(pts
			(xy 79.927196 -248.332498) (xy 79.927196 -248.288048) (xy 79.727298 -248.288048) (xy 79.727298 -248.332498)
			(xy 79.82712 -248.432574)
		)
		(stroke
			(width 0)
			(type solid)
		)
		(fill yes)
		(layer "In6.Cu")
		(net "M_E_CPU1_SA_CB<6>")
	)
	(gr_poly
		(pts
			(xy 79.927196 -247.116092) (xy 79.82712 -247.01627) (xy 79.727298 -247.116092) (xy 79.727298 -247.163844)
			(xy 79.927196 -247.163844)
		)
		(stroke
			(width 0)
			(type solid)
		)
		(fill yes)
		(layer "In6.Cu")
		(net "M_E_CPU1_SA_DQS_DN<9>")
	)
	(gr_poly
		(pts
			(xy 79.927196 -246.71274) (xy 79.927196 -246.664988) (xy 79.727298 -246.664988) (xy 79.727298 -246.71274)
			(xy 79.82712 -246.812562)
		)
		(stroke
			(width 0)
			(type solid)
		)
		(fill yes)
		(layer "In6.Cu")
		(net "M_E_CPU1_SA_DQS_DN<4>")
	)
	(gr_poly
		(pts
			(xy 79.927196 -245.496334) (xy 79.82712 -245.396258) (xy 79.727298 -245.496334) (xy 79.727298 -245.540784)
			(xy 79.927196 -245.540784)
		)
		(stroke
			(width 0)
			(type solid)
		)
		(fill yes)
		(layer "In6.Cu")
		(net "M_E_CPU1_SA_CB<1>")
	)
	(gr_poly
		(pts
			(xy 79.927196 -245.092474) (xy 79.927196 -245.048024) (xy 79.727298 -245.048024) (xy 79.727298 -245.092474)
			(xy 79.82712 -245.19255)
		)
		(stroke
			(width 0)
			(type solid)
		)
		(fill yes)
		(layer "In6.Cu")
		(net "M_E_CPU1_SA_CB<2>")
	)
	(gr_poly
		(pts
			(xy 79.927196 -243.876322) (xy 79.82712 -243.776246) (xy 79.727298 -243.876322) (xy 79.727298 -243.920772)
			(xy 79.927196 -243.920772)
		)
		(stroke
			(width 0)
			(type solid)
		)
		(fill yes)
		(layer "In6.Cu")
		(net "M_E_CPU1_SA_DQ<29>")
	)
	(gr_poly
		(pts
			(xy 79.927196 -242.256056) (xy 79.82712 -242.156234) (xy 79.727298 -242.256056) (xy 79.727298 -242.303808)
			(xy 79.927196 -242.303808)
		)
		(stroke
			(width 0)
			(type solid)
		)
		(fill yes)
		(layer "In6.Cu")
		(net "M_E_CPU1_SA_DQS_DN<8>")
	)
	(gr_poly
		(pts
			(xy 79.927196 -241.852704) (xy 79.927196 -241.804952) (xy 79.727298 -241.804952) (xy 79.727298 -241.852704)
			(xy 79.82712 -241.952526)
		)
		(stroke
			(width 0)
			(type solid)
		)
		(fill yes)
		(layer "In6.Cu")
		(net "M_E_CPU1_SA_DQS_DN<3>")
	)
	(gr_poly
		(pts
			(xy 79.927196 -240.636298) (xy 79.82712 -240.536222) (xy 79.727298 -240.636298) (xy 79.727298 -240.680748)
			(xy 79.927196 -240.680748)
		)
		(stroke
			(width 0)
			(type solid)
		)
		(fill yes)
		(layer "In6.Cu")
		(net "M_E_CPU1_SA_DQ<25>")
	)
	(gr_poly
		(pts
			(xy 79.927196 -240.232438) (xy 79.927196 -240.187988) (xy 79.727298 -240.187988) (xy 79.727298 -240.232438)
			(xy 79.82712 -240.332514)
		)
		(stroke
			(width 0)
			(type solid)
		)
		(fill yes)
		(layer "In6.Cu")
		(net "M_E_CPU1_SA_DQ<26>")
	)
	(gr_poly
		(pts
			(xy 79.927196 -239.016286) (xy 79.82712 -238.91621) (xy 79.727298 -239.016286) (xy 79.727298 -239.060736)
			(xy 79.927196 -239.060736)
		)
		(stroke
			(width 0)
			(type solid)
		)
		(fill yes)
		(layer "In6.Cu")
		(net "M_E_CPU1_SA_DQ<21>")
	)
	(gr_poly
		(pts
			(xy 79.927196 -237.39602) (xy 79.82712 -237.296198) (xy 79.727298 -237.39602) (xy 79.727298 -237.443772)
			(xy 79.927196 -237.443772)
		)
		(stroke
			(width 0)
			(type solid)
		)
		(fill yes)
		(layer "In6.Cu")
		(net "M_E_CPU1_SA_DQS_DN<7>")
	)
	(gr_poly
		(pts
			(xy 79.927196 -236.992668) (xy 79.927196 -236.944916) (xy 79.727298 -236.944916) (xy 79.727298 -236.992668)
			(xy 79.82712 -237.09249)
		)
		(stroke
			(width 0)
			(type solid)
		)
		(fill yes)
		(layer "In6.Cu")
		(net "M_E_CPU1_SA_DQS_DN<2>")
	)
	(gr_poly
		(pts
			(xy 79.927196 -235.776262) (xy 79.82712 -235.676186) (xy 79.727298 -235.776262) (xy 79.727298 -235.820712)
			(xy 79.927196 -235.820712)
		)
		(stroke
			(width 0)
			(type solid)
		)
		(fill yes)
		(layer "In6.Cu")
		(net "M_E_CPU1_SA_DQ<17>")
	)
	(gr_poly
		(pts
			(xy 79.927196 -234.15625) (xy 79.82712 -234.056174) (xy 79.727298 -234.15625) (xy 79.727298 -234.2007)
			(xy 79.927196 -234.2007)
		)
		(stroke
			(width 0)
			(type solid)
		)
		(fill yes)
		(layer "In6.Cu")
		(net "M_E_CPU1_SA_DQ<13>")
	)
	(gr_poly
		(pts
			(xy 79.927196 -233.75239) (xy 79.927196 -233.70794) (xy 79.727298 -233.70794) (xy 79.727298 -233.75239)
			(xy 79.82712 -233.852466)
		)
		(stroke
			(width 0)
			(type solid)
		)
		(fill yes)
		(layer "In6.Cu")
		(net "M_E_CPU1_SA_DQ<14>")
	)
	(gr_poly
		(pts
			(xy 79.927196 -232.535984) (xy 79.82712 -232.436162) (xy 79.727298 -232.535984) (xy 79.727298 -232.583736)
			(xy 79.927196 -232.583736)
		)
		(stroke
			(width 0)
			(type solid)
		)
		(fill yes)
		(layer "In6.Cu")
		(net "M_E_CPU1_SA_DQS_DN<6>")
	)
	(gr_poly
		(pts
			(xy 79.927196 -232.132632) (xy 79.927196 -232.08488) (xy 79.727298 -232.08488) (xy 79.727298 -232.132632)
			(xy 79.82712 -232.232454)
		)
		(stroke
			(width 0)
			(type solid)
		)
		(fill yes)
		(layer "In6.Cu")
		(net "M_E_CPU1_SA_DQS_DN<1>")
	)
	(gr_poly
		(pts
			(xy 79.927196 -230.51262) (xy 79.927196 -230.46817) (xy 79.727298 -230.46817) (xy 79.727298 -230.51262)
			(xy 79.82712 -230.612696)
		)
		(stroke
			(width 0)
			(type solid)
		)
		(fill yes)
		(layer "In6.Cu")
		(net "M_E_CPU1_SA_DQ<10>")
	)
	(gr_poly
		(pts
			(xy 79.927196 -227.27285) (xy 79.927196 -227.225098) (xy 79.727298 -227.225098) (xy 79.727298 -227.27285)
			(xy 79.82712 -227.372672)
		)
		(stroke
			(width 0)
			(type solid)
		)
		(fill yes)
		(layer "In6.Cu")
		(net "M_E_CPU1_SA_DQS_DN<0>")
	)
	(gr_poly
		(pts
			(xy 79.939896 -224.035366) (xy 79.976472 -223.898714) (xy 79.83982 -223.862138) (xy 79.801212 -223.884236)
			(xy 79.901288 -224.057464)
		)
		(stroke
			(width 0)
			(type solid)
		)
		(fill yes)
		(layer "In6.Cu")
		(net "M_E_CPU1_SA_DQ<1>")
	)
	(gr_poly
		(pts
			(xy 79.94015 -225.656648) (xy 79.976726 -225.519996) (xy 79.840328 -225.48342) (xy 79.80172 -225.505772)
			(xy 79.901796 -225.679)
		)
		(stroke
			(width 0)
			(type solid)
		)
		(fill yes)
		(layer "In6.Cu")
		(net "M_E_CPU1_SA_DQ<1>")
	)
	(gr_poly
		(pts
			(xy 79.94015 -222.415862) (xy 79.976726 -222.27921) (xy 79.840074 -222.242634) (xy 79.80172 -222.264986)
			(xy 79.901542 -222.438214)
		)
		(stroke
			(width 0)
			(type solid)
		)
		(fill yes)
		(layer "In6.Cu")
		(net "M_E_CPU1_SA_DQ<0>")
	)
	(gr_poly
		(pts
			(xy 79.976726 -224.569782) (xy 79.94015 -224.43313) (xy 79.901542 -224.410778) (xy 79.80172 -224.584006)
			(xy 79.840074 -224.606358)
		)
		(stroke
			(width 0)
			(type solid)
		)
		(fill yes)
		(layer "In6.Cu")
		(net "M_E_CPU1_SA_DQ<1>")
	)
	(gr_poly
		(pts
			(xy 80.141318 -294.795956) (xy 80.10271 -294.773858) (xy 79.966058 -294.810434) (xy 80.002634 -294.947086)
			(xy 80.041242 -294.969184)
		)
		(stroke
			(width 0)
			(type solid)
		)
		(fill yes)
		(layer "In6.Cu")
		(net "M_E_CPU1_SB_DQ<29>")
	)
	(gr_poly
		(pts
			(xy 80.214978 -290.487862) (xy 80.114902 -290.387786) (xy 80.014826 -290.487862) (xy 80.014826 -290.53536)
			(xy 80.214978 -290.53536)
		)
		(stroke
			(width 0)
			(type solid)
		)
		(fill yes)
		(layer "In6.Cu")
		(net "M_E_CPU1_SB_DQS_DP<3>")
	)
	(gr_poly
		(pts
			(xy 80.214978 -284.008322) (xy 80.114902 -283.908246) (xy 80.014826 -284.008322) (xy 80.014826 -284.052772)
			(xy 80.214978 -284.052772)
		)
		(stroke
			(width 0)
			(type solid)
		)
		(fill yes)
		(layer "In6.Cu")
		(net "M_E_CPU1_SB_DQ<16>")
	)
	(gr_poly
		(pts
			(xy 80.214978 -282.38831) (xy 80.114902 -282.288234) (xy 80.014826 -282.38831) (xy 80.014826 -282.43276)
			(xy 80.214978 -282.43276)
		)
		(stroke
			(width 0)
			(type solid)
		)
		(fill yes)
		(layer "In6.Cu")
		(net "M_E_CPU1_SB_DQ<12>")
	)
	(gr_poly
		(pts
			(xy 80.214978 -272.668238) (xy 80.114902 -272.568162) (xy 80.014826 -272.668238) (xy 80.014826 -272.712688)
			(xy 80.214978 -272.712688)
		)
		(stroke
			(width 0)
			(type solid)
		)
		(fill yes)
		(layer "In6.Cu")
		(net "M_E_CPU1_SB_CB<0>")
	)
	(gr_poly
		(pts
			(xy 80.219042 -277.12416) (xy 80.219042 -277.076408) (xy 80.019144 -277.076408) (xy 80.019144 -277.12416)
			(xy 80.118966 -277.223982)
		)
		(stroke
			(width 0)
			(type solid)
		)
		(fill yes)
		(layer "In6.Cu")
		(net "M_E_CPU1_SB_DQS_DP<5>")
	)
	(gr_poly
		(pts
			(xy 80.221074 -292.108128) (xy 80.120998 -292.008052) (xy 80.020922 -292.108128) (xy 80.020922 -292.152578)
			(xy 80.221074 -292.152578)
		)
		(stroke
			(width 0)
			(type solid)
		)
		(fill yes)
		(layer "In6.Cu")
		(net "M_E_CPU1_SB_DQ<28>")
	)
	(gr_poly
		(pts
			(xy 80.221074 -286.844486) (xy 80.221074 -286.796734) (xy 80.020922 -286.796734) (xy 80.020922 -286.844486)
			(xy 80.120998 -286.944562)
		)
		(stroke
			(width 0)
			(type solid)
		)
		(fill yes)
		(layer "In6.Cu")
		(net "M_E_CPU1_SB_DQS_DP<7>")
	)
	(gr_poly
		(pts
			(xy 80.221074 -280.364438) (xy 80.221074 -280.319988) (xy 80.020922 -280.319988) (xy 80.020922 -280.364438)
			(xy 80.120998 -280.464514)
		)
		(stroke
			(width 0)
			(type solid)
		)
		(fill yes)
		(layer "In6.Cu")
		(net "M_E_CPU1_SB_DQ<11>")
	)
	(gr_poly
		(pts
			(xy 80.221074 -278.744426) (xy 80.221074 -278.699976) (xy 80.020922 -278.699976) (xy 80.020922 -278.744426)
			(xy 80.120998 -278.844502)
		)
		(stroke
			(width 0)
			(type solid)
		)
		(fill yes)
		(layer "In6.Cu")
		(net "M_E_CPU1_SB_DQ<7>")
	)
	(gr_poly
		(pts
			(xy 80.221074 -275.504402) (xy 80.221074 -275.459952) (xy 80.020922 -275.459952) (xy 80.020922 -275.504402)
			(xy 80.120998 -275.604478)
		)
		(stroke
			(width 0)
			(type solid)
		)
		(fill yes)
		(layer "In6.Cu")
		(net "M_E_CPU1_SB_DQ<3>")
	)
	(gr_poly
		(pts
			(xy 80.221074 -270.644366) (xy 80.221074 -270.599916) (xy 80.020922 -270.599916) (xy 80.020922 -270.644366)
			(xy 80.120998 -270.744442)
		)
		(stroke
			(width 0)
			(type solid)
		)
		(fill yes)
		(layer "In6.Cu")
		(net "M_E_CPU1_SB_CB<7>")
	)
	(gr_poly
		(pts
			(xy 80.221074 -269.428214) (xy 80.120998 -269.328138) (xy 80.020922 -269.428214) (xy 80.020922 -269.472664)
			(xy 80.221074 -269.472664)
		)
		(stroke
			(width 0)
			(type solid)
		)
		(fill yes)
		(layer "In6.Cu")
		(net "M_E_CPU1_SB_CB<4>")
	)
	(gr_poly
		(pts
			(xy 80.221074 -265.78433) (xy 80.221074 -265.73988) (xy 80.020922 -265.73988) (xy 80.020922 -265.78433)
			(xy 80.120998 -265.884406)
		)
		(stroke
			(width 0)
			(type solid)
		)
		(fill yes)
		(layer "In6.Cu")
		(net "M_E_CPU1_SB_CS_N<0>")
	)
	(gr_poly
		(pts
			(xy 80.221074 -262.948166) (xy 80.120998 -262.84809) (xy 80.020922 -262.948166) (xy 80.020922 -262.992616)
			(xy 80.221074 -262.992616)
		)
		(stroke
			(width 0)
			(type solid)
		)
		(fill yes)
		(layer "In6.Cu")
		(net "M_E_CPU1_SB_CA<2>")
	)
	(gr_poly
		(pts
			(xy 80.221074 -262.544306) (xy 80.221074 -262.499856) (xy 80.020922 -262.499856) (xy 80.020922 -262.544306)
			(xy 80.120998 -262.644382)
		)
		(stroke
			(width 0)
			(type solid)
		)
		(fill yes)
		(layer "In6.Cu")
		(net "M_E_CPU1_SB_CA<1>")
	)
	(gr_poly
		(pts
			(xy 80.22717 -288.868104) (xy 80.127094 -288.768028) (xy 80.027018 -288.868104) (xy 80.027018 -288.912554)
			(xy 80.22717 -288.912554)
		)
		(stroke
			(width 0)
			(type solid)
		)
		(fill yes)
		(layer "In6.Cu")
		(net "M_E_CPU1_SB_DQ<24>")
	)
	(gr_poly
		(pts
			(xy 80.22717 -288.464498) (xy 80.22717 -288.420048) (xy 80.027018 -288.420048) (xy 80.027018 -288.464498)
			(xy 80.127094 -288.564574)
		)
		(stroke
			(width 0)
			(type solid)
		)
		(fill yes)
		(layer "In6.Cu")
		(net "M_E_CPU1_SB_DQ<23>")
	)
	(gr_poly
		(pts
			(xy 80.22717 -287.248092) (xy 80.127094 -287.148016) (xy 80.027018 -287.248092) (xy 80.027018 -287.292542)
			(xy 80.22717 -287.292542)
		)
		(stroke
			(width 0)
			(type solid)
		)
		(fill yes)
		(layer "In6.Cu")
		(net "M_E_CPU1_SB_DQ<20>")
	)
	(gr_poly
		(pts
			(xy 80.22717 -285.224474) (xy 80.22717 -285.180024) (xy 80.027018 -285.180024) (xy 80.027018 -285.224474)
			(xy 80.127094 -285.32455)
		)
		(stroke
			(width 0)
			(type solid)
		)
		(fill yes)
		(layer "In6.Cu")
		(net "M_E_CPU1_SB_DQ<19>")
	)
	(gr_poly
		(pts
			(xy 80.22717 -283.604462) (xy 80.22717 -283.560012) (xy 80.027018 -283.560012) (xy 80.027018 -283.604462)
			(xy 80.127094 -283.704538)
		)
		(stroke
			(width 0)
			(type solid)
		)
		(fill yes)
		(layer "In6.Cu")
		(net "M_E_CPU1_SB_DQ<15>")
	)
	(gr_poly
		(pts
			(xy 80.22717 -281.984704) (xy 80.22717 -281.936952) (xy 80.027018 -281.936952) (xy 80.027018 -281.984704)
			(xy 80.127094 -282.084526)
		)
		(stroke
			(width 0)
			(type solid)
		)
		(fill yes)
		(layer "In6.Cu")
		(net "M_E_CPU1_SB_DQS_DP<6>")
	)
	(gr_poly
		(pts
			(xy 80.22717 -280.768044) (xy 80.127094 -280.668222) (xy 80.027018 -280.768044) (xy 80.027018 -280.815796)
			(xy 80.22717 -280.815796)
		)
		(stroke
			(width 0)
			(type solid)
		)
		(fill yes)
		(layer "In6.Cu")
		(net "M_E_CPU1_SB_DQS_DP<1>")
	)
	(gr_poly
		(pts
			(xy 80.22717 -279.148286) (xy 80.127094 -279.04821) (xy 80.027018 -279.148286) (xy 80.027018 -279.192736)
			(xy 80.22717 -279.192736)
		)
		(stroke
			(width 0)
			(type solid)
		)
		(fill yes)
		(layer "In6.Cu")
		(net "M_E_CPU1_SB_DQ<8>")
	)
	(gr_poly
		(pts
			(xy 80.22717 -277.528274) (xy 80.127094 -277.428198) (xy 80.027018 -277.528274) (xy 80.027018 -277.572724)
			(xy 80.22717 -277.572724)
		)
		(stroke
			(width 0)
			(type solid)
		)
		(fill yes)
		(layer "In6.Cu")
		(net "M_E_CPU1_SB_DQ<4>")
	)
	(gr_poly
		(pts
			(xy 80.22717 -275.908008) (xy 80.127094 -275.808186) (xy 80.027018 -275.908008) (xy 80.027018 -275.95576)
			(xy 80.22717 -275.95576)
		)
		(stroke
			(width 0)
			(type solid)
		)
		(fill yes)
		(layer "In6.Cu")
		(net "M_E_CPU1_SB_DQS_DP<0>")
	)
	(gr_poly
		(pts
			(xy 80.22717 -274.28825) (xy 80.127094 -274.188174) (xy 80.027018 -274.28825) (xy 80.027018 -274.3327)
			(xy 80.22717 -274.3327)
		)
		(stroke
			(width 0)
			(type solid)
		)
		(fill yes)
		(layer "In6.Cu")
		(net "M_E_CPU1_SB_DQ<0>")
	)
	(gr_poly
		(pts
			(xy 80.22717 -267.795502) (xy 80.127348 -267.695426) (xy 80.027272 -267.795502) (xy 80.027272 -267.846302)
			(xy 80.22717 -267.846302)
		)
		(stroke
			(width 0)
			(type solid)
		)
		(fill yes)
		(layer "In6.Cu")
		(net "M_E_CPU1_SB_RSP<0>")
	)
	(gr_poly
		(pts
			(xy 80.22717 -264.568178) (xy 80.127094 -264.468102) (xy 80.027018 -264.568178) (xy 80.027018 -264.612628)
			(xy 80.22717 -264.612628)
		)
		(stroke
			(width 0)
			(type solid)
		)
		(fill yes)
		(layer "In6.Cu")
		(net "M_E_CPU1_SB_CA<6>")
	)
	(gr_poly
		(pts
			(xy 80.228694 -272.264632) (xy 80.228694 -272.21688) (xy 80.028542 -272.21688) (xy 80.028542 -272.264632)
			(xy 80.128618 -272.364708)
		)
		(stroke
			(width 0)
			(type solid)
		)
		(fill yes)
		(layer "In6.Cu")
		(net "M_E_CPU1_SB_DQS_DP<4>")
	)
	(gr_poly
		(pts
			(xy 80.23098 -285.628334) (xy 80.130904 -285.528258) (xy 80.031082 -285.628334) (xy 80.031082 -285.675832)
			(xy 80.23098 -285.675832)
		)
		(stroke
			(width 0)
			(type solid)
		)
		(fill yes)
		(layer "In6.Cu")
		(net "M_E_CPU1_SB_DQS_DP<2>")
	)
	(gr_poly
		(pts
			(xy 80.238346 -273.884136) (xy 80.238346 -273.839686) (xy 80.038194 -273.839686) (xy 80.038194 -273.884136)
			(xy 80.13827 -273.984212)
		)
		(stroke
			(width 0)
			(type solid)
		)
		(fill yes)
		(layer "In6.Cu")
		(net "M_E_CPU1_SB_CB<3>")
	)
	(gr_poly
		(pts
			(xy 80.241902 -271.048226) (xy 80.141826 -270.948404) (xy 80.04175 -271.048226) (xy 80.04175 -271.095978)
			(xy 80.241902 -271.095978)
		)
		(stroke
			(width 0)
			(type solid)
		)
		(fill yes)
		(layer "In6.Cu")
		(net "M_E_CPU1_SB_DQS_DP<9>")
	)
	(gr_poly
		(pts
			(xy 80.243172 -264.16381) (xy 80.243172 -264.11936) (xy 80.043274 -264.11936) (xy 80.043274 -264.16381)
			(xy 80.143096 -264.263886)
		)
		(stroke
			(width 0)
			(type solid)
		)
		(fill yes)
		(layer "In6.Cu")
		(net "M_E_CPU1_SB_CA<5>")
	)
	(gr_poly
		(pts
			(xy 80.276954 -293.860728) (xy 80.240378 -293.724076) (xy 80.202024 -293.701724) (xy 80.101948 -293.874952)
			(xy 80.140556 -293.897304)
		)
		(stroke
			(width 0)
			(type solid)
		)
		(fill yes)
		(layer "In6.Cu")
		(net "M_E_CPU1_SB_DQ<30>")
	)
	(gr_poly
		(pts
			(xy 80.309974 -224.696274) (xy 80.271366 -224.674176) (xy 80.134714 -224.710752) (xy 80.171544 -224.847404)
			(xy 80.209898 -224.869502)
		)
		(stroke
			(width 0)
			(type solid)
		)
		(fill yes)
		(layer "In6.Cu")
		(net "M_E_CPU1_SA_DQ<2>")
	)
	(gr_poly
		(pts
			(xy 80.310228 -225.39325) (xy 80.210152 -225.220022) (xy 80.171798 -225.242374) (xy 80.135222 -225.379026)
			(xy 80.27162 -225.415602)
		)
		(stroke
			(width 0)
			(type solid)
		)
		(fill yes)
		(layer "In6.Cu")
		(net "M_E_CPU1_SA_DQ<2>")
	)
	(gr_poly
		(pts
			(xy 80.311244 -223.774762) (xy 80.211168 -223.601534) (xy 80.17256 -223.623632) (xy 80.135984 -223.760284)
			(xy 80.272636 -223.79686)
		)
		(stroke
			(width 0)
			(type solid)
		)
		(fill yes)
		(layer "In6.Cu")
		(net "M_E_CPU1_SA_DQ<2>")
	)
	(gr_poly
		(pts
			(xy 80.391254 -256.026158) (xy 80.291178 -255.926336) (xy 80.191102 -256.026158) (xy 80.191102 -256.07391)
			(xy 80.391254 -256.07391)
		)
		(stroke
			(width 0)
			(type solid)
		)
		(fill yes)
		(layer "In6.Cu")
		(net "M_E_CPU1_CLK_DP<0>")
	)
	(gr_poly
		(pts
			(xy 80.391254 -255.622552) (xy 80.391254 -255.578102) (xy 80.191102 -255.578102) (xy 80.191102 -255.622552)
			(xy 80.291178 -255.722628)
		)
		(stroke
			(width 0)
			(type solid)
		)
		(fill yes)
		(layer "In6.Cu")
		(net "M_E_CPU1_SA_PAR")
	)
	(gr_poly
		(pts
			(xy 80.391254 -254.4064) (xy 80.291178 -254.306324) (xy 80.191102 -254.4064) (xy 80.191102 -254.45085)
			(xy 80.391254 -254.45085)
		)
		(stroke
			(width 0)
			(type solid)
		)
		(fill yes)
		(layer "In6.Cu")
		(net "M_E_CPU1_SA_CA<4>")
	)
	(gr_poly
		(pts
			(xy 80.391254 -254.00254) (xy 80.391254 -253.95809) (xy 80.191102 -253.95809) (xy 80.191102 -254.00254)
			(xy 80.291178 -254.102616)
		)
		(stroke
			(width 0)
			(type solid)
		)
		(fill yes)
		(layer "In6.Cu")
		(net "M_E_CPU1_SA_CA<3>")
	)
	(gr_poly
		(pts
			(xy 80.391254 -252.786388) (xy 80.291178 -252.686312) (xy 80.191102 -252.786388) (xy 80.191102 -252.830838)
			(xy 80.391254 -252.830838)
		)
		(stroke
			(width 0)
			(type solid)
		)
		(fill yes)
		(layer "In6.Cu")
		(net "M_E_CPU1_SA_CA<0>")
	)
	(gr_poly
		(pts
			(xy 80.391254 -252.382528) (xy 80.391254 -252.338078) (xy 80.191102 -252.338078) (xy 80.191102 -252.382528)
			(xy 80.291178 -252.482604)
		)
		(stroke
			(width 0)
			(type solid)
		)
		(fill yes)
		(layer "In6.Cu")
		(net "M_E_CPU1_SA_CS_N<1>")
	)
	(gr_poly
		(pts
			(xy 80.391254 -250.762516) (xy 80.391254 -250.718066) (xy 80.191102 -250.718066) (xy 80.191102 -250.762516)
			(xy 80.291178 -250.862592)
		)
		(stroke
			(width 0)
			(type solid)
		)
		(fill yes)
		(layer "In6.Cu")
		(net "M_E_CPU1_RESET_N")
	)
	(gr_poly
		(pts
			(xy 80.391254 -249.142504) (xy 80.391254 -249.098054) (xy 80.191102 -249.098054) (xy 80.191102 -249.142504)
			(xy 80.291178 -249.24258)
		)
		(stroke
			(width 0)
			(type solid)
		)
		(fill yes)
		(layer "In6.Cu")
		(net "M_E_CPU1_SA_CB<7>")
	)
	(gr_poly
		(pts
			(xy 80.391254 -247.926352) (xy 80.291178 -247.826276) (xy 80.191102 -247.926352) (xy 80.191102 -247.970802)
			(xy 80.391254 -247.970802)
		)
		(stroke
			(width 0)
			(type solid)
		)
		(fill yes)
		(layer "In6.Cu")
		(net "M_E_CPU1_SA_CB<4>")
	)
	(gr_poly
		(pts
			(xy 80.391254 -247.522746) (xy 80.391254 -247.474994) (xy 80.191102 -247.474994) (xy 80.191102 -247.522746)
			(xy 80.291178 -247.622568)
		)
		(stroke
			(width 0)
			(type solid)
		)
		(fill yes)
		(layer "In6.Cu")
		(net "M_E_CPU1_SA_DQS_DP<9>")
	)
	(gr_poly
		(pts
			(xy 80.391254 -246.306086) (xy 80.291178 -246.206264) (xy 80.191102 -246.306086) (xy 80.191102 -246.353838)
			(xy 80.391254 -246.353838)
		)
		(stroke
			(width 0)
			(type solid)
		)
		(fill yes)
		(layer "In6.Cu")
		(net "M_E_CPU1_SA_DQS_DP<4>")
	)
	(gr_poly
		(pts
			(xy 80.391254 -245.90248) (xy 80.391254 -245.85803) (xy 80.191102 -245.85803) (xy 80.191102 -245.90248)
			(xy 80.291178 -246.002556)
		)
		(stroke
			(width 0)
			(type solid)
		)
		(fill yes)
		(layer "In6.Cu")
		(net "M_E_CPU1_SA_CB<3>")
	)
	(gr_poly
		(pts
			(xy 80.391254 -244.686328) (xy 80.291178 -244.586252) (xy 80.191102 -244.686328) (xy 80.191102 -244.730778)
			(xy 80.391254 -244.730778)
		)
		(stroke
			(width 0)
			(type solid)
		)
		(fill yes)
		(layer "In6.Cu")
		(net "M_E_CPU1_SA_CB<0>")
	)
	(gr_poly
		(pts
			(xy 80.391254 -244.282468) (xy 80.391254 -244.238018) (xy 80.191102 -244.238018) (xy 80.191102 -244.282468)
			(xy 80.291178 -244.382544)
		)
		(stroke
			(width 0)
			(type solid)
		)
		(fill yes)
		(layer "In6.Cu")
		(net "M_E_CPU1_SA_DQ<31>")
	)
	(gr_poly
		(pts
			(xy 80.391254 -243.066316) (xy 80.291178 -242.96624) (xy 80.191102 -243.066316) (xy 80.191102 -243.110766)
			(xy 80.391254 -243.110766)
		)
		(stroke
			(width 0)
			(type solid)
		)
		(fill yes)
		(layer "In6.Cu")
		(net "M_E_CPU1_SA_DQ<28>")
	)
	(gr_poly
		(pts
			(xy 80.391254 -242.66271) (xy 80.391254 -242.614958) (xy 80.191102 -242.614958) (xy 80.191102 -242.66271)
			(xy 80.291178 -242.762532)
		)
		(stroke
			(width 0)
			(type solid)
		)
		(fill yes)
		(layer "In6.Cu")
		(net "M_E_CPU1_SA_DQS_DP<8>")
	)
	(gr_poly
		(pts
			(xy 80.391254 -241.44605) (xy 80.291178 -241.346228) (xy 80.191102 -241.44605) (xy 80.191102 -241.493802)
			(xy 80.391254 -241.493802)
		)
		(stroke
			(width 0)
			(type solid)
		)
		(fill yes)
		(layer "In6.Cu")
		(net "M_E_CPU1_SA_DQS_DP<3>")
	)
	(gr_poly
		(pts
			(xy 80.391254 -241.042444) (xy 80.391254 -240.997994) (xy 80.191102 -240.997994) (xy 80.191102 -241.042444)
			(xy 80.291178 -241.14252)
		)
		(stroke
			(width 0)
			(type solid)
		)
		(fill yes)
		(layer "In6.Cu")
		(net "M_E_CPU1_SA_DQ<27>")
	)
	(gr_poly
		(pts
			(xy 80.391254 -239.826292) (xy 80.291178 -239.726216) (xy 80.191102 -239.826292) (xy 80.191102 -239.870742)
			(xy 80.391254 -239.870742)
		)
		(stroke
			(width 0)
			(type solid)
		)
		(fill yes)
		(layer "In6.Cu")
		(net "M_E_CPU1_SA_DQ<24>")
	)
	(gr_poly
		(pts
			(xy 80.391254 -239.422432) (xy 80.391254 -239.377982) (xy 80.191102 -239.377982) (xy 80.191102 -239.422432)
			(xy 80.291178 -239.522508)
		)
		(stroke
			(width 0)
			(type solid)
		)
		(fill yes)
		(layer "In6.Cu")
		(net "M_E_CPU1_SA_DQ<23>")
	)
	(gr_poly
		(pts
			(xy 80.391254 -238.20628) (xy 80.291178 -238.106204) (xy 80.191102 -238.20628) (xy 80.191102 -238.25073)
			(xy 80.391254 -238.25073)
		)
		(stroke
			(width 0)
			(type solid)
		)
		(fill yes)
		(layer "In6.Cu")
		(net "M_E_CPU1_SA_DQ<20>")
	)
	(gr_poly
		(pts
			(xy 80.391254 -237.802674) (xy 80.391254 -237.754922) (xy 80.191102 -237.754922) (xy 80.191102 -237.802674)
			(xy 80.291178 -237.902496)
		)
		(stroke
			(width 0)
			(type solid)
		)
		(fill yes)
		(layer "In6.Cu")
		(net "M_E_CPU1_SA_DQS_DP<7>")
	)
	(gr_poly
		(pts
			(xy 80.391254 -236.586014) (xy 80.291178 -236.486192) (xy 80.191102 -236.586014) (xy 80.191102 -236.633766)
			(xy 80.391254 -236.633766)
		)
		(stroke
			(width 0)
			(type solid)
		)
		(fill yes)
		(layer "In6.Cu")
		(net "M_E_CPU1_SA_DQS_DP<2>")
	)
	(gr_poly
		(pts
			(xy 80.391254 -236.182408) (xy 80.391254 -236.137958) (xy 80.191102 -236.137958) (xy 80.191102 -236.182408)
			(xy 80.291178 -236.282484)
		)
		(stroke
			(width 0)
			(type solid)
		)
		(fill yes)
		(layer "In6.Cu")
		(net "M_E_CPU1_SA_DQ<19>")
	)
	(gr_poly
		(pts
			(xy 80.391254 -234.966256) (xy 80.291178 -234.86618) (xy 80.191102 -234.966256) (xy 80.191102 -235.010706)
			(xy 80.391254 -235.010706)
		)
		(stroke
			(width 0)
			(type solid)
		)
		(fill yes)
		(layer "In6.Cu")
		(net "M_E_CPU1_SA_DQ<16>")
	)
	(gr_poly
		(pts
			(xy 80.391254 -234.562396) (xy 80.391254 -234.517946) (xy 80.191102 -234.517946) (xy 80.191102 -234.562396)
			(xy 80.291178 -234.662472)
		)
		(stroke
			(width 0)
			(type solid)
		)
		(fill yes)
		(layer "In6.Cu")
		(net "M_E_CPU1_SA_DQ<15>")
	)
	(gr_poly
		(pts
			(xy 80.391254 -233.346244) (xy 80.291178 -233.246168) (xy 80.191102 -233.346244) (xy 80.191102 -233.390694)
			(xy 80.391254 -233.390694)
		)
		(stroke
			(width 0)
			(type solid)
		)
		(fill yes)
		(layer "In6.Cu")
		(net "M_E_CPU1_SA_DQ<12>")
	)
	(gr_poly
		(pts
			(xy 80.391254 -232.942638) (xy 80.391254 -232.894886) (xy 80.191102 -232.894886) (xy 80.191102 -232.942638)
			(xy 80.291178 -233.04246)
		)
		(stroke
			(width 0)
			(type solid)
		)
		(fill yes)
		(layer "In6.Cu")
		(net "M_E_CPU1_SA_DQS_DP<6>")
	)
	(gr_poly
		(pts
			(xy 80.391254 -231.725978) (xy 80.291178 -231.626156) (xy 80.191102 -231.725978) (xy 80.191102 -231.77373)
			(xy 80.391254 -231.77373)
		)
		(stroke
			(width 0)
			(type solid)
		)
		(fill yes)
		(layer "In6.Cu")
		(net "M_E_CPU1_SA_DQS_DP<1>")
	)
	(gr_poly
		(pts
			(xy 80.391254 -231.322626) (xy 80.391254 -231.278176) (xy 80.191102 -231.278176) (xy 80.191102 -231.322626)
			(xy 80.291178 -231.422702)
		)
		(stroke
			(width 0)
			(type solid)
		)
		(fill yes)
		(layer "In6.Cu")
		(net "M_E_CPU1_SA_DQ<11>")
	)
	(gr_poly
		(pts
			(xy 80.391254 -230.10622) (xy 80.291178 -230.006144) (xy 80.191102 -230.10622) (xy 80.191102 -230.15067)
			(xy 80.391254 -230.15067)
		)
		(stroke
			(width 0)
			(type solid)
		)
		(fill yes)
		(layer "In6.Cu")
		(net "M_E_CPU1_SA_DQ<8>")
	)
	(gr_poly
		(pts
			(xy 80.391254 -229.702614) (xy 80.391254 -229.658164) (xy 80.191102 -229.658164) (xy 80.191102 -229.702614)
			(xy 80.291178 -229.80269)
		)
		(stroke
			(width 0)
			(type solid)
		)
		(fill yes)
		(layer "In6.Cu")
		(net "M_E_CPU1_SA_DQ<7>")
	)
	(gr_poly
		(pts
			(xy 80.391254 -228.486462) (xy 80.291178 -228.386386) (xy 80.191102 -228.486462) (xy 80.191102 -228.530912)
			(xy 80.391254 -228.530912)
		)
		(stroke
			(width 0)
			(type solid)
		)
		(fill yes)
		(layer "In6.Cu")
		(net "M_E_CPU1_SA_DQ<4>")
	)
	(gr_poly
		(pts
			(xy 80.391254 -228.082856) (xy 80.391254 -228.035104) (xy 80.191102 -228.035104) (xy 80.191102 -228.082856)
			(xy 80.291178 -228.182678)
		)
		(stroke
			(width 0)
			(type solid)
		)
		(fill yes)
		(layer "In6.Cu")
		(net "M_E_CPU1_SA_DQS_DP<5>")
	)
	(gr_poly
		(pts
			(xy 80.391254 -226.866196) (xy 80.291178 -226.766374) (xy 80.191102 -226.866196) (xy 80.191102 -226.913948)
			(xy 80.391254 -226.913948)
		)
		(stroke
			(width 0)
			(type solid)
		)
		(fill yes)
		(layer "In6.Cu")
		(net "M_E_CPU1_SA_DQS_DP<0>")
	)
	(gr_poly
		(pts
			(xy 80.391254 -226.46259) (xy 80.391254 -226.41814) (xy 80.191102 -226.41814) (xy 80.191102 -226.46259)
			(xy 80.291178 -226.562666)
		)
		(stroke
			(width 0)
			(type solid)
		)
		(fill yes)
		(layer "In6.Cu")
		(net "M_E_CPU1_SA_DQ<3>")
	)
	(gr_poly
		(pts
			(xy 80.409796 -223.22536) (xy 80.446372 -223.088708) (xy 80.30972 -223.052132) (xy 80.271112 -223.07423)
			(xy 80.371188 -223.247458)
		)
		(stroke
			(width 0)
			(type solid)
		)
		(fill yes)
		(layer "In6.Cu")
		(net "M_E_CPU1_SA_DQ<0>")
	)
	(gr_poly
		(pts
			(xy 80.610202 -293.987474) (xy 80.571594 -293.965122) (xy 80.434942 -294.001698) (xy 80.471772 -294.13835)
			(xy 80.510126 -294.160702)
		)
		(stroke
			(width 0)
			(type solid)
		)
		(fill yes)
		(layer "In6.Cu")
		(net "M_E_CPU1_SB_DQ<29>")
	)
	(gr_poly
		(pts
			(xy 80.691228 -291.297868) (xy 80.591152 -291.198046) (xy 80.491076 -291.297868) (xy 80.491076 -291.34562)
			(xy 80.691228 -291.34562)
		)
		(stroke
			(width 0)
			(type solid)
		)
		(fill yes)
		(layer "In6.Cu")
		(net "M_E_CPU1_SB_DQS_DN<8>")
	)
	(gr_poly
		(pts
			(xy 80.691228 -290.894516) (xy 80.691228 -290.846764) (xy 80.491076 -290.846764) (xy 80.491076 -290.894516)
			(xy 80.591152 -290.994338)
		)
		(stroke
			(width 0)
			(type solid)
		)
		(fill yes)
		(layer "In6.Cu")
		(net "M_E_CPU1_SB_DQS_DN<3>")
	)
	(gr_poly
		(pts
			(xy 80.691228 -289.67811) (xy 80.591152 -289.578034) (xy 80.491076 -289.67811) (xy 80.491076 -289.72256)
			(xy 80.691228 -289.72256)
		)
		(stroke
			(width 0)
			(type solid)
		)
		(fill yes)
		(layer "In6.Cu")
		(net "M_E_CPU1_SB_DQ<25>")
	)
	(gr_poly
		(pts
			(xy 80.691228 -289.27425) (xy 80.691228 -289.2298) (xy 80.491076 -289.2298) (xy 80.491076 -289.27425)
			(xy 80.591152 -289.374326)
		)
		(stroke
			(width 0)
			(type solid)
		)
		(fill yes)
		(layer "In6.Cu")
		(net "M_E_CPU1_SB_DQ<26>")
	)
	(gr_poly
		(pts
			(xy 80.691228 -288.058098) (xy 80.591152 -287.958022) (xy 80.491076 -288.058098) (xy 80.491076 -288.102548)
			(xy 80.691228 -288.102548)
		)
		(stroke
			(width 0)
			(type solid)
		)
		(fill yes)
		(layer "In6.Cu")
		(net "M_E_CPU1_SB_DQ<21>")
	)
	(gr_poly
		(pts
			(xy 80.691228 -287.654492) (xy 80.691228 -287.610042) (xy 80.491076 -287.610042) (xy 80.491076 -287.654492)
			(xy 80.591152 -287.754568)
		)
		(stroke
			(width 0)
			(type solid)
		)
		(fill yes)
		(layer "In6.Cu")
		(net "M_E_CPU1_SB_DQ<22>")
	)
	(gr_poly
		(pts
			(xy 80.691228 -286.438086) (xy 80.591152 -286.33801) (xy 80.491076 -286.438086) (xy 80.491076 -286.485838)
			(xy 80.691228 -286.485838)
		)
		(stroke
			(width 0)
			(type solid)
		)
		(fill yes)
		(layer "In6.Cu")
		(net "M_E_CPU1_SB_DQS_DN<7>")
	)
	(gr_poly
		(pts
			(xy 80.691228 -286.034734) (xy 80.691228 -285.986982) (xy 80.491076 -285.986982) (xy 80.491076 -286.034734)
			(xy 80.591152 -286.134556)
		)
		(stroke
			(width 0)
			(type solid)
		)
		(fill yes)
		(layer "In6.Cu")
		(net "M_E_CPU1_SB_DQS_DN<2>")
	)
	(gr_poly
		(pts
			(xy 80.691228 -284.818328) (xy 80.591152 -284.718252) (xy 80.491076 -284.818328) (xy 80.491076 -284.862778)
			(xy 80.691228 -284.862778)
		)
		(stroke
			(width 0)
			(type solid)
		)
		(fill yes)
		(layer "In6.Cu")
		(net "M_E_CPU1_SB_DQ<17>")
	)
	(gr_poly
		(pts
			(xy 80.691228 -284.414468) (xy 80.691228 -284.370018) (xy 80.491076 -284.370018) (xy 80.491076 -284.414468)
			(xy 80.591152 -284.514544)
		)
		(stroke
			(width 0)
			(type solid)
		)
		(fill yes)
		(layer "In6.Cu")
		(net "M_E_CPU1_SB_DQ<18>")
	)
	(gr_poly
		(pts
			(xy 80.691228 -283.198316) (xy 80.591152 -283.09824) (xy 80.491076 -283.198316) (xy 80.491076 -283.242766)
			(xy 80.691228 -283.242766)
		)
		(stroke
			(width 0)
			(type solid)
		)
		(fill yes)
		(layer "In6.Cu")
		(net "M_E_CPU1_SB_DQ<13>")
	)
	(gr_poly
		(pts
			(xy 80.691228 -282.794456) (xy 80.691228 -282.750006) (xy 80.491076 -282.750006) (xy 80.491076 -282.794456)
			(xy 80.591152 -282.894532)
		)
		(stroke
			(width 0)
			(type solid)
		)
		(fill yes)
		(layer "In6.Cu")
		(net "M_E_CPU1_SB_DQ<14>")
	)
	(gr_poly
		(pts
			(xy 80.691228 -281.57805) (xy 80.591152 -281.478228) (xy 80.491076 -281.57805) (xy 80.491076 -281.625802)
			(xy 80.691228 -281.625802)
		)
		(stroke
			(width 0)
			(type solid)
		)
		(fill yes)
		(layer "In6.Cu")
		(net "M_E_CPU1_SB_DQS_DN<6>")
	)
	(gr_poly
		(pts
			(xy 80.691228 -281.174698) (xy 80.691228 -281.126946) (xy 80.491076 -281.126946) (xy 80.491076 -281.174698)
			(xy 80.591152 -281.27452)
		)
		(stroke
			(width 0)
			(type solid)
		)
		(fill yes)
		(layer "In6.Cu")
		(net "M_E_CPU1_SB_DQS_DN<1>")
	)
	(gr_poly
		(pts
			(xy 80.691228 -279.958292) (xy 80.591152 -279.858216) (xy 80.491076 -279.958292) (xy 80.491076 -280.002742)
			(xy 80.691228 -280.002742)
		)
		(stroke
			(width 0)
			(type solid)
		)
		(fill yes)
		(layer "In6.Cu")
		(net "M_E_CPU1_SB_DQ<9>")
	)
	(gr_poly
		(pts
			(xy 80.691228 -279.554432) (xy 80.691228 -279.509982) (xy 80.491076 -279.509982) (xy 80.491076 -279.554432)
			(xy 80.591152 -279.654508)
		)
		(stroke
			(width 0)
			(type solid)
		)
		(fill yes)
		(layer "In6.Cu")
		(net "M_E_CPU1_SB_DQ<10>")
	)
	(gr_poly
		(pts
			(xy 80.691228 -278.33828) (xy 80.591152 -278.238204) (xy 80.491076 -278.33828) (xy 80.491076 -278.38273)
			(xy 80.691228 -278.38273)
		)
		(stroke
			(width 0)
			(type solid)
		)
		(fill yes)
		(layer "In6.Cu")
		(net "M_E_CPU1_SB_DQ<5>")
	)
	(gr_poly
		(pts
			(xy 80.691228 -277.93442) (xy 80.691228 -277.88997) (xy 80.491076 -277.88997) (xy 80.491076 -277.93442)
			(xy 80.591152 -278.034496)
		)
		(stroke
			(width 0)
			(type solid)
		)
		(fill yes)
		(layer "In6.Cu")
		(net "M_E_CPU1_SB_DQ<6>")
	)
	(gr_poly
		(pts
			(xy 80.691228 -276.718014) (xy 80.591152 -276.618192) (xy 80.491076 -276.718014) (xy 80.491076 -276.765766)
			(xy 80.691228 -276.765766)
		)
		(stroke
			(width 0)
			(type solid)
		)
		(fill yes)
		(layer "In6.Cu")
		(net "M_E_CPU1_SB_DQS_DN<5>")
	)
	(gr_poly
		(pts
			(xy 80.691228 -276.314662) (xy 80.691228 -276.26691) (xy 80.491076 -276.26691) (xy 80.491076 -276.314662)
			(xy 80.591152 -276.414484)
		)
		(stroke
			(width 0)
			(type solid)
		)
		(fill yes)
		(layer "In6.Cu")
		(net "M_E_CPU1_SB_DQS_DN<0>")
	)
	(gr_poly
		(pts
			(xy 80.691228 -275.098256) (xy 80.591152 -274.99818) (xy 80.491076 -275.098256) (xy 80.491076 -275.142706)
			(xy 80.691228 -275.142706)
		)
		(stroke
			(width 0)
			(type solid)
		)
		(fill yes)
		(layer "In6.Cu")
		(net "M_E_CPU1_SB_DQ<1>")
	)
	(gr_poly
		(pts
			(xy 80.691228 -274.694396) (xy 80.691228 -274.649946) (xy 80.491076 -274.649946) (xy 80.491076 -274.694396)
			(xy 80.591152 -274.794472)
		)
		(stroke
			(width 0)
			(type solid)
		)
		(fill yes)
		(layer "In6.Cu")
		(net "M_E_CPU1_SB_DQ<2>")
	)
	(gr_poly
		(pts
			(xy 80.691228 -273.478244) (xy 80.591152 -273.378168) (xy 80.491076 -273.478244) (xy 80.491076 -273.522694)
			(xy 80.691228 -273.522694)
		)
		(stroke
			(width 0)
			(type solid)
		)
		(fill yes)
		(layer "In6.Cu")
		(net "M_E_CPU1_SB_CB<1>")
	)
	(gr_poly
		(pts
			(xy 80.691228 -273.074384) (xy 80.691228 -273.029934) (xy 80.491076 -273.029934) (xy 80.491076 -273.074384)
			(xy 80.591152 -273.17446)
		)
		(stroke
			(width 0)
			(type solid)
		)
		(fill yes)
		(layer "In6.Cu")
		(net "M_E_CPU1_SB_CB<2>")
	)
	(gr_poly
		(pts
			(xy 80.691228 -271.857978) (xy 80.591152 -271.758156) (xy 80.491076 -271.857978) (xy 80.491076 -271.90573)
			(xy 80.691228 -271.90573)
		)
		(stroke
			(width 0)
			(type solid)
		)
		(fill yes)
		(layer "In6.Cu")
		(net "M_E_CPU1_SB_DQS_DN<4>")
	)
	(gr_poly
		(pts
			(xy 80.691228 -271.454626) (xy 80.691228 -271.406874) (xy 80.491076 -271.406874) (xy 80.491076 -271.454626)
			(xy 80.591152 -271.554448)
		)
		(stroke
			(width 0)
			(type solid)
		)
		(fill yes)
		(layer "In6.Cu")
		(net "M_E_CPU1_SB_DQS_DN<9>")
	)
	(gr_poly
		(pts
			(xy 80.691228 -270.23822) (xy 80.591152 -270.138144) (xy 80.491076 -270.23822) (xy 80.491076 -270.28267)
			(xy 80.691228 -270.28267)
		)
		(stroke
			(width 0)
			(type solid)
		)
		(fill yes)
		(layer "In6.Cu")
		(net "M_E_CPU1_SB_CB<5>")
	)
	(gr_poly
		(pts
			(xy 80.691228 -269.83436) (xy 80.691228 -269.78991) (xy 80.491076 -269.78991) (xy 80.491076 -269.83436)
			(xy 80.591152 -269.934436)
		)
		(stroke
			(width 0)
			(type solid)
		)
		(fill yes)
		(layer "In6.Cu")
		(net "M_E_CPU1_SB_CB<6>")
	)
	(gr_poly
		(pts
			(xy 80.691228 -266.998196) (xy 80.591152 -266.89812) (xy 80.491076 -266.998196) (xy 80.491076 -267.042646)
			(xy 80.691228 -267.042646)
		)
		(stroke
			(width 0)
			(type solid)
		)
		(fill yes)
		(layer "In6.Cu")
		(net "M_E_CPU1_SA_RSP<0>")
	)
	(gr_poly
		(pts
			(xy 80.691228 -266.594336) (xy 80.691228 -266.549886) (xy 80.491076 -266.549886) (xy 80.491076 -266.594336)
			(xy 80.591152 -266.694412)
		)
		(stroke
			(width 0)
			(type solid)
		)
		(fill yes)
		(layer "In6.Cu")
		(net "M_E_CPU1_SB_CS_N<1>")
	)
	(gr_poly
		(pts
			(xy 80.691228 -264.974324) (xy 80.691228 -264.929874) (xy 80.491076 -264.929874) (xy 80.491076 -264.974324)
			(xy 80.591152 -265.0744)
		)
		(stroke
			(width 0)
			(type solid)
		)
		(fill yes)
		(layer "In6.Cu")
		(net "M_E_CPU1_SB_PAR")
	)
	(gr_poly
		(pts
			(xy 80.691228 -263.758172) (xy 80.591152 -263.658096) (xy 80.491076 -263.758172) (xy 80.491076 -263.802622)
			(xy 80.691228 -263.802622)
		)
		(stroke
			(width 0)
			(type solid)
		)
		(fill yes)
		(layer "In6.Cu")
		(net "M_E_CPU1_SB_CA<4>")
	)
	(gr_poly
		(pts
			(xy 80.691228 -263.354312) (xy 80.691228 -263.309862) (xy 80.491076 -263.309862) (xy 80.491076 -263.354312)
			(xy 80.591152 -263.454388)
		)
		(stroke
			(width 0)
			(type solid)
		)
		(fill yes)
		(layer "In6.Cu")
		(net "M_E_CPU1_SB_CA<3>")
	)
	(gr_poly
		(pts
			(xy 80.691228 -262.13816) (xy 80.591152 -262.038084) (xy 80.491076 -262.13816) (xy 80.491076 -262.18261)
			(xy 80.691228 -262.18261)
		)
		(stroke
			(width 0)
			(type solid)
		)
		(fill yes)
		(layer "In6.Cu")
		(net "M_E_CPU1_SB_CA<0>")
	)
	(gr_poly
		(pts
			(xy 80.73644 -293.068756) (xy 80.699864 -292.932104) (xy 80.66151 -292.909752) (xy 80.561434 -293.08298)
			(xy 80.599788 -293.105332)
		)
		(stroke
			(width 0)
			(type solid)
		)
		(fill yes)
		(layer "In6.Cu")
		(net "M_E_CPU1_SB_DQ<30>")
	)
	(gr_poly
		(pts
			(xy 80.80883 -256.439416) (xy 80.813148 -256.391918) (xy 80.613758 -256.374392) (xy 80.609694 -256.42189)
			(xy 80.700626 -256.530348)
		)
		(stroke
			(width 0)
			(type solid)
		)
		(fill yes)
		(layer "In6.Cu")
		(net "M_E_CPU1_CLK_DN<0>")
	)
	(gr_poly
		(pts
			(xy 80.80883 -246.719344) (xy 80.813148 -246.671846) (xy 80.613758 -246.65432) (xy 80.609694 -246.701818)
			(xy 80.700626 -246.810276)
		)
		(stroke
			(width 0)
			(type solid)
		)
		(fill yes)
		(layer "In6.Cu")
		(net "M_E_CPU1_SA_DQS_DN<4>")
	)
	(gr_poly
		(pts
			(xy 80.80883 -241.859308) (xy 80.813148 -241.81181) (xy 80.613758 -241.794284) (xy 80.609694 -241.841782)
			(xy 80.700626 -241.95024)
		)
		(stroke
			(width 0)
			(type solid)
		)
		(fill yes)
		(layer "In6.Cu")
		(net "M_E_CPU1_SA_DQS_DN<3>")
	)
	(gr_poly
		(pts
			(xy 80.80883 -236.999272) (xy 80.813148 -236.951774) (xy 80.613758 -236.934502) (xy 80.609694 -236.981746)
			(xy 80.700626 -237.090204)
		)
		(stroke
			(width 0)
			(type solid)
		)
		(fill yes)
		(layer "In6.Cu")
		(net "M_E_CPU1_SA_DQS_DN<2>")
	)
	(gr_poly
		(pts
			(xy 80.80883 -232.139236) (xy 80.813148 -232.091738) (xy 80.613758 -232.074466) (xy 80.609694 -232.12171)
			(xy 80.700626 -232.230168)
		)
		(stroke
			(width 0)
			(type solid)
		)
		(fill yes)
		(layer "In6.Cu")
		(net "M_E_CPU1_SA_DQS_DN<1>")
	)
	(gr_poly
		(pts
			(xy 80.816958 -296.17035) (xy 80.757268 -296.04208) (xy 80.715612 -296.02684) (xy 80.647032 -296.2148)
			(xy 80.688942 -296.23004)
		)
		(stroke
			(width 0)
			(type solid)
		)
		(fill yes)
		(layer "In6.Cu")
		(net "M_E_CPU1_SB_DQ<31>")
	)
	(gr_poly
		(pts
			(xy 80.819498 -227.280216) (xy 80.823562 -227.232718) (xy 80.624426 -227.215192) (xy 80.620362 -227.26269)
			(xy 80.711294 -227.371148)
		)
		(stroke
			(width 0)
			(type solid)
		)
		(fill yes)
		(layer "In6.Cu")
		(net "M_E_CPU1_SA_DQS_DN<0>")
	)
	(gr_poly
		(pts
			(xy 80.82153 -254.820166) (xy 80.825594 -254.775716) (xy 80.626204 -254.758444) (xy 80.622394 -254.80264)
			(xy 80.713326 -254.911098)
		)
		(stroke
			(width 0)
			(type solid)
		)
		(fill yes)
		(layer "In6.Cu")
		(net "M_E_CPU1_SA_CA<5>")
	)
	(gr_poly
		(pts
			(xy 80.82153 -253.200154) (xy 80.825594 -253.155704) (xy 80.626204 -253.138432) (xy 80.622394 -253.182628)
			(xy 80.713326 -253.291086)
		)
		(stroke
			(width 0)
			(type solid)
		)
		(fill yes)
		(layer "In6.Cu")
		(net "M_E_CPU1_SA_CA<1>")
	)
	(gr_poly
		(pts
			(xy 80.82153 -251.580142) (xy 80.825594 -251.535692) (xy 80.626204 -251.51842) (xy 80.622394 -251.562616)
			(xy 80.713326 -251.671074)
		)
		(stroke
			(width 0)
			(type solid)
		)
		(fill yes)
		(layer "In6.Cu")
		(net "M_E_CPU1_SA_CS_N<0>")
	)
	(gr_poly
		(pts
			(xy 80.82153 -248.340118) (xy 80.825594 -248.295668) (xy 80.626204 -248.278396) (xy 80.622394 -248.322592)
			(xy 80.713326 -248.43105)
		)
		(stroke
			(width 0)
			(type solid)
		)
		(fill yes)
		(layer "In6.Cu")
		(net "M_E_CPU1_SA_CB<6>")
	)
	(gr_poly
		(pts
			(xy 80.82153 -245.100094) (xy 80.825594 -245.055644) (xy 80.626204 -245.038372) (xy 80.622394 -245.082568)
			(xy 80.713326 -245.191026)
		)
		(stroke
			(width 0)
			(type solid)
		)
		(fill yes)
		(layer "In6.Cu")
		(net "M_E_CPU1_SA_CB<2>")
	)
	(gr_poly
		(pts
			(xy 80.82153 -243.480082) (xy 80.825594 -243.435632) (xy 80.626204 -243.41836) (xy 80.622394 -243.462556)
			(xy 80.713326 -243.571014)
		)
		(stroke
			(width 0)
			(type solid)
		)
		(fill yes)
		(layer "In6.Cu")
		(net "M_E_CPU1_SA_DQ<30>")
	)
	(gr_poly
		(pts
			(xy 80.82153 -240.240058) (xy 80.825594 -240.195608) (xy 80.626204 -240.178336) (xy 80.622394 -240.222532)
			(xy 80.713326 -240.33099)
		)
		(stroke
			(width 0)
			(type solid)
		)
		(fill yes)
		(layer "In6.Cu")
		(net "M_E_CPU1_SA_DQ<26>")
	)
	(gr_poly
		(pts
			(xy 80.82153 -238.620046) (xy 80.825594 -238.575596) (xy 80.626204 -238.558324) (xy 80.622394 -238.60252)
			(xy 80.713326 -238.710978)
		)
		(stroke
			(width 0)
			(type solid)
		)
		(fill yes)
		(layer "In6.Cu")
		(net "M_E_CPU1_SA_DQ<22>")
	)
	(gr_poly
		(pts
			(xy 80.82153 -235.380022) (xy 80.825594 -235.335572) (xy 80.626204 -235.3183) (xy 80.622394 -235.362496)
			(xy 80.713326 -235.470954)
		)
		(stroke
			(width 0)
			(type solid)
		)
		(fill yes)
		(layer "In6.Cu")
		(net "M_E_CPU1_SA_DQ<18>")
	)
	(gr_poly
		(pts
			(xy 80.82153 -233.76001) (xy 80.825594 -233.71556) (xy 80.626204 -233.698288) (xy 80.622394 -233.742484)
			(xy 80.713326 -233.850942)
		)
		(stroke
			(width 0)
			(type solid)
		)
		(fill yes)
		(layer "In6.Cu")
		(net "M_E_CPU1_SA_DQ<14>")
	)
	(gr_poly
		(pts
			(xy 80.82153 -230.52024) (xy 80.825594 -230.47579) (xy 80.626204 -230.458518) (xy 80.622394 -230.502714)
			(xy 80.713326 -230.611172)
		)
		(stroke
			(width 0)
			(type solid)
		)
		(fill yes)
		(layer "In6.Cu")
		(net "M_E_CPU1_SA_DQ<10>")
	)
	(gr_poly
		(pts
			(xy 80.82153 -228.900228) (xy 80.825594 -228.855778) (xy 80.626204 -228.838506) (xy 80.622394 -228.882702)
			(xy 80.713326 -228.99116)
		)
		(stroke
			(width 0)
			(type solid)
		)
		(fill yes)
		(layer "In6.Cu")
		(net "M_E_CPU1_SA_DQ<6>")
	)
	(gr_poly
		(pts
			(xy 80.82153 -225.660204) (xy 80.825594 -225.615754) (xy 80.626204 -225.598482) (xy 80.622394 -225.642678)
			(xy 80.713326 -225.751136)
		)
		(stroke
			(width 0)
			(type solid)
		)
		(fill yes)
		(layer "In6.Cu")
		(net "M_E_CPU1_SA_DQ<2>")
	)
	(gr_poly
		(pts
			(xy 80.861154 -255.216406) (xy 80.761078 -255.11633) (xy 80.661002 -255.216406) (xy 80.661002 -255.260856)
			(xy 80.861154 -255.260856)
		)
		(stroke
			(width 0)
			(type solid)
		)
		(fill yes)
		(layer "In6.Cu")
		(net "M_E_CPU1_SA_CA<6>")
	)
	(gr_poly
		(pts
			(xy 80.861154 -253.596394) (xy 80.761078 -253.496318) (xy 80.661002 -253.596394) (xy 80.661002 -253.640844)
			(xy 80.861154 -253.640844)
		)
		(stroke
			(width 0)
			(type solid)
		)
		(fill yes)
		(layer "In6.Cu")
		(net "M_E_CPU1_SA_CA<2>")
	)
	(gr_poly
		(pts
			(xy 80.861154 -250.35637) (xy 80.761078 -250.256294) (xy 80.661002 -250.35637) (xy 80.661002 -250.40082)
			(xy 80.861154 -250.40082)
		)
		(stroke
			(width 0)
			(type solid)
		)
		(fill yes)
		(layer "In6.Cu")
		(net "M_E_CPU1_ALERT_R_N")
	)
	(gr_poly
		(pts
			(xy 80.861154 -248.736358) (xy 80.761078 -248.636282) (xy 80.661002 -248.736358) (xy 80.661002 -248.780808)
			(xy 80.861154 -248.780808)
		)
		(stroke
			(width 0)
			(type solid)
		)
		(fill yes)
		(layer "In6.Cu")
		(net "M_E_CPU1_SA_CB<5>")
	)
	(gr_poly
		(pts
			(xy 80.861154 -247.116092) (xy 80.761078 -247.01627) (xy 80.661002 -247.116092) (xy 80.661002 -247.163844)
			(xy 80.861154 -247.163844)
		)
		(stroke
			(width 0)
			(type solid)
		)
		(fill yes)
		(layer "In6.Cu")
		(net "M_E_CPU1_SA_DQS_DN<9>")
	)
	(gr_poly
		(pts
			(xy 80.861154 -245.496334) (xy 80.761078 -245.396258) (xy 80.661002 -245.496334) (xy 80.661002 -245.540784)
			(xy 80.861154 -245.540784)
		)
		(stroke
			(width 0)
			(type solid)
		)
		(fill yes)
		(layer "In6.Cu")
		(net "M_E_CPU1_SA_CB<1>")
	)
	(gr_poly
		(pts
			(xy 80.861154 -243.876322) (xy 80.761078 -243.776246) (xy 80.661002 -243.876322) (xy 80.661002 -243.920772)
			(xy 80.861154 -243.920772)
		)
		(stroke
			(width 0)
			(type solid)
		)
		(fill yes)
		(layer "In6.Cu")
		(net "M_E_CPU1_SA_DQ<29>")
	)
	(gr_poly
		(pts
			(xy 80.861154 -242.256056) (xy 80.761078 -242.156234) (xy 80.661002 -242.256056) (xy 80.661002 -242.303808)
			(xy 80.861154 -242.303808)
		)
		(stroke
			(width 0)
			(type solid)
		)
		(fill yes)
		(layer "In6.Cu")
		(net "M_E_CPU1_SA_DQS_DN<8>")
	)
	(gr_poly
		(pts
			(xy 80.861154 -240.636298) (xy 80.761078 -240.536222) (xy 80.661002 -240.636298) (xy 80.661002 -240.680748)
			(xy 80.861154 -240.680748)
		)
		(stroke
			(width 0)
			(type solid)
		)
		(fill yes)
		(layer "In6.Cu")
		(net "M_E_CPU1_SA_DQ<25>")
	)
	(gr_poly
		(pts
			(xy 80.861154 -239.016286) (xy 80.761078 -238.91621) (xy 80.661002 -239.016286) (xy 80.661002 -239.060736)
			(xy 80.861154 -239.060736)
		)
		(stroke
			(width 0)
			(type solid)
		)
		(fill yes)
		(layer "In6.Cu")
		(net "M_E_CPU1_SA_DQ<21>")
	)
	(gr_poly
		(pts
			(xy 80.861154 -237.39602) (xy 80.761078 -237.296198) (xy 80.661002 -237.39602) (xy 80.661002 -237.443772)
			(xy 80.861154 -237.443772)
		)
		(stroke
			(width 0)
			(type solid)
		)
		(fill yes)
		(layer "In6.Cu")
		(net "M_E_CPU1_SA_DQS_DN<7>")
	)
	(gr_poly
		(pts
			(xy 80.861154 -235.776262) (xy 80.761078 -235.676186) (xy 80.661002 -235.776262) (xy 80.661002 -235.820712)
			(xy 80.861154 -235.820712)
		)
		(stroke
			(width 0)
			(type solid)
		)
		(fill yes)
		(layer "In6.Cu")
		(net "M_E_CPU1_SA_DQ<17>")
	)
	(gr_poly
		(pts
			(xy 80.861154 -234.15625) (xy 80.761078 -234.056174) (xy 80.661002 -234.15625) (xy 80.661002 -234.2007)
			(xy 80.861154 -234.2007)
		)
		(stroke
			(width 0)
			(type solid)
		)
		(fill yes)
		(layer "In6.Cu")
		(net "M_E_CPU1_SA_DQ<13>")
	)
	(gr_poly
		(pts
			(xy 80.861154 -232.535984) (xy 80.761078 -232.436162) (xy 80.661002 -232.535984) (xy 80.661002 -232.583736)
			(xy 80.861154 -232.583736)
		)
		(stroke
			(width 0)
			(type solid)
		)
		(fill yes)
		(layer "In6.Cu")
		(net "M_E_CPU1_SA_DQS_DN<6>")
	)
	(gr_poly
		(pts
			(xy 80.861154 -230.916226) (xy 80.761078 -230.81615) (xy 80.661002 -230.916226) (xy 80.661002 -230.960676)
			(xy 80.861154 -230.960676)
		)
		(stroke
			(width 0)
			(type solid)
		)
		(fill yes)
		(layer "In6.Cu")
		(net "M_E_CPU1_SA_DQ<9>")
	)
	(gr_poly
		(pts
			(xy 80.861154 -229.296214) (xy 80.761078 -229.196138) (xy 80.661002 -229.296214) (xy 80.661002 -229.340664)
			(xy 80.861154 -229.340664)
		)
		(stroke
			(width 0)
			(type solid)
		)
		(fill yes)
		(layer "In6.Cu")
		(net "M_E_CPU1_SA_DQ<5>")
	)
	(gr_poly
		(pts
			(xy 80.861154 -227.676202) (xy 80.761078 -227.57638) (xy 80.661002 -227.676202) (xy 80.661002 -227.723954)
			(xy 80.861154 -227.723954)
		)
		(stroke
			(width 0)
			(type solid)
		)
		(fill yes)
		(layer "In6.Cu")
		(net "M_E_CPU1_SA_DQS_DN<5>")
	)
	(gr_poly
		(pts
			(xy 80.861154 -226.056444) (xy 80.761078 -225.956368) (xy 80.661002 -226.056444) (xy 80.661002 -226.100894)
			(xy 80.861154 -226.100894)
		)
		(stroke
			(width 0)
			(type solid)
		)
		(fill yes)
		(layer "In6.Cu")
		(net "M_E_CPU1_SA_DQ<1>")
	)
	(gr_poly
		(pts
			(xy 80.879696 -224.035366) (xy 80.916272 -223.898714) (xy 80.77962 -223.862138) (xy 80.741012 -223.884236)
			(xy 80.841088 -224.057464)
		)
		(stroke
			(width 0)
			(type solid)
		)
		(fill yes)
		(layer "In6.Cu")
		(net "M_E_CPU1_SA_DQ<0>")
	)
	(gr_poly
		(pts
			(xy 80.916526 -224.569782) (xy 80.87995 -224.43313) (xy 80.841342 -224.410778) (xy 80.74152 -224.584006)
			(xy 80.779874 -224.606358)
		)
		(stroke
			(width 0)
			(type solid)
		)
		(fill yes)
		(layer "In6.Cu")
		(net "M_E_CPU1_SA_DQ<0>")
	)
	(gr_poly
		(pts
			(xy 81.09077 -293.15918) (xy 81.052416 -293.136828) (xy 80.915764 -293.173404) (xy 80.95234 -293.310056)
			(xy 80.990948 -293.332408)
		)
		(stroke
			(width 0)
			(type solid)
		)
		(fill yes)
		(layer "In6.Cu")
		(net "M_E_CPU1_SB_DQ<29>")
	)
	(gr_poly
		(pts
			(xy 81.113122 -290.528756) (xy 81.108804 -290.481258) (xy 81.0006 -290.390326) (xy 80.909668 -290.498784)
			(xy 80.913732 -290.546028)
		)
		(stroke
			(width 0)
			(type solid)
		)
		(fill yes)
		(layer "In6.Cu")
		(net "M_E_CPU1_SB_DQS_DP<3>")
	)
	(gr_poly
		(pts
			(xy 81.113122 -285.668974) (xy 81.108804 -285.621476) (xy 81.0006 -285.530544) (xy 80.909668 -285.639002)
			(xy 80.913732 -285.6865)
		)
		(stroke
			(width 0)
			(type solid)
		)
		(fill yes)
		(layer "In6.Cu")
		(net "M_E_CPU1_SB_DQS_DP<2>")
	)
	(gr_poly
		(pts
			(xy 81.113122 -275.948902) (xy 81.108804 -275.901404) (xy 81.0006 -275.810472) (xy 80.909668 -275.91893)
			(xy 80.913732 -275.966428)
		)
		(stroke
			(width 0)
			(type solid)
		)
		(fill yes)
		(layer "In6.Cu")
		(net "M_E_CPU1_SB_DQS_DP<0>")
	)
	(gr_poly
		(pts
			(xy 81.113122 -271.088866) (xy 81.108804 -271.041368) (xy 81.0006 -270.950436) (xy 80.909668 -271.058894)
			(xy 80.913732 -271.106392)
		)
		(stroke
			(width 0)
			(type solid)
		)
		(fill yes)
		(layer "In6.Cu")
		(net "M_E_CPU1_SB_DQS_DP<9>")
	)
	(gr_poly
		(pts
			(xy 81.123028 -267.838936) (xy 81.118456 -267.788136) (xy 81.010252 -267.697204) (xy 80.91932 -267.805662)
			(xy 80.923638 -267.856208)
		)
		(stroke
			(width 0)
			(type solid)
		)
		(fill yes)
		(layer "In6.Cu")
		(net "M_E_CPU1_SB_RSP<0>")
	)
	(gr_poly
		(pts
			(xy 81.12379 -280.808176) (xy 81.119472 -280.760678) (xy 81.011268 -280.669746) (xy 80.920336 -280.778204)
			(xy 80.9244 -280.825448)
		)
		(stroke
			(width 0)
			(type solid)
		)
		(fill yes)
		(layer "In6.Cu")
		(net "M_E_CPU1_SB_DQS_DP<1>")
	)
	(gr_poly
		(pts
			(xy 81.125314 -288.904934) (xy 81.121504 -288.860484) (xy 81.0133 -288.769552) (xy 80.922368 -288.87801)
			(xy 80.926178 -288.922206)
		)
		(stroke
			(width 0)
			(type solid)
		)
		(fill yes)
		(layer "In6.Cu")
		(net "M_E_CPU1_SB_DQ<24>")
	)
	(gr_poly
		(pts
			(xy 81.125314 -287.284922) (xy 81.121504 -287.240472) (xy 81.0133 -287.14954) (xy 80.922368 -287.257998)
			(xy 80.926178 -287.302194)
		)
		(stroke
			(width 0)
			(type solid)
		)
		(fill yes)
		(layer "In6.Cu")
		(net "M_E_CPU1_SB_DQ<20>")
	)
	(gr_poly
		(pts
			(xy 81.125314 -284.045152) (xy 81.121504 -284.000702) (xy 81.0133 -283.90977) (xy 80.922368 -284.018228)
			(xy 80.926178 -284.062424)
		)
		(stroke
			(width 0)
			(type solid)
		)
		(fill yes)
		(layer "In6.Cu")
		(net "M_E_CPU1_SB_DQ<16>")
	)
	(gr_poly
		(pts
			(xy 81.125314 -282.42514) (xy 81.121504 -282.38069) (xy 81.0133 -282.289758) (xy 80.922368 -282.398216)
			(xy 80.926178 -282.442412)
		)
		(stroke
			(width 0)
			(type solid)
		)
		(fill yes)
		(layer "In6.Cu")
		(net "M_E_CPU1_SB_DQ<12>")
	)
	(gr_poly
		(pts
			(xy 81.125314 -279.185116) (xy 81.121504 -279.140666) (xy 81.0133 -279.049734) (xy 80.922368 -279.158192)
			(xy 80.926178 -279.202388)
		)
		(stroke
			(width 0)
			(type solid)
		)
		(fill yes)
		(layer "In6.Cu")
		(net "M_E_CPU1_SB_DQ<8>")
	)
	(gr_poly
		(pts
			(xy 81.125314 -277.565104) (xy 81.121504 -277.520654) (xy 81.0133 -277.429722) (xy 80.922368 -277.53818)
			(xy 80.926178 -277.582376)
		)
		(stroke
			(width 0)
			(type solid)
		)
		(fill yes)
		(layer "In6.Cu")
		(net "M_E_CPU1_SB_DQ<4>")
	)
	(gr_poly
		(pts
			(xy 81.125314 -274.32508) (xy 81.121504 -274.28063) (xy 81.0133 -274.189698) (xy 80.922368 -274.298156)
			(xy 80.926178 -274.342352)
		)
		(stroke
			(width 0)
			(type solid)
		)
		(fill yes)
		(layer "In6.Cu")
		(net "M_E_CPU1_SB_DQ<0>")
	)
	(gr_poly
		(pts
			(xy 81.125314 -272.705068) (xy 81.121504 -272.660618) (xy 81.0133 -272.569686) (xy 80.922368 -272.678144)
			(xy 80.926178 -272.72234)
		)
		(stroke
			(width 0)
			(type solid)
		)
		(fill yes)
		(layer "In6.Cu")
		(net "M_E_CPU1_SB_CB<0>")
	)
	(gr_poly
		(pts
			(xy 81.125314 -269.465044) (xy 81.121504 -269.420594) (xy 81.0133 -269.329662) (xy 80.922368 -269.43812)
			(xy 80.926178 -269.482316)
		)
		(stroke
			(width 0)
			(type solid)
		)
		(fill yes)
		(layer "In6.Cu")
		(net "M_E_CPU1_SB_CB<4>")
	)
	(gr_poly
		(pts
			(xy 81.125314 -264.605008) (xy 81.121504 -264.560558) (xy 81.0133 -264.469626) (xy 80.922368 -264.578084)
			(xy 80.926178 -264.62228)
		)
		(stroke
			(width 0)
			(type solid)
		)
		(fill yes)
		(layer "In6.Cu")
		(net "M_E_CPU1_SB_CA<6>")
	)
	(gr_poly
		(pts
			(xy 81.125314 -262.984996) (xy 81.121504 -262.940546) (xy 81.0133 -262.849614) (xy 80.922368 -262.958072)
			(xy 80.926178 -263.002268)
		)
		(stroke
			(width 0)
			(type solid)
		)
		(fill yes)
		(layer "In6.Cu")
		(net "M_E_CPU1_SB_CA<2>")
	)
	(gr_poly
		(pts
			(xy 81.125822 -292.109144) (xy 81.025746 -292.009068) (xy 80.92567 -292.109144) (xy 80.92567 -292.153594)
			(xy 81.125822 -292.153594)
		)
		(stroke
			(width 0)
			(type solid)
		)
		(fill yes)
		(layer "In6.Cu")
		(net "M_E_CPU1_SB_DQ<28>")
	)
	(gr_poly
		(pts
			(xy 81.161128 -291.704522) (xy 81.161128 -291.65677) (xy 80.960976 -291.65677) (xy 80.960976 -291.704522)
			(xy 81.061052 -291.804344)
		)
		(stroke
			(width 0)
			(type solid)
		)
		(fill yes)
		(layer "In6.Cu")
		(net "M_E_CPU1_SB_DQS_DP<8>")
	)
	(gr_poly
		(pts
			(xy 81.161128 -290.084256) (xy 81.161128 -290.039806) (xy 80.960976 -290.039806) (xy 80.960976 -290.084256)
			(xy 81.061052 -290.184332)
		)
		(stroke
			(width 0)
			(type solid)
		)
		(fill yes)
		(layer "In6.Cu")
		(net "M_E_CPU1_SB_DQ<27>")
	)
	(gr_poly
		(pts
			(xy 81.161128 -288.464498) (xy 81.161128 -288.420048) (xy 80.960976 -288.420048) (xy 80.960976 -288.464498)
			(xy 81.061052 -288.564574)
		)
		(stroke
			(width 0)
			(type solid)
		)
		(fill yes)
		(layer "In6.Cu")
		(net "M_E_CPU1_SB_DQ<23>")
	)
	(gr_poly
		(pts
			(xy 81.161128 -286.844486) (xy 81.161128 -286.796734) (xy 80.960976 -286.796734) (xy 80.960976 -286.844486)
			(xy 81.061052 -286.944562)
		)
		(stroke
			(width 0)
			(type solid)
		)
		(fill yes)
		(layer "In6.Cu")
		(net "M_E_CPU1_SB_DQS_DP<7>")
	)
	(gr_poly
		(pts
			(xy 81.161128 -285.224474) (xy 81.161128 -285.180024) (xy 80.960976 -285.180024) (xy 80.960976 -285.224474)
			(xy 81.061052 -285.32455)
		)
		(stroke
			(width 0)
			(type solid)
		)
		(fill yes)
		(layer "In6.Cu")
		(net "M_E_CPU1_SB_DQ<19>")
	)
	(gr_poly
		(pts
			(xy 81.161128 -283.604462) (xy 81.161128 -283.560012) (xy 80.960976 -283.560012) (xy 80.960976 -283.604462)
			(xy 81.061052 -283.704538)
		)
		(stroke
			(width 0)
			(type solid)
		)
		(fill yes)
		(layer "In6.Cu")
		(net "M_E_CPU1_SB_DQ<15>")
	)
	(gr_poly
		(pts
			(xy 81.161128 -281.984704) (xy 81.161128 -281.936952) (xy 80.960976 -281.936952) (xy 80.960976 -281.984704)
			(xy 81.061052 -282.084526)
		)
		(stroke
			(width 0)
			(type solid)
		)
		(fill yes)
		(layer "In6.Cu")
		(net "M_E_CPU1_SB_DQS_DP<6>")
	)
	(gr_poly
		(pts
			(xy 81.161128 -280.364438) (xy 81.161128 -280.319988) (xy 80.960976 -280.319988) (xy 80.960976 -280.364438)
			(xy 81.061052 -280.464514)
		)
		(stroke
			(width 0)
			(type solid)
		)
		(fill yes)
		(layer "In6.Cu")
		(net "M_E_CPU1_SB_DQ<11>")
	)
	(gr_poly
		(pts
			(xy 81.161128 -278.744426) (xy 81.161128 -278.699976) (xy 80.960976 -278.699976) (xy 80.960976 -278.744426)
			(xy 81.061052 -278.844502)
		)
		(stroke
			(width 0)
			(type solid)
		)
		(fill yes)
		(layer "In6.Cu")
		(net "M_E_CPU1_SB_DQ<7>")
	)
	(gr_poly
		(pts
			(xy 81.161128 -277.124668) (xy 81.161128 -277.076916) (xy 80.960976 -277.076916) (xy 80.960976 -277.124668)
			(xy 81.061052 -277.22449)
		)
		(stroke
			(width 0)
			(type solid)
		)
		(fill yes)
		(layer "In6.Cu")
		(net "M_E_CPU1_SB_DQS_DP<5>")
	)
	(gr_poly
		(pts
			(xy 81.161128 -275.504402) (xy 81.161128 -275.459952) (xy 80.960976 -275.459952) (xy 80.960976 -275.504402)
			(xy 81.061052 -275.604478)
		)
		(stroke
			(width 0)
			(type solid)
		)
		(fill yes)
		(layer "In6.Cu")
		(net "M_E_CPU1_SB_DQ<3>")
	)
	(gr_poly
		(pts
			(xy 81.161128 -273.88439) (xy 81.161128 -273.83994) (xy 80.960976 -273.83994) (xy 80.960976 -273.88439)
			(xy 81.061052 -273.984466)
		)
		(stroke
			(width 0)
			(type solid)
		)
		(fill yes)
		(layer "In6.Cu")
		(net "M_E_CPU1_SB_CB<3>")
	)
	(gr_poly
		(pts
			(xy 81.161128 -272.264632) (xy 81.161128 -272.21688) (xy 80.960976 -272.21688) (xy 80.960976 -272.264632)
			(xy 81.061052 -272.364454)
		)
		(stroke
			(width 0)
			(type solid)
		)
		(fill yes)
		(layer "In6.Cu")
		(net "M_E_CPU1_SB_DQS_DP<4>")
	)
	(gr_poly
		(pts
			(xy 81.161128 -270.644366) (xy 81.161128 -270.599916) (xy 80.960976 -270.599916) (xy 80.960976 -270.644366)
			(xy 81.061052 -270.744442)
		)
		(stroke
			(width 0)
			(type solid)
		)
		(fill yes)
		(layer "In6.Cu")
		(net "M_E_CPU1_SB_CB<7>")
	)
	(gr_poly
		(pts
			(xy 81.161128 -265.78433) (xy 81.161128 -265.73988) (xy 80.960976 -265.73988) (xy 80.960976 -265.78433)
			(xy 81.061052 -265.884406)
		)
		(stroke
			(width 0)
			(type solid)
		)
		(fill yes)
		(layer "In6.Cu")
		(net "M_E_CPU1_SB_CS_N<0>")
	)
	(gr_poly
		(pts
			(xy 81.161128 -264.164318) (xy 81.161128 -264.119868) (xy 80.960976 -264.119868) (xy 80.960976 -264.164318)
			(xy 81.061052 -264.264394)
		)
		(stroke
			(width 0)
			(type solid)
		)
		(fill yes)
		(layer "In6.Cu")
		(net "M_E_CPU1_SB_CA<5>")
	)
	(gr_poly
		(pts
			(xy 81.161128 -262.544306) (xy 81.161128 -262.499856) (xy 80.960976 -262.499856) (xy 80.960976 -262.544306)
			(xy 81.061052 -262.644382)
		)
		(stroke
			(width 0)
			(type solid)
		)
		(fill yes)
		(layer "In6.Cu")
		(net "M_E_CPU1_SB_CA<1>")
	)
	(gr_poly
		(pts
			(xy 81.258156 -295.386506) (xy 81.198466 -295.258236) (xy 81.15681 -295.242996) (xy 81.08823 -295.430956)
			(xy 81.13014 -295.446196)
		)
		(stroke
			(width 0)
			(type solid)
		)
		(fill yes)
		(layer "In6.Cu")
		(net "M_E_CPU1_SB_DQ<31>")
	)
	(gr_poly
		(pts
			(xy 81.331054 -255.622552) (xy 81.331054 -255.578102) (xy 81.130902 -255.578102) (xy 81.130902 -255.622552)
			(xy 81.230978 -255.722628)
		)
		(stroke
			(width 0)
			(type solid)
		)
		(fill yes)
		(layer "In6.Cu")
		(net "M_E_CPU1_SA_PAR")
	)
	(gr_poly
		(pts
			(xy 81.331054 -254.00254) (xy 81.331054 -253.95809) (xy 81.130902 -253.95809) (xy 81.130902 -254.00254)
			(xy 81.230978 -254.102616)
		)
		(stroke
			(width 0)
			(type solid)
		)
		(fill yes)
		(layer "In6.Cu")
		(net "M_E_CPU1_SA_CA<3>")
	)
	(gr_poly
		(pts
			(xy 81.331054 -252.382528) (xy 81.331054 -252.338078) (xy 81.130902 -252.338078) (xy 81.130902 -252.382528)
			(xy 81.230978 -252.482604)
		)
		(stroke
			(width 0)
			(type solid)
		)
		(fill yes)
		(layer "In6.Cu")
		(net "M_E_CPU1_SA_CS_N<1>")
	)
	(gr_poly
		(pts
			(xy 81.331054 -250.762516) (xy 81.331054 -250.718066) (xy 81.130902 -250.718066) (xy 81.130902 -250.762516)
			(xy 81.230978 -250.862592)
		)
		(stroke
			(width 0)
			(type solid)
		)
		(fill yes)
		(layer "In6.Cu")
		(net "M_E_CPU1_RESET_N")
	)
	(gr_poly
		(pts
			(xy 81.331054 -249.142504) (xy 81.331054 -249.098054) (xy 81.130902 -249.098054) (xy 81.130902 -249.142504)
			(xy 81.230978 -249.24258)
		)
		(stroke
			(width 0)
			(type solid)
		)
		(fill yes)
		(layer "In6.Cu")
		(net "M_E_CPU1_SA_CB<7>")
	)
	(gr_poly
		(pts
			(xy 81.331054 -247.522746) (xy 81.331054 -247.474994) (xy 81.130902 -247.474994) (xy 81.130902 -247.522746)
			(xy 81.230978 -247.622568)
		)
		(stroke
			(width 0)
			(type solid)
		)
		(fill yes)
		(layer "In6.Cu")
		(net "M_E_CPU1_SA_DQS_DP<9>")
	)
	(gr_poly
		(pts
			(xy 81.331054 -245.90248) (xy 81.331054 -245.85803) (xy 81.130902 -245.85803) (xy 81.130902 -245.90248)
			(xy 81.230978 -246.002556)
		)
		(stroke
			(width 0)
			(type solid)
		)
		(fill yes)
		(layer "In6.Cu")
		(net "M_E_CPU1_SA_CB<3>")
	)
	(gr_poly
		(pts
			(xy 81.331054 -244.282468) (xy 81.331054 -244.238018) (xy 81.130902 -244.238018) (xy 81.130902 -244.282468)
			(xy 81.230978 -244.382544)
		)
		(stroke
			(width 0)
			(type solid)
		)
		(fill yes)
		(layer "In6.Cu")
		(net "M_E_CPU1_SA_DQ<31>")
	)
	(gr_poly
		(pts
			(xy 81.331054 -242.66271) (xy 81.331054 -242.614958) (xy 81.130902 -242.614958) (xy 81.130902 -242.66271)
			(xy 81.230978 -242.762532)
		)
		(stroke
			(width 0)
			(type solid)
		)
		(fill yes)
		(layer "In6.Cu")
		(net "M_E_CPU1_SA_DQS_DP<8>")
	)
	(gr_poly
		(pts
			(xy 81.331054 -241.042444) (xy 81.331054 -240.997994) (xy 81.130902 -240.997994) (xy 81.130902 -241.042444)
			(xy 81.230978 -241.14252)
		)
		(stroke
			(width 0)
			(type solid)
		)
		(fill yes)
		(layer "In6.Cu")
		(net "M_E_CPU1_SA_DQ<27>")
	)
	(gr_poly
		(pts
			(xy 81.331054 -239.422432) (xy 81.331054 -239.377982) (xy 81.130902 -239.377982) (xy 81.130902 -239.422432)
			(xy 81.230978 -239.522508)
		)
		(stroke
			(width 0)
			(type solid)
		)
		(fill yes)
		(layer "In6.Cu")
		(net "M_E_CPU1_SA_DQ<23>")
	)
	(gr_poly
		(pts
			(xy 81.331054 -237.802674) (xy 81.331054 -237.754922) (xy 81.130902 -237.754922) (xy 81.130902 -237.802674)
			(xy 81.230978 -237.902496)
		)
		(stroke
			(width 0)
			(type solid)
		)
		(fill yes)
		(layer "In6.Cu")
		(net "M_E_CPU1_SA_DQS_DP<7>")
	)
	(gr_poly
		(pts
			(xy 81.331054 -236.182408) (xy 81.331054 -236.137958) (xy 81.130902 -236.137958) (xy 81.130902 -236.182408)
			(xy 81.230978 -236.282484)
		)
		(stroke
			(width 0)
			(type solid)
		)
		(fill yes)
		(layer "In6.Cu")
		(net "M_E_CPU1_SA_DQ<19>")
	)
	(gr_poly
		(pts
			(xy 81.331054 -234.562396) (xy 81.331054 -234.517946) (xy 81.130902 -234.517946) (xy 81.130902 -234.562396)
			(xy 81.230978 -234.662472)
		)
		(stroke
			(width 0)
			(type solid)
		)
		(fill yes)
		(layer "In6.Cu")
		(net "M_E_CPU1_SA_DQ<15>")
	)
	(gr_poly
		(pts
			(xy 81.331054 -232.942638) (xy 81.331054 -232.894886) (xy 81.130902 -232.894886) (xy 81.130902 -232.942638)
			(xy 81.230978 -233.04246)
		)
		(stroke
			(width 0)
			(type solid)
		)
		(fill yes)
		(layer "In6.Cu")
		(net "M_E_CPU1_SA_DQS_DP<6>")
	)
	(gr_poly
		(pts
			(xy 81.331054 -231.322626) (xy 81.331054 -231.278176) (xy 81.130902 -231.278176) (xy 81.130902 -231.322626)
			(xy 81.230978 -231.422702)
		)
		(stroke
			(width 0)
			(type solid)
		)
		(fill yes)
		(layer "In6.Cu")
		(net "M_E_CPU1_SA_DQ<11>")
	)
	(gr_poly
		(pts
			(xy 81.331054 -229.702614) (xy 81.331054 -229.658164) (xy 81.130902 -229.658164) (xy 81.130902 -229.702614)
			(xy 81.230978 -229.80269)
		)
		(stroke
			(width 0)
			(type solid)
		)
		(fill yes)
		(layer "In6.Cu")
		(net "M_E_CPU1_SA_DQ<7>")
	)
	(gr_poly
		(pts
			(xy 81.331054 -228.082856) (xy 81.331054 -228.035104) (xy 81.130902 -228.035104) (xy 81.130902 -228.082856)
			(xy 81.230978 -228.182678)
		)
		(stroke
			(width 0)
			(type solid)
		)
		(fill yes)
		(layer "In6.Cu")
		(net "M_E_CPU1_SA_DQS_DP<5>")
	)
	(gr_poly
		(pts
			(xy 81.331054 -226.46259) (xy 81.331054 -226.41814) (xy 81.130902 -226.41814) (xy 81.130902 -226.46259)
			(xy 81.230978 -226.562666)
		)
		(stroke
			(width 0)
			(type solid)
		)
		(fill yes)
		(layer "In6.Cu")
		(net "M_E_CPU1_SA_DQ<3>")
	)
	(gr_poly
		(pts
			(xy 81.631028 -292.918134) (xy 81.530952 -292.818058) (xy 81.430876 -292.918134) (xy 81.430876 -292.962584)
			(xy 81.631028 -292.962584)
		)
		(stroke
			(width 0)
			(type solid)
		)
		(fill yes)
		(layer "In6.Cu")
		(net "M_E_CPU1_SB_DQ<29>")
	)
	(gr_poly
		(pts
			(xy 81.631028 -291.297868) (xy 81.530952 -291.198046) (xy 81.430876 -291.297868) (xy 81.430876 -291.34562)
			(xy 81.631028 -291.34562)
		)
		(stroke
			(width 0)
			(type solid)
		)
		(fill yes)
		(layer "In6.Cu")
		(net "M_E_CPU1_SB_DQS_DN<8>")
	)
	(gr_poly
		(pts
			(xy 81.631028 -289.67811) (xy 81.530952 -289.578034) (xy 81.430876 -289.67811) (xy 81.430876 -289.72256)
			(xy 81.631028 -289.72256)
		)
		(stroke
			(width 0)
			(type solid)
		)
		(fill yes)
		(layer "In6.Cu")
		(net "M_E_CPU1_SB_DQ<25>")
	)
	(gr_poly
		(pts
			(xy 81.631028 -288.058098) (xy 81.530952 -287.958022) (xy 81.430876 -288.058098) (xy 81.430876 -288.102548)
			(xy 81.631028 -288.102548)
		)
		(stroke
			(width 0)
			(type solid)
		)
		(fill yes)
		(layer "In6.Cu")
		(net "M_E_CPU1_SB_DQ<21>")
	)
	(gr_poly
		(pts
			(xy 81.631028 -286.438086) (xy 81.530952 -286.33801) (xy 81.430876 -286.438086) (xy 81.430876 -286.485838)
			(xy 81.631028 -286.485838)
		)
		(stroke
			(width 0)
			(type solid)
		)
		(fill yes)
		(layer "In6.Cu")
		(net "M_E_CPU1_SB_DQS_DN<7>")
	)
	(gr_poly
		(pts
			(xy 81.631028 -284.818328) (xy 81.530952 -284.718252) (xy 81.430876 -284.818328) (xy 81.430876 -284.862778)
			(xy 81.631028 -284.862778)
		)
		(stroke
			(width 0)
			(type solid)
		)
		(fill yes)
		(layer "In6.Cu")
		(net "M_E_CPU1_SB_DQ<17>")
	)
	(gr_poly
		(pts
			(xy 81.631028 -283.198316) (xy 81.530952 -283.09824) (xy 81.430876 -283.198316) (xy 81.430876 -283.242766)
			(xy 81.631028 -283.242766)
		)
		(stroke
			(width 0)
			(type solid)
		)
		(fill yes)
		(layer "In6.Cu")
		(net "M_E_CPU1_SB_DQ<13>")
	)
	(gr_poly
		(pts
			(xy 81.631028 -281.57805) (xy 81.530952 -281.478228) (xy 81.430876 -281.57805) (xy 81.430876 -281.625802)
			(xy 81.631028 -281.625802)
		)
		(stroke
			(width 0)
			(type solid)
		)
		(fill yes)
		(layer "In6.Cu")
		(net "M_E_CPU1_SB_DQS_DN<6>")
	)
	(gr_poly
		(pts
			(xy 81.631028 -279.958292) (xy 81.530952 -279.858216) (xy 81.430876 -279.958292) (xy 81.430876 -280.002742)
			(xy 81.631028 -280.002742)
		)
		(stroke
			(width 0)
			(type solid)
		)
		(fill yes)
		(layer "In6.Cu")
		(net "M_E_CPU1_SB_DQ<9>")
	)
	(gr_poly
		(pts
			(xy 81.631028 -278.33828) (xy 81.530952 -278.238204) (xy 81.430876 -278.33828) (xy 81.430876 -278.38273)
			(xy 81.631028 -278.38273)
		)
		(stroke
			(width 0)
			(type solid)
		)
		(fill yes)
		(layer "In6.Cu")
		(net "M_E_CPU1_SB_DQ<5>")
	)
	(gr_poly
		(pts
			(xy 81.631028 -276.718014) (xy 81.530952 -276.618192) (xy 81.430876 -276.718014) (xy 81.430876 -276.765766)
			(xy 81.631028 -276.765766)
		)
		(stroke
			(width 0)
			(type solid)
		)
		(fill yes)
		(layer "In6.Cu")
		(net "M_E_CPU1_SB_DQS_DN<5>")
	)
	(gr_poly
		(pts
			(xy 81.631028 -275.098256) (xy 81.530952 -274.99818) (xy 81.430876 -275.098256) (xy 81.430876 -275.142706)
			(xy 81.631028 -275.142706)
		)
		(stroke
			(width 0)
			(type solid)
		)
		(fill yes)
		(layer "In6.Cu")
		(net "M_E_CPU1_SB_DQ<1>")
	)
	(gr_poly
		(pts
			(xy 81.631028 -273.478244) (xy 81.530952 -273.378168) (xy 81.430876 -273.478244) (xy 81.430876 -273.522694)
			(xy 81.631028 -273.522694)
		)
		(stroke
			(width 0)
			(type solid)
		)
		(fill yes)
		(layer "In6.Cu")
		(net "M_E_CPU1_SB_CB<1>")
	)
	(gr_poly
		(pts
			(xy 81.631028 -271.857978) (xy 81.530952 -271.758156) (xy 81.430876 -271.857978) (xy 81.430876 -271.90573)
			(xy 81.631028 -271.90573)
		)
		(stroke
			(width 0)
			(type solid)
		)
		(fill yes)
		(layer "In6.Cu")
		(net "M_E_CPU1_SB_DQS_DN<4>")
	)
	(gr_poly
		(pts
			(xy 81.631028 -270.23822) (xy 81.530952 -270.138144) (xy 81.430876 -270.23822) (xy 81.430876 -270.28267)
			(xy 81.631028 -270.28267)
		)
		(stroke
			(width 0)
			(type solid)
		)
		(fill yes)
		(layer "In6.Cu")
		(net "M_E_CPU1_SB_CB<5>")
	)
	(gr_poly
		(pts
			(xy 81.631028 -266.998196) (xy 81.530952 -266.89812) (xy 81.430876 -266.998196) (xy 81.430876 -267.042646)
			(xy 81.631028 -267.042646)
		)
		(stroke
			(width 0)
			(type solid)
		)
		(fill yes)
		(layer "In6.Cu")
		(net "M_E_CPU1_SA_RSP<0>")
	)
	(gr_poly
		(pts
			(xy 81.631028 -263.758172) (xy 81.530952 -263.658096) (xy 81.430876 -263.758172) (xy 81.430876 -263.802622)
			(xy 81.631028 -263.802622)
		)
		(stroke
			(width 0)
			(type solid)
		)
		(fill yes)
		(layer "In6.Cu")
		(net "M_E_CPU1_SB_CA<4>")
	)
	(gr_poly
		(pts
			(xy 81.631028 -262.13816) (xy 81.530952 -262.038084) (xy 81.430876 -262.13816) (xy 81.430876 -262.18261)
			(xy 81.631028 -262.18261)
		)
		(stroke
			(width 0)
			(type solid)
		)
		(fill yes)
		(layer "In6.Cu")
		(net "M_E_CPU1_SB_CA<0>")
	)
	(gr_poly
		(pts
			(xy 81.687162 -294.670734) (xy 81.650332 -294.534082) (xy 81.611978 -294.51173) (xy 81.511902 -294.684958)
			(xy 81.55051 -294.70731)
		)
		(stroke
			(width 0)
			(type solid)
		)
		(fill yes)
		(layer "In6.Cu")
		(net "M_E_CPU1_SB_DQ<31>")
	)
	(gr_poly
		(pts
			(xy 81.801208 -255.216406) (xy 81.701132 -255.11633) (xy 81.601056 -255.216406) (xy 81.601056 -255.260856)
			(xy 81.801208 -255.260856)
		)
		(stroke
			(width 0)
			(type solid)
		)
		(fill yes)
		(layer "In6.Cu")
		(net "M_E_CPU1_SA_CA<6>")
	)
	(gr_poly
		(pts
			(xy 81.801208 -253.596394) (xy 81.701132 -253.496318) (xy 81.601056 -253.596394) (xy 81.601056 -253.640844)
			(xy 81.801208 -253.640844)
		)
		(stroke
			(width 0)
			(type solid)
		)
		(fill yes)
		(layer "In6.Cu")
		(net "M_E_CPU1_SA_CA<2>")
	)
	(gr_poly
		(pts
			(xy 81.801208 -250.35637) (xy 81.701132 -250.256294) (xy 81.601056 -250.35637) (xy 81.601056 -250.40082)
			(xy 81.801208 -250.40082)
		)
		(stroke
			(width 0)
			(type solid)
		)
		(fill yes)
		(layer "In6.Cu")
		(net "M_E_CPU1_ALERT_R_N")
	)
	(gr_poly
		(pts
			(xy 81.801208 -248.736358) (xy 81.701132 -248.636282) (xy 81.601056 -248.736358) (xy 81.601056 -248.780808)
			(xy 81.801208 -248.780808)
		)
		(stroke
			(width 0)
			(type solid)
		)
		(fill yes)
		(layer "In6.Cu")
		(net "M_E_CPU1_SA_CB<5>")
	)
	(gr_poly
		(pts
			(xy 81.801208 -247.116092) (xy 81.701132 -247.01627) (xy 81.601056 -247.116092) (xy 81.601056 -247.163844)
			(xy 81.801208 -247.163844)
		)
		(stroke
			(width 0)
			(type solid)
		)
		(fill yes)
		(layer "In6.Cu")
		(net "M_E_CPU1_SA_DQS_DN<9>")
	)
	(gr_poly
		(pts
			(xy 81.801208 -245.496334) (xy 81.701132 -245.396258) (xy 81.601056 -245.496334) (xy 81.601056 -245.540784)
			(xy 81.801208 -245.540784)
		)
		(stroke
			(width 0)
			(type solid)
		)
		(fill yes)
		(layer "In6.Cu")
		(net "M_E_CPU1_SA_CB<1>")
	)
	(gr_poly
		(pts
			(xy 81.801208 -243.876322) (xy 81.701132 -243.776246) (xy 81.601056 -243.876322) (xy 81.601056 -243.920772)
			(xy 81.801208 -243.920772)
		)
		(stroke
			(width 0)
			(type solid)
		)
		(fill yes)
		(layer "In6.Cu")
		(net "M_E_CPU1_SA_DQ<29>")
	)
	(gr_poly
		(pts
			(xy 81.801208 -242.256056) (xy 81.701132 -242.156234) (xy 81.601056 -242.256056) (xy 81.601056 -242.303808)
			(xy 81.801208 -242.303808)
		)
		(stroke
			(width 0)
			(type solid)
		)
		(fill yes)
		(layer "In6.Cu")
		(net "M_E_CPU1_SA_DQS_DN<8>")
	)
	(gr_poly
		(pts
			(xy 81.801208 -240.636298) (xy 81.701132 -240.536222) (xy 81.601056 -240.636298) (xy 81.601056 -240.680748)
			(xy 81.801208 -240.680748)
		)
		(stroke
			(width 0)
			(type solid)
		)
		(fill yes)
		(layer "In6.Cu")
		(net "M_E_CPU1_SA_DQ<25>")
	)
	(gr_poly
		(pts
			(xy 81.801208 -239.016286) (xy 81.701132 -238.91621) (xy 81.601056 -239.016286) (xy 81.601056 -239.060736)
			(xy 81.801208 -239.060736)
		)
		(stroke
			(width 0)
			(type solid)
		)
		(fill yes)
		(layer "In6.Cu")
		(net "M_E_CPU1_SA_DQ<21>")
	)
	(gr_poly
		(pts
			(xy 81.801208 -237.39602) (xy 81.701132 -237.296198) (xy 81.601056 -237.39602) (xy 81.601056 -237.443772)
			(xy 81.801208 -237.443772)
		)
		(stroke
			(width 0)
			(type solid)
		)
		(fill yes)
		(layer "In6.Cu")
		(net "M_E_CPU1_SA_DQS_DN<7>")
	)
	(gr_poly
		(pts
			(xy 81.801208 -235.776262) (xy 81.701132 -235.676186) (xy 81.601056 -235.776262) (xy 81.601056 -235.820712)
			(xy 81.801208 -235.820712)
		)
		(stroke
			(width 0)
			(type solid)
		)
		(fill yes)
		(layer "In6.Cu")
		(net "M_E_CPU1_SA_DQ<17>")
	)
	(gr_poly
		(pts
			(xy 81.801208 -234.15625) (xy 81.701132 -234.056174) (xy 81.601056 -234.15625) (xy 81.601056 -234.2007)
			(xy 81.801208 -234.2007)
		)
		(stroke
			(width 0)
			(type solid)
		)
		(fill yes)
		(layer "In6.Cu")
		(net "M_E_CPU1_SA_DQ<13>")
	)
	(gr_poly
		(pts
			(xy 81.801208 -232.535984) (xy 81.701132 -232.436162) (xy 81.601056 -232.535984) (xy 81.601056 -232.583736)
			(xy 81.801208 -232.583736)
		)
		(stroke
			(width 0)
			(type solid)
		)
		(fill yes)
		(layer "In6.Cu")
		(net "M_E_CPU1_SA_DQS_DN<6>")
	)
	(gr_poly
		(pts
			(xy 81.801208 -230.916226) (xy 81.701132 -230.81615) (xy 81.601056 -230.916226) (xy 81.601056 -230.960676)
			(xy 81.801208 -230.960676)
		)
		(stroke
			(width 0)
			(type solid)
		)
		(fill yes)
		(layer "In6.Cu")
		(net "M_E_CPU1_SA_DQ<9>")
	)
	(gr_poly
		(pts
			(xy 81.801208 -229.296214) (xy 81.701132 -229.196138) (xy 81.601056 -229.296214) (xy 81.601056 -229.340664)
			(xy 81.801208 -229.340664)
		)
		(stroke
			(width 0)
			(type solid)
		)
		(fill yes)
		(layer "In6.Cu")
		(net "M_E_CPU1_SA_DQ<5>")
	)
	(gr_poly
		(pts
			(xy 81.801208 -227.676202) (xy 81.701132 -227.57638) (xy 81.601056 -227.676202) (xy 81.601056 -227.723954)
			(xy 81.801208 -227.723954)
		)
		(stroke
			(width 0)
			(type solid)
		)
		(fill yes)
		(layer "In6.Cu")
		(net "M_E_CPU1_SA_DQS_DN<5>")
	)
	(gr_poly
		(pts
			(xy 81.801208 -226.056444) (xy 81.701132 -225.956368) (xy 81.601056 -226.056444) (xy 81.601056 -226.100894)
			(xy 81.801208 -226.100894)
		)
		(stroke
			(width 0)
			(type solid)
		)
		(fill yes)
		(layer "In6.Cu")
		(net "M_E_CPU1_SA_DQ<1>")
	)
	(gr_poly
		(pts
			(xy 82.101182 -291.704522) (xy 82.101182 -291.65677) (xy 81.90103 -291.65677) (xy 81.90103 -291.704522)
			(xy 82.001106 -291.804344)
		)
		(stroke
			(width 0)
			(type solid)
		)
		(fill yes)
		(layer "In6.Cu")
		(net "M_E_CPU1_SB_DQS_DP<8>")
	)
	(gr_poly
		(pts
			(xy 82.101182 -290.084256) (xy 82.101182 -290.039806) (xy 81.90103 -290.039806) (xy 81.90103 -290.084256)
			(xy 82.001106 -290.184332)
		)
		(stroke
			(width 0)
			(type solid)
		)
		(fill yes)
		(layer "In6.Cu")
		(net "M_E_CPU1_SB_DQ<27>")
	)
	(gr_poly
		(pts
			(xy 82.101182 -288.464498) (xy 82.101182 -288.420048) (xy 81.90103 -288.420048) (xy 81.90103 -288.464498)
			(xy 82.001106 -288.564574)
		)
		(stroke
			(width 0)
			(type solid)
		)
		(fill yes)
		(layer "In6.Cu")
		(net "M_E_CPU1_SB_DQ<23>")
	)
	(gr_poly
		(pts
			(xy 82.101182 -286.844486) (xy 82.101182 -286.796734) (xy 81.90103 -286.796734) (xy 81.90103 -286.844486)
			(xy 82.001106 -286.944562)
		)
		(stroke
			(width 0)
			(type solid)
		)
		(fill yes)
		(layer "In6.Cu")
		(net "M_E_CPU1_SB_DQS_DP<7>")
	)
	(gr_poly
		(pts
			(xy 82.101182 -285.224474) (xy 82.101182 -285.180024) (xy 81.90103 -285.180024) (xy 81.90103 -285.224474)
			(xy 82.001106 -285.32455)
		)
		(stroke
			(width 0)
			(type solid)
		)
		(fill yes)
		(layer "In6.Cu")
		(net "M_E_CPU1_SB_DQ<19>")
	)
	(gr_poly
		(pts
			(xy 82.101182 -283.604462) (xy 82.101182 -283.560012) (xy 81.90103 -283.560012) (xy 81.90103 -283.604462)
			(xy 82.001106 -283.704538)
		)
		(stroke
			(width 0)
			(type solid)
		)
		(fill yes)
		(layer "In6.Cu")
		(net "M_E_CPU1_SB_DQ<15>")
	)
	(gr_poly
		(pts
			(xy 82.101182 -281.984704) (xy 82.101182 -281.936952) (xy 81.90103 -281.936952) (xy 81.90103 -281.984704)
			(xy 82.001106 -282.084526)
		)
		(stroke
			(width 0)
			(type solid)
		)
		(fill yes)
		(layer "In6.Cu")
		(net "M_E_CPU1_SB_DQS_DP<6>")
	)
	(gr_poly
		(pts
			(xy 82.101182 -280.364438) (xy 82.101182 -280.319988) (xy 81.90103 -280.319988) (xy 81.90103 -280.364438)
			(xy 82.001106 -280.464514)
		)
		(stroke
			(width 0)
			(type solid)
		)
		(fill yes)
		(layer "In6.Cu")
		(net "M_E_CPU1_SB_DQ<11>")
	)
	(gr_poly
		(pts
			(xy 82.101182 -278.744426) (xy 82.101182 -278.699976) (xy 81.90103 -278.699976) (xy 81.90103 -278.744426)
			(xy 82.001106 -278.844502)
		)
		(stroke
			(width 0)
			(type solid)
		)
		(fill yes)
		(layer "In6.Cu")
		(net "M_E_CPU1_SB_DQ<7>")
	)
	(gr_poly
		(pts
			(xy 82.101182 -277.124668) (xy 82.101182 -277.076916) (xy 81.90103 -277.076916) (xy 81.90103 -277.124668)
			(xy 82.001106 -277.22449)
		)
		(stroke
			(width 0)
			(type solid)
		)
		(fill yes)
		(layer "In6.Cu")
		(net "M_E_CPU1_SB_DQS_DP<5>")
	)
	(gr_poly
		(pts
			(xy 82.101182 -275.504402) (xy 82.101182 -275.459952) (xy 81.90103 -275.459952) (xy 81.90103 -275.504402)
			(xy 82.001106 -275.604478)
		)
		(stroke
			(width 0)
			(type solid)
		)
		(fill yes)
		(layer "In6.Cu")
		(net "M_E_CPU1_SB_DQ<3>")
	)
	(gr_poly
		(pts
			(xy 82.101182 -273.88439) (xy 82.101182 -273.83994) (xy 81.90103 -273.83994) (xy 81.90103 -273.88439)
			(xy 82.001106 -273.984466)
		)
		(stroke
			(width 0)
			(type solid)
		)
		(fill yes)
		(layer "In6.Cu")
		(net "M_E_CPU1_SB_CB<3>")
	)
	(gr_poly
		(pts
			(xy 82.101182 -272.264632) (xy 82.101182 -272.21688) (xy 81.90103 -272.21688) (xy 81.90103 -272.264632)
			(xy 82.001106 -272.364454)
		)
		(stroke
			(width 0)
			(type solid)
		)
		(fill yes)
		(layer "In6.Cu")
		(net "M_E_CPU1_SB_DQS_DP<4>")
	)
	(gr_poly
		(pts
			(xy 82.101182 -270.644366) (xy 82.101182 -270.599916) (xy 81.90103 -270.599916) (xy 81.90103 -270.644366)
			(xy 82.001106 -270.744442)
		)
		(stroke
			(width 0)
			(type solid)
		)
		(fill yes)
		(layer "In6.Cu")
		(net "M_E_CPU1_SB_CB<7>")
	)
	(gr_poly
		(pts
			(xy 82.101182 -265.78433) (xy 82.101182 -265.73988) (xy 81.90103 -265.73988) (xy 81.90103 -265.78433)
			(xy 82.001106 -265.884406)
		)
		(stroke
			(width 0)
			(type solid)
		)
		(fill yes)
		(layer "In6.Cu")
		(net "M_E_CPU1_SB_CS_N<0>")
	)
	(gr_poly
		(pts
			(xy 82.101182 -264.164318) (xy 82.101182 -264.119868) (xy 81.90103 -264.119868) (xy 81.90103 -264.164318)
			(xy 82.001106 -264.264394)
		)
		(stroke
			(width 0)
			(type solid)
		)
		(fill yes)
		(layer "In6.Cu")
		(net "M_E_CPU1_SB_CA<5>")
	)
	(gr_poly
		(pts
			(xy 82.101182 -262.544306) (xy 82.101182 -262.499856) (xy 81.90103 -262.499856) (xy 81.90103 -262.544306)
			(xy 82.001106 -262.644382)
		)
		(stroke
			(width 0)
			(type solid)
		)
		(fill yes)
		(layer "In6.Cu")
		(net "M_E_CPU1_SB_CA<1>")
	)
	(gr_poly
		(pts
			(xy 82.157062 -293.860728) (xy 82.120232 -293.724076) (xy 82.081878 -293.701724) (xy 81.981802 -293.874952)
			(xy 82.02041 -293.897304)
		)
		(stroke
			(width 0)
			(type solid)
		)
		(fill yes)
		(layer "In6.Cu")
		(net "M_E_CPU1_SB_DQ<31>")
	)
	(gr_poly
		(pts
			(xy 82.218784 -247.52935) (xy 82.223102 -247.481852) (xy 82.023712 -247.46458) (xy 82.019648 -247.511824)
			(xy 82.11058 -247.620282)
		)
		(stroke
			(width 0)
			(type solid)
		)
		(fill yes)
		(layer "In6.Cu")
		(net "M_E_CPU1_SA_DQS_DP<9>")
	)
	(gr_poly
		(pts
			(xy 82.218784 -242.669314) (xy 82.223102 -242.621816) (xy 82.023712 -242.604544) (xy 82.019648 -242.651788)
			(xy 82.11058 -242.760246)
		)
		(stroke
			(width 0)
			(type solid)
		)
		(fill yes)
		(layer "In6.Cu")
		(net "M_E_CPU1_SA_DQS_DP<8>")
	)
	(gr_poly
		(pts
			(xy 82.218784 -237.809278) (xy 82.223102 -237.76178) (xy 82.023712 -237.744508) (xy 82.019648 -237.791752)
			(xy 82.11058 -237.90021)
		)
		(stroke
			(width 0)
			(type solid)
		)
		(fill yes)
		(layer "In6.Cu")
		(net "M_E_CPU1_SA_DQS_DP<7>")
	)
	(gr_poly
		(pts
			(xy 82.218784 -232.949242) (xy 82.223102 -232.901744) (xy 82.023712 -232.884472) (xy 82.019648 -232.931716)
			(xy 82.11058 -233.040174)
		)
		(stroke
			(width 0)
			(type solid)
		)
		(fill yes)
		(layer "In6.Cu")
		(net "M_E_CPU1_SA_DQS_DP<6>")
	)
	(gr_poly
		(pts
			(xy 82.218784 -228.08946) (xy 82.223102 -228.041962) (xy 82.023712 -228.024436) (xy 82.019648 -228.071934)
			(xy 82.11058 -228.180392)
		)
		(stroke
			(width 0)
			(type solid)
		)
		(fill yes)
		(layer "In6.Cu")
		(net "M_E_CPU1_SA_DQS_DP<5>")
	)
	(gr_poly
		(pts
			(xy 82.231484 -255.630172) (xy 82.235294 -255.585722) (xy 82.036158 -255.56845) (xy 82.032348 -255.612646)
			(xy 82.12328 -255.721104)
		)
		(stroke
			(width 0)
			(type solid)
		)
		(fill yes)
		(layer "In6.Cu")
		(net "M_E_CPU1_SA_PAR")
	)
	(gr_poly
		(pts
			(xy 82.231484 -254.01016) (xy 82.235294 -253.96571) (xy 82.036158 -253.948438) (xy 82.032348 -253.992634)
			(xy 82.12328 -254.101092)
		)
		(stroke
			(width 0)
			(type solid)
		)
		(fill yes)
		(layer "In6.Cu")
		(net "M_E_CPU1_SA_CA<3>")
	)
	(gr_poly
		(pts
			(xy 82.231484 -252.390148) (xy 82.235294 -252.345698) (xy 82.036158 -252.328426) (xy 82.032348 -252.372622)
			(xy 82.12328 -252.48108)
		)
		(stroke
			(width 0)
			(type solid)
		)
		(fill yes)
		(layer "In6.Cu")
		(net "M_E_CPU1_SA_CS_N<1>")
	)
	(gr_poly
		(pts
			(xy 82.231484 -250.770136) (xy 82.235294 -250.725686) (xy 82.036158 -250.708414) (xy 82.032348 -250.75261)
			(xy 82.12328 -250.861068)
		)
		(stroke
			(width 0)
			(type solid)
		)
		(fill yes)
		(layer "In6.Cu")
		(net "M_E_CPU1_RESET_N")
	)
	(gr_poly
		(pts
			(xy 82.231484 -249.150124) (xy 82.235294 -249.105674) (xy 82.036158 -249.088402) (xy 82.032348 -249.132598)
			(xy 82.12328 -249.241056)
		)
		(stroke
			(width 0)
			(type solid)
		)
		(fill yes)
		(layer "In6.Cu")
		(net "M_E_CPU1_SA_CB<7>")
	)
	(gr_poly
		(pts
			(xy 82.231484 -245.9101) (xy 82.235294 -245.86565) (xy 82.036158 -245.848378) (xy 82.032348 -245.892574)
			(xy 82.12328 -246.001032)
		)
		(stroke
			(width 0)
			(type solid)
		)
		(fill yes)
		(layer "In6.Cu")
		(net "M_E_CPU1_SA_CB<3>")
	)
	(gr_poly
		(pts
			(xy 82.231484 -244.290088) (xy 82.235294 -244.245638) (xy 82.036158 -244.228366) (xy 82.032348 -244.272562)
			(xy 82.12328 -244.38102)
		)
		(stroke
			(width 0)
			(type solid)
		)
		(fill yes)
		(layer "In6.Cu")
		(net "M_E_CPU1_SA_DQ<31>")
	)
	(gr_poly
		(pts
			(xy 82.231484 -241.050064) (xy 82.235294 -241.005614) (xy 82.036158 -240.988342) (xy 82.032348 -241.032538)
			(xy 82.12328 -241.140996)
		)
		(stroke
			(width 0)
			(type solid)
		)
		(fill yes)
		(layer "In6.Cu")
		(net "M_E_CPU1_SA_DQ<27>")
	)
	(gr_poly
		(pts
			(xy 82.231484 -239.430052) (xy 82.235294 -239.385602) (xy 82.036158 -239.36833) (xy 82.032348 -239.412526)
			(xy 82.12328 -239.520984)
		)
		(stroke
			(width 0)
			(type solid)
		)
		(fill yes)
		(layer "In6.Cu")
		(net "M_E_CPU1_SA_DQ<23>")
	)
	(gr_poly
		(pts
			(xy 82.231484 -236.190028) (xy 82.235294 -236.145578) (xy 82.036158 -236.128306) (xy 82.032348 -236.172502)
			(xy 82.12328 -236.28096)
		)
		(stroke
			(width 0)
			(type solid)
		)
		(fill yes)
		(layer "In6.Cu")
		(net "M_E_CPU1_SA_DQ<19>")
	)
	(gr_poly
		(pts
			(xy 82.231484 -234.570016) (xy 82.235294 -234.525566) (xy 82.036158 -234.508294) (xy 82.032348 -234.55249)
			(xy 82.12328 -234.660948)
		)
		(stroke
			(width 0)
			(type solid)
		)
		(fill yes)
		(layer "In6.Cu")
		(net "M_E_CPU1_SA_DQ<15>")
	)
	(gr_poly
		(pts
			(xy 82.231484 -226.47021) (xy 82.235294 -226.42576) (xy 82.036158 -226.408488) (xy 82.032348 -226.452684)
			(xy 82.12328 -226.561142)
		)
		(stroke
			(width 0)
			(type solid)
		)
		(fill yes)
		(layer "In6.Cu")
		(net "M_E_CPU1_SA_DQ<3>")
	)
	(gr_poly
		(pts
			(xy 82.231738 -231.329992) (xy 82.235548 -231.285796) (xy 82.036412 -231.268524) (xy 82.032348 -231.31272)
			(xy 82.12328 -231.420924)
		)
		(stroke
			(width 0)
			(type solid)
		)
		(fill yes)
		(layer "In6.Cu")
		(net "M_E_CPU1_SA_DQ<11>")
	)
	(gr_poly
		(pts
			(xy 82.231738 -229.710234) (xy 82.235548 -229.665784) (xy 82.036412 -229.648512) (xy 82.032348 -229.692708)
			(xy 82.12328 -229.800912)
		)
		(stroke
			(width 0)
			(type solid)
		)
		(fill yes)
		(layer "In6.Cu")
		(net "M_E_CPU1_SA_DQ<7>")
	)
	(gr_poly
		(pts
			(xy 82.523076 -281.618944) (xy 82.518758 -281.571446) (xy 82.410554 -281.480514) (xy 82.319622 -281.588972)
			(xy 82.323686 -281.636216)
		)
		(stroke
			(width 0)
			(type solid)
		)
		(fill yes)
		(layer "In6.Cu")
		(net "M_E_CPU1_SB_DQS_DN<6>")
	)
	(gr_poly
		(pts
			(xy 82.53349 -291.338) (xy 82.529426 -291.290502) (xy 82.421222 -291.19957) (xy 82.33029 -291.308028)
			(xy 82.334354 -291.355272)
		)
		(stroke
			(width 0)
			(type solid)
		)
		(fill yes)
		(layer "In6.Cu")
		(net "M_E_CPU1_SB_DQS_DN<8>")
	)
	(gr_poly
		(pts
			(xy 82.53349 -286.478218) (xy 82.529426 -286.43072) (xy 82.421222 -286.339788) (xy 82.33029 -286.448246)
			(xy 82.334354 -286.49549)
		)
		(stroke
			(width 0)
			(type solid)
		)
		(fill yes)
		(layer "In6.Cu")
		(net "M_E_CPU1_SB_DQS_DN<7>")
	)
	(gr_poly
		(pts
			(xy 82.53349 -276.758146) (xy 82.529426 -276.710648) (xy 82.421222 -276.619716) (xy 82.33029 -276.728174)
			(xy 82.334354 -276.775672)
		)
		(stroke
			(width 0)
			(type solid)
		)
		(fill yes)
		(layer "In6.Cu")
		(net "M_E_CPU1_SB_DQS_DN<5>")
	)
	(gr_poly
		(pts
			(xy 82.53349 -271.89811) (xy 82.529426 -271.850612) (xy 82.421222 -271.75968) (xy 82.33029 -271.868138)
			(xy 82.334354 -271.915636)
		)
		(stroke
			(width 0)
			(type solid)
		)
		(fill yes)
		(layer "In6.Cu")
		(net "M_E_CPU1_SB_DQS_DN<4>")
	)
	(gr_poly
		(pts
			(xy 82.535522 -292.954964) (xy 82.531458 -292.910514) (xy 82.423254 -292.819582) (xy 82.332322 -292.92804)
			(xy 82.336132 -292.972236)
		)
		(stroke
			(width 0)
			(type solid)
		)
		(fill yes)
		(layer "In6.Cu")
		(net "M_E_CPU1_SB_DQ<29>")
	)
	(gr_poly
		(pts
			(xy 82.535522 -289.71494) (xy 82.531458 -289.67049) (xy 82.423254 -289.579558) (xy 82.332322 -289.688016)
			(xy 82.336132 -289.732212)
		)
		(stroke
			(width 0)
			(type solid)
		)
		(fill yes)
		(layer "In6.Cu")
		(net "M_E_CPU1_SB_DQ<25>")
	)
	(gr_poly
		(pts
			(xy 82.535522 -288.094928) (xy 82.531712 -288.050732) (xy 82.423254 -287.9598) (xy 82.332322 -288.068004)
			(xy 82.336386 -288.1122)
		)
		(stroke
			(width 0)
			(type solid)
		)
		(fill yes)
		(layer "In6.Cu")
		(net "M_E_CPU1_SB_DQ<21>")
	)
	(gr_poly
		(pts
			(xy 82.535522 -284.855158) (xy 82.531458 -284.810708) (xy 82.423254 -284.719776) (xy 82.332322 -284.828234)
			(xy 82.336132 -284.87243)
		)
		(stroke
			(width 0)
			(type solid)
		)
		(fill yes)
		(layer "In6.Cu")
		(net "M_E_CPU1_SB_DQ<17>")
	)
	(gr_poly
		(pts
			(xy 82.535522 -283.235146) (xy 82.531458 -283.190696) (xy 82.423254 -283.099764) (xy 82.332322 -283.208222)
			(xy 82.336132 -283.252418)
		)
		(stroke
			(width 0)
			(type solid)
		)
		(fill yes)
		(layer "In6.Cu")
		(net "M_E_CPU1_SB_DQ<13>")
	)
	(gr_poly
		(pts
			(xy 82.535522 -279.995122) (xy 82.531458 -279.950672) (xy 82.423254 -279.85974) (xy 82.332322 -279.968198)
			(xy 82.336132 -280.012394)
		)
		(stroke
			(width 0)
			(type solid)
		)
		(fill yes)
		(layer "In6.Cu")
		(net "M_E_CPU1_SB_DQ<9>")
	)
	(gr_poly
		(pts
			(xy 82.535522 -278.37511) (xy 82.531458 -278.33066) (xy 82.423254 -278.239728) (xy 82.332322 -278.348186)
			(xy 82.336132 -278.392382)
		)
		(stroke
			(width 0)
			(type solid)
		)
		(fill yes)
		(layer "In6.Cu")
		(net "M_E_CPU1_SB_DQ<5>")
	)
	(gr_poly
		(pts
			(xy 82.535522 -275.135086) (xy 82.531458 -275.090636) (xy 82.423254 -274.999704) (xy 82.332322 -275.108162)
			(xy 82.336132 -275.152358)
		)
		(stroke
			(width 0)
			(type solid)
		)
		(fill yes)
		(layer "In6.Cu")
		(net "M_E_CPU1_SB_DQ<1>")
	)
	(gr_poly
		(pts
			(xy 82.535522 -273.515074) (xy 82.531458 -273.470624) (xy 82.423254 -273.379692) (xy 82.332322 -273.48815)
			(xy 82.336132 -273.532346)
		)
		(stroke
			(width 0)
			(type solid)
		)
		(fill yes)
		(layer "In6.Cu")
		(net "M_E_CPU1_SB_CB<1>")
	)
	(gr_poly
		(pts
			(xy 82.535522 -270.27505) (xy 82.531458 -270.2306) (xy 82.423254 -270.139668) (xy 82.332322 -270.248126)
			(xy 82.336132 -270.292322)
		)
		(stroke
			(width 0)
			(type solid)
		)
		(fill yes)
		(layer "In6.Cu")
		(net "M_E_CPU1_SB_CB<5>")
	)
	(gr_poly
		(pts
			(xy 82.535522 -267.035026) (xy 82.531458 -266.990576) (xy 82.423254 -266.899644) (xy 82.332322 -267.008102)
			(xy 82.336132 -267.052298)
		)
		(stroke
			(width 0)
			(type solid)
		)
		(fill yes)
		(layer "In6.Cu")
		(net "M_E_CPU1_SA_RSP<0>")
	)
	(gr_poly
		(pts
			(xy 82.535522 -263.795002) (xy 82.531458 -263.750552) (xy 82.423254 -263.65962) (xy 82.332322 -263.768078)
			(xy 82.336132 -263.812274)
		)
		(stroke
			(width 0)
			(type solid)
		)
		(fill yes)
		(layer "In6.Cu")
		(net "M_E_CPU1_SB_CA<4>")
	)
	(gr_poly
		(pts
			(xy 82.535522 -262.17499) (xy 82.531458 -262.13054) (xy 82.423254 -262.039608) (xy 82.332322 -262.148066)
			(xy 82.336132 -262.192262)
		)
		(stroke
			(width 0)
			(type solid)
		)
		(fill yes)
		(layer "In6.Cu")
		(net "M_E_CPU1_SB_CA<0>")
	)
	(gr_poly
		(pts
			(xy 141.523466 -255.612646) (xy 141.519656 -255.56845) (xy 141.320266 -255.585722) (xy 141.32433 -255.630172)
			(xy 141.432534 -255.721104)
		)
		(stroke
			(width 0)
			(type solid)
		)
		(fill yes)
		(layer "In6.Cu")
		(net "M_K_CPU1_SA_PAR")
	)
	(gr_poly
		(pts
			(xy 141.523466 -253.992634) (xy 141.519656 -253.948438) (xy 141.320266 -253.96571) (xy 141.32433 -254.01016)
			(xy 141.432534 -254.101092)
		)
		(stroke
			(width 0)
			(type solid)
		)
		(fill yes)
		(layer "In6.Cu")
		(net "M_K_CPU1_SA_CA<3>")
	)
	(gr_poly
		(pts
			(xy 141.523466 -250.75261) (xy 141.519656 -250.708414) (xy 141.320266 -250.725686) (xy 141.32433 -250.770136)
			(xy 141.432534 -250.861068)
		)
		(stroke
			(width 0)
			(type solid)
		)
		(fill yes)
		(layer "In6.Cu")
		(net "M_K_CPU1_RESET_N")
	)
	(gr_poly
		(pts
			(xy 141.523466 -249.132598) (xy 141.519656 -249.088402) (xy 141.320266 -249.105674) (xy 141.32433 -249.150124)
			(xy 141.432534 -249.241056)
		)
		(stroke
			(width 0)
			(type solid)
		)
		(fill yes)
		(layer "In6.Cu")
		(net "M_K_CPU1_SA_CB<7>")
	)
	(gr_poly
		(pts
			(xy 141.523466 -245.892574) (xy 141.519656 -245.848378) (xy 141.320266 -245.86565) (xy 141.32433 -245.9101)
			(xy 141.432534 -246.001032)
		)
		(stroke
			(width 0)
			(type solid)
		)
		(fill yes)
		(layer "In6.Cu")
		(net "M_K_CPU1_SA_CB<3>")
	)
	(gr_poly
		(pts
			(xy 141.523466 -244.272562) (xy 141.519656 -244.228366) (xy 141.320266 -244.245638) (xy 141.32433 -244.290088)
			(xy 141.432534 -244.38102)
		)
		(stroke
			(width 0)
			(type solid)
		)
		(fill yes)
		(layer "In6.Cu")
		(net "M_K_CPU1_SA_DQ<31>")
	)
	(gr_poly
		(pts
			(xy 141.523466 -241.032538) (xy 141.519656 -240.988342) (xy 141.320266 -241.005614) (xy 141.32433 -241.050064)
			(xy 141.432534 -241.140996)
		)
		(stroke
			(width 0)
			(type solid)
		)
		(fill yes)
		(layer "In6.Cu")
		(net "M_K_CPU1_SA_DQ<27>")
	)
	(gr_poly
		(pts
			(xy 141.523466 -239.412526) (xy 141.519656 -239.36833) (xy 141.320266 -239.385602) (xy 141.32433 -239.430052)
			(xy 141.432534 -239.520984)
		)
		(stroke
			(width 0)
			(type solid)
		)
		(fill yes)
		(layer "In6.Cu")
		(net "M_K_CPU1_SA_DQ<23>")
	)
	(gr_poly
		(pts
			(xy 141.523466 -236.172502) (xy 141.519656 -236.128306) (xy 141.320266 -236.145578) (xy 141.32433 -236.190028)
			(xy 141.432534 -236.28096)
		)
		(stroke
			(width 0)
			(type solid)
		)
		(fill yes)
		(layer "In6.Cu")
		(net "M_K_CPU1_SA_DQ<19>")
	)
	(gr_poly
		(pts
			(xy 141.523466 -234.55249) (xy 141.519656 -234.508294) (xy 141.320266 -234.525566) (xy 141.32433 -234.570016)
			(xy 141.432534 -234.660948)
		)
		(stroke
			(width 0)
			(type solid)
		)
		(fill yes)
		(layer "In6.Cu")
		(net "M_K_CPU1_SA_DQ<15>")
	)
	(gr_poly
		(pts
			(xy 141.523466 -231.31272) (xy 141.519402 -231.268524) (xy 141.320266 -231.285796) (xy 141.324076 -231.329992)
			(xy 141.432534 -231.420924)
		)
		(stroke
			(width 0)
			(type solid)
		)
		(fill yes)
		(layer "In6.Cu")
		(net "M_K_CPU1_SA_DQ<11>")
	)
	(gr_poly
		(pts
			(xy 141.523466 -229.692708) (xy 141.519402 -229.648512) (xy 141.320266 -229.665784) (xy 141.324076 -229.710234)
			(xy 141.432534 -229.800912)
		)
		(stroke
			(width 0)
			(type solid)
		)
		(fill yes)
		(layer "In6.Cu")
		(net "M_K_CPU1_SA_DQ<7>")
	)
	(gr_poly
		(pts
			(xy 141.523466 -226.452684) (xy 141.519656 -226.408488) (xy 141.320266 -226.42576) (xy 141.32433 -226.47021)
			(xy 141.432534 -226.561142)
		)
		(stroke
			(width 0)
			(type solid)
		)
		(fill yes)
		(layer "In6.Cu")
		(net "M_K_CPU1_SA_DQ<3>")
	)
	(gr_poly
		(pts
			(xy 141.525498 -237.792514) (xy 141.521434 -237.74527) (xy 141.322298 -237.762542) (xy 141.326362 -237.81004)
			(xy 141.434566 -237.900972)
		)
		(stroke
			(width 0)
			(type solid)
		)
		(fill yes)
		(layer "In6.Cu")
		(net "M_K_CPU1_SA_DQS_DP<7>")
	)
	(gr_poly
		(pts
			(xy 141.525498 -232.932478) (xy 141.521434 -232.885234) (xy 141.322298 -232.902506) (xy 141.326362 -232.950004)
			(xy 141.434566 -233.040936)
		)
		(stroke
			(width 0)
			(type solid)
		)
		(fill yes)
		(layer "In6.Cu")
		(net "M_K_CPU1_SA_DQS_DP<6>")
	)
	(gr_poly
		(pts
			(xy 141.536166 -247.511824) (xy 141.532102 -247.46458) (xy 141.332712 -247.481852) (xy 141.33703 -247.52935)
			(xy 141.445234 -247.620282)
		)
		(stroke
			(width 0)
			(type solid)
		)
		(fill yes)
		(layer "In6.Cu")
		(net "M_K_CPU1_SA_DQS_DP<9>")
	)
	(gr_poly
		(pts
			(xy 141.536166 -242.651788) (xy 141.532102 -242.604544) (xy 141.332712 -242.621816) (xy 141.33703 -242.669314)
			(xy 141.445234 -242.760246)
		)
		(stroke
			(width 0)
			(type solid)
		)
		(fill yes)
		(layer "In6.Cu")
		(net "M_K_CPU1_SA_DQS_DP<8>")
	)
	(gr_poly
		(pts
			(xy 141.536166 -228.071934) (xy 141.532102 -228.024436) (xy 141.332712 -228.041962) (xy 141.33703 -228.08946)
			(xy 141.445234 -228.180392)
		)
		(stroke
			(width 0)
			(type solid)
		)
		(fill yes)
		(layer "In6.Cu")
		(net "M_K_CPU1_SA_DQS_DP<5>")
	)
	(gr_poly
		(pts
			(xy 141.82344 -292.92804) (xy 141.732508 -292.819582) (xy 141.624304 -292.910514) (xy 141.620494 -292.954964)
			(xy 141.81963 -292.972236)
		)
		(stroke
			(width 0)
			(type solid)
		)
		(fill yes)
		(layer "In6.Cu")
		(net "M_K_CPU1_SB_DQ<29>")
	)
	(gr_poly
		(pts
			(xy 141.82344 -289.688016) (xy 141.732508 -289.579558) (xy 141.624304 -289.67049) (xy 141.620494 -289.71494)
			(xy 141.81963 -289.732212)
		)
		(stroke
			(width 0)
			(type solid)
		)
		(fill yes)
		(layer "In6.Cu")
		(net "M_K_CPU1_SB_DQ<25>")
	)
	(gr_poly
		(pts
			(xy 141.82344 -288.068004) (xy 141.732508 -287.9598) (xy 141.62405 -288.050732) (xy 141.62024 -288.094928)
			(xy 141.819376 -288.1122)
		)
		(stroke
			(width 0)
			(type solid)
		)
		(fill yes)
		(layer "In6.Cu")
		(net "M_K_CPU1_SB_DQ<21>")
	)
	(gr_poly
		(pts
			(xy 141.82344 -284.828234) (xy 141.732508 -284.719776) (xy 141.624304 -284.810708) (xy 141.620494 -284.855158)
			(xy 141.81963 -284.87243)
		)
		(stroke
			(width 0)
			(type solid)
		)
		(fill yes)
		(layer "In6.Cu")
		(net "M_K_CPU1_SB_DQ<17>")
	)
	(gr_poly
		(pts
			(xy 141.82344 -283.208222) (xy 141.732508 -283.099764) (xy 141.624304 -283.190696) (xy 141.620494 -283.235146)
			(xy 141.81963 -283.252418)
		)
		(stroke
			(width 0)
			(type solid)
		)
		(fill yes)
		(layer "In6.Cu")
		(net "M_K_CPU1_SB_DQ<13>")
	)
	(gr_poly
		(pts
			(xy 141.82344 -279.968198) (xy 141.732508 -279.85974) (xy 141.624304 -279.950672) (xy 141.620494 -279.995122)
			(xy 141.81963 -280.012394)
		)
		(stroke
			(width 0)
			(type solid)
		)
		(fill yes)
		(layer "In6.Cu")
		(net "M_K_CPU1_SB_DQ<9>")
	)
	(gr_poly
		(pts
			(xy 141.82344 -278.348186) (xy 141.732508 -278.239728) (xy 141.624304 -278.33066) (xy 141.620494 -278.37511)
			(xy 141.81963 -278.392382)
		)
		(stroke
			(width 0)
			(type solid)
		)
		(fill yes)
		(layer "In6.Cu")
		(net "M_K_CPU1_SB_DQ<5>")
	)
	(gr_poly
		(pts
			(xy 141.82344 -275.108162) (xy 141.732508 -274.999704) (xy 141.624304 -275.090636) (xy 141.620494 -275.135086)
			(xy 141.81963 -275.152358)
		)
		(stroke
			(width 0)
			(type solid)
		)
		(fill yes)
		(layer "In6.Cu")
		(net "M_K_CPU1_SB_DQ<1>")
	)
	(gr_poly
		(pts
			(xy 141.82344 -273.48815) (xy 141.732508 -273.379692) (xy 141.624304 -273.470624) (xy 141.620494 -273.515074)
			(xy 141.81963 -273.532346)
		)
		(stroke
			(width 0)
			(type solid)
		)
		(fill yes)
		(layer "In6.Cu")
		(net "M_K_CPU1_SB_CB<1>")
	)
	(gr_poly
		(pts
			(xy 141.82344 -270.248126) (xy 141.732508 -270.139668) (xy 141.624304 -270.2306) (xy 141.620494 -270.27505)
			(xy 141.81963 -270.292322)
		)
		(stroke
			(width 0)
			(type solid)
		)
		(fill yes)
		(layer "In6.Cu")
		(net "M_K_CPU1_SB_CB<5>")
	)
	(gr_poly
		(pts
			(xy 141.82344 -267.008102) (xy 141.732508 -266.899644) (xy 141.624304 -266.990576) (xy 141.620494 -267.035026)
			(xy 141.81963 -267.052298)
		)
		(stroke
			(width 0)
			(type solid)
		)
		(fill yes)
		(layer "In6.Cu")
		(net "M_K_CPU1_SA_RSP<0>")
	)
	(gr_poly
		(pts
			(xy 141.82344 -265.38809) (xy 141.732508 -265.279632) (xy 141.624304 -265.370564) (xy 141.620494 -265.415014)
			(xy 141.81963 -265.432286)
		)
		(stroke
			(width 0)
			(type solid)
		)
		(fill yes)
		(layer "In6.Cu")
		(net "M_K_CPU1_SB_PAR")
	)
	(gr_poly
		(pts
			(xy 141.82344 -263.768078) (xy 141.732508 -263.65962) (xy 141.624304 -263.750552) (xy 141.620494 -263.795002)
			(xy 141.81963 -263.812274)
		)
		(stroke
			(width 0)
			(type solid)
		)
		(fill yes)
		(layer "In6.Cu")
		(net "M_K_CPU1_SB_CA<4>")
	)
	(gr_poly
		(pts
			(xy 141.82344 -262.148066) (xy 141.732508 -262.039608) (xy 141.624304 -262.13054) (xy 141.620494 -262.17499)
			(xy 141.81963 -262.192262)
		)
		(stroke
			(width 0)
			(type solid)
		)
		(fill yes)
		(layer "In6.Cu")
		(net "M_K_CPU1_SB_CA<0>")
	)
	(gr_poly
		(pts
			(xy 141.825472 -286.448246) (xy 141.73454 -286.339788) (xy 141.626336 -286.43072) (xy 141.622018 -286.478218)
			(xy 141.821408 -286.49549)
		)
		(stroke
			(width 0)
			(type solid)
		)
		(fill yes)
		(layer "In6.Cu")
		(net "M_K_CPU1_SB_DQS_DN<7>")
	)
	(gr_poly
		(pts
			(xy 141.825472 -281.58821) (xy 141.73454 -281.479752) (xy 141.626336 -281.570684) (xy 141.622018 -281.618182)
			(xy 141.821408 -281.635708)
		)
		(stroke
			(width 0)
			(type solid)
		)
		(fill yes)
		(layer "In6.Cu")
		(net "M_K_CPU1_SB_DQS_DN<6>")
	)
	(gr_poly
		(pts
			(xy 141.825472 -276.728174) (xy 141.73454 -276.619716) (xy 141.626336 -276.710648) (xy 141.622018 -276.758146)
			(xy 141.821408 -276.775672)
		)
		(stroke
			(width 0)
			(type solid)
		)
		(fill yes)
		(layer "In6.Cu")
		(net "M_K_CPU1_SB_DQS_DN<5>")
	)
	(gr_poly
		(pts
			(xy 141.83614 -291.30879) (xy 141.745208 -291.200332) (xy 141.637004 -291.291264) (xy 141.632686 -291.338762)
			(xy 141.832076 -291.356288)
		)
		(stroke
			(width 0)
			(type solid)
		)
		(fill yes)
		(layer "In6.Cu")
		(net "M_K_CPU1_SB_DQS_DN<8>")
	)
	(gr_poly
		(pts
			(xy 141.83614 -271.8689) (xy 141.745208 -271.760442) (xy 141.637004 -271.851374) (xy 141.632686 -271.898872)
			(xy 141.832076 -271.916144)
		)
		(stroke
			(width 0)
			(type solid)
		)
		(fill yes)
		(layer "In6.Cu")
		(net "M_K_CPU1_SB_DQS_DN<4>")
	)
	(gr_poly
		(pts
			(xy 141.954504 -251.976382) (xy 141.854428 -251.876306) (xy 141.754352 -251.976382) (xy 141.754352 -252.020832)
			(xy 141.954504 -252.020832)
		)
		(stroke
			(width 0)
			(type solid)
		)
		(fill yes)
		(layer "In6.Cu")
		(net "M_K_CPU1_SA_CS_N<1>")
	)
	(gr_poly
		(pts
			(xy 141.954758 -255.216406) (xy 141.854682 -255.11633) (xy 141.754606 -255.216406) (xy 141.754606 -255.260856)
			(xy 141.954758 -255.260856)
		)
		(stroke
			(width 0)
			(type solid)
		)
		(fill yes)
		(layer "In6.Cu")
		(net "M_K_CPU1_SA_CA<6>")
	)
	(gr_poly
		(pts
			(xy 141.954758 -253.596394) (xy 141.854682 -253.496318) (xy 141.754606 -253.596394) (xy 141.754606 -253.640844)
			(xy 141.954758 -253.640844)
		)
		(stroke
			(width 0)
			(type solid)
		)
		(fill yes)
		(layer "In6.Cu")
		(net "M_K_CPU1_SA_CA<2>")
	)
	(gr_poly
		(pts
			(xy 141.954758 -250.35637) (xy 141.854682 -250.256294) (xy 141.754606 -250.35637) (xy 141.754606 -250.40082)
			(xy 141.954758 -250.40082)
		)
		(stroke
			(width 0)
			(type solid)
		)
		(fill yes)
		(layer "In6.Cu")
		(net "M_K_CPU1_ALERT_R_N")
	)
	(gr_poly
		(pts
			(xy 141.954758 -248.736358) (xy 141.854682 -248.636282) (xy 141.754606 -248.736358) (xy 141.754606 -248.780808)
			(xy 141.954758 -248.780808)
		)
		(stroke
			(width 0)
			(type solid)
		)
		(fill yes)
		(layer "In6.Cu")
		(net "M_K_CPU1_SA_CB<5>")
	)
	(gr_poly
		(pts
			(xy 141.954758 -247.116092) (xy 141.854682 -247.01627) (xy 141.754606 -247.116092) (xy 141.754606 -247.163844)
			(xy 141.954758 -247.163844)
		)
		(stroke
			(width 0)
			(type solid)
		)
		(fill yes)
		(layer "In6.Cu")
		(net "M_K_CPU1_SA_DQS_DN<9>")
	)
	(gr_poly
		(pts
			(xy 141.954758 -245.496334) (xy 141.854682 -245.396258) (xy 141.754606 -245.496334) (xy 141.754606 -245.540784)
			(xy 141.954758 -245.540784)
		)
		(stroke
			(width 0)
			(type solid)
		)
		(fill yes)
		(layer "In6.Cu")
		(net "M_K_CPU1_SA_CB<1>")
	)
	(gr_poly
		(pts
			(xy 141.954758 -243.876322) (xy 141.854682 -243.776246) (xy 141.754606 -243.876322) (xy 141.754606 -243.920772)
			(xy 141.954758 -243.920772)
		)
		(stroke
			(width 0)
			(type solid)
		)
		(fill yes)
		(layer "In6.Cu")
		(net "M_K_CPU1_SA_DQ<29>")
	)
	(gr_poly
		(pts
			(xy 141.954758 -242.256056) (xy 141.854682 -242.156234) (xy 141.754606 -242.256056) (xy 141.754606 -242.303808)
			(xy 141.954758 -242.303808)
		)
		(stroke
			(width 0)
			(type solid)
		)
		(fill yes)
		(layer "In6.Cu")
		(net "M_K_CPU1_SA_DQS_DN<8>")
	)
	(gr_poly
		(pts
			(xy 141.954758 -240.636298) (xy 141.854682 -240.536222) (xy 141.754606 -240.636298) (xy 141.754606 -240.680748)
			(xy 141.954758 -240.680748)
		)
		(stroke
			(width 0)
			(type solid)
		)
		(fill yes)
		(layer "In6.Cu")
		(net "M_K_CPU1_SA_DQ<25>")
	)
	(gr_poly
		(pts
			(xy 141.954758 -239.016286) (xy 141.854682 -238.91621) (xy 141.754606 -239.016286) (xy 141.754606 -239.060736)
			(xy 141.954758 -239.060736)
		)
		(stroke
			(width 0)
			(type solid)
		)
		(fill yes)
		(layer "In6.Cu")
		(net "M_K_CPU1_SA_DQ<21>")
	)
	(gr_poly
		(pts
			(xy 141.954758 -237.39602) (xy 141.854682 -237.296198) (xy 141.754606 -237.39602) (xy 141.754606 -237.443772)
			(xy 141.954758 -237.443772)
		)
		(stroke
			(width 0)
			(type solid)
		)
		(fill yes)
		(layer "In6.Cu")
		(net "M_K_CPU1_SA_DQS_DN<7>")
	)
	(gr_poly
		(pts
			(xy 141.954758 -235.776262) (xy 141.854682 -235.676186) (xy 141.754606 -235.776262) (xy 141.754606 -235.820712)
			(xy 141.954758 -235.820712)
		)
		(stroke
			(width 0)
			(type solid)
		)
		(fill yes)
		(layer "In6.Cu")
		(net "M_K_CPU1_SA_DQ<17>")
	)
	(gr_poly
		(pts
			(xy 141.954758 -234.15625) (xy 141.854682 -234.056174) (xy 141.754606 -234.15625) (xy 141.754606 -234.2007)
			(xy 141.954758 -234.2007)
		)
		(stroke
			(width 0)
			(type solid)
		)
		(fill yes)
		(layer "In6.Cu")
		(net "M_K_CPU1_SA_DQ<13>")
	)
	(gr_poly
		(pts
			(xy 141.954758 -232.535984) (xy 141.854682 -232.436162) (xy 141.754606 -232.535984) (xy 141.754606 -232.583736)
			(xy 141.954758 -232.583736)
		)
		(stroke
			(width 0)
			(type solid)
		)
		(fill yes)
		(layer "In6.Cu")
		(net "M_K_CPU1_SA_DQS_DN<6>")
	)
	(gr_poly
		(pts
			(xy 141.954758 -230.916226) (xy 141.854682 -230.81615) (xy 141.754606 -230.916226) (xy 141.754606 -230.960676)
			(xy 141.954758 -230.960676)
		)
		(stroke
			(width 0)
			(type solid)
		)
		(fill yes)
		(layer "In6.Cu")
		(net "M_K_CPU1_SA_DQ<9>")
	)
	(gr_poly
		(pts
			(xy 141.954758 -229.296214) (xy 141.854682 -229.196138) (xy 141.754606 -229.296214) (xy 141.754606 -229.340664)
			(xy 141.954758 -229.340664)
		)
		(stroke
			(width 0)
			(type solid)
		)
		(fill yes)
		(layer "In6.Cu")
		(net "M_K_CPU1_SA_DQ<5>")
	)
	(gr_poly
		(pts
			(xy 141.954758 -227.676202) (xy 141.854682 -227.57638) (xy 141.754606 -227.676202) (xy 141.754606 -227.723954)
			(xy 141.954758 -227.723954)
		)
		(stroke
			(width 0)
			(type solid)
		)
		(fill yes)
		(layer "In6.Cu")
		(net "M_K_CPU1_SA_DQS_DN<5>")
	)
	(gr_poly
		(pts
			(xy 141.954758 -226.056444) (xy 141.854682 -225.956368) (xy 141.754606 -226.056444) (xy 141.754606 -226.100894)
			(xy 141.954758 -226.100894)
		)
		(stroke
			(width 0)
			(type solid)
		)
		(fill yes)
		(layer "In6.Cu")
		(net "M_K_CPU1_SA_DQ<1>")
	)
	(gr_poly
		(pts
			(xy 142.254732 -293.32428) (xy 142.254732 -293.27983) (xy 142.05458 -293.27983) (xy 142.05458 -293.32428)
			(xy 142.154656 -293.424356)
		)
		(stroke
			(width 0)
			(type solid)
		)
		(fill yes)
		(layer "In6.Cu")
		(net "M_K_CPU1_SB_DQ<31>")
	)
	(gr_poly
		(pts
			(xy 142.254732 -291.704522) (xy 142.254732 -291.65677) (xy 142.05458 -291.65677) (xy 142.05458 -291.704522)
			(xy 142.154656 -291.804344)
		)
		(stroke
			(width 0)
			(type solid)
		)
		(fill yes)
		(layer "In6.Cu")
		(net "M_K_CPU1_SB_DQS_DP<8>")
	)
	(gr_poly
		(pts
			(xy 142.254732 -290.084256) (xy 142.254732 -290.039806) (xy 142.05458 -290.039806) (xy 142.05458 -290.084256)
			(xy 142.154656 -290.184332)
		)
		(stroke
			(width 0)
			(type solid)
		)
		(fill yes)
		(layer "In6.Cu")
		(net "M_K_CPU1_SB_DQ<27>")
	)
	(gr_poly
		(pts
			(xy 142.254732 -288.464498) (xy 142.254732 -288.420048) (xy 142.05458 -288.420048) (xy 142.05458 -288.464498)
			(xy 142.154656 -288.564574)
		)
		(stroke
			(width 0)
			(type solid)
		)
		(fill yes)
		(layer "In6.Cu")
		(net "M_K_CPU1_SB_DQ<23>")
	)
	(gr_poly
		(pts
			(xy 142.254732 -286.844486) (xy 142.254732 -286.796734) (xy 142.05458 -286.796734) (xy 142.05458 -286.844486)
			(xy 142.154656 -286.944562)
		)
		(stroke
			(width 0)
			(type solid)
		)
		(fill yes)
		(layer "In6.Cu")
		(net "M_K_CPU1_SB_DQS_DP<7>")
	)
	(gr_poly
		(pts
			(xy 142.254732 -285.224474) (xy 142.254732 -285.180024) (xy 142.05458 -285.180024) (xy 142.05458 -285.224474)
			(xy 142.154656 -285.32455)
		)
		(stroke
			(width 0)
			(type solid)
		)
		(fill yes)
		(layer "In6.Cu")
		(net "M_K_CPU1_SB_DQ<19>")
	)
	(gr_poly
		(pts
			(xy 142.254732 -283.604462) (xy 142.254732 -283.560012) (xy 142.05458 -283.560012) (xy 142.05458 -283.604462)
			(xy 142.154656 -283.704538)
		)
		(stroke
			(width 0)
			(type solid)
		)
		(fill yes)
		(layer "In6.Cu")
		(net "M_K_CPU1_SB_DQ<15>")
	)
	(gr_poly
		(pts
			(xy 142.254732 -281.984704) (xy 142.254732 -281.936952) (xy 142.05458 -281.936952) (xy 142.05458 -281.984704)
			(xy 142.154656 -282.084526)
		)
		(stroke
			(width 0)
			(type solid)
		)
		(fill yes)
		(layer "In6.Cu")
		(net "M_K_CPU1_SB_DQS_DP<6>")
	)
	(gr_poly
		(pts
			(xy 142.254732 -280.364438) (xy 142.254732 -280.319988) (xy 142.05458 -280.319988) (xy 142.05458 -280.364438)
			(xy 142.154656 -280.464514)
		)
		(stroke
			(width 0)
			(type solid)
		)
		(fill yes)
		(layer "In6.Cu")
		(net "M_K_CPU1_SB_DQ<11>")
	)
	(gr_poly
		(pts
			(xy 142.254732 -278.744426) (xy 142.254732 -278.699976) (xy 142.05458 -278.699976) (xy 142.05458 -278.744426)
			(xy 142.154656 -278.844502)
		)
		(stroke
			(width 0)
			(type solid)
		)
		(fill yes)
		(layer "In6.Cu")
		(net "M_K_CPU1_SB_DQ<7>")
	)
	(gr_poly
		(pts
			(xy 142.254732 -277.124668) (xy 142.254732 -277.076916) (xy 142.05458 -277.076916) (xy 142.05458 -277.124668)
			(xy 142.154656 -277.22449)
		)
		(stroke
			(width 0)
			(type solid)
		)
		(fill yes)
		(layer "In6.Cu")
		(net "M_K_CPU1_SB_DQS_DP<5>")
	)
	(gr_poly
		(pts
			(xy 142.254732 -275.504402) (xy 142.254732 -275.459952) (xy 142.05458 -275.459952) (xy 142.05458 -275.504402)
			(xy 142.154656 -275.604478)
		)
		(stroke
			(width 0)
			(type solid)
		)
		(fill yes)
		(layer "In6.Cu")
		(net "M_K_CPU1_SB_DQ<3>")
	)
	(gr_poly
		(pts
			(xy 142.254732 -273.88439) (xy 142.254732 -273.83994) (xy 142.05458 -273.83994) (xy 142.05458 -273.88439)
			(xy 142.154656 -273.984466)
		)
		(stroke
			(width 0)
			(type solid)
		)
		(fill yes)
		(layer "In6.Cu")
		(net "M_K_CPU1_SB_CB<3>")
	)
	(gr_poly
		(pts
			(xy 142.254732 -272.264632) (xy 142.254732 -272.21688) (xy 142.05458 -272.21688) (xy 142.05458 -272.264632)
			(xy 142.154656 -272.364454)
		)
		(stroke
			(width 0)
			(type solid)
		)
		(fill yes)
		(layer "In6.Cu")
		(net "M_K_CPU1_SB_DQS_DP<4>")
	)
	(gr_poly
		(pts
			(xy 142.254732 -270.644366) (xy 142.254732 -270.599916) (xy 142.05458 -270.599916) (xy 142.05458 -270.644366)
			(xy 142.154656 -270.744442)
		)
		(stroke
			(width 0)
			(type solid)
		)
		(fill yes)
		(layer "In6.Cu")
		(net "M_K_CPU1_SB_CB<7>")
	)
	(gr_poly
		(pts
			(xy 142.254732 -265.78433) (xy 142.254732 -265.73988) (xy 142.05458 -265.73988) (xy 142.05458 -265.78433)
			(xy 142.154656 -265.884406)
		)
		(stroke
			(width 0)
			(type solid)
		)
		(fill yes)
		(layer "In6.Cu")
		(net "M_K_CPU1_SB_CS_N<0>")
	)
	(gr_poly
		(pts
			(xy 142.254732 -264.164318) (xy 142.254732 -264.119868) (xy 142.05458 -264.119868) (xy 142.05458 -264.164318)
			(xy 142.154656 -264.264394)
		)
		(stroke
			(width 0)
			(type solid)
		)
		(fill yes)
		(layer "In6.Cu")
		(net "M_K_CPU1_SB_CA<5>")
	)
	(gr_poly
		(pts
			(xy 142.254732 -262.544306) (xy 142.254732 -262.499856) (xy 142.05458 -262.499856) (xy 142.05458 -262.544306)
			(xy 142.154656 -262.644382)
		)
		(stroke
			(width 0)
			(type solid)
		)
		(fill yes)
		(layer "In6.Cu")
		(net "M_K_CPU1_SB_CA<1>")
	)
	(gr_poly
		(pts
			(xy 142.424912 -255.622552) (xy 142.424912 -255.578102) (xy 142.22476 -255.578102) (xy 142.22476 -255.622552)
			(xy 142.324836 -255.722628)
		)
		(stroke
			(width 0)
			(type solid)
		)
		(fill yes)
		(layer "In6.Cu")
		(net "M_K_CPU1_SA_PAR")
	)
	(gr_poly
		(pts
			(xy 142.424912 -254.00254) (xy 142.424912 -253.95809) (xy 142.22476 -253.95809) (xy 142.22476 -254.00254)
			(xy 142.324836 -254.102616)
		)
		(stroke
			(width 0)
			(type solid)
		)
		(fill yes)
		(layer "In6.Cu")
		(net "M_K_CPU1_SA_CA<3>")
	)
	(gr_poly
		(pts
			(xy 142.424912 -250.762516) (xy 142.424912 -250.718066) (xy 142.22476 -250.718066) (xy 142.22476 -250.762516)
			(xy 142.324836 -250.862592)
		)
		(stroke
			(width 0)
			(type solid)
		)
		(fill yes)
		(layer "In6.Cu")
		(net "M_K_CPU1_RESET_N")
	)
	(gr_poly
		(pts
			(xy 142.424912 -249.142504) (xy 142.424912 -249.098054) (xy 142.22476 -249.098054) (xy 142.22476 -249.142504)
			(xy 142.324836 -249.24258)
		)
		(stroke
			(width 0)
			(type solid)
		)
		(fill yes)
		(layer "In6.Cu")
		(net "M_K_CPU1_SA_CB<7>")
	)
	(gr_poly
		(pts
			(xy 142.424912 -247.522746) (xy 142.424912 -247.474994) (xy 142.22476 -247.474994) (xy 142.22476 -247.522746)
			(xy 142.324836 -247.622568)
		)
		(stroke
			(width 0)
			(type solid)
		)
		(fill yes)
		(layer "In6.Cu")
		(net "M_K_CPU1_SA_DQS_DP<9>")
	)
	(gr_poly
		(pts
			(xy 142.424912 -245.90248) (xy 142.424912 -245.85803) (xy 142.22476 -245.85803) (xy 142.22476 -245.90248)
			(xy 142.324836 -246.002556)
		)
		(stroke
			(width 0)
			(type solid)
		)
		(fill yes)
		(layer "In6.Cu")
		(net "M_K_CPU1_SA_CB<3>")
	)
	(gr_poly
		(pts
			(xy 142.424912 -244.282468) (xy 142.424912 -244.238018) (xy 142.22476 -244.238018) (xy 142.22476 -244.282468)
			(xy 142.324836 -244.382544)
		)
		(stroke
			(width 0)
			(type solid)
		)
		(fill yes)
		(layer "In6.Cu")
		(net "M_K_CPU1_SA_DQ<31>")
	)
	(gr_poly
		(pts
			(xy 142.424912 -242.66271) (xy 142.424912 -242.614958) (xy 142.22476 -242.614958) (xy 142.22476 -242.66271)
			(xy 142.324836 -242.762532)
		)
		(stroke
			(width 0)
			(type solid)
		)
		(fill yes)
		(layer "In6.Cu")
		(net "M_K_CPU1_SA_DQS_DP<8>")
	)
	(gr_poly
		(pts
			(xy 142.424912 -241.042444) (xy 142.424912 -240.997994) (xy 142.22476 -240.997994) (xy 142.22476 -241.042444)
			(xy 142.324836 -241.14252)
		)
		(stroke
			(width 0)
			(type solid)
		)
		(fill yes)
		(layer "In6.Cu")
		(net "M_K_CPU1_SA_DQ<27>")
	)
	(gr_poly
		(pts
			(xy 142.424912 -239.422432) (xy 142.424912 -239.377982) (xy 142.22476 -239.377982) (xy 142.22476 -239.422432)
			(xy 142.324836 -239.522508)
		)
		(stroke
			(width 0)
			(type solid)
		)
		(fill yes)
		(layer "In6.Cu")
		(net "M_K_CPU1_SA_DQ<23>")
	)
	(gr_poly
		(pts
			(xy 142.424912 -237.802674) (xy 142.424912 -237.754922) (xy 142.22476 -237.754922) (xy 142.22476 -237.802674)
			(xy 142.324836 -237.902496)
		)
		(stroke
			(width 0)
			(type solid)
		)
		(fill yes)
		(layer "In6.Cu")
		(net "M_K_CPU1_SA_DQS_DP<7>")
	)
	(gr_poly
		(pts
			(xy 142.424912 -236.182408) (xy 142.424912 -236.137958) (xy 142.22476 -236.137958) (xy 142.22476 -236.182408)
			(xy 142.324836 -236.282484)
		)
		(stroke
			(width 0)
			(type solid)
		)
		(fill yes)
		(layer "In6.Cu")
		(net "M_K_CPU1_SA_DQ<19>")
	)
	(gr_poly
		(pts
			(xy 142.424912 -234.562396) (xy 142.424912 -234.517946) (xy 142.22476 -234.517946) (xy 142.22476 -234.562396)
			(xy 142.324836 -234.662472)
		)
		(stroke
			(width 0)
			(type solid)
		)
		(fill yes)
		(layer "In6.Cu")
		(net "M_K_CPU1_SA_DQ<15>")
	)
	(gr_poly
		(pts
			(xy 142.424912 -232.942638) (xy 142.424912 -232.894886) (xy 142.22476 -232.894886) (xy 142.22476 -232.942638)
			(xy 142.324836 -233.04246)
		)
		(stroke
			(width 0)
			(type solid)
		)
		(fill yes)
		(layer "In6.Cu")
		(net "M_K_CPU1_SA_DQS_DP<6>")
	)
	(gr_poly
		(pts
			(xy 142.424912 -231.322626) (xy 142.424912 -231.278176) (xy 142.22476 -231.278176) (xy 142.22476 -231.322626)
			(xy 142.324836 -231.422702)
		)
		(stroke
			(width 0)
			(type solid)
		)
		(fill yes)
		(layer "In6.Cu")
		(net "M_K_CPU1_SA_DQ<11>")
	)
	(gr_poly
		(pts
			(xy 142.424912 -229.702614) (xy 142.424912 -229.658164) (xy 142.22476 -229.658164) (xy 142.22476 -229.702614)
			(xy 142.324836 -229.80269)
		)
		(stroke
			(width 0)
			(type solid)
		)
		(fill yes)
		(layer "In6.Cu")
		(net "M_K_CPU1_SA_DQ<7>")
	)
	(gr_poly
		(pts
			(xy 142.424912 -228.082856) (xy 142.424912 -228.035104) (xy 142.22476 -228.035104) (xy 142.22476 -228.082856)
			(xy 142.324836 -228.182678)
		)
		(stroke
			(width 0)
			(type solid)
		)
		(fill yes)
		(layer "In6.Cu")
		(net "M_K_CPU1_SA_DQS_DP<5>")
	)
	(gr_poly
		(pts
			(xy 142.424912 -226.46259) (xy 142.424912 -226.41814) (xy 142.22476 -226.41814) (xy 142.22476 -226.46259)
			(xy 142.324836 -226.562666)
		)
		(stroke
			(width 0)
			(type solid)
		)
		(fill yes)
		(layer "In6.Cu")
		(net "M_K_CPU1_SA_DQ<3>")
	)
	(gr_poly
		(pts
			(xy 142.724886 -292.918134) (xy 142.62481 -292.818058) (xy 142.524734 -292.918134) (xy 142.524734 -292.962584)
			(xy 142.724886 -292.962584)
		)
		(stroke
			(width 0)
			(type solid)
		)
		(fill yes)
		(layer "In6.Cu")
		(net "M_K_CPU1_SB_DQ<29>")
	)
	(gr_poly
		(pts
			(xy 142.724886 -291.297868) (xy 142.62481 -291.198046) (xy 142.524734 -291.297868) (xy 142.524734 -291.34562)
			(xy 142.724886 -291.34562)
		)
		(stroke
			(width 0)
			(type solid)
		)
		(fill yes)
		(layer "In6.Cu")
		(net "M_K_CPU1_SB_DQS_DN<8>")
	)
	(gr_poly
		(pts
			(xy 142.724886 -289.67811) (xy 142.62481 -289.578034) (xy 142.524734 -289.67811) (xy 142.524734 -289.72256)
			(xy 142.724886 -289.72256)
		)
		(stroke
			(width 0)
			(type solid)
		)
		(fill yes)
		(layer "In6.Cu")
		(net "M_K_CPU1_SB_DQ<25>")
	)
	(gr_poly
		(pts
			(xy 142.724886 -288.058098) (xy 142.62481 -287.958022) (xy 142.524734 -288.058098) (xy 142.524734 -288.102548)
			(xy 142.724886 -288.102548)
		)
		(stroke
			(width 0)
			(type solid)
		)
		(fill yes)
		(layer "In6.Cu")
		(net "M_K_CPU1_SB_DQ<21>")
	)
	(gr_poly
		(pts
			(xy 142.724886 -286.438086) (xy 142.62481 -286.33801) (xy 142.524734 -286.438086) (xy 142.524734 -286.485838)
			(xy 142.724886 -286.485838)
		)
		(stroke
			(width 0)
			(type solid)
		)
		(fill yes)
		(layer "In6.Cu")
		(net "M_K_CPU1_SB_DQS_DN<7>")
	)
	(gr_poly
		(pts
			(xy 142.724886 -284.818328) (xy 142.62481 -284.718252) (xy 142.524734 -284.818328) (xy 142.524734 -284.862778)
			(xy 142.724886 -284.862778)
		)
		(stroke
			(width 0)
			(type solid)
		)
		(fill yes)
		(layer "In6.Cu")
		(net "M_K_CPU1_SB_DQ<17>")
	)
	(gr_poly
		(pts
			(xy 142.724886 -283.198316) (xy 142.62481 -283.09824) (xy 142.524734 -283.198316) (xy 142.524734 -283.242766)
			(xy 142.724886 -283.242766)
		)
		(stroke
			(width 0)
			(type solid)
		)
		(fill yes)
		(layer "In6.Cu")
		(net "M_K_CPU1_SB_DQ<13>")
	)
	(gr_poly
		(pts
			(xy 142.724886 -281.57805) (xy 142.62481 -281.478228) (xy 142.524734 -281.57805) (xy 142.524734 -281.625802)
			(xy 142.724886 -281.625802)
		)
		(stroke
			(width 0)
			(type solid)
		)
		(fill yes)
		(layer "In6.Cu")
		(net "M_K_CPU1_SB_DQS_DN<6>")
	)
	(gr_poly
		(pts
			(xy 142.724886 -279.958292) (xy 142.62481 -279.858216) (xy 142.524734 -279.958292) (xy 142.524734 -280.002742)
			(xy 142.724886 -280.002742)
		)
		(stroke
			(width 0)
			(type solid)
		)
		(fill yes)
		(layer "In6.Cu")
		(net "M_K_CPU1_SB_DQ<9>")
	)
	(gr_poly
		(pts
			(xy 142.724886 -278.33828) (xy 142.62481 -278.238204) (xy 142.524734 -278.33828) (xy 142.524734 -278.38273)
			(xy 142.724886 -278.38273)
		)
		(stroke
			(width 0)
			(type solid)
		)
		(fill yes)
		(layer "In6.Cu")
		(net "M_K_CPU1_SB_DQ<5>")
	)
	(gr_poly
		(pts
			(xy 142.724886 -276.718014) (xy 142.62481 -276.618192) (xy 142.524734 -276.718014) (xy 142.524734 -276.765766)
			(xy 142.724886 -276.765766)
		)
		(stroke
			(width 0)
			(type solid)
		)
		(fill yes)
		(layer "In6.Cu")
		(net "M_K_CPU1_SB_DQS_DN<5>")
	)
	(gr_poly
		(pts
			(xy 142.724886 -275.098256) (xy 142.62481 -274.99818) (xy 142.524734 -275.098256) (xy 142.524734 -275.142706)
			(xy 142.724886 -275.142706)
		)
		(stroke
			(width 0)
			(type solid)
		)
		(fill yes)
		(layer "In6.Cu")
		(net "M_K_CPU1_SB_DQ<1>")
	)
	(gr_poly
		(pts
			(xy 142.724886 -273.478244) (xy 142.62481 -273.378168) (xy 142.524734 -273.478244) (xy 142.524734 -273.522694)
			(xy 142.724886 -273.522694)
		)
		(stroke
			(width 0)
			(type solid)
		)
		(fill yes)
		(layer "In6.Cu")
		(net "M_K_CPU1_SB_CB<1>")
	)
	(gr_poly
		(pts
			(xy 142.724886 -271.857978) (xy 142.62481 -271.758156) (xy 142.524734 -271.857978) (xy 142.524734 -271.90573)
			(xy 142.724886 -271.90573)
		)
		(stroke
			(width 0)
			(type solid)
		)
		(fill yes)
		(layer "In6.Cu")
		(net "M_K_CPU1_SB_DQS_DN<4>")
	)
	(gr_poly
		(pts
			(xy 142.724886 -270.23822) (xy 142.62481 -270.138144) (xy 142.524734 -270.23822) (xy 142.524734 -270.28267)
			(xy 142.724886 -270.28267)
		)
		(stroke
			(width 0)
			(type solid)
		)
		(fill yes)
		(layer "In6.Cu")
		(net "M_K_CPU1_SB_CB<5>")
	)
	(gr_poly
		(pts
			(xy 142.724886 -266.998196) (xy 142.62481 -266.89812) (xy 142.524734 -266.998196) (xy 142.524734 -267.042646)
			(xy 142.724886 -267.042646)
		)
		(stroke
			(width 0)
			(type solid)
		)
		(fill yes)
		(layer "In6.Cu")
		(net "M_K_CPU1_SA_RSP<0>")
	)
	(gr_poly
		(pts
			(xy 142.724886 -265.378184) (xy 142.62481 -265.278108) (xy 142.524734 -265.378184) (xy 142.524734 -265.422634)
			(xy 142.724886 -265.422634)
		)
		(stroke
			(width 0)
			(type solid)
		)
		(fill yes)
		(layer "In6.Cu")
		(net "M_K_CPU1_SB_PAR")
	)
	(gr_poly
		(pts
			(xy 142.724886 -263.758172) (xy 142.62481 -263.658096) (xy 142.524734 -263.758172) (xy 142.524734 -263.802622)
			(xy 142.724886 -263.802622)
		)
		(stroke
			(width 0)
			(type solid)
		)
		(fill yes)
		(layer "In6.Cu")
		(net "M_K_CPU1_SB_CA<4>")
	)
	(gr_poly
		(pts
			(xy 142.724886 -262.13816) (xy 142.62481 -262.038084) (xy 142.524734 -262.13816) (xy 142.524734 -262.18261)
			(xy 142.724886 -262.18261)
		)
		(stroke
			(width 0)
			(type solid)
		)
		(fill yes)
		(layer "In6.Cu")
		(net "M_K_CPU1_SB_CA<0>")
	)
	(gr_poly
		(pts
			(xy 142.894558 -251.976382) (xy 142.794482 -251.876306) (xy 142.694406 -251.976382) (xy 142.694406 -252.020832)
			(xy 142.894558 -252.020832)
		)
		(stroke
			(width 0)
			(type solid)
		)
		(fill yes)
		(layer "In6.Cu")
		(net "M_K_CPU1_SA_CS_N<1>")
	)
	(gr_poly
		(pts
			(xy 142.894812 -255.216406) (xy 142.794736 -255.11633) (xy 142.69466 -255.216406) (xy 142.69466 -255.260856)
			(xy 142.894812 -255.260856)
		)
		(stroke
			(width 0)
			(type solid)
		)
		(fill yes)
		(layer "In6.Cu")
		(net "M_K_CPU1_SA_CA<6>")
	)
	(gr_poly
		(pts
			(xy 142.894812 -253.596394) (xy 142.794736 -253.496318) (xy 142.69466 -253.596394) (xy 142.69466 -253.640844)
			(xy 142.894812 -253.640844)
		)
		(stroke
			(width 0)
			(type solid)
		)
		(fill yes)
		(layer "In6.Cu")
		(net "M_K_CPU1_SA_CA<2>")
	)
	(gr_poly
		(pts
			(xy 142.894812 -250.35637) (xy 142.794736 -250.256294) (xy 142.69466 -250.35637) (xy 142.69466 -250.40082)
			(xy 142.894812 -250.40082)
		)
		(stroke
			(width 0)
			(type solid)
		)
		(fill yes)
		(layer "In6.Cu")
		(net "M_K_CPU1_ALERT_R_N")
	)
	(gr_poly
		(pts
			(xy 142.894812 -248.736358) (xy 142.794736 -248.636282) (xy 142.69466 -248.736358) (xy 142.69466 -248.780808)
			(xy 142.894812 -248.780808)
		)
		(stroke
			(width 0)
			(type solid)
		)
		(fill yes)
		(layer "In6.Cu")
		(net "M_K_CPU1_SA_CB<5>")
	)
	(gr_poly
		(pts
			(xy 142.894812 -247.116092) (xy 142.794736 -247.01627) (xy 142.69466 -247.116092) (xy 142.69466 -247.163844)
			(xy 142.894812 -247.163844)
		)
		(stroke
			(width 0)
			(type solid)
		)
		(fill yes)
		(layer "In6.Cu")
		(net "M_K_CPU1_SA_DQS_DN<9>")
	)
	(gr_poly
		(pts
			(xy 142.894812 -245.496334) (xy 142.794736 -245.396258) (xy 142.69466 -245.496334) (xy 142.69466 -245.540784)
			(xy 142.894812 -245.540784)
		)
		(stroke
			(width 0)
			(type solid)
		)
		(fill yes)
		(layer "In6.Cu")
		(net "M_K_CPU1_SA_CB<1>")
	)
	(gr_poly
		(pts
			(xy 142.894812 -243.876322) (xy 142.794736 -243.776246) (xy 142.69466 -243.876322) (xy 142.69466 -243.920772)
			(xy 142.894812 -243.920772)
		)
		(stroke
			(width 0)
			(type solid)
		)
		(fill yes)
		(layer "In6.Cu")
		(net "M_K_CPU1_SA_DQ<29>")
	)
	(gr_poly
		(pts
			(xy 142.894812 -242.256056) (xy 142.794736 -242.156234) (xy 142.69466 -242.256056) (xy 142.69466 -242.303808)
			(xy 142.894812 -242.303808)
		)
		(stroke
			(width 0)
			(type solid)
		)
		(fill yes)
		(layer "In6.Cu")
		(net "M_K_CPU1_SA_DQS_DN<8>")
	)
	(gr_poly
		(pts
			(xy 142.894812 -240.636298) (xy 142.794736 -240.536222) (xy 142.69466 -240.636298) (xy 142.69466 -240.680748)
			(xy 142.894812 -240.680748)
		)
		(stroke
			(width 0)
			(type solid)
		)
		(fill yes)
		(layer "In6.Cu")
		(net "M_K_CPU1_SA_DQ<25>")
	)
	(gr_poly
		(pts
			(xy 142.894812 -239.016286) (xy 142.794736 -238.91621) (xy 142.69466 -239.016286) (xy 142.69466 -239.060736)
			(xy 142.894812 -239.060736)
		)
		(stroke
			(width 0)
			(type solid)
		)
		(fill yes)
		(layer "In6.Cu")
		(net "M_K_CPU1_SA_DQ<21>")
	)
	(gr_poly
		(pts
			(xy 142.894812 -237.39602) (xy 142.794736 -237.296198) (xy 142.69466 -237.39602) (xy 142.69466 -237.443772)
			(xy 142.894812 -237.443772)
		)
		(stroke
			(width 0)
			(type solid)
		)
		(fill yes)
		(layer "In6.Cu")
		(net "M_K_CPU1_SA_DQS_DN<7>")
	)
	(gr_poly
		(pts
			(xy 142.894812 -235.776262) (xy 142.794736 -235.676186) (xy 142.69466 -235.776262) (xy 142.69466 -235.820712)
			(xy 142.894812 -235.820712)
		)
		(stroke
			(width 0)
			(type solid)
		)
		(fill yes)
		(layer "In6.Cu")
		(net "M_K_CPU1_SA_DQ<17>")
	)
	(gr_poly
		(pts
			(xy 142.894812 -234.15625) (xy 142.794736 -234.056174) (xy 142.69466 -234.15625) (xy 142.69466 -234.2007)
			(xy 142.894812 -234.2007)
		)
		(stroke
			(width 0)
			(type solid)
		)
		(fill yes)
		(layer "In6.Cu")
		(net "M_K_CPU1_SA_DQ<13>")
	)
	(gr_poly
		(pts
			(xy 142.894812 -232.535984) (xy 142.794736 -232.436162) (xy 142.69466 -232.535984) (xy 142.69466 -232.583736)
			(xy 142.894812 -232.583736)
		)
		(stroke
			(width 0)
			(type solid)
		)
		(fill yes)
		(layer "In6.Cu")
		(net "M_K_CPU1_SA_DQS_DN<6>")
	)
	(gr_poly
		(pts
			(xy 142.894812 -230.916226) (xy 142.794736 -230.81615) (xy 142.69466 -230.916226) (xy 142.69466 -230.960676)
			(xy 142.894812 -230.960676)
		)
		(stroke
			(width 0)
			(type solid)
		)
		(fill yes)
		(layer "In6.Cu")
		(net "M_K_CPU1_SA_DQ<9>")
	)
	(gr_poly
		(pts
			(xy 142.894812 -229.296214) (xy 142.794736 -229.196138) (xy 142.69466 -229.296214) (xy 142.69466 -229.340664)
			(xy 142.894812 -229.340664)
		)
		(stroke
			(width 0)
			(type solid)
		)
		(fill yes)
		(layer "In6.Cu")
		(net "M_K_CPU1_SA_DQ<5>")
	)
	(gr_poly
		(pts
			(xy 142.894812 -227.676202) (xy 142.794736 -227.57638) (xy 142.69466 -227.676202) (xy 142.69466 -227.723954)
			(xy 142.894812 -227.723954)
		)
		(stroke
			(width 0)
			(type solid)
		)
		(fill yes)
		(layer "In6.Cu")
		(net "M_K_CPU1_SA_DQS_DN<5>")
	)
	(gr_poly
		(pts
			(xy 142.894812 -226.056444) (xy 142.794736 -225.956368) (xy 142.69466 -226.056444) (xy 142.69466 -226.100894)
			(xy 142.894812 -226.100894)
		)
		(stroke
			(width 0)
			(type solid)
		)
		(fill yes)
		(layer "In6.Cu")
		(net "M_K_CPU1_SA_DQ<1>")
	)
	(gr_poly
		(pts
			(xy 142.93342 -254.80264) (xy 142.92961 -254.758444) (xy 142.730474 -254.775716) (xy 142.734284 -254.820166)
			(xy 142.842488 -254.911098)
		)
		(stroke
			(width 0)
			(type solid)
		)
		(fill yes)
		(layer "In6.Cu")
		(net "M_K_CPU1_SA_CA<5>")
	)
	(gr_poly
		(pts
			(xy 142.93342 -253.182628) (xy 142.92961 -253.138432) (xy 142.730474 -253.155704) (xy 142.734284 -253.200154)
			(xy 142.842488 -253.291086)
		)
		(stroke
			(width 0)
			(type solid)
		)
		(fill yes)
		(layer "In6.Cu")
		(net "M_K_CPU1_SA_CA<1>")
	)
	(gr_poly
		(pts
			(xy 142.93342 -248.322592) (xy 142.92961 -248.278396) (xy 142.730474 -248.295668) (xy 142.734284 -248.340118)
			(xy 142.842488 -248.43105)
		)
		(stroke
			(width 0)
			(type solid)
		)
		(fill yes)
		(layer "In6.Cu")
		(net "M_K_CPU1_SA_CB<6>")
	)
	(gr_poly
		(pts
			(xy 142.93342 -245.082568) (xy 142.92961 -245.038372) (xy 142.730474 -245.055644) (xy 142.734284 -245.100094)
			(xy 142.842488 -245.191026)
		)
		(stroke
			(width 0)
			(type solid)
		)
		(fill yes)
		(layer "In6.Cu")
		(net "M_K_CPU1_SA_CB<2>")
	)
	(gr_poly
		(pts
			(xy 142.93342 -243.462556) (xy 142.92961 -243.41836) (xy 142.730474 -243.435632) (xy 142.734284 -243.480082)
			(xy 142.842488 -243.571014)
		)
		(stroke
			(width 0)
			(type solid)
		)
		(fill yes)
		(layer "In6.Cu")
		(net "M_K_CPU1_SA_DQ<30>")
	)
	(gr_poly
		(pts
			(xy 142.93342 -240.222532) (xy 142.92961 -240.178336) (xy 142.730474 -240.195608) (xy 142.734284 -240.240058)
			(xy 142.842488 -240.33099)
		)
		(stroke
			(width 0)
			(type solid)
		)
		(fill yes)
		(layer "In6.Cu")
		(net "M_K_CPU1_SA_DQ<26>")
	)
	(gr_poly
		(pts
			(xy 142.93342 -238.60252) (xy 142.92961 -238.558324) (xy 142.730474 -238.575596) (xy 142.734284 -238.620046)
			(xy 142.842488 -238.710978)
		)
		(stroke
			(width 0)
			(type solid)
		)
		(fill yes)
		(layer "In6.Cu")
		(net "M_K_CPU1_SA_DQ<22>")
	)
	(gr_poly
		(pts
			(xy 142.93342 -235.362496) (xy 142.92961 -235.3183) (xy 142.730474 -235.335572) (xy 142.734284 -235.380022)
			(xy 142.842488 -235.470954)
		)
		(stroke
			(width 0)
			(type solid)
		)
		(fill yes)
		(layer "In6.Cu")
		(net "M_K_CPU1_SA_DQ<18>")
	)
	(gr_poly
		(pts
			(xy 142.93342 -233.742484) (xy 142.92961 -233.698288) (xy 142.730474 -233.71556) (xy 142.734284 -233.76001)
			(xy 142.842488 -233.850942)
		)
		(stroke
			(width 0)
			(type solid)
		)
		(fill yes)
		(layer "In6.Cu")
		(net "M_K_CPU1_SA_DQ<14>")
	)
	(gr_poly
		(pts
			(xy 142.93342 -230.502714) (xy 142.92961 -230.458518) (xy 142.730474 -230.47579) (xy 142.734284 -230.52024)
			(xy 142.842488 -230.611172)
		)
		(stroke
			(width 0)
			(type solid)
		)
		(fill yes)
		(layer "In6.Cu")
		(net "M_K_CPU1_SA_DQ<10>")
	)
	(gr_poly
		(pts
			(xy 142.93342 -228.882702) (xy 142.92961 -228.838506) (xy 142.730474 -228.855778) (xy 142.734284 -228.900228)
			(xy 142.842488 -228.99116)
		)
		(stroke
			(width 0)
			(type solid)
		)
		(fill yes)
		(layer "In6.Cu")
		(net "M_K_CPU1_SA_DQ<6>")
	)
	(gr_poly
		(pts
			(xy 142.93342 -225.642678) (xy 142.92961 -225.598482) (xy 142.730474 -225.615754) (xy 142.734284 -225.660204)
			(xy 142.842488 -225.751136)
		)
		(stroke
			(width 0)
			(type solid)
		)
		(fill yes)
		(layer "In6.Cu")
		(net "M_K_CPU1_SA_DQ<2>")
	)
	(gr_poly
		(pts
			(xy 142.935452 -256.422652) (xy 142.931388 -256.375408) (xy 142.731998 -256.39268) (xy 142.736316 -256.440178)
			(xy 142.84452 -256.53111)
		)
		(stroke
			(width 0)
			(type solid)
		)
		(fill yes)
		(layer "In6.Cu")
		(net "M_K_CPU1_CLK_DN<0>")
	)
	(gr_poly
		(pts
			(xy 142.935452 -241.842544) (xy 142.931388 -241.7953) (xy 142.731998 -241.812572) (xy 142.736316 -241.86007)
			(xy 142.84452 -241.951002)
		)
		(stroke
			(width 0)
			(type solid)
		)
		(fill yes)
		(layer "In6.Cu")
		(net "M_K_CPU1_SA_DQS_DN<3>")
	)
	(gr_poly
		(pts
			(xy 142.935452 -236.982508) (xy 142.931388 -236.935264) (xy 142.731998 -236.952536) (xy 142.736316 -237.000034)
			(xy 142.84452 -237.090966)
		)
		(stroke
			(width 0)
			(type solid)
		)
		(fill yes)
		(layer "In6.Cu")
		(net "M_K_CPU1_SA_DQS_DN<2>")
	)
	(gr_poly
		(pts
			(xy 142.935452 -232.122472) (xy 142.931388 -232.075228) (xy 142.731998 -232.0925) (xy 142.736316 -232.139998)
			(xy 142.84452 -232.23093)
		)
		(stroke
			(width 0)
			(type solid)
		)
		(fill yes)
		(layer "In6.Cu")
		(net "M_K_CPU1_SA_DQS_DN<1>")
	)
	(gr_poly
		(pts
			(xy 142.94612 -246.701818) (xy 142.942056 -246.65432) (xy 142.742666 -246.671846) (xy 142.746984 -246.719344)
			(xy 142.855188 -246.810276)
		)
		(stroke
			(width 0)
			(type solid)
		)
		(fill yes)
		(layer "In6.Cu")
		(net "M_K_CPU1_SA_DQS_DN<4>")
	)
	(gr_poly
		(pts
			(xy 142.94612 -227.261928) (xy 142.942056 -227.214684) (xy 142.742666 -227.231956) (xy 142.746984 -227.279454)
			(xy 142.855188 -227.370386)
		)
		(stroke
			(width 0)
			(type solid)
		)
		(fill yes)
		(layer "In6.Cu")
		(net "M_K_CPU1_SA_DQS_DN<0>")
	)
	(gr_poly
		(pts
			(xy 143.194786 -293.32428) (xy 143.194786 -293.27983) (xy 142.994634 -293.27983) (xy 142.994634 -293.32428)
			(xy 143.09471 -293.424356)
		)
		(stroke
			(width 0)
			(type solid)
		)
		(fill yes)
		(layer "In6.Cu")
		(net "M_K_CPU1_SB_DQ<31>")
	)
	(gr_poly
		(pts
			(xy 143.194786 -291.704522) (xy 143.194786 -291.65677) (xy 142.994634 -291.65677) (xy 142.994634 -291.704522)
			(xy 143.09471 -291.804344)
		)
		(stroke
			(width 0)
			(type solid)
		)
		(fill yes)
		(layer "In6.Cu")
		(net "M_K_CPU1_SB_DQS_DP<8>")
	)
	(gr_poly
		(pts
			(xy 143.194786 -290.084256) (xy 143.194786 -290.039806) (xy 142.994634 -290.039806) (xy 142.994634 -290.084256)
			(xy 143.09471 -290.184332)
		)
		(stroke
			(width 0)
			(type solid)
		)
		(fill yes)
		(layer "In6.Cu")
		(net "M_K_CPU1_SB_DQ<27>")
	)
	(gr_poly
		(pts
			(xy 143.194786 -288.464498) (xy 143.194786 -288.420048) (xy 142.994634 -288.420048) (xy 142.994634 -288.464498)
			(xy 143.09471 -288.564574)
		)
		(stroke
			(width 0)
			(type solid)
		)
		(fill yes)
		(layer "In6.Cu")
		(net "M_K_CPU1_SB_DQ<23>")
	)
	(gr_poly
		(pts
			(xy 143.194786 -286.844486) (xy 143.194786 -286.796734) (xy 142.994634 -286.796734) (xy 142.994634 -286.844486)
			(xy 143.09471 -286.944562)
		)
		(stroke
			(width 0)
			(type solid)
		)
		(fill yes)
		(layer "In6.Cu")
		(net "M_K_CPU1_SB_DQS_DP<7>")
	)
	(gr_poly
		(pts
			(xy 143.194786 -285.224474) (xy 143.194786 -285.180024) (xy 142.994634 -285.180024) (xy 142.994634 -285.224474)
			(xy 143.09471 -285.32455)
		)
		(stroke
			(width 0)
			(type solid)
		)
		(fill yes)
		(layer "In6.Cu")
		(net "M_K_CPU1_SB_DQ<19>")
	)
	(gr_poly
		(pts
			(xy 143.194786 -283.604462) (xy 143.194786 -283.560012) (xy 142.994634 -283.560012) (xy 142.994634 -283.604462)
			(xy 143.09471 -283.704538)
		)
		(stroke
			(width 0)
			(type solid)
		)
		(fill yes)
		(layer "In6.Cu")
		(net "M_K_CPU1_SB_DQ<15>")
	)
	(gr_poly
		(pts
			(xy 143.194786 -281.984704) (xy 143.194786 -281.936952) (xy 142.994634 -281.936952) (xy 142.994634 -281.984704)
			(xy 143.09471 -282.084526)
		)
		(stroke
			(width 0)
			(type solid)
		)
		(fill yes)
		(layer "In6.Cu")
		(net "M_K_CPU1_SB_DQS_DP<6>")
	)
	(gr_poly
		(pts
			(xy 143.194786 -280.364438) (xy 143.194786 -280.319988) (xy 142.994634 -280.319988) (xy 142.994634 -280.364438)
			(xy 143.09471 -280.464514)
		)
		(stroke
			(width 0)
			(type solid)
		)
		(fill yes)
		(layer "In6.Cu")
		(net "M_K_CPU1_SB_DQ<11>")
	)
	(gr_poly
		(pts
			(xy 143.194786 -278.744426) (xy 143.194786 -278.699976) (xy 142.994634 -278.699976) (xy 142.994634 -278.744426)
			(xy 143.09471 -278.844502)
		)
		(stroke
			(width 0)
			(type solid)
		)
		(fill yes)
		(layer "In6.Cu")
		(net "M_K_CPU1_SB_DQ<7>")
	)
	(gr_poly
		(pts
			(xy 143.194786 -277.124668) (xy 143.194786 -277.076916) (xy 142.994634 -277.076916) (xy 142.994634 -277.124668)
			(xy 143.09471 -277.22449)
		)
		(stroke
			(width 0)
			(type solid)
		)
		(fill yes)
		(layer "In6.Cu")
		(net "M_K_CPU1_SB_DQS_DP<5>")
	)
	(gr_poly
		(pts
			(xy 143.194786 -275.504402) (xy 143.194786 -275.459952) (xy 142.994634 -275.459952) (xy 142.994634 -275.504402)
			(xy 143.09471 -275.604478)
		)
		(stroke
			(width 0)
			(type solid)
		)
		(fill yes)
		(layer "In6.Cu")
		(net "M_K_CPU1_SB_DQ<3>")
	)
	(gr_poly
		(pts
			(xy 143.194786 -273.88439) (xy 143.194786 -273.83994) (xy 142.994634 -273.83994) (xy 142.994634 -273.88439)
			(xy 143.09471 -273.984466)
		)
		(stroke
			(width 0)
			(type solid)
		)
		(fill yes)
		(layer "In6.Cu")
		(net "M_K_CPU1_SB_CB<3>")
	)
	(gr_poly
		(pts
			(xy 143.194786 -272.264632) (xy 143.194786 -272.21688) (xy 142.994634 -272.21688) (xy 142.994634 -272.264632)
			(xy 143.09471 -272.364454)
		)
		(stroke
			(width 0)
			(type solid)
		)
		(fill yes)
		(layer "In6.Cu")
		(net "M_K_CPU1_SB_DQS_DP<4>")
	)
	(gr_poly
		(pts
			(xy 143.194786 -270.644366) (xy 143.194786 -270.599916) (xy 142.994634 -270.599916) (xy 142.994634 -270.644366)
			(xy 143.09471 -270.744442)
		)
		(stroke
			(width 0)
			(type solid)
		)
		(fill yes)
		(layer "In6.Cu")
		(net "M_K_CPU1_SB_CB<7>")
	)
	(gr_poly
		(pts
			(xy 143.194786 -265.78433) (xy 143.194786 -265.73988) (xy 142.994634 -265.73988) (xy 142.994634 -265.78433)
			(xy 143.09471 -265.884406)
		)
		(stroke
			(width 0)
			(type solid)
		)
		(fill yes)
		(layer "In6.Cu")
		(net "M_K_CPU1_SB_CS_N<0>")
	)
	(gr_poly
		(pts
			(xy 143.194786 -264.164318) (xy 143.194786 -264.119868) (xy 142.994634 -264.119868) (xy 142.994634 -264.164318)
			(xy 143.09471 -264.264394)
		)
		(stroke
			(width 0)
			(type solid)
		)
		(fill yes)
		(layer "In6.Cu")
		(net "M_K_CPU1_SB_CA<5>")
	)
	(gr_poly
		(pts
			(xy 143.194786 -262.544306) (xy 143.194786 -262.499856) (xy 142.994634 -262.499856) (xy 142.994634 -262.544306)
			(xy 143.09471 -262.644382)
		)
		(stroke
			(width 0)
			(type solid)
		)
		(fill yes)
		(layer "In6.Cu")
		(net "M_K_CPU1_SB_CA<1>")
	)
	(gr_poly
		(pts
			(xy 143.233394 -292.118034) (xy 143.142462 -292.009576) (xy 143.034258 -292.100508) (xy 143.030194 -292.144958)
			(xy 143.229584 -292.16223)
		)
		(stroke
			(width 0)
			(type solid)
		)
		(fill yes)
		(layer "In6.Cu")
		(net "M_K_CPU1_SB_DQ<28>")
	)
	(gr_poly
		(pts
			(xy 143.233394 -288.87801) (xy 143.142462 -288.769552) (xy 143.034258 -288.860484) (xy 143.030194 -288.904934)
			(xy 143.229584 -288.922206)
		)
		(stroke
			(width 0)
			(type solid)
		)
		(fill yes)
		(layer "In6.Cu")
		(net "M_K_CPU1_SB_DQ<24>")
	)
	(gr_poly
		(pts
			(xy 143.233394 -287.257998) (xy 143.142462 -287.14954) (xy 143.034258 -287.240472) (xy 143.030194 -287.284922)
			(xy 143.229584 -287.302194)
		)
		(stroke
			(width 0)
			(type solid)
		)
		(fill yes)
		(layer "In6.Cu")
		(net "M_K_CPU1_SB_DQ<20>")
	)
	(gr_poly
		(pts
			(xy 143.233394 -284.018228) (xy 143.142462 -283.90977) (xy 143.034258 -284.000702) (xy 143.030194 -284.045152)
			(xy 143.229584 -284.062424)
		)
		(stroke
			(width 0)
			(type solid)
		)
		(fill yes)
		(layer "In6.Cu")
		(net "M_K_CPU1_SB_DQ<16>")
	)
	(gr_poly
		(pts
			(xy 143.233394 -282.398216) (xy 143.142462 -282.289758) (xy 143.034258 -282.38069) (xy 143.030194 -282.42514)
			(xy 143.229584 -282.442412)
		)
		(stroke
			(width 0)
			(type solid)
		)
		(fill yes)
		(layer "In6.Cu")
		(net "M_K_CPU1_SB_DQ<12>")
	)
	(gr_poly
		(pts
			(xy 143.233394 -279.158192) (xy 143.142462 -279.049734) (xy 143.034258 -279.140666) (xy 143.030194 -279.185116)
			(xy 143.229584 -279.202388)
		)
		(stroke
			(width 0)
			(type solid)
		)
		(fill yes)
		(layer "In6.Cu")
		(net "M_K_CPU1_SB_DQ<8>")
	)
	(gr_poly
		(pts
			(xy 143.233394 -277.53818) (xy 143.142462 -277.429722) (xy 143.034258 -277.520654) (xy 143.030194 -277.565104)
			(xy 143.229584 -277.582376)
		)
		(stroke
			(width 0)
			(type solid)
		)
		(fill yes)
		(layer "In6.Cu")
		(net "M_K_CPU1_SB_DQ<4>")
	)
	(gr_poly
		(pts
			(xy 143.233394 -274.298156) (xy 143.142462 -274.189698) (xy 143.034258 -274.28063) (xy 143.030194 -274.32508)
			(xy 143.229584 -274.342352)
		)
		(stroke
			(width 0)
			(type solid)
		)
		(fill yes)
		(layer "In6.Cu")
		(net "M_K_CPU1_SB_DQ<0>")
	)
	(gr_poly
		(pts
			(xy 143.233394 -272.678144) (xy 143.142462 -272.569686) (xy 143.034258 -272.660618) (xy 143.030194 -272.705068)
			(xy 143.229584 -272.72234)
		)
		(stroke
			(width 0)
			(type solid)
		)
		(fill yes)
		(layer "In6.Cu")
		(net "M_K_CPU1_SB_CB<0>")
	)
	(gr_poly
		(pts
			(xy 143.233394 -269.43812) (xy 143.142462 -269.329662) (xy 143.034258 -269.420594) (xy 143.030194 -269.465044)
			(xy 143.229584 -269.482316)
		)
		(stroke
			(width 0)
			(type solid)
		)
		(fill yes)
		(layer "In6.Cu")
		(net "M_K_CPU1_SB_CB<4>")
	)
	(gr_poly
		(pts
			(xy 143.233394 -267.818108) (xy 143.142462 -267.70965) (xy 143.034258 -267.800582) (xy 143.030194 -267.845032)
			(xy 143.229584 -267.862304)
		)
		(stroke
			(width 0)
			(type solid)
		)
		(fill yes)
		(layer "In6.Cu")
		(net "M_K_CPU1_SB_RSP<0>")
	)
	(gr_poly
		(pts
			(xy 143.233394 -264.578084) (xy 143.142462 -264.469626) (xy 143.034258 -264.560558) (xy 143.030194 -264.605008)
			(xy 143.229584 -264.62228)
		)
		(stroke
			(width 0)
			(type solid)
		)
		(fill yes)
		(layer "In6.Cu")
		(net "M_K_CPU1_SB_CA<6>")
	)
	(gr_poly
		(pts
			(xy 143.233394 -262.958072) (xy 143.142462 -262.849614) (xy 143.034258 -262.940546) (xy 143.030194 -262.984996)
			(xy 143.229584 -263.002268)
		)
		(stroke
			(width 0)
			(type solid)
		)
		(fill yes)
		(layer "In6.Cu")
		(net "M_K_CPU1_SB_CA<2>")
	)
	(gr_poly
		(pts
			(xy 143.235426 -285.63824) (xy 143.144494 -285.529782) (xy 143.03629 -285.620714) (xy 143.032226 -285.668212)
			(xy 143.231362 -285.685484)
		)
		(stroke
			(width 0)
			(type solid)
		)
		(fill yes)
		(layer "In6.Cu")
		(net "M_K_CPU1_SB_DQS_DP<2>")
	)
	(gr_poly
		(pts
			(xy 143.235426 -280.778204) (xy 143.144494 -280.669746) (xy 143.03629 -280.760678) (xy 143.032226 -280.808176)
			(xy 143.231362 -280.825448)
		)
		(stroke
			(width 0)
			(type solid)
		)
		(fill yes)
		(layer "In6.Cu")
		(net "M_K_CPU1_SB_DQS_DP<1>")
	)
	(gr_poly
		(pts
			(xy 143.235426 -271.058132) (xy 143.144494 -270.949674) (xy 143.03629 -271.040606) (xy 143.032226 -271.088104)
			(xy 143.231362 -271.105376)
		)
		(stroke
			(width 0)
			(type solid)
		)
		(fill yes)
		(layer "In6.Cu")
		(net "M_K_CPU1_SB_DQS_DP<9>")
	)
	(gr_poly
		(pts
			(xy 143.246094 -290.498784) (xy 143.155162 -290.390326) (xy 143.046958 -290.481258) (xy 143.04264 -290.528756)
			(xy 143.24203 -290.546028)
		)
		(stroke
			(width 0)
			(type solid)
		)
		(fill yes)
		(layer "In6.Cu")
		(net "M_K_CPU1_SB_DQS_DP<3>")
	)
	(gr_poly
		(pts
			(xy 143.246094 -275.91893) (xy 143.155162 -275.810472) (xy 143.046958 -275.901404) (xy 143.04264 -275.948902)
			(xy 143.24203 -275.966428)
		)
		(stroke
			(width 0)
			(type solid)
		)
		(fill yes)
		(layer "In6.Cu")
		(net "M_K_CPU1_SB_DQS_DP<0>")
	)
	(gr_poly
		(pts
			(xy 143.28394 -223.075754) (xy 143.245332 -223.053402) (xy 143.108934 -223.089978) (xy 143.14551 -223.22663)
			(xy 143.183864 -223.248982)
		)
		(stroke
			(width 0)
			(type solid)
		)
		(fill yes)
		(layer "In6.Cu")
		(net "M_K_CPU1_SA_DQ<0>")
	)
	(gr_poly
		(pts
			(xy 143.364712 -256.026158) (xy 143.264636 -255.926336) (xy 143.16456 -256.026158) (xy 143.16456 -256.07391)
			(xy 143.364712 -256.07391)
		)
		(stroke
			(width 0)
			(type solid)
		)
		(fill yes)
		(layer "In6.Cu")
		(net "M_K_CPU1_CLK_DP<0>")
	)
	(gr_poly
		(pts
			(xy 143.364712 -255.622552) (xy 143.364712 -255.578102) (xy 143.16456 -255.578102) (xy 143.16456 -255.622552)
			(xy 143.264636 -255.722628)
		)
		(stroke
			(width 0)
			(type solid)
		)
		(fill yes)
		(layer "In6.Cu")
		(net "M_K_CPU1_SA_PAR")
	)
	(gr_poly
		(pts
			(xy 143.364712 -254.4064) (xy 143.264636 -254.306324) (xy 143.16456 -254.4064) (xy 143.16456 -254.45085)
			(xy 143.364712 -254.45085)
		)
		(stroke
			(width 0)
			(type solid)
		)
		(fill yes)
		(layer "In6.Cu")
		(net "M_K_CPU1_SA_CA<4>")
	)
	(gr_poly
		(pts
			(xy 143.364712 -254.00254) (xy 143.364712 -253.95809) (xy 143.16456 -253.95809) (xy 143.16456 -254.00254)
			(xy 143.264636 -254.102616)
		)
		(stroke
			(width 0)
			(type solid)
		)
		(fill yes)
		(layer "In6.Cu")
		(net "M_K_CPU1_SA_CA<3>")
	)
	(gr_poly
		(pts
			(xy 143.364712 -252.786388) (xy 143.264636 -252.686312) (xy 143.16456 -252.786388) (xy 143.16456 -252.830838)
			(xy 143.364712 -252.830838)
		)
		(stroke
			(width 0)
			(type solid)
		)
		(fill yes)
		(layer "In6.Cu")
		(net "M_K_CPU1_SA_CA<0>")
	)
	(gr_poly
		(pts
			(xy 143.364712 -251.166376) (xy 143.264636 -251.0663) (xy 143.16456 -251.166376) (xy 143.16456 -251.210826)
			(xy 143.364712 -251.210826)
		)
		(stroke
			(width 0)
			(type solid)
		)
		(fill yes)
		(layer "In6.Cu")
		(net "M_K_CPU1_SA_CS_N<0>")
	)
	(gr_poly
		(pts
			(xy 143.364712 -250.762516) (xy 143.364712 -250.718066) (xy 143.16456 -250.718066) (xy 143.16456 -250.762516)
			(xy 143.264636 -250.862592)
		)
		(stroke
			(width 0)
			(type solid)
		)
		(fill yes)
		(layer "In6.Cu")
		(net "M_K_CPU1_RESET_N")
	)
	(gr_poly
		(pts
			(xy 143.364712 -249.142504) (xy 143.364712 -249.098054) (xy 143.16456 -249.098054) (xy 143.16456 -249.142504)
			(xy 143.264636 -249.24258)
		)
		(stroke
			(width 0)
			(type solid)
		)
		(fill yes)
		(layer "In6.Cu")
		(net "M_K_CPU1_SA_CB<7>")
	)
	(gr_poly
		(pts
			(xy 143.364712 -247.926352) (xy 143.264636 -247.826276) (xy 143.16456 -247.926352) (xy 143.16456 -247.970802)
			(xy 143.364712 -247.970802)
		)
		(stroke
			(width 0)
			(type solid)
		)
		(fill yes)
		(layer "In6.Cu")
		(net "M_K_CPU1_SA_CB<4>")
	)
	(gr_poly
		(pts
			(xy 143.364712 -247.522746) (xy 143.364712 -247.474994) (xy 143.16456 -247.474994) (xy 143.16456 -247.522746)
			(xy 143.264636 -247.622568)
		)
		(stroke
			(width 0)
			(type solid)
		)
		(fill yes)
		(layer "In6.Cu")
		(net "M_K_CPU1_SA_DQS_DP<9>")
	)
	(gr_poly
		(pts
			(xy 143.364712 -246.306086) (xy 143.264636 -246.206264) (xy 143.16456 -246.306086) (xy 143.16456 -246.353838)
			(xy 143.364712 -246.353838)
		)
		(stroke
			(width 0)
			(type solid)
		)
		(fill yes)
		(layer "In6.Cu")
		(net "M_K_CPU1_SA_DQS_DP<4>")
	)
	(gr_poly
		(pts
			(xy 143.364712 -245.90248) (xy 143.364712 -245.85803) (xy 143.16456 -245.85803) (xy 143.16456 -245.90248)
			(xy 143.264636 -246.002556)
		)
		(stroke
			(width 0)
			(type solid)
		)
		(fill yes)
		(layer "In6.Cu")
		(net "M_K_CPU1_SA_CB<3>")
	)
	(gr_poly
		(pts
			(xy 143.364712 -244.686328) (xy 143.264636 -244.586252) (xy 143.16456 -244.686328) (xy 143.16456 -244.730778)
			(xy 143.364712 -244.730778)
		)
		(stroke
			(width 0)
			(type solid)
		)
		(fill yes)
		(layer "In6.Cu")
		(net "M_K_CPU1_SA_CB<0>")
	)
	(gr_poly
		(pts
			(xy 143.364712 -244.282468) (xy 143.364712 -244.238018) (xy 143.16456 -244.238018) (xy 143.16456 -244.282468)
			(xy 143.264636 -244.382544)
		)
		(stroke
			(width 0)
			(type solid)
		)
		(fill yes)
		(layer "In6.Cu")
		(net "M_K_CPU1_SA_DQ<31>")
	)
	(gr_poly
		(pts
			(xy 143.364712 -243.066316) (xy 143.264636 -242.96624) (xy 143.16456 -243.066316) (xy 143.16456 -243.110766)
			(xy 143.364712 -243.110766)
		)
		(stroke
			(width 0)
			(type solid)
		)
		(fill yes)
		(layer "In6.Cu")
		(net "M_K_CPU1_SA_DQ<28>")
	)
	(gr_poly
		(pts
			(xy 143.364712 -242.66271) (xy 143.364712 -242.614958) (xy 143.16456 -242.614958) (xy 143.16456 -242.66271)
			(xy 143.264636 -242.762532)
		)
		(stroke
			(width 0)
			(type solid)
		)
		(fill yes)
		(layer "In6.Cu")
		(net "M_K_CPU1_SA_DQS_DP<8>")
	)
	(gr_poly
		(pts
			(xy 143.364712 -241.44605) (xy 143.264636 -241.346228) (xy 143.16456 -241.44605) (xy 143.16456 -241.493802)
			(xy 143.364712 -241.493802)
		)
		(stroke
			(width 0)
			(type solid)
		)
		(fill yes)
		(layer "In6.Cu")
		(net "M_K_CPU1_SA_DQS_DP<3>")
	)
	(gr_poly
		(pts
			(xy 143.364712 -241.042444) (xy 143.364712 -240.997994) (xy 143.16456 -240.997994) (xy 143.16456 -241.042444)
			(xy 143.264636 -241.14252)
		)
		(stroke
			(width 0)
			(type solid)
		)
		(fill yes)
		(layer "In6.Cu")
		(net "M_K_CPU1_SA_DQ<27>")
	)
	(gr_poly
		(pts
			(xy 143.364712 -239.826292) (xy 143.264636 -239.726216) (xy 143.16456 -239.826292) (xy 143.16456 -239.870742)
			(xy 143.364712 -239.870742)
		)
		(stroke
			(width 0)
			(type solid)
		)
		(fill yes)
		(layer "In6.Cu")
		(net "M_K_CPU1_SA_DQ<24>")
	)
	(gr_poly
		(pts
			(xy 143.364712 -239.422432) (xy 143.364712 -239.377982) (xy 143.16456 -239.377982) (xy 143.16456 -239.422432)
			(xy 143.264636 -239.522508)
		)
		(stroke
			(width 0)
			(type solid)
		)
		(fill yes)
		(layer "In6.Cu")
		(net "M_K_CPU1_SA_DQ<23>")
	)
	(gr_poly
		(pts
			(xy 143.364712 -238.20628) (xy 143.264636 -238.106204) (xy 143.16456 -238.20628) (xy 143.16456 -238.25073)
			(xy 143.364712 -238.25073)
		)
		(stroke
			(width 0)
			(type solid)
		)
		(fill yes)
		(layer "In6.Cu")
		(net "M_K_CPU1_SA_DQ<20>")
	)
	(gr_poly
		(pts
			(xy 143.364712 -237.802674) (xy 143.364712 -237.754922) (xy 143.16456 -237.754922) (xy 143.16456 -237.802674)
			(xy 143.264636 -237.902496)
		)
		(stroke
			(width 0)
			(type solid)
		)
		(fill yes)
		(layer "In6.Cu")
		(net "M_K_CPU1_SA_DQS_DP<7>")
	)
	(gr_poly
		(pts
			(xy 143.364712 -236.586014) (xy 143.264636 -236.486192) (xy 143.16456 -236.586014) (xy 143.16456 -236.633766)
			(xy 143.364712 -236.633766)
		)
		(stroke
			(width 0)
			(type solid)
		)
		(fill yes)
		(layer "In6.Cu")
		(net "M_K_CPU1_SA_DQS_DP<2>")
	)
	(gr_poly
		(pts
			(xy 143.364712 -236.182408) (xy 143.364712 -236.137958) (xy 143.16456 -236.137958) (xy 143.16456 -236.182408)
			(xy 143.264636 -236.282484)
		)
		(stroke
			(width 0)
			(type solid)
		)
		(fill yes)
		(layer "In6.Cu")
		(net "M_K_CPU1_SA_DQ<19>")
	)
	(gr_poly
		(pts
			(xy 143.364712 -234.966256) (xy 143.264636 -234.86618) (xy 143.16456 -234.966256) (xy 143.16456 -235.010706)
			(xy 143.364712 -235.010706)
		)
		(stroke
			(width 0)
			(type solid)
		)
		(fill yes)
		(layer "In6.Cu")
		(net "M_K_CPU1_SA_DQ<16>")
	)
	(gr_poly
		(pts
			(xy 143.364712 -234.562396) (xy 143.364712 -234.517946) (xy 143.16456 -234.517946) (xy 143.16456 -234.562396)
			(xy 143.264636 -234.662472)
		)
		(stroke
			(width 0)
			(type solid)
		)
		(fill yes)
		(layer "In6.Cu")
		(net "M_K_CPU1_SA_DQ<15>")
	)
	(gr_poly
		(pts
			(xy 143.364712 -233.346244) (xy 143.264636 -233.246168) (xy 143.16456 -233.346244) (xy 143.16456 -233.390694)
			(xy 143.364712 -233.390694)
		)
		(stroke
			(width 0)
			(type solid)
		)
		(fill yes)
		(layer "In6.Cu")
		(net "M_K_CPU1_SA_DQ<12>")
	)
	(gr_poly
		(pts
			(xy 143.364712 -232.942638) (xy 143.364712 -232.894886) (xy 143.16456 -232.894886) (xy 143.16456 -232.942638)
			(xy 143.264636 -233.04246)
		)
		(stroke
			(width 0)
			(type solid)
		)
		(fill yes)
		(layer "In6.Cu")
		(net "M_K_CPU1_SA_DQS_DP<6>")
	)
	(gr_poly
		(pts
			(xy 143.364712 -231.725978) (xy 143.264636 -231.626156) (xy 143.16456 -231.725978) (xy 143.16456 -231.77373)
			(xy 143.364712 -231.77373)
		)
		(stroke
			(width 0)
			(type solid)
		)
		(fill yes)
		(layer "In6.Cu")
		(net "M_K_CPU1_SA_DQS_DP<1>")
	)
	(gr_poly
		(pts
			(xy 143.364712 -231.322626) (xy 143.364712 -231.278176) (xy 143.16456 -231.278176) (xy 143.16456 -231.322626)
			(xy 143.264636 -231.422702)
		)
		(stroke
			(width 0)
			(type solid)
		)
		(fill yes)
		(layer "In6.Cu")
		(net "M_K_CPU1_SA_DQ<11>")
	)
	(gr_poly
		(pts
			(xy 143.364712 -230.10622) (xy 143.264636 -230.006144) (xy 143.16456 -230.10622) (xy 143.16456 -230.15067)
			(xy 143.364712 -230.15067)
		)
		(stroke
			(width 0)
			(type solid)
		)
		(fill yes)
		(layer "In6.Cu")
		(net "M_K_CPU1_SA_DQ<8>")
	)
	(gr_poly
		(pts
			(xy 143.364712 -229.702614) (xy 143.364712 -229.658164) (xy 143.16456 -229.658164) (xy 143.16456 -229.702614)
			(xy 143.264636 -229.80269)
		)
		(stroke
			(width 0)
			(type solid)
		)
		(fill yes)
		(layer "In6.Cu")
		(net "M_K_CPU1_SA_DQ<7>")
	)
	(gr_poly
		(pts
			(xy 143.364712 -228.486462) (xy 143.264636 -228.386386) (xy 143.16456 -228.486462) (xy 143.16456 -228.530912)
			(xy 143.364712 -228.530912)
		)
		(stroke
			(width 0)
			(type solid)
		)
		(fill yes)
		(layer "In6.Cu")
		(net "M_K_CPU1_SA_DQ<4>")
	)
	(gr_poly
		(pts
			(xy 143.364712 -228.082856) (xy 143.364712 -228.035104) (xy 143.16456 -228.035104) (xy 143.16456 -228.082856)
			(xy 143.264636 -228.182678)
		)
		(stroke
			(width 0)
			(type solid)
		)
		(fill yes)
		(layer "In6.Cu")
		(net "M_K_CPU1_SA_DQS_DP<5>")
	)
	(gr_poly
		(pts
			(xy 143.364712 -226.866196) (xy 143.264636 -226.766374) (xy 143.16456 -226.866196) (xy 143.16456 -226.913948)
			(xy 143.364712 -226.913948)
		)
		(stroke
			(width 0)
			(type solid)
		)
		(fill yes)
		(layer "In6.Cu")
		(net "M_K_CPU1_SA_DQS_DP<0>")
	)
	(gr_poly
		(pts
			(xy 143.364712 -226.46259) (xy 143.364712 -226.41814) (xy 143.16456 -226.41814) (xy 143.16456 -226.46259)
			(xy 143.264636 -226.562666)
		)
		(stroke
			(width 0)
			(type solid)
		)
		(fill yes)
		(layer "In6.Cu")
		(net "M_K_CPU1_SA_DQ<3>")
	)
	(gr_poly
		(pts
			(xy 143.420846 -223.759014) (xy 143.384016 -223.622362) (xy 143.345662 -223.60001) (xy 143.245586 -223.773238)
			(xy 143.284194 -223.79559)
		)
		(stroke
			(width 0)
			(type solid)
		)
		(fill yes)
		(layer "In6.Cu")
		(net "M_K_CPU1_SA_DQ<2>")
	)
	(gr_poly
		(pts
			(xy 143.664686 -292.918134) (xy 143.56461 -292.818058) (xy 143.464534 -292.918134) (xy 143.464534 -292.962584)
			(xy 143.664686 -292.962584)
		)
		(stroke
			(width 0)
			(type solid)
		)
		(fill yes)
		(layer "In6.Cu")
		(net "M_K_CPU1_SB_DQ<29>")
	)
	(gr_poly
		(pts
			(xy 143.664686 -292.514274) (xy 143.664686 -292.469824) (xy 143.464534 -292.469824) (xy 143.464534 -292.514274)
			(xy 143.56461 -292.61435)
		)
		(stroke
			(width 0)
			(type solid)
		)
		(fill yes)
		(layer "In6.Cu")
		(net "M_K_CPU1_SB_DQ<30>")
	)
	(gr_poly
		(pts
			(xy 143.664686 -291.297868) (xy 143.56461 -291.198046) (xy 143.464534 -291.297868) (xy 143.464534 -291.34562)
			(xy 143.664686 -291.34562)
		)
		(stroke
			(width 0)
			(type solid)
		)
		(fill yes)
		(layer "In6.Cu")
		(net "M_K_CPU1_SB_DQS_DN<8>")
	)
	(gr_poly
		(pts
			(xy 143.664686 -290.894516) (xy 143.664686 -290.846764) (xy 143.464534 -290.846764) (xy 143.464534 -290.894516)
			(xy 143.56461 -290.994338)
		)
		(stroke
			(width 0)
			(type solid)
		)
		(fill yes)
		(layer "In6.Cu")
		(net "M_K_CPU1_SB_DQS_DN<3>")
	)
	(gr_poly
		(pts
			(xy 143.664686 -289.67811) (xy 143.56461 -289.578034) (xy 143.464534 -289.67811) (xy 143.464534 -289.72256)
			(xy 143.664686 -289.72256)
		)
		(stroke
			(width 0)
			(type solid)
		)
		(fill yes)
		(layer "In6.Cu")
		(net "M_K_CPU1_SB_DQ<25>")
	)
	(gr_poly
		(pts
			(xy 143.664686 -289.27425) (xy 143.664686 -289.2298) (xy 143.464534 -289.2298) (xy 143.464534 -289.27425)
			(xy 143.56461 -289.374326)
		)
		(stroke
			(width 0)
			(type solid)
		)
		(fill yes)
		(layer "In6.Cu")
		(net "M_K_CPU1_SB_DQ<26>")
	)
	(gr_poly
		(pts
			(xy 143.664686 -288.058098) (xy 143.56461 -287.958022) (xy 143.464534 -288.058098) (xy 143.464534 -288.102548)
			(xy 143.664686 -288.102548)
		)
		(stroke
			(width 0)
			(type solid)
		)
		(fill yes)
		(layer "In6.Cu")
		(net "M_K_CPU1_SB_DQ<21>")
	)
	(gr_poly
		(pts
			(xy 143.664686 -287.654492) (xy 143.664686 -287.610042) (xy 143.464534 -287.610042) (xy 143.464534 -287.654492)
			(xy 143.56461 -287.754568)
		)
		(stroke
			(width 0)
			(type solid)
		)
		(fill yes)
		(layer "In6.Cu")
		(net "M_K_CPU1_SB_DQ<22>")
	)
	(gr_poly
		(pts
			(xy 143.664686 -286.438086) (xy 143.56461 -286.33801) (xy 143.464534 -286.438086) (xy 143.464534 -286.485838)
			(xy 143.664686 -286.485838)
		)
		(stroke
			(width 0)
			(type solid)
		)
		(fill yes)
		(layer "In6.Cu")
		(net "M_K_CPU1_SB_DQS_DN<7>")
	)
	(gr_poly
		(pts
			(xy 143.664686 -286.034734) (xy 143.664686 -285.986982) (xy 143.464534 -285.986982) (xy 143.464534 -286.034734)
			(xy 143.56461 -286.134556)
		)
		(stroke
			(width 0)
			(type solid)
		)
		(fill yes)
		(layer "In6.Cu")
		(net "M_K_CPU1_SB_DQS_DN<2>")
	)
	(gr_poly
		(pts
			(xy 143.664686 -284.818328) (xy 143.56461 -284.718252) (xy 143.464534 -284.818328) (xy 143.464534 -284.862778)
			(xy 143.664686 -284.862778)
		)
		(stroke
			(width 0)
			(type solid)
		)
		(fill yes)
		(layer "In6.Cu")
		(net "M_K_CPU1_SB_DQ<17>")
	)
	(gr_poly
		(pts
			(xy 143.664686 -284.414468) (xy 143.664686 -284.370018) (xy 143.464534 -284.370018) (xy 143.464534 -284.414468)
			(xy 143.56461 -284.514544)
		)
		(stroke
			(width 0)
			(type solid)
		)
		(fill yes)
		(layer "In6.Cu")
		(net "M_K_CPU1_SB_DQ<18>")
	)
	(gr_poly
		(pts
			(xy 143.664686 -283.198316) (xy 143.56461 -283.09824) (xy 143.464534 -283.198316) (xy 143.464534 -283.242766)
			(xy 143.664686 -283.242766)
		)
		(stroke
			(width 0)
			(type solid)
		)
		(fill yes)
		(layer "In6.Cu")
		(net "M_K_CPU1_SB_DQ<13>")
	)
	(gr_poly
		(pts
			(xy 143.664686 -282.794456) (xy 143.664686 -282.750006) (xy 143.464534 -282.750006) (xy 143.464534 -282.794456)
			(xy 143.56461 -282.894532)
		)
		(stroke
			(width 0)
			(type solid)
		)
		(fill yes)
		(layer "In6.Cu")
		(net "M_K_CPU1_SB_DQ<14>")
	)
	(gr_poly
		(pts
			(xy 143.664686 -281.57805) (xy 143.56461 -281.478228) (xy 143.464534 -281.57805) (xy 143.464534 -281.625802)
			(xy 143.664686 -281.625802)
		)
		(stroke
			(width 0)
			(type solid)
		)
		(fill yes)
		(layer "In6.Cu")
		(net "M_K_CPU1_SB_DQS_DN<6>")
	)
	(gr_poly
		(pts
			(xy 143.664686 -281.174698) (xy 143.664686 -281.126946) (xy 143.464534 -281.126946) (xy 143.464534 -281.174698)
			(xy 143.56461 -281.27452)
		)
		(stroke
			(width 0)
			(type solid)
		)
		(fill yes)
		(layer "In6.Cu")
		(net "M_K_CPU1_SB_DQS_DN<1>")
	)
	(gr_poly
		(pts
			(xy 143.664686 -279.958292) (xy 143.56461 -279.858216) (xy 143.464534 -279.958292) (xy 143.464534 -280.002742)
			(xy 143.664686 -280.002742)
		)
		(stroke
			(width 0)
			(type solid)
		)
		(fill yes)
		(layer "In6.Cu")
		(net "M_K_CPU1_SB_DQ<9>")
	)
	(gr_poly
		(pts
			(xy 143.664686 -279.554432) (xy 143.664686 -279.509982) (xy 143.464534 -279.509982) (xy 143.464534 -279.554432)
			(xy 143.56461 -279.654508)
		)
		(stroke
			(width 0)
			(type solid)
		)
		(fill yes)
		(layer "In6.Cu")
		(net "M_K_CPU1_SB_DQ<10>")
	)
	(gr_poly
		(pts
			(xy 143.664686 -278.33828) (xy 143.56461 -278.238204) (xy 143.464534 -278.33828) (xy 143.464534 -278.38273)
			(xy 143.664686 -278.38273)
		)
		(stroke
			(width 0)
			(type solid)
		)
		(fill yes)
		(layer "In6.Cu")
		(net "M_K_CPU1_SB_DQ<5>")
	)
	(gr_poly
		(pts
			(xy 143.664686 -277.93442) (xy 143.664686 -277.88997) (xy 143.464534 -277.88997) (xy 143.464534 -277.93442)
			(xy 143.56461 -278.034496)
		)
		(stroke
			(width 0)
			(type solid)
		)
		(fill yes)
		(layer "In6.Cu")
		(net "M_K_CPU1_SB_DQ<6>")
	)
	(gr_poly
		(pts
			(xy 143.664686 -276.718014) (xy 143.56461 -276.618192) (xy 143.464534 -276.718014) (xy 143.464534 -276.765766)
			(xy 143.664686 -276.765766)
		)
		(stroke
			(width 0)
			(type solid)
		)
		(fill yes)
		(layer "In6.Cu")
		(net "M_K_CPU1_SB_DQS_DN<5>")
	)
	(gr_poly
		(pts
			(xy 143.664686 -276.314662) (xy 143.664686 -276.26691) (xy 143.464534 -276.26691) (xy 143.464534 -276.314662)
			(xy 143.56461 -276.414484)
		)
		(stroke
			(width 0)
			(type solid)
		)
		(fill yes)
		(layer "In6.Cu")
		(net "M_K_CPU1_SB_DQS_DN<0>")
	)
	(gr_poly
		(pts
			(xy 143.664686 -275.098256) (xy 143.56461 -274.99818) (xy 143.464534 -275.098256) (xy 143.464534 -275.142706)
			(xy 143.664686 -275.142706)
		)
		(stroke
			(width 0)
			(type solid)
		)
		(fill yes)
		(layer "In6.Cu")
		(net "M_K_CPU1_SB_DQ<1>")
	)
	(gr_poly
		(pts
			(xy 143.664686 -274.694396) (xy 143.664686 -274.649946) (xy 143.464534 -274.649946) (xy 143.464534 -274.694396)
			(xy 143.56461 -274.794472)
		)
		(stroke
			(width 0)
			(type solid)
		)
		(fill yes)
		(layer "In6.Cu")
		(net "M_K_CPU1_SB_DQ<2>")
	)
	(gr_poly
		(pts
			(xy 143.664686 -273.478244) (xy 143.56461 -273.378168) (xy 143.464534 -273.478244) (xy 143.464534 -273.522694)
			(xy 143.664686 -273.522694)
		)
		(stroke
			(width 0)
			(type solid)
		)
		(fill yes)
		(layer "In6.Cu")
		(net "M_K_CPU1_SB_CB<1>")
	)
	(gr_poly
		(pts
			(xy 143.664686 -273.074384) (xy 143.664686 -273.029934) (xy 143.464534 -273.029934) (xy 143.464534 -273.074384)
			(xy 143.56461 -273.17446)
		)
		(stroke
			(width 0)
			(type solid)
		)
		(fill yes)
		(layer "In6.Cu")
		(net "M_K_CPU1_SB_CB<2>")
	)
	(gr_poly
		(pts
			(xy 143.664686 -271.857978) (xy 143.56461 -271.758156) (xy 143.464534 -271.857978) (xy 143.464534 -271.90573)
			(xy 143.664686 -271.90573)
		)
		(stroke
			(width 0)
			(type solid)
		)
		(fill yes)
		(layer "In6.Cu")
		(net "M_K_CPU1_SB_DQS_DN<4>")
	)
	(gr_poly
		(pts
			(xy 143.664686 -270.23822) (xy 143.56461 -270.138144) (xy 143.464534 -270.23822) (xy 143.464534 -270.28267)
			(xy 143.664686 -270.28267)
		)
		(stroke
			(width 0)
			(type solid)
		)
		(fill yes)
		(layer "In6.Cu")
		(net "M_K_CPU1_SB_CB<5>")
	)
	(gr_poly
		(pts
			(xy 143.664686 -269.83436) (xy 143.664686 -269.78991) (xy 143.464534 -269.78991) (xy 143.464534 -269.83436)
			(xy 143.56461 -269.934436)
		)
		(stroke
			(width 0)
			(type solid)
		)
		(fill yes)
		(layer "In6.Cu")
		(net "M_K_CPU1_SB_CB<6>")
	)
	(gr_poly
		(pts
			(xy 143.664686 -266.998196) (xy 143.56461 -266.89812) (xy 143.464534 -266.998196) (xy 143.464534 -267.042646)
			(xy 143.664686 -267.042646)
		)
		(stroke
			(width 0)
			(type solid)
		)
		(fill yes)
		(layer "In6.Cu")
		(net "M_K_CPU1_SA_RSP<0>")
	)
	(gr_poly
		(pts
			(xy 143.664686 -266.594336) (xy 143.664686 -266.549886) (xy 143.464534 -266.549886) (xy 143.464534 -266.594336)
			(xy 143.56461 -266.694412)
		)
		(stroke
			(width 0)
			(type solid)
		)
		(fill yes)
		(layer "In6.Cu")
		(net "M_K_CPU1_SB_CS_N<1>")
	)
	(gr_poly
		(pts
			(xy 143.664686 -265.378184) (xy 143.56461 -265.278108) (xy 143.464534 -265.378184) (xy 143.464534 -265.422634)
			(xy 143.664686 -265.422634)
		)
		(stroke
			(width 0)
			(type solid)
		)
		(fill yes)
		(layer "In6.Cu")
		(net "M_K_CPU1_SB_PAR")
	)
	(gr_poly
		(pts
			(xy 143.664686 -263.758172) (xy 143.56461 -263.658096) (xy 143.464534 -263.758172) (xy 143.464534 -263.802622)
			(xy 143.664686 -263.802622)
		)
		(stroke
			(width 0)
			(type solid)
		)
		(fill yes)
		(layer "In6.Cu")
		(net "M_K_CPU1_SB_CA<4>")
	)
	(gr_poly
		(pts
			(xy 143.664686 -263.354312) (xy 143.664686 -263.309862) (xy 143.464534 -263.309862) (xy 143.464534 -263.354312)
			(xy 143.56461 -263.454388)
		)
		(stroke
			(width 0)
			(type solid)
		)
		(fill yes)
		(layer "In6.Cu")
		(net "M_K_CPU1_SB_CA<3>")
	)
	(gr_poly
		(pts
			(xy 143.664686 -262.13816) (xy 143.56461 -262.038084) (xy 143.464534 -262.13816) (xy 143.464534 -262.18261)
			(xy 143.664686 -262.18261)
		)
		(stroke
			(width 0)
			(type solid)
		)
		(fill yes)
		(layer "In6.Cu")
		(net "M_K_CPU1_SB_CA<0>")
	)
	(gr_poly
		(pts
			(xy 143.75384 -225.505772) (xy 143.715232 -225.48342) (xy 143.578834 -225.519996) (xy 143.61541 -225.656648)
			(xy 143.653764 -225.679)
		)
		(stroke
			(width 0)
			(type solid)
		)
		(fill yes)
		(layer "In6.Cu")
		(net "M_K_CPU1_SA_DQ<1>")
	)
	(gr_poly
		(pts
			(xy 143.75384 -222.265748) (xy 143.715232 -222.243396) (xy 143.578834 -222.279972) (xy 143.61541 -222.416624)
			(xy 143.653764 -222.438976)
		)
		(stroke
			(width 0)
			(type solid)
		)
		(fill yes)
		(layer "In6.Cu")
		(net "M_K_CPU1_SA_DQ<0>")
	)
	(gr_poly
		(pts
			(xy 143.757904 -224.583752) (xy 143.657828 -224.410524) (xy 143.61668 -224.4344) (xy 143.57985 -224.571052)
			(xy 143.716502 -224.607628)
		)
		(stroke
			(width 0)
			(type solid)
		)
		(fill yes)
		(layer "In6.Cu")
		(net "M_K_CPU1_SA_DQ<1>")
	)
	(gr_poly
		(pts
			(xy 143.757904 -223.885252) (xy 143.716502 -223.861376) (xy 143.57985 -223.897952) (xy 143.61668 -224.034604)
			(xy 143.657828 -224.05848)
		)
		(stroke
			(width 0)
			(type solid)
		)
		(fill yes)
		(layer "In6.Cu")
		(net "M_K_CPU1_SA_DQ<1>")
	)
	(gr_poly
		(pts
			(xy 143.828262 -251.976382) (xy 143.72844 -251.876306) (xy 143.628364 -251.976382) (xy 143.628364 -252.020832)
			(xy 143.828262 -252.020832)
		)
		(stroke
			(width 0)
			(type solid)
		)
		(fill yes)
		(layer "In6.Cu")
		(net "M_K_CPU1_SA_CS_N<1>")
	)
	(gr_poly
		(pts
			(xy 143.82877 -255.216406) (xy 143.728694 -255.11633) (xy 143.628618 -255.216406) (xy 143.628618 -255.260856)
			(xy 143.82877 -255.260856)
		)
		(stroke
			(width 0)
			(type solid)
		)
		(fill yes)
		(layer "In6.Cu")
		(net "M_K_CPU1_SA_CA<6>")
	)
	(gr_poly
		(pts
			(xy 143.82877 -254.812546) (xy 143.82877 -254.768096) (xy 143.628618 -254.768096) (xy 143.628618 -254.812546)
			(xy 143.728694 -254.912622)
		)
		(stroke
			(width 0)
			(type solid)
		)
		(fill yes)
		(layer "In6.Cu")
		(net "M_K_CPU1_SA_CA<5>")
	)
	(gr_poly
		(pts
			(xy 143.82877 -253.596394) (xy 143.728694 -253.496318) (xy 143.628618 -253.596394) (xy 143.628618 -253.640844)
			(xy 143.82877 -253.640844)
		)
		(stroke
			(width 0)
			(type solid)
		)
		(fill yes)
		(layer "In6.Cu")
		(net "M_K_CPU1_SA_CA<2>")
	)
	(gr_poly
		(pts
			(xy 143.82877 -253.192534) (xy 143.82877 -253.148084) (xy 143.628618 -253.148084) (xy 143.628618 -253.192534)
			(xy 143.728694 -253.29261)
		)
		(stroke
			(width 0)
			(type solid)
		)
		(fill yes)
		(layer "In6.Cu")
		(net "M_K_CPU1_SA_CA<1>")
	)
	(gr_poly
		(pts
			(xy 143.82877 -250.35637) (xy 143.728694 -250.256294) (xy 143.628618 -250.35637) (xy 143.628618 -250.40082)
			(xy 143.82877 -250.40082)
		)
		(stroke
			(width 0)
			(type solid)
		)
		(fill yes)
		(layer "In6.Cu")
		(net "M_K_CPU1_ALERT_R_N")
	)
	(gr_poly
		(pts
			(xy 143.82877 -248.736358) (xy 143.728694 -248.636282) (xy 143.628618 -248.736358) (xy 143.628618 -248.780808)
			(xy 143.82877 -248.780808)
		)
		(stroke
			(width 0)
			(type solid)
		)
		(fill yes)
		(layer "In6.Cu")
		(net "M_K_CPU1_SA_CB<5>")
	)
	(gr_poly
		(pts
			(xy 143.82877 -248.332498) (xy 143.82877 -248.288048) (xy 143.628618 -248.288048) (xy 143.628618 -248.332498)
			(xy 143.728694 -248.432574)
		)
		(stroke
			(width 0)
			(type solid)
		)
		(fill yes)
		(layer "In6.Cu")
		(net "M_K_CPU1_SA_CB<6>")
	)
	(gr_poly
		(pts
			(xy 143.82877 -247.116092) (xy 143.728694 -247.01627) (xy 143.628618 -247.116092) (xy 143.628618 -247.163844)
			(xy 143.82877 -247.163844)
		)
		(stroke
			(width 0)
			(type solid)
		)
		(fill yes)
		(layer "In6.Cu")
		(net "M_K_CPU1_SA_DQS_DN<9>")
	)
	(gr_poly
		(pts
			(xy 143.82877 -246.71274) (xy 143.82877 -246.664988) (xy 143.628618 -246.664988) (xy 143.628618 -246.71274)
			(xy 143.728694 -246.812562)
		)
		(stroke
			(width 0)
			(type solid)
		)
		(fill yes)
		(layer "In6.Cu")
		(net "M_K_CPU1_SA_DQS_DN<4>")
	)
	(gr_poly
		(pts
			(xy 143.82877 -245.496334) (xy 143.728694 -245.396258) (xy 143.628618 -245.496334) (xy 143.628618 -245.540784)
			(xy 143.82877 -245.540784)
		)
		(stroke
			(width 0)
			(type solid)
		)
		(fill yes)
		(layer "In6.Cu")
		(net "M_K_CPU1_SA_CB<1>")
	)
	(gr_poly
		(pts
			(xy 143.82877 -245.092474) (xy 143.82877 -245.048024) (xy 143.628618 -245.048024) (xy 143.628618 -245.092474)
			(xy 143.728694 -245.19255)
		)
		(stroke
			(width 0)
			(type solid)
		)
		(fill yes)
		(layer "In6.Cu")
		(net "M_K_CPU1_SA_CB<2>")
	)
	(gr_poly
		(pts
			(xy 143.82877 -243.876322) (xy 143.728694 -243.776246) (xy 143.628618 -243.876322) (xy 143.628618 -243.920772)
			(xy 143.82877 -243.920772)
		)
		(stroke
			(width 0)
			(type solid)
		)
		(fill yes)
		(layer "In6.Cu")
		(net "M_K_CPU1_SA_DQ<29>")
	)
	(gr_poly
		(pts
			(xy 143.82877 -243.472462) (xy 143.82877 -243.428012) (xy 143.628618 -243.428012) (xy 143.628618 -243.472462)
			(xy 143.728694 -243.572538)
		)
		(stroke
			(width 0)
			(type solid)
		)
		(fill yes)
		(layer "In6.Cu")
		(net "M_K_CPU1_SA_DQ<30>")
	)
	(gr_poly
		(pts
			(xy 143.82877 -242.256056) (xy 143.728694 -242.156234) (xy 143.628618 -242.256056) (xy 143.628618 -242.303808)
			(xy 143.82877 -242.303808)
		)
		(stroke
			(width 0)
			(type solid)
		)
		(fill yes)
		(layer "In6.Cu")
		(net "M_K_CPU1_SA_DQS_DN<8>")
	)
	(gr_poly
		(pts
			(xy 143.82877 -241.852704) (xy 143.82877 -241.804952) (xy 143.628618 -241.804952) (xy 143.628618 -241.852704)
			(xy 143.728694 -241.952526)
		)
		(stroke
			(width 0)
			(type solid)
		)
		(fill yes)
		(layer "In6.Cu")
		(net "M_K_CPU1_SA_DQS_DN<3>")
	)
	(gr_poly
		(pts
			(xy 143.82877 -240.636298) (xy 143.728694 -240.536222) (xy 143.628618 -240.636298) (xy 143.628618 -240.680748)
			(xy 143.82877 -240.680748)
		)
		(stroke
			(width 0)
			(type solid)
		)
		(fill yes)
		(layer "In6.Cu")
		(net "M_K_CPU1_SA_DQ<25>")
	)
	(gr_poly
		(pts
			(xy 143.82877 -240.232438) (xy 143.82877 -240.187988) (xy 143.628618 -240.187988) (xy 143.628618 -240.232438)
			(xy 143.728694 -240.332514)
		)
		(stroke
			(width 0)
			(type solid)
		)
		(fill yes)
		(layer "In6.Cu")
		(net "M_K_CPU1_SA_DQ<26>")
	)
	(gr_poly
		(pts
			(xy 143.82877 -239.016286) (xy 143.728694 -238.91621) (xy 143.628618 -239.016286) (xy 143.628618 -239.060736)
			(xy 143.82877 -239.060736)
		)
		(stroke
			(width 0)
			(type solid)
		)
		(fill yes)
		(layer "In6.Cu")
		(net "M_K_CPU1_SA_DQ<21>")
	)
	(gr_poly
		(pts
			(xy 143.82877 -238.612426) (xy 143.82877 -238.567976) (xy 143.628618 -238.567976) (xy 143.628618 -238.612426)
			(xy 143.728694 -238.712502)
		)
		(stroke
			(width 0)
			(type solid)
		)
		(fill yes)
		(layer "In6.Cu")
		(net "M_K_CPU1_SA_DQ<22>")
	)
	(gr_poly
		(pts
			(xy 143.82877 -237.39602) (xy 143.728694 -237.296198) (xy 143.628618 -237.39602) (xy 143.628618 -237.443772)
			(xy 143.82877 -237.443772)
		)
		(stroke
			(width 0)
			(type solid)
		)
		(fill yes)
		(layer "In6.Cu")
		(net "M_K_CPU1_SA_DQS_DN<7>")
	)
	(gr_poly
		(pts
			(xy 143.82877 -236.992668) (xy 143.82877 -236.944916) (xy 143.628618 -236.944916) (xy 143.628618 -236.992668)
			(xy 143.728694 -237.09249)
		)
		(stroke
			(width 0)
			(type solid)
		)
		(fill yes)
		(layer "In6.Cu")
		(net "M_K_CPU1_SA_DQS_DN<2>")
	)
	(gr_poly
		(pts
			(xy 143.82877 -235.776262) (xy 143.728694 -235.676186) (xy 143.628618 -235.776262) (xy 143.628618 -235.820712)
			(xy 143.82877 -235.820712)
		)
		(stroke
			(width 0)
			(type solid)
		)
		(fill yes)
		(layer "In6.Cu")
		(net "M_K_CPU1_SA_DQ<17>")
	)
	(gr_poly
		(pts
			(xy 143.82877 -235.372402) (xy 143.82877 -235.327952) (xy 143.628618 -235.327952) (xy 143.628618 -235.372402)
			(xy 143.728694 -235.472478)
		)
		(stroke
			(width 0)
			(type solid)
		)
		(fill yes)
		(layer "In6.Cu")
		(net "M_K_CPU1_SA_DQ<18>")
	)
	(gr_poly
		(pts
			(xy 143.82877 -234.15625) (xy 143.728694 -234.056174) (xy 143.628618 -234.15625) (xy 143.628618 -234.2007)
			(xy 143.82877 -234.2007)
		)
		(stroke
			(width 0)
			(type solid)
		)
		(fill yes)
		(layer "In6.Cu")
		(net "M_K_CPU1_SA_DQ<13>")
	)
	(gr_poly
		(pts
			(xy 143.82877 -233.75239) (xy 143.82877 -233.70794) (xy 143.628618 -233.70794) (xy 143.628618 -233.75239)
			(xy 143.728694 -233.852466)
		)
		(stroke
			(width 0)
			(type solid)
		)
		(fill yes)
		(layer "In6.Cu")
		(net "M_K_CPU1_SA_DQ<14>")
	)
	(gr_poly
		(pts
			(xy 143.82877 -232.535984) (xy 143.728694 -232.436162) (xy 143.628618 -232.535984) (xy 143.628618 -232.583736)
			(xy 143.82877 -232.583736)
		)
		(stroke
			(width 0)
			(type solid)
		)
		(fill yes)
		(layer "In6.Cu")
		(net "M_K_CPU1_SA_DQS_DN<6>")
	)
	(gr_poly
		(pts
			(xy 143.82877 -232.132632) (xy 143.82877 -232.08488) (xy 143.628618 -232.08488) (xy 143.628618 -232.132632)
			(xy 143.728694 -232.232454)
		)
		(stroke
			(width 0)
			(type solid)
		)
		(fill yes)
		(layer "In6.Cu")
		(net "M_K_CPU1_SA_DQS_DN<1>")
	)
	(gr_poly
		(pts
			(xy 143.82877 -230.51262) (xy 143.82877 -230.46817) (xy 143.628618 -230.46817) (xy 143.628618 -230.51262)
			(xy 143.728694 -230.612696)
		)
		(stroke
			(width 0)
			(type solid)
		)
		(fill yes)
		(layer "In6.Cu")
		(net "M_K_CPU1_SA_DQ<10>")
	)
	(gr_poly
		(pts
			(xy 143.834866 -256.432812) (xy 143.834866 -256.38506) (xy 143.634714 -256.38506) (xy 143.634714 -256.432812)
			(xy 143.73479 -256.532634)
		)
		(stroke
			(width 0)
			(type solid)
		)
		(fill yes)
		(layer "In6.Cu")
		(net "M_K_CPU1_CLK_DN<0>")
	)
	(gr_poly
		(pts
			(xy 143.834866 -227.27285) (xy 143.834866 -227.225098) (xy 143.634714 -227.225098) (xy 143.634714 -227.27285)
			(xy 143.73479 -227.372672)
		)
		(stroke
			(width 0)
			(type solid)
		)
		(fill yes)
		(layer "In6.Cu")
		(net "M_K_CPU1_SA_DQS_DN<0>")
	)
	(gr_poly
		(pts
			(xy 143.890746 -226.189032) (xy 143.853916 -226.05238) (xy 143.815562 -226.030028) (xy 143.715486 -226.203256)
			(xy 143.754094 -226.225608)
		)
		(stroke
			(width 0)
			(type solid)
		)
		(fill yes)
		(layer "In6.Cu")
		(net "M_K_CPU1_SA_DQ<3>")
	)
	(gr_poly
		(pts
			(xy 143.890746 -222.949008) (xy 143.853916 -222.812356) (xy 143.815562 -222.790004) (xy 143.715486 -222.963232)
			(xy 143.754094 -222.985584)
		)
		(stroke
			(width 0)
			(type solid)
		)
		(fill yes)
		(layer "In6.Cu")
		(net "M_K_CPU1_SA_DQ<2>")
	)
	(gr_poly
		(pts
			(xy 144.053814 -293.874952) (xy 143.953738 -293.701724) (xy 143.915384 -293.724076) (xy 143.878554 -293.860728)
			(xy 144.015206 -293.897304)
		)
		(stroke
			(width 0)
			(type solid)
		)
		(fill yes)
		(layer "In6.Cu")
		(net "M_K_CPU1_SB_DQ<31>")
	)
	(gr_poly
		(pts
			(xy 144.053814 -268.877542) (xy 144.015206 -268.85519) (xy 143.878554 -268.891766) (xy 143.915384 -269.028418)
			(xy 143.953738 -269.05077)
		)
		(stroke
			(width 0)
			(type solid)
		)
		(fill yes)
		(layer "In6.Cu")
		(net "M_K_CPU1_SB_CB<4>")
	)
	(gr_poly
		(pts
			(xy 144.125696 -286.844486) (xy 144.125696 -286.796988) (xy 143.925798 -286.796988) (xy 143.925798 -286.844486)
			(xy 144.02562 -286.944562)
		)
		(stroke
			(width 0)
			(type solid)
		)
		(fill yes)
		(layer "In6.Cu")
		(net "M_K_CPU1_SB_DQS_DP<7>")
	)
	(gr_poly
		(pts
			(xy 144.12849 -291.704522) (xy 144.12849 -291.65677) (xy 143.928592 -291.65677) (xy 143.928592 -291.704522)
			(xy 144.028668 -291.804344)
		)
		(stroke
			(width 0)
			(type solid)
		)
		(fill yes)
		(layer "In6.Cu")
		(net "M_K_CPU1_SB_DQS_DP<8>")
	)
	(gr_poly
		(pts
			(xy 144.12849 -290.084256) (xy 144.12849 -290.039806) (xy 143.928592 -290.039806) (xy 143.928592 -290.084256)
			(xy 144.028668 -290.184332)
		)
		(stroke
			(width 0)
			(type solid)
		)
		(fill yes)
		(layer "In6.Cu")
		(net "M_K_CPU1_SB_DQ<27>")
	)
	(gr_poly
		(pts
			(xy 144.12849 -288.868104) (xy 144.028668 -288.768028) (xy 143.928592 -288.868104) (xy 143.928592 -288.912554)
			(xy 144.12849 -288.912554)
		)
		(stroke
			(width 0)
			(type solid)
		)
		(fill yes)
		(layer "In6.Cu")
		(net "M_K_CPU1_SB_DQ<24>")
	)
	(gr_poly
		(pts
			(xy 144.12849 -288.464498) (xy 144.12849 -288.420048) (xy 143.928592 -288.420048) (xy 143.928592 -288.464498)
			(xy 144.028668 -288.564574)
		)
		(stroke
			(width 0)
			(type solid)
		)
		(fill yes)
		(layer "In6.Cu")
		(net "M_K_CPU1_SB_DQ<23>")
	)
	(gr_poly
		(pts
			(xy 144.12849 -287.248092) (xy 144.028668 -287.148016) (xy 143.928592 -287.248092) (xy 143.928592 -287.292542)
			(xy 144.12849 -287.292542)
		)
		(stroke
			(width 0)
			(type solid)
		)
		(fill yes)
		(layer "In6.Cu")
		(net "M_K_CPU1_SB_DQ<20>")
	)
	(gr_poly
		(pts
			(xy 144.12849 -285.224474) (xy 144.12849 -285.180024) (xy 143.928592 -285.180024) (xy 143.928592 -285.224474)
			(xy 144.028668 -285.32455)
		)
		(stroke
			(width 0)
			(type solid)
		)
		(fill yes)
		(layer "In6.Cu")
		(net "M_K_CPU1_SB_DQ<19>")
	)
	(gr_poly
		(pts
			(xy 144.12849 -284.008322) (xy 144.028668 -283.908246) (xy 143.928592 -284.008322) (xy 143.928592 -284.052772)
			(xy 144.12849 -284.052772)
		)
		(stroke
			(width 0)
			(type solid)
		)
		(fill yes)
		(layer "In6.Cu")
		(net "M_K_CPU1_SB_DQ<16>")
	)
	(gr_poly
		(pts
			(xy 144.12849 -283.604462) (xy 144.12849 -283.560012) (xy 143.928592 -283.560012) (xy 143.928592 -283.604462)
			(xy 144.028668 -283.704538)
		)
		(stroke
			(width 0)
			(type solid)
		)
		(fill yes)
		(layer "In6.Cu")
		(net "M_K_CPU1_SB_DQ<15>")
	)
	(gr_poly
		(pts
			(xy 144.12849 -282.38831) (xy 144.028668 -282.288234) (xy 143.928592 -282.38831) (xy 143.928592 -282.43276)
			(xy 144.12849 -282.43276)
		)
		(stroke
			(width 0)
			(type solid)
		)
		(fill yes)
		(layer "In6.Cu")
		(net "M_K_CPU1_SB_DQ<12>")
	)
	(gr_poly
		(pts
			(xy 144.12849 -281.984704) (xy 144.12849 -281.936952) (xy 143.928592 -281.936952) (xy 143.928592 -281.984704)
			(xy 144.028668 -282.084526)
		)
		(stroke
			(width 0)
			(type solid)
		)
		(fill yes)
		(layer "In6.Cu")
		(net "M_K_CPU1_SB_DQS_DP<6>")
	)
	(gr_poly
		(pts
			(xy 144.12849 -280.364438) (xy 144.12849 -280.319988) (xy 143.928592 -280.319988) (xy 143.928592 -280.364438)
			(xy 144.028668 -280.464514)
		)
		(stroke
			(width 0)
			(type solid)
		)
		(fill yes)
		(layer "In6.Cu")
		(net "M_K_CPU1_SB_DQ<11>")
	)
	(gr_poly
		(pts
			(xy 144.12849 -279.148286) (xy 144.028668 -279.04821) (xy 143.928592 -279.148286) (xy 143.928592 -279.192736)
			(xy 144.12849 -279.192736)
		)
		(stroke
			(width 0)
			(type solid)
		)
		(fill yes)
		(layer "In6.Cu")
		(net "M_K_CPU1_SB_DQ<8>")
	)
	(gr_poly
		(pts
			(xy 144.12849 -278.744426) (xy 144.12849 -278.699976) (xy 143.928592 -278.699976) (xy 143.928592 -278.744426)
			(xy 144.028668 -278.844502)
		)
		(stroke
			(width 0)
			(type solid)
		)
		(fill yes)
		(layer "In6.Cu")
		(net "M_K_CPU1_SB_DQ<7>")
	)
	(gr_poly
		(pts
			(xy 144.12849 -277.528274) (xy 144.028668 -277.428198) (xy 143.928592 -277.528274) (xy 143.928592 -277.572724)
			(xy 144.12849 -277.572724)
		)
		(stroke
			(width 0)
			(type solid)
		)
		(fill yes)
		(layer "In6.Cu")
		(net "M_K_CPU1_SB_DQ<4>")
	)
	(gr_poly
		(pts
			(xy 144.12849 -277.124668) (xy 144.12849 -277.076916) (xy 143.928592 -277.076916) (xy 143.928592 -277.124668)
			(xy 144.028668 -277.22449)
		)
		(stroke
			(width 0)
			(type solid)
		)
		(fill yes)
		(layer "In6.Cu")
		(net "M_K_CPU1_SB_DQS_DP<5>")
	)
	(gr_poly
		(pts
			(xy 144.12849 -275.504402) (xy 144.12849 -275.459952) (xy 143.928592 -275.459952) (xy 143.928592 -275.504402)
			(xy 144.028668 -275.604478)
		)
		(stroke
			(width 0)
			(type solid)
		)
		(fill yes)
		(layer "In6.Cu")
		(net "M_K_CPU1_SB_DQ<3>")
	)
	(gr_poly
		(pts
			(xy 144.12849 -274.28825) (xy 144.028668 -274.188174) (xy 143.928592 -274.28825) (xy 143.928592 -274.3327)
			(xy 144.12849 -274.3327)
		)
		(stroke
			(width 0)
			(type solid)
		)
		(fill yes)
		(layer "In6.Cu")
		(net "M_K_CPU1_SB_DQ<0>")
	)
	(gr_poly
		(pts
			(xy 144.12849 -273.88439) (xy 144.12849 -273.83994) (xy 143.928592 -273.83994) (xy 143.928592 -273.88439)
			(xy 144.028668 -273.984466)
		)
		(stroke
			(width 0)
			(type solid)
		)
		(fill yes)
		(layer "In6.Cu")
		(net "M_K_CPU1_SB_CB<3>")
	)
	(gr_poly
		(pts
			(xy 144.12849 -272.668238) (xy 144.028668 -272.568162) (xy 143.928592 -272.668238) (xy 143.928592 -272.712688)
			(xy 144.12849 -272.712688)
		)
		(stroke
			(width 0)
			(type solid)
		)
		(fill yes)
		(layer "In6.Cu")
		(net "M_K_CPU1_SB_CB<0>")
	)
	(gr_poly
		(pts
			(xy 144.12849 -272.264632) (xy 144.12849 -272.21688) (xy 143.928592 -272.21688) (xy 143.928592 -272.264632)
			(xy 144.028668 -272.364454)
		)
		(stroke
			(width 0)
			(type solid)
		)
		(fill yes)
		(layer "In6.Cu")
		(net "M_K_CPU1_SB_DQS_DP<4>")
	)
	(gr_poly
		(pts
			(xy 144.12849 -267.808202) (xy 144.028668 -267.708126) (xy 143.928592 -267.808202) (xy 143.928592 -267.852652)
			(xy 144.12849 -267.852652)
		)
		(stroke
			(width 0)
			(type solid)
		)
		(fill yes)
		(layer "In6.Cu")
		(net "M_K_CPU1_SB_RSP<0>")
	)
	(gr_poly
		(pts
			(xy 144.12849 -265.78433) (xy 144.12849 -265.73988) (xy 143.928592 -265.73988) (xy 143.928592 -265.78433)
			(xy 144.028668 -265.884406)
		)
		(stroke
			(width 0)
			(type solid)
		)
		(fill yes)
		(layer "In6.Cu")
		(net "M_K_CPU1_SB_CS_N<0>")
	)
	(gr_poly
		(pts
			(xy 144.12849 -264.568178) (xy 144.028668 -264.468102) (xy 143.928592 -264.568178) (xy 143.928592 -264.612628)
			(xy 144.12849 -264.612628)
		)
		(stroke
			(width 0)
			(type solid)
		)
		(fill yes)
		(layer "In6.Cu")
		(net "M_K_CPU1_SB_CA<6>")
	)
	(gr_poly
		(pts
			(xy 144.12849 -264.164318) (xy 144.12849 -264.119868) (xy 143.928592 -264.119868) (xy 143.928592 -264.164318)
			(xy 144.028668 -264.264394)
		)
		(stroke
			(width 0)
			(type solid)
		)
		(fill yes)
		(layer "In6.Cu")
		(net "M_K_CPU1_SB_CA<5>")
	)
	(gr_poly
		(pts
			(xy 144.12849 -262.948166) (xy 144.028668 -262.84809) (xy 143.928592 -262.948166) (xy 143.928592 -262.992616)
			(xy 144.12849 -262.992616)
		)
		(stroke
			(width 0)
			(type solid)
		)
		(fill yes)
		(layer "In6.Cu")
		(net "M_K_CPU1_SB_CA<2>")
	)
	(gr_poly
		(pts
			(xy 144.12849 -262.544306) (xy 144.12849 -262.499856) (xy 143.928592 -262.499856) (xy 143.928592 -262.544306)
			(xy 144.028668 -262.644382)
		)
		(stroke
			(width 0)
			(type solid)
		)
		(fill yes)
		(layer "In6.Cu")
		(net "M_K_CPU1_SB_CA<1>")
	)
	(gr_poly
		(pts
			(xy 144.13484 -292.108128) (xy 144.034764 -292.008052) (xy 143.934688 -292.108128) (xy 143.934688 -292.152578)
			(xy 144.13484 -292.152578)
		)
		(stroke
			(width 0)
			(type solid)
		)
		(fill yes)
		(layer "In6.Cu")
		(net "M_K_CPU1_SB_DQ<28>")
	)
	(gr_poly
		(pts
			(xy 144.13484 -290.487862) (xy 144.034764 -290.38804) (xy 143.934688 -290.487862) (xy 143.934688 -290.535614)
			(xy 144.13484 -290.535614)
		)
		(stroke
			(width 0)
			(type solid)
		)
		(fill yes)
		(layer "In6.Cu")
		(net "M_K_CPU1_SB_DQS_DP<3>")
	)
	(gr_poly
		(pts
			(xy 144.13484 -285.62808) (xy 144.034764 -285.528258) (xy 143.934688 -285.62808) (xy 143.934688 -285.675832)
			(xy 144.13484 -285.675832)
		)
		(stroke
			(width 0)
			(type solid)
		)
		(fill yes)
		(layer "In6.Cu")
		(net "M_K_CPU1_SB_DQS_DP<2>")
	)
	(gr_poly
		(pts
			(xy 144.13484 -280.768044) (xy 144.034764 -280.668222) (xy 143.934688 -280.768044) (xy 143.934688 -280.815796)
			(xy 144.13484 -280.815796)
		)
		(stroke
			(width 0)
			(type solid)
		)
		(fill yes)
		(layer "In6.Cu")
		(net "M_K_CPU1_SB_DQS_DP<1>")
	)
	(gr_poly
		(pts
			(xy 144.13484 -275.908008) (xy 144.034764 -275.808186) (xy 143.934688 -275.908008) (xy 143.934688 -275.95576)
			(xy 144.13484 -275.95576)
		)
		(stroke
			(width 0)
			(type solid)
		)
		(fill yes)
		(layer "In6.Cu")
		(net "M_K_CPU1_SB_DQS_DP<0>")
	)
	(gr_poly
		(pts
			(xy 144.13484 -271.047972) (xy 144.034764 -270.94815) (xy 143.934688 -271.047972) (xy 143.934688 -271.095724)
			(xy 144.13484 -271.095724)
		)
		(stroke
			(width 0)
			(type solid)
		)
		(fill yes)
		(layer "In6.Cu")
		(net "M_K_CPU1_SB_DQS_DP<9>")
	)
	(gr_poly
		(pts
			(xy 144.13484 -270.644366) (xy 144.13484 -270.599916) (xy 143.934688 -270.599916) (xy 143.934688 -270.644366)
			(xy 144.034764 -270.744442)
		)
		(stroke
			(width 0)
			(type solid)
		)
		(fill yes)
		(layer "In6.Cu")
		(net "M_K_CPU1_SB_CB<7>")
	)
	(gr_poly
		(pts
			(xy 144.15389 -293.328344) (xy 144.190466 -293.191692) (xy 144.054068 -293.155116) (xy 144.01546 -293.177468)
			(xy 144.115536 -293.350696)
		)
		(stroke
			(width 0)
			(type solid)
		)
		(fill yes)
		(layer "In6.Cu")
		(net "M_K_CPU1_SB_DQ<29>")
	)
	(gr_poly
		(pts
			(xy 144.190466 -269.560802) (xy 144.15389 -269.42415) (xy 144.115536 -269.401798) (xy 144.01546 -269.575026)
			(xy 144.054068 -269.597378)
		)
		(stroke
			(width 0)
			(type solid)
		)
		(fill yes)
		(layer "In6.Cu")
		(net "M_K_CPU1_SB_CB<6>")
	)
	(gr_poly
		(pts
			(xy 144.223994 -223.075754) (xy 144.185386 -223.053402) (xy 144.048734 -223.089978) (xy 144.085564 -223.22663)
			(xy 144.123918 -223.248982)
		)
		(stroke
			(width 0)
			(type solid)
		)
		(fill yes)
		(layer "In6.Cu")
		(net "M_K_CPU1_SA_DQ<1>")
	)
	(gr_poly
		(pts
			(xy 144.226788 -226.31654) (xy 144.18564 -226.292664) (xy 144.048988 -226.329494) (xy 144.085564 -226.465892)
			(xy 144.126966 -226.489768)
		)
		(stroke
			(width 0)
			(type solid)
		)
		(fill yes)
		(layer "In6.Cu")
		(net "M_K_CPU1_SA_DQS_DP<0>")
	)
	(gr_poly
		(pts
			(xy 144.29867 -256.026158) (xy 144.198594 -255.926336) (xy 144.098518 -256.026158) (xy 144.098518 -256.07391)
			(xy 144.29867 -256.07391)
		)
		(stroke
			(width 0)
			(type solid)
		)
		(fill yes)
		(layer "In6.Cu")
		(net "M_K_CPU1_CLK_DP<0>")
	)
	(gr_poly
		(pts
			(xy 144.310354 -255.622552) (xy 144.310354 -255.578102) (xy 144.110202 -255.578102) (xy 144.110202 -255.622552)
			(xy 144.210278 -255.722628)
		)
		(stroke
			(width 0)
			(type solid)
		)
		(fill yes)
		(layer "In6.Cu")
		(net "M_K_CPU1_SA_PAR")
	)
	(gr_poly
		(pts
			(xy 144.310354 -254.00254) (xy 144.310354 -253.95809) (xy 144.110202 -253.95809) (xy 144.110202 -254.00254)
			(xy 144.210278 -254.102616)
		)
		(stroke
			(width 0)
			(type solid)
		)
		(fill yes)
		(layer "In6.Cu")
		(net "M_K_CPU1_SA_CA<3>")
	)
	(gr_poly
		(pts
			(xy 144.310354 -250.762516) (xy 144.310354 -250.718066) (xy 144.110202 -250.718066) (xy 144.110202 -250.762516)
			(xy 144.210278 -250.862592)
		)
		(stroke
			(width 0)
			(type solid)
		)
		(fill yes)
		(layer "In6.Cu")
		(net "M_K_CPU1_RESET_N")
	)
	(gr_poly
		(pts
			(xy 144.310354 -249.142504) (xy 144.310354 -249.098054) (xy 144.110202 -249.098054) (xy 144.110202 -249.142504)
			(xy 144.210278 -249.24258)
		)
		(stroke
			(width 0)
			(type solid)
		)
		(fill yes)
		(layer "In6.Cu")
		(net "M_K_CPU1_SA_CB<7>")
	)
	(gr_poly
		(pts
			(xy 144.310354 -247.522746) (xy 144.310354 -247.474994) (xy 144.110202 -247.474994) (xy 144.110202 -247.522746)
			(xy 144.210278 -247.622568)
		)
		(stroke
			(width 0)
			(type solid)
		)
		(fill yes)
		(layer "In6.Cu")
		(net "M_K_CPU1_SA_DQS_DP<9>")
	)
	(gr_poly
		(pts
			(xy 144.310354 -244.282468) (xy 144.310354 -244.238018) (xy 144.110202 -244.238018) (xy 144.110202 -244.282468)
			(xy 144.210278 -244.382544)
		)
		(stroke
			(width 0)
			(type solid)
		)
		(fill yes)
		(layer "In6.Cu")
		(net "M_K_CPU1_SA_DQ<31>")
	)
	(gr_poly
		(pts
			(xy 144.310354 -242.66271) (xy 144.310354 -242.614958) (xy 144.110202 -242.614958) (xy 144.110202 -242.66271)
			(xy 144.210278 -242.762532)
		)
		(stroke
			(width 0)
			(type solid)
		)
		(fill yes)
		(layer "In6.Cu")
		(net "M_K_CPU1_SA_DQS_DP<8>")
	)
	(gr_poly
		(pts
			(xy 144.310354 -241.042444) (xy 144.310354 -240.997994) (xy 144.110202 -240.997994) (xy 144.110202 -241.042444)
			(xy 144.210278 -241.14252)
		)
		(stroke
			(width 0)
			(type solid)
		)
		(fill yes)
		(layer "In6.Cu")
		(net "M_K_CPU1_SA_DQ<27>")
	)
	(gr_poly
		(pts
			(xy 144.310354 -239.422432) (xy 144.310354 -239.377982) (xy 144.110202 -239.377982) (xy 144.110202 -239.422432)
			(xy 144.210278 -239.522508)
		)
		(stroke
			(width 0)
			(type solid)
		)
		(fill yes)
		(layer "In6.Cu")
		(net "M_K_CPU1_SA_DQ<23>")
	)
	(gr_poly
		(pts
			(xy 144.310354 -237.802674) (xy 144.310354 -237.754922) (xy 144.110202 -237.754922) (xy 144.110202 -237.802674)
			(xy 144.210278 -237.902496)
		)
		(stroke
			(width 0)
			(type solid)
		)
		(fill yes)
		(layer "In6.Cu")
		(net "M_K_CPU1_SA_DQS_DP<7>")
	)
	(gr_poly
		(pts
			(xy 144.310354 -236.182408) (xy 144.310354 -236.137958) (xy 144.110202 -236.137958) (xy 144.110202 -236.182408)
			(xy 144.210278 -236.282484)
		)
		(stroke
			(width 0)
			(type solid)
		)
		(fill yes)
		(layer "In6.Cu")
		(net "M_K_CPU1_SA_DQ<19>")
	)
	(gr_poly
		(pts
			(xy 144.310354 -234.562396) (xy 144.310354 -234.517946) (xy 144.110202 -234.517946) (xy 144.110202 -234.562396)
			(xy 144.210278 -234.662472)
		)
		(stroke
			(width 0)
			(type solid)
		)
		(fill yes)
		(layer "In6.Cu")
		(net "M_K_CPU1_SA_DQ<15>")
	)
	(gr_poly
		(pts
			(xy 144.310354 -231.322626) (xy 144.310354 -231.278176) (xy 144.110202 -231.278176) (xy 144.110202 -231.322626)
			(xy 144.210278 -231.422702)
		)
		(stroke
			(width 0)
			(type solid)
		)
		(fill yes)
		(layer "In6.Cu")
		(net "M_K_CPU1_SA_DQ<11>")
	)
	(gr_poly
		(pts
			(xy 144.310608 -254.4064) (xy 144.210532 -254.306324) (xy 144.11071 -254.4064) (xy 144.11071 -254.45085)
			(xy 144.310608 -254.45085)
		)
		(stroke
			(width 0)
			(type solid)
		)
		(fill yes)
		(layer "In6.Cu")
		(net "M_K_CPU1_SA_CA<4>")
	)
	(gr_poly
		(pts
			(xy 144.310608 -252.786388) (xy 144.210532 -252.686312) (xy 144.11071 -252.786388) (xy 144.11071 -252.830838)
			(xy 144.310608 -252.830838)
		)
		(stroke
			(width 0)
			(type solid)
		)
		(fill yes)
		(layer "In6.Cu")
		(net "M_K_CPU1_SA_CA<0>")
	)
	(gr_poly
		(pts
			(xy 144.310608 -251.166376) (xy 144.210532 -251.0663) (xy 144.11071 -251.166376) (xy 144.11071 -251.210826)
			(xy 144.310608 -251.210826)
		)
		(stroke
			(width 0)
			(type solid)
		)
		(fill yes)
		(layer "In6.Cu")
		(net "M_K_CPU1_SA_CS_N<0>")
	)
	(gr_poly
		(pts
			(xy 144.310608 -247.926352) (xy 144.210532 -247.826276) (xy 144.11071 -247.926352) (xy 144.11071 -247.970802)
			(xy 144.310608 -247.970802)
		)
		(stroke
			(width 0)
			(type solid)
		)
		(fill yes)
		(layer "In6.Cu")
		(net "M_K_CPU1_SA_CB<4>")
	)
	(gr_poly
		(pts
			(xy 144.310608 -246.306086) (xy 144.210532 -246.206264) (xy 144.11071 -246.306086) (xy 144.11071 -246.353838)
			(xy 144.310608 -246.353838)
		)
		(stroke
			(width 0)
			(type solid)
		)
		(fill yes)
		(layer "In6.Cu")
		(net "M_K_CPU1_SA_DQS_DP<4>")
	)
	(gr_poly
		(pts
			(xy 144.310608 -245.90248) (xy 144.310608 -245.85803) (xy 144.11071 -245.85803) (xy 144.11071 -245.90248)
			(xy 144.210532 -246.002556)
		)
		(stroke
			(width 0)
			(type solid)
		)
		(fill yes)
		(layer "In6.Cu")
		(net "M_K_CPU1_SA_CB<3>")
	)
	(gr_poly
		(pts
			(xy 144.310608 -244.686328) (xy 144.210532 -244.586252) (xy 144.11071 -244.686328) (xy 144.11071 -244.730778)
			(xy 144.310608 -244.730778)
		)
		(stroke
			(width 0)
			(type solid)
		)
		(fill yes)
		(layer "In6.Cu")
		(net "M_K_CPU1_SA_CB<0>")
	)
	(gr_poly
		(pts
			(xy 144.310608 -243.066316) (xy 144.210532 -242.96624) (xy 144.11071 -243.066316) (xy 144.11071 -243.110766)
			(xy 144.310608 -243.110766)
		)
		(stroke
			(width 0)
			(type solid)
		)
		(fill yes)
		(layer "In6.Cu")
		(net "M_K_CPU1_SA_DQ<28>")
	)
	(gr_poly
		(pts
			(xy 144.310608 -241.44605) (xy 144.210532 -241.346228) (xy 144.11071 -241.44605) (xy 144.11071 -241.493802)
			(xy 144.310608 -241.493802)
		)
		(stroke
			(width 0)
			(type solid)
		)
		(fill yes)
		(layer "In6.Cu")
		(net "M_K_CPU1_SA_DQS_DP<3>")
	)
	(gr_poly
		(pts
			(xy 144.310608 -239.826292) (xy 144.210532 -239.726216) (xy 144.11071 -239.826292) (xy 144.11071 -239.870742)
			(xy 144.310608 -239.870742)
		)
		(stroke
			(width 0)
			(type solid)
		)
		(fill yes)
		(layer "In6.Cu")
		(net "M_K_CPU1_SA_DQ<24>")
	)
	(gr_poly
		(pts
			(xy 144.310608 -238.20628) (xy 144.210532 -238.106204) (xy 144.11071 -238.20628) (xy 144.11071 -238.25073)
			(xy 144.310608 -238.25073)
		)
		(stroke
			(width 0)
			(type solid)
		)
		(fill yes)
		(layer "In6.Cu")
		(net "M_K_CPU1_SA_DQ<20>")
	)
	(gr_poly
		(pts
			(xy 144.310608 -236.586014) (xy 144.210532 -236.486192) (xy 144.11071 -236.586014) (xy 144.11071 -236.633766)
			(xy 144.310608 -236.633766)
		)
		(stroke
			(width 0)
			(type solid)
		)
		(fill yes)
		(layer "In6.Cu")
		(net "M_K_CPU1_SA_DQS_DP<2>")
	)
	(gr_poly
		(pts
			(xy 144.310608 -234.966256) (xy 144.210532 -234.86618) (xy 144.11071 -234.966256) (xy 144.11071 -235.010706)
			(xy 144.310608 -235.010706)
		)
		(stroke
			(width 0)
			(type solid)
		)
		(fill yes)
		(layer "In6.Cu")
		(net "M_K_CPU1_SA_DQ<16>")
	)
	(gr_poly
		(pts
			(xy 144.310608 -233.346244) (xy 144.210532 -233.246168) (xy 144.11071 -233.346244) (xy 144.11071 -233.390694)
			(xy 144.310608 -233.390694)
		)
		(stroke
			(width 0)
			(type solid)
		)
		(fill yes)
		(layer "In6.Cu")
		(net "M_K_CPU1_SA_DQ<12>")
	)
	(gr_poly
		(pts
			(xy 144.310608 -232.942638) (xy 144.310608 -232.894886) (xy 144.11071 -232.894886) (xy 144.11071 -232.942638)
			(xy 144.210532 -233.04246)
		)
		(stroke
			(width 0)
			(type solid)
		)
		(fill yes)
		(layer "In6.Cu")
		(net "M_K_CPU1_SA_DQS_DP<6>")
	)
	(gr_poly
		(pts
			(xy 144.310608 -231.725978) (xy 144.210532 -231.626156) (xy 144.11071 -231.725978) (xy 144.11071 -231.77373)
			(xy 144.310608 -231.77373)
		)
		(stroke
			(width 0)
			(type solid)
		)
		(fill yes)
		(layer "In6.Cu")
		(net "M_K_CPU1_SA_DQS_DP<1>")
	)
	(gr_poly
		(pts
			(xy 144.3228 -224.84461) (xy 144.35963 -224.708212) (xy 144.222978 -224.671382) (xy 144.181576 -224.695258)
			(xy 144.281652 -224.868486)
		)
		(stroke
			(width 0)
			(type solid)
		)
		(fill yes)
		(layer "In6.Cu")
		(net "M_K_CPU1_SA_DQ<3>")
	)
	(gr_poly
		(pts
			(xy 144.35963 -225.380804) (xy 144.3228 -225.244406) (xy 144.281652 -225.22053) (xy 144.181576 -225.393758)
			(xy 144.222978 -225.417634)
		)
		(stroke
			(width 0)
			(type solid)
		)
		(fill yes)
		(layer "In6.Cu")
		(net "M_K_CPU1_SA_DQ<3>")
	)
	(gr_poly
		(pts
			(xy 144.360646 -226.999546) (xy 144.32407 -226.863148) (xy 144.282668 -226.839272) (xy 144.182846 -227.0125)
			(xy 144.223994 -227.036376)
		)
		(stroke
			(width 0)
			(type solid)
		)
		(fill yes)
		(layer "In6.Cu")
		(net "M_K_CPU1_SA_DQS_DN<0>")
	)
	(gr_poly
		(pts
			(xy 144.360646 -223.759014) (xy 144.32407 -223.622362) (xy 144.285716 -223.60001) (xy 144.18564 -223.773238)
			(xy 144.224248 -223.79559)
		)
		(stroke
			(width 0)
			(type solid)
		)
		(fill yes)
		(layer "In6.Cu")
		(net "M_K_CPU1_SA_DQ<3>")
	)
	(gr_poly
		(pts
			(xy 144.360646 -222.139002) (xy 144.323816 -222.00235) (xy 144.285462 -221.979998) (xy 144.185386 -222.153226)
			(xy 144.223994 -222.175578)
		)
		(stroke
			(width 0)
			(type solid)
		)
		(fill yes)
		(layer "In6.Cu")
		(net "M_K_CPU1_SA_DQ<2>")
	)
	(gr_poly
		(pts
			(xy 144.523714 -294.684958) (xy 144.423638 -294.51173) (xy 144.385284 -294.534082) (xy 144.348454 -294.670734)
			(xy 144.485106 -294.70731)
		)
		(stroke
			(width 0)
			(type solid)
		)
		(fill yes)
		(layer "In6.Cu")
		(net "M_K_CPU1_SB_DQ<31>")
	)
	(gr_poly
		(pts
			(xy 144.523968 -293.064946) (xy 144.423892 -292.891718) (xy 144.385538 -292.91407) (xy 144.348962 -293.050722)
			(xy 144.48536 -293.087298)
		)
		(stroke
			(width 0)
			(type solid)
		)
		(fill yes)
		(layer "In6.Cu")
		(net "M_K_CPU1_SB_DQ<30>")
	)
	(gr_poly
		(pts
			(xy 144.523968 -269.687548) (xy 144.48536 -269.665196) (xy 144.348962 -269.701772) (xy 144.385538 -269.838424)
			(xy 144.423892 -269.860776)
		)
		(stroke
			(width 0)
			(type solid)
		)
		(fill yes)
		(layer "In6.Cu")
		(net "M_K_CPU1_SB_CB<5>")
	)
	(gr_poly
		(pts
			(xy 144.59204 -271.454372) (xy 144.59204 -271.406874) (xy 144.392142 -271.406874) (xy 144.392142 -271.454372)
			(xy 144.491964 -271.554448)
		)
		(stroke
			(width 0)
			(type solid)
		)
		(fill yes)
		(layer "In6.Cu")
		(net "M_K_CPU1_SB_DQS_DN<9>")
	)
	(gr_poly
		(pts
			(xy 144.59839 -290.894516) (xy 144.59839 -290.846764) (xy 144.398492 -290.846764) (xy 144.398492 -290.894516)
			(xy 144.498568 -290.994338)
		)
		(stroke
			(width 0)
			(type solid)
		)
		(fill yes)
		(layer "In6.Cu")
		(net "M_K_CPU1_SB_DQS_DN<3>")
	)
	(gr_poly
		(pts
			(xy 144.59839 -286.034734) (xy 144.59839 -285.986982) (xy 144.398492 -285.986982) (xy 144.398492 -286.034734)
			(xy 144.498568 -286.134556)
		)
		(stroke
			(width 0)
			(type solid)
		)
		(fill yes)
		(layer "In6.Cu")
		(net "M_K_CPU1_SB_DQS_DN<2>")
	)
	(gr_poly
		(pts
			(xy 144.59839 -281.174698) (xy 144.59839 -281.126946) (xy 144.398492 -281.126946) (xy 144.398492 -281.174698)
			(xy 144.498568 -281.27452)
		)
		(stroke
			(width 0)
			(type solid)
		)
		(fill yes)
		(layer "In6.Cu")
		(net "M_K_CPU1_SB_DQS_DN<1>")
	)
	(gr_poly
		(pts
			(xy 144.59839 -276.314662) (xy 144.59839 -276.26691) (xy 144.398492 -276.26691) (xy 144.398492 -276.314662)
			(xy 144.498568 -276.414484)
		)
		(stroke
			(width 0)
			(type solid)
		)
		(fill yes)
		(layer "In6.Cu")
		(net "M_K_CPU1_SB_DQS_DN<0>")
	)
	(gr_poly
		(pts
			(xy 144.60474 -268.618208) (xy 144.504664 -268.518132) (xy 144.404588 -268.618208) (xy 144.404588 -268.662658)
			(xy 144.60474 -268.662658)
		)
		(stroke
			(width 0)
			(type solid)
		)
		(fill yes)
		(layer "In6.Cu")
		(net "M_K_CPU1_SB_CB<4>")
	)
	(gr_poly
		(pts
			(xy 144.610328 -291.297868) (xy 144.510252 -291.198046) (xy 144.41043 -291.297868) (xy 144.41043 -291.34562)
			(xy 144.610328 -291.34562)
		)
		(stroke
			(width 0)
			(type solid)
		)
		(fill yes)
		(layer "In6.Cu")
		(net "M_K_CPU1_SB_DQS_DN<8>")
	)
	(gr_poly
		(pts
			(xy 144.610328 -284.818328) (xy 144.510252 -284.718252) (xy 144.41043 -284.818328) (xy 144.41043 -284.862778)
			(xy 144.610328 -284.862778)
		)
		(stroke
			(width 0)
			(type solid)
		)
		(fill yes)
		(layer "In6.Cu")
		(net "M_K_CPU1_SB_DQ<17>")
	)
	(gr_poly
		(pts
			(xy 144.610328 -283.198316) (xy 144.510252 -283.09824) (xy 144.41043 -283.198316) (xy 144.41043 -283.242766)
			(xy 144.610328 -283.242766)
		)
		(stroke
			(width 0)
			(type solid)
		)
		(fill yes)
		(layer "In6.Cu")
		(net "M_K_CPU1_SB_DQ<13>")
	)
	(gr_poly
		(pts
			(xy 144.610328 -281.57805) (xy 144.510252 -281.478228) (xy 144.41043 -281.57805) (xy 144.41043 -281.625802)
			(xy 144.610328 -281.625802)
		)
		(stroke
			(width 0)
			(type solid)
		)
		(fill yes)
		(layer "In6.Cu")
		(net "M_K_CPU1_SB_DQS_DN<6>")
	)
	(gr_poly
		(pts
			(xy 144.610328 -279.958292) (xy 144.510252 -279.858216) (xy 144.41043 -279.958292) (xy 144.41043 -280.002742)
			(xy 144.610328 -280.002742)
		)
		(stroke
			(width 0)
			(type solid)
		)
		(fill yes)
		(layer "In6.Cu")
		(net "M_K_CPU1_SB_DQ<9>")
	)
	(gr_poly
		(pts
			(xy 144.610328 -278.33828) (xy 144.510252 -278.238204) (xy 144.41043 -278.33828) (xy 144.41043 -278.38273)
			(xy 144.610328 -278.38273)
		)
		(stroke
			(width 0)
			(type solid)
		)
		(fill yes)
		(layer "In6.Cu")
		(net "M_K_CPU1_SB_DQ<5>")
	)
	(gr_poly
		(pts
			(xy 144.610328 -276.718014) (xy 144.510252 -276.618192) (xy 144.41043 -276.718014) (xy 144.41043 -276.765766)
			(xy 144.610328 -276.765766)
		)
		(stroke
			(width 0)
			(type solid)
		)
		(fill yes)
		(layer "In6.Cu")
		(net "M_K_CPU1_SB_DQS_DN<5>")
	)
	(gr_poly
		(pts
			(xy 144.610328 -275.098256) (xy 144.510252 -274.99818) (xy 144.41043 -275.098256) (xy 144.41043 -275.142706)
			(xy 144.610328 -275.142706)
		)
		(stroke
			(width 0)
			(type solid)
		)
		(fill yes)
		(layer "In6.Cu")
		(net "M_K_CPU1_SB_DQ<1>")
	)
	(gr_poly
		(pts
			(xy 144.610328 -273.478244) (xy 144.510252 -273.378168) (xy 144.41043 -273.478244) (xy 144.41043 -273.522694)
			(xy 144.610328 -273.522694)
		)
		(stroke
			(width 0)
			(type solid)
		)
		(fill yes)
		(layer "In6.Cu")
		(net "M_K_CPU1_SB_CB<1>")
	)
	(gr_poly
		(pts
			(xy 144.610328 -266.998196) (xy 144.510252 -266.89812) (xy 144.41043 -266.998196) (xy 144.41043 -267.042646)
			(xy 144.610328 -267.042646)
		)
		(stroke
			(width 0)
			(type solid)
		)
		(fill yes)
		(layer "In6.Cu")
		(net "M_K_CPU1_SA_RSP<0>")
	)
	(gr_poly
		(pts
			(xy 144.610328 -265.378184) (xy 144.510252 -265.278108) (xy 144.41043 -265.378184) (xy 144.41043 -265.422634)
			(xy 144.610328 -265.422634)
		)
		(stroke
			(width 0)
			(type solid)
		)
		(fill yes)
		(layer "In6.Cu")
		(net "M_K_CPU1_SB_PAR")
	)
	(gr_poly
		(pts
			(xy 144.610328 -263.758172) (xy 144.510252 -263.658096) (xy 144.41043 -263.758172) (xy 144.41043 -263.802622)
			(xy 144.610328 -263.802622)
		)
		(stroke
			(width 0)
			(type solid)
		)
		(fill yes)
		(layer "In6.Cu")
		(net "M_K_CPU1_SB_CA<4>")
	)
	(gr_poly
		(pts
			(xy 144.610328 -262.13816) (xy 144.510252 -262.038084) (xy 144.41043 -262.13816) (xy 144.41043 -262.18261)
			(xy 144.610328 -262.18261)
		)
		(stroke
			(width 0)
			(type solid)
		)
		(fill yes)
		(layer "In6.Cu")
		(net "M_K_CPU1_SB_CA<0>")
	)
	(gr_poly
		(pts
			(xy 144.610582 -284.414468) (xy 144.610582 -284.370018) (xy 144.41043 -284.370018) (xy 144.41043 -284.414468)
			(xy 144.510506 -284.514544)
		)
		(stroke
			(width 0)
			(type solid)
		)
		(fill yes)
		(layer "In6.Cu")
		(net "M_K_CPU1_SB_DQ<18>")
	)
	(gr_poly
		(pts
			(xy 144.610582 -282.794456) (xy 144.610582 -282.750006) (xy 144.41043 -282.750006) (xy 144.41043 -282.794456)
			(xy 144.510506 -282.894532)
		)
		(stroke
			(width 0)
			(type solid)
		)
		(fill yes)
		(layer "In6.Cu")
		(net "M_K_CPU1_SB_DQ<14>")
	)
	(gr_poly
		(pts
			(xy 144.610582 -279.554432) (xy 144.610582 -279.509982) (xy 144.41043 -279.509982) (xy 144.41043 -279.554432)
			(xy 144.510506 -279.654508)
		)
		(stroke
			(width 0)
			(type solid)
		)
		(fill yes)
		(layer "In6.Cu")
		(net "M_K_CPU1_SB_DQ<10>")
	)
	(gr_poly
		(pts
			(xy 144.610582 -277.93442) (xy 144.610582 -277.88997) (xy 144.41043 -277.88997) (xy 144.41043 -277.93442)
			(xy 144.510506 -278.034496)
		)
		(stroke
			(width 0)
			(type solid)
		)
		(fill yes)
		(layer "In6.Cu")
		(net "M_K_CPU1_SB_DQ<6>")
	)
	(gr_poly
		(pts
			(xy 144.610582 -274.694396) (xy 144.610582 -274.649946) (xy 144.41043 -274.649946) (xy 144.41043 -274.694396)
			(xy 144.510506 -274.794472)
		)
		(stroke
			(width 0)
			(type solid)
		)
		(fill yes)
		(layer "In6.Cu")
		(net "M_K_CPU1_SB_DQ<2>")
	)
	(gr_poly
		(pts
			(xy 144.610582 -273.074384) (xy 144.610582 -273.029934) (xy 144.41043 -273.029934) (xy 144.41043 -273.074384)
			(xy 144.510506 -273.17446)
		)
		(stroke
			(width 0)
			(type solid)
		)
		(fill yes)
		(layer "In6.Cu")
		(net "M_K_CPU1_SB_CB<2>")
	)
	(gr_poly
		(pts
			(xy 144.610582 -266.594336) (xy 144.610582 -266.549886) (xy 144.41043 -266.549886) (xy 144.41043 -266.594336)
			(xy 144.510506 -266.694412)
		)
		(stroke
			(width 0)
			(type solid)
		)
		(fill yes)
		(layer "In6.Cu")
		(net "M_K_CPU1_SB_CS_N<1>")
	)
	(gr_poly
		(pts
			(xy 144.610582 -263.354312) (xy 144.610582 -263.309862) (xy 144.41043 -263.309862) (xy 144.41043 -263.354312)
			(xy 144.510506 -263.454388)
		)
		(stroke
			(width 0)
			(type solid)
		)
		(fill yes)
		(layer "In6.Cu")
		(net "M_K_CPU1_SB_CA<3>")
	)
	(gr_poly
		(pts
			(xy 144.615408 -271.857724) (xy 144.515332 -271.757902) (xy 144.41551 -271.857724) (xy 144.41551 -271.905476)
			(xy 144.615408 -271.905476)
		)
		(stroke
			(width 0)
			(type solid)
		)
		(fill yes)
		(layer "In6.Cu")
		(net "M_K_CPU1_SB_DQS_DN<4>")
	)
	(gr_poly
		(pts
			(xy 144.62379 -294.13835) (xy 144.660366 -294.001698) (xy 144.523968 -293.965122) (xy 144.48536 -293.987474)
			(xy 144.585436 -294.160702)
		)
		(stroke
			(width 0)
			(type solid)
		)
		(fill yes)
		(layer "In6.Cu")
		(net "M_K_CPU1_SB_DQ<29>")
	)
	(gr_poly
		(pts
			(xy 144.624044 -292.518338) (xy 144.660874 -292.381686) (xy 144.524222 -292.34511) (xy 144.485614 -292.367462)
			(xy 144.58569 -292.54069)
		)
		(stroke
			(width 0)
			(type solid)
		)
		(fill yes)
		(layer "In6.Cu")
		(net "M_K_CPU1_SB_DQ<28>")
	)
	(gr_poly
		(pts
			(xy 144.660874 -270.370808) (xy 144.624044 -270.234156) (xy 144.58569 -270.211804) (xy 144.485614 -270.385032)
			(xy 144.524222 -270.407384)
		)
		(stroke
			(width 0)
			(type solid)
		)
		(fill yes)
		(layer "In6.Cu")
		(net "M_K_CPU1_SB_CB<7>")
	)
	(gr_poly
		(pts
			(xy 144.694148 -222.265748) (xy 144.65554 -222.243396) (xy 144.519142 -222.279972) (xy 144.555718 -222.416624)
			(xy 144.594072 -222.438976)
		)
		(stroke
			(width 0)
			(type solid)
		)
		(fill yes)
		(layer "In6.Cu")
		(net "M_K_CPU1_SA_DQ<1>")
	)
	(gr_poly
		(pts
			(xy 144.696688 -225.506534) (xy 144.65554 -225.482912) (xy 144.518888 -225.519488) (xy 144.555464 -225.655886)
			(xy 144.596866 -225.679762)
		)
		(stroke
			(width 0)
			(type solid)
		)
		(fill yes)
		(layer "In6.Cu")
		(net "M_K_CPU1_SA_DQS_DP<0>")
	)
	(gr_poly
		(pts
			(xy 144.78 -251.976382) (xy 144.679924 -251.876306) (xy 144.580102 -251.976382) (xy 144.580102 -252.020832)
			(xy 144.78 -252.020832)
		)
		(stroke
			(width 0)
			(type solid)
		)
		(fill yes)
		(layer "In6.Cu")
		(net "M_K_CPU1_SA_CS_N<1>")
	)
	(gr_poly
		(pts
			(xy 144.780254 -255.216406) (xy 144.680178 -255.11633) (xy 144.580102 -255.216406) (xy 144.580102 -255.260856)
			(xy 144.780254 -255.260856)
		)
		(stroke
			(width 0)
			(type solid)
		)
		(fill yes)
		(layer "In6.Cu")
		(net "M_K_CPU1_SA_CA<6>")
	)
	(gr_poly
		(pts
			(xy 144.780254 -253.596394) (xy 144.680178 -253.496318) (xy 144.580102 -253.596394) (xy 144.580102 -253.640844)
			(xy 144.780254 -253.640844)
		)
		(stroke
			(width 0)
			(type solid)
		)
		(fill yes)
		(layer "In6.Cu")
		(net "M_K_CPU1_SA_CA<2>")
	)
	(gr_poly
		(pts
			(xy 144.780254 -250.35637) (xy 144.680178 -250.256294) (xy 144.580102 -250.35637) (xy 144.580102 -250.40082)
			(xy 144.780254 -250.40082)
		)
		(stroke
			(width 0)
			(type solid)
		)
		(fill yes)
		(layer "In6.Cu")
		(net "M_K_CPU1_ALERT_R_N")
	)
	(gr_poly
		(pts
			(xy 144.780254 -248.736358) (xy 144.680178 -248.636282) (xy 144.580102 -248.736358) (xy 144.580102 -248.780808)
			(xy 144.780254 -248.780808)
		)
		(stroke
			(width 0)
			(type solid)
		)
		(fill yes)
		(layer "In6.Cu")
		(net "M_K_CPU1_SA_CB<5>")
	)
	(gr_poly
		(pts
			(xy 144.780254 -247.116092) (xy 144.680178 -247.016016) (xy 144.580102 -247.116092) (xy 144.580102 -247.16359)
			(xy 144.780254 -247.16359)
		)
		(stroke
			(width 0)
			(type solid)
		)
		(fill yes)
		(layer "In6.Cu")
		(net "M_K_CPU1_SA_DQS_DN<9>")
	)
	(gr_poly
		(pts
			(xy 144.780254 -243.876322) (xy 144.680178 -243.776246) (xy 144.580102 -243.876322) (xy 144.580102 -243.920772)
			(xy 144.780254 -243.920772)
		)
		(stroke
			(width 0)
			(type solid)
		)
		(fill yes)
		(layer "In6.Cu")
		(net "M_K_CPU1_SA_DQ<29>")
	)
	(gr_poly
		(pts
			(xy 144.780254 -242.256056) (xy 144.680178 -242.15598) (xy 144.580102 -242.256056) (xy 144.580102 -242.303554)
			(xy 144.780254 -242.303554)
		)
		(stroke
			(width 0)
			(type solid)
		)
		(fill yes)
		(layer "In6.Cu")
		(net "M_K_CPU1_SA_DQS_DN<8>")
	)
	(gr_poly
		(pts
			(xy 144.780254 -240.636298) (xy 144.680178 -240.536222) (xy 144.580102 -240.636298) (xy 144.580102 -240.680748)
			(xy 144.780254 -240.680748)
		)
		(stroke
			(width 0)
			(type solid)
		)
		(fill yes)
		(layer "In6.Cu")
		(net "M_K_CPU1_SA_DQ<25>")
	)
	(gr_poly
		(pts
			(xy 144.780254 -239.016286) (xy 144.680178 -238.91621) (xy 144.580102 -239.016286) (xy 144.580102 -239.060736)
			(xy 144.780254 -239.060736)
		)
		(stroke
			(width 0)
			(type solid)
		)
		(fill yes)
		(layer "In6.Cu")
		(net "M_K_CPU1_SA_DQ<21>")
	)
	(gr_poly
		(pts
			(xy 144.780254 -235.776262) (xy 144.680178 -235.676186) (xy 144.580102 -235.776262) (xy 144.580102 -235.820712)
			(xy 144.780254 -235.820712)
		)
		(stroke
			(width 0)
			(type solid)
		)
		(fill yes)
		(layer "In6.Cu")
		(net "M_K_CPU1_SA_DQ<17>")
	)
	(gr_poly
		(pts
			(xy 144.780254 -234.15625) (xy 144.680178 -234.056174) (xy 144.580102 -234.15625) (xy 144.580102 -234.2007)
			(xy 144.780254 -234.2007)
		)
		(stroke
			(width 0)
			(type solid)
		)
		(fill yes)
		(layer "In6.Cu")
		(net "M_K_CPU1_SA_DQ<13>")
	)
	(gr_poly
		(pts
			(xy 144.780508 -254.812546) (xy 144.780508 -254.768096) (xy 144.58061 -254.768096) (xy 144.58061 -254.812546)
			(xy 144.680432 -254.912622)
		)
		(stroke
			(width 0)
			(type solid)
		)
		(fill yes)
		(layer "In6.Cu")
		(net "M_K_CPU1_SA_CA<5>")
	)
	(gr_poly
		(pts
			(xy 144.780508 -253.192534) (xy 144.780508 -253.148084) (xy 144.58061 -253.148084) (xy 144.58061 -253.192534)
			(xy 144.680432 -253.29261)
		)
		(stroke
			(width 0)
			(type solid)
		)
		(fill yes)
		(layer "In6.Cu")
		(net "M_K_CPU1_SA_CA<1>")
	)
	(gr_poly
		(pts
			(xy 144.780508 -248.332498) (xy 144.780508 -248.288048) (xy 144.58061 -248.288048) (xy 144.58061 -248.332498)
			(xy 144.680432 -248.432574)
		)
		(stroke
			(width 0)
			(type solid)
		)
		(fill yes)
		(layer "In6.Cu")
		(net "M_K_CPU1_SA_CB<6>")
	)
	(gr_poly
		(pts
			(xy 144.780508 -246.71274) (xy 144.780508 -246.665242) (xy 144.58061 -246.665242) (xy 144.58061 -246.71274)
			(xy 144.680432 -246.812816)
		)
		(stroke
			(width 0)
			(type solid)
		)
		(fill yes)
		(layer "In6.Cu")
		(net "M_K_CPU1_SA_DQS_DN<4>")
	)
	(gr_poly
		(pts
			(xy 144.780508 -245.496334) (xy 144.680432 -245.396258) (xy 144.58061 -245.496334) (xy 144.58061 -245.540784)
			(xy 144.780508 -245.540784)
		)
		(stroke
			(width 0)
			(type solid)
		)
		(fill yes)
		(layer "In6.Cu")
		(net "M_K_CPU1_SA_CB<1>")
	)
	(gr_poly
		(pts
			(xy 144.780508 -245.092474) (xy 144.780508 -245.048024) (xy 144.58061 -245.048024) (xy 144.58061 -245.092474)
			(xy 144.680432 -245.19255)
		)
		(stroke
			(width 0)
			(type solid)
		)
		(fill yes)
		(layer "In6.Cu")
		(net "M_K_CPU1_SA_CB<2>")
	)
	(gr_poly
		(pts
			(xy 144.780508 -243.472462) (xy 144.780508 -243.428012) (xy 144.58061 -243.428012) (xy 144.58061 -243.472462)
			(xy 144.680432 -243.572538)
		)
		(stroke
			(width 0)
			(type solid)
		)
		(fill yes)
		(layer "In6.Cu")
		(net "M_K_CPU1_SA_DQ<30>")
	)
	(gr_poly
		(pts
			(xy 144.780508 -241.852704) (xy 144.780508 -241.805206) (xy 144.58061 -241.805206) (xy 144.58061 -241.852704)
			(xy 144.680432 -241.95278)
		)
		(stroke
			(width 0)
			(type solid)
		)
		(fill yes)
		(layer "In6.Cu")
		(net "M_K_CPU1_SA_DQS_DN<3>")
	)
	(gr_poly
		(pts
			(xy 144.780508 -240.232438) (xy 144.780508 -240.187988) (xy 144.58061 -240.187988) (xy 144.58061 -240.232438)
			(xy 144.680432 -240.332514)
		)
		(stroke
			(width 0)
			(type solid)
		)
		(fill yes)
		(layer "In6.Cu")
		(net "M_K_CPU1_SA_DQ<26>")
	)
	(gr_poly
		(pts
			(xy 144.780508 -238.612426) (xy 144.780508 -238.567976) (xy 144.58061 -238.567976) (xy 144.58061 -238.612426)
			(xy 144.680432 -238.712502)
		)
		(stroke
			(width 0)
			(type solid)
		)
		(fill yes)
		(layer "In6.Cu")
		(net "M_K_CPU1_SA_DQ<22>")
	)
	(gr_poly
		(pts
			(xy 144.780508 -236.992668) (xy 144.780508 -236.94517) (xy 144.58061 -236.94517) (xy 144.58061 -236.992668)
			(xy 144.680432 -237.092744)
		)
		(stroke
			(width 0)
			(type solid)
		)
		(fill yes)
		(layer "In6.Cu")
		(net "M_K_CPU1_SA_DQS_DN<2>")
	)
	(gr_poly
		(pts
			(xy 144.780508 -235.372402) (xy 144.780508 -235.327952) (xy 144.58061 -235.327952) (xy 144.58061 -235.372402)
			(xy 144.680432 -235.472478)
		)
		(stroke
			(width 0)
			(type solid)
		)
		(fill yes)
		(layer "In6.Cu")
		(net "M_K_CPU1_SA_DQ<18>")
	)
	(gr_poly
		(pts
			(xy 144.780508 -233.75239) (xy 144.780508 -233.70794) (xy 144.58061 -233.70794) (xy 144.58061 -233.75239)
			(xy 144.680432 -233.852466)
		)
		(stroke
			(width 0)
			(type solid)
		)
		(fill yes)
		(layer "In6.Cu")
		(net "M_K_CPU1_SA_DQ<14>")
	)
	(gr_poly
		(pts
			(xy 144.780508 -232.535984) (xy 144.680432 -232.435908) (xy 144.58061 -232.535984) (xy 144.58061 -232.583482)
			(xy 144.780508 -232.583482)
		)
		(stroke
			(width 0)
			(type solid)
		)
		(fill yes)
		(layer "In6.Cu")
		(net "M_K_CPU1_SA_DQS_DN<6>")
	)
	(gr_poly
		(pts
			(xy 144.780508 -232.132632) (xy 144.780508 -232.085134) (xy 144.58061 -232.085134) (xy 144.58061 -232.132632)
			(xy 144.680432 -232.232708)
		)
		(stroke
			(width 0)
			(type solid)
		)
		(fill yes)
		(layer "In6.Cu")
		(net "M_K_CPU1_SA_DQS_DN<1>")
	)
	(gr_poly
		(pts
			(xy 144.782794 -237.396528) (xy 144.682972 -237.296452) (xy 144.582896 -237.396528) (xy 144.582896 -237.444026)
			(xy 144.782794 -237.444026)
		)
		(stroke
			(width 0)
			(type solid)
		)
		(fill yes)
		(layer "In6.Cu")
		(net "M_K_CPU1_SA_DQS_DN<7>")
	)
	(gr_poly
		(pts
			(xy 144.783048 -256.432812) (xy 144.783048 -256.385314) (xy 144.58315 -256.385314) (xy 144.58315 -256.432812)
			(xy 144.682972 -256.532888)
		)
		(stroke
			(width 0)
			(type solid)
		)
		(fill yes)
		(layer "In6.Cu")
		(net "M_K_CPU1_CLK_DN<0>")
	)
	(gr_poly
		(pts
			(xy 144.830546 -226.18954) (xy 144.79397 -226.053142) (xy 144.752568 -226.029266) (xy 144.652746 -226.202494)
			(xy 144.693894 -226.22637)
		)
		(stroke
			(width 0)
			(type solid)
		)
		(fill yes)
		(layer "In6.Cu")
		(net "M_K_CPU1_SA_DQS_DN<0>")
	)
	(gr_poly
		(pts
			(xy 144.830546 -222.949008) (xy 144.79397 -222.812356) (xy 144.755616 -222.790004) (xy 144.65554 -222.963232)
			(xy 144.694148 -222.985584)
		)
		(stroke
			(width 0)
			(type solid)
		)
		(fill yes)
		(layer "In6.Cu")
		(net "M_K_CPU1_SA_DQ<3>")
	)
	(gr_poly
		(pts
			(xy 144.99082 -295.505632) (xy 144.890744 -295.332404) (xy 144.85239 -295.354756) (xy 144.815814 -295.491408)
			(xy 144.952212 -295.527984)
		)
		(stroke
			(width 0)
			(type solid)
		)
		(fill yes)
		(layer "In6.Cu")
		(net "M_K_CPU1_SB_DQ<31>")
	)
	(gr_poly
		(pts
			(xy 144.993868 -293.874952) (xy 144.893792 -293.701724) (xy 144.855438 -293.724076) (xy 144.818862 -293.860728)
			(xy 144.95526 -293.897304)
		)
		(stroke
			(width 0)
			(type solid)
		)
		(fill yes)
		(layer "In6.Cu")
		(net "M_K_CPU1_SB_DQ<30>")
	)
	(gr_poly
		(pts
			(xy 145.074894 -269.428214) (xy 144.974818 -269.328138) (xy 144.874742 -269.428214) (xy 144.874742 -269.472664)
			(xy 145.074894 -269.472664)
		)
		(stroke
			(width 0)
			(type solid)
		)
		(fill yes)
		(layer "In6.Cu")
		(net "M_K_CPU1_SB_CB<5>")
	)
	(gr_poly
		(pts
			(xy 145.074894 -269.024354) (xy 145.074894 -268.979904) (xy 144.874742 -268.979904) (xy 144.874742 -269.024354)
			(xy 144.974818 -269.12443)
		)
		(stroke
			(width 0)
			(type solid)
		)
		(fill yes)
		(layer "In6.Cu")
		(net "M_K_CPU1_SB_CB<6>")
	)
	(gr_poly
		(pts
			(xy 145.075148 -277.52802) (xy 144.975072 -277.428198) (xy 144.87525 -277.52802) (xy 144.87525 -277.57247)
			(xy 145.075148 -277.57247)
		)
		(stroke
			(width 0)
			(type solid)
		)
		(fill yes)
		(layer "In6.Cu")
		(net "M_K_CPU1_SB_DQ<4>")
	)
	(gr_poly
		(pts
			(xy 145.076164 -281.984196) (xy 145.076164 -281.936698) (xy 144.876266 -281.936698) (xy 144.876266 -281.984196)
			(xy 144.976088 -282.084272)
		)
		(stroke
			(width 0)
			(type solid)
		)
		(fill yes)
		(layer "In6.Cu")
		(net "M_K_CPU1_SB_DQS_DP<6>")
	)
	(gr_poly
		(pts
			(xy 145.080228 -285.224474) (xy 145.080228 -285.180024) (xy 144.88033 -285.180024) (xy 144.88033 -285.224474)
			(xy 144.980152 -285.32455)
		)
		(stroke
			(width 0)
			(type solid)
		)
		(fill yes)
		(layer "In6.Cu")
		(net "M_K_CPU1_SB_DQ<19>")
	)
	(gr_poly
		(pts
			(xy 145.080228 -283.604462) (xy 145.080228 -283.560012) (xy 144.88033 -283.560012) (xy 144.88033 -283.604462)
			(xy 144.980152 -283.704538)
		)
		(stroke
			(width 0)
			(type solid)
		)
		(fill yes)
		(layer "In6.Cu")
		(net "M_K_CPU1_SB_DQ<15>")
	)
	(gr_poly
		(pts
			(xy 145.080228 -280.364438) (xy 145.080228 -280.319988) (xy 144.88033 -280.319988) (xy 144.88033 -280.364438)
			(xy 144.980152 -280.464514)
		)
		(stroke
			(width 0)
			(type solid)
		)
		(fill yes)
		(layer "In6.Cu")
		(net "M_K_CPU1_SB_DQ<11>")
	)
	(gr_poly
		(pts
			(xy 145.080228 -278.744426) (xy 145.080228 -278.699976) (xy 144.88033 -278.699976) (xy 144.88033 -278.744426)
			(xy 144.980152 -278.844502)
		)
		(stroke
			(width 0)
			(type solid)
		)
		(fill yes)
		(layer "In6.Cu")
		(net "M_K_CPU1_SB_DQ<7>")
	)
	(gr_poly
		(pts
			(xy 145.080228 -277.124668) (xy 145.080228 -277.07717) (xy 144.88033 -277.07717) (xy 144.88033 -277.124668)
			(xy 144.980406 -277.224744)
		)
		(stroke
			(width 0)
			(type solid)
		)
		(fill yes)
		(layer "In6.Cu")
		(net "M_K_CPU1_SB_DQS_DP<5>")
	)
	(gr_poly
		(pts
			(xy 145.080228 -275.504402) (xy 145.080228 -275.459952) (xy 144.88033 -275.459952) (xy 144.88033 -275.504402)
			(xy 144.980152 -275.604478)
		)
		(stroke
			(width 0)
			(type solid)
		)
		(fill yes)
		(layer "In6.Cu")
		(net "M_K_CPU1_SB_DQ<3>")
	)
	(gr_poly
		(pts
			(xy 145.080228 -273.88439) (xy 145.080228 -273.83994) (xy 144.88033 -273.83994) (xy 144.88033 -273.88439)
			(xy 144.980152 -273.984466)
		)
		(stroke
			(width 0)
			(type solid)
		)
		(fill yes)
		(layer "In6.Cu")
		(net "M_K_CPU1_SB_CB<3>")
	)
	(gr_poly
		(pts
			(xy 145.080228 -265.78433) (xy 145.080228 -265.73988) (xy 144.88033 -265.73988) (xy 144.88033 -265.78433)
			(xy 144.980152 -265.884406)
		)
		(stroke
			(width 0)
			(type solid)
		)
		(fill yes)
		(layer "In6.Cu")
		(net "M_K_CPU1_SB_CS_N<0>")
	)
	(gr_poly
		(pts
			(xy 145.080228 -264.164318) (xy 145.080228 -264.119868) (xy 144.88033 -264.119868) (xy 144.88033 -264.164318)
			(xy 144.980152 -264.264394)
		)
		(stroke
			(width 0)
			(type solid)
		)
		(fill yes)
		(layer "In6.Cu")
		(net "M_K_CPU1_SB_CA<5>")
	)
	(gr_poly
		(pts
			(xy 145.080228 -262.544306) (xy 145.080228 -262.499856) (xy 144.88033 -262.499856) (xy 144.88033 -262.544306)
			(xy 144.980152 -262.644382)
		)
		(stroke
			(width 0)
			(type solid)
		)
		(fill yes)
		(layer "In6.Cu")
		(net "M_K_CPU1_SB_CA<1>")
	)
	(gr_poly
		(pts
			(xy 145.080482 -284.008322) (xy 144.980406 -283.908246) (xy 144.88033 -284.008322) (xy 144.88033 -284.052772)
			(xy 145.080482 -284.052772)
		)
		(stroke
			(width 0)
			(type solid)
		)
		(fill yes)
		(layer "In6.Cu")
		(net "M_K_CPU1_SB_DQ<16>")
	)
	(gr_poly
		(pts
			(xy 145.080482 -282.38831) (xy 144.980406 -282.288234) (xy 144.88033 -282.38831) (xy 144.88033 -282.43276)
			(xy 145.080482 -282.43276)
		)
		(stroke
			(width 0)
			(type solid)
		)
		(fill yes)
		(layer "In6.Cu")
		(net "M_K_CPU1_SB_DQ<12>")
	)
	(gr_poly
		(pts
			(xy 145.080482 -279.148286) (xy 144.980406 -279.04821) (xy 144.88033 -279.148286) (xy 144.88033 -279.192736)
			(xy 145.080482 -279.192736)
		)
		(stroke
			(width 0)
			(type solid)
		)
		(fill yes)
		(layer "In6.Cu")
		(net "M_K_CPU1_SB_DQ<8>")
	)
	(gr_poly
		(pts
			(xy 145.080482 -274.28825) (xy 144.980406 -274.188174) (xy 144.88033 -274.28825) (xy 144.88033 -274.3327)
			(xy 145.080482 -274.3327)
		)
		(stroke
			(width 0)
			(type solid)
		)
		(fill yes)
		(layer "In6.Cu")
		(net "M_K_CPU1_SB_DQ<0>")
	)
	(gr_poly
		(pts
			(xy 145.080482 -272.668238) (xy 144.980406 -272.568162) (xy 144.88033 -272.668238) (xy 144.88033 -272.712688)
			(xy 145.080482 -272.712688)
		)
		(stroke
			(width 0)
			(type solid)
		)
		(fill yes)
		(layer "In6.Cu")
		(net "M_K_CPU1_SB_CB<0>")
	)
	(gr_poly
		(pts
			(xy 145.080482 -267.808202) (xy 144.980406 -267.708126) (xy 144.88033 -267.808202) (xy 144.88033 -267.852652)
			(xy 145.080482 -267.852652)
		)
		(stroke
			(width 0)
			(type solid)
		)
		(fill yes)
		(layer "In6.Cu")
		(net "M_K_CPU1_SB_RSP<0>")
	)
	(gr_poly
		(pts
			(xy 145.080482 -264.568178) (xy 144.980406 -264.468102) (xy 144.88033 -264.568178) (xy 144.88033 -264.612628)
			(xy 145.080482 -264.612628)
		)
		(stroke
			(width 0)
			(type solid)
		)
		(fill yes)
		(layer "In6.Cu")
		(net "M_K_CPU1_SB_CA<6>")
	)
	(gr_poly
		(pts
			(xy 145.080482 -262.948166) (xy 144.980406 -262.84809) (xy 144.88033 -262.948166) (xy 144.88033 -262.992616)
			(xy 145.080482 -262.992616)
		)
		(stroke
			(width 0)
			(type solid)
		)
		(fill yes)
		(layer "In6.Cu")
		(net "M_K_CPU1_SB_CA<2>")
	)
	(gr_poly
		(pts
			(xy 145.083022 -290.487862) (xy 144.982946 -290.387786) (xy 144.88287 -290.487862) (xy 144.88287 -290.535614)
			(xy 145.083022 -290.535614)
		)
		(stroke
			(width 0)
			(type solid)
		)
		(fill yes)
		(layer "In6.Cu")
		(net "M_K_CPU1_SB_DQS_DP<3>")
	)
	(gr_poly
		(pts
			(xy 145.083022 -285.62808) (xy 144.982946 -285.528004) (xy 144.883124 -285.62808) (xy 144.883124 -285.675578)
			(xy 145.083022 -285.675578)
		)
		(stroke
			(width 0)
			(type solid)
		)
		(fill yes)
		(layer "In6.Cu")
		(net "M_K_CPU1_SB_DQS_DP<2>")
	)
	(gr_poly
		(pts
			(xy 145.083022 -280.768044) (xy 144.982946 -280.667968) (xy 144.883124 -280.768044) (xy 144.883124 -280.815542)
			(xy 145.083022 -280.815542)
		)
		(stroke
			(width 0)
			(type solid)
		)
		(fill yes)
		(layer "In6.Cu")
		(net "M_K_CPU1_SB_DQS_DP<1>")
	)
	(gr_poly
		(pts
			(xy 145.083022 -275.908008) (xy 144.982946 -275.807932) (xy 144.883124 -275.908008) (xy 144.883124 -275.955506)
			(xy 145.083022 -275.955506)
		)
		(stroke
			(width 0)
			(type solid)
		)
		(fill yes)
		(layer "In6.Cu")
		(net "M_K_CPU1_SB_DQS_DP<0>")
	)
	(gr_poly
		(pts
			(xy 145.083022 -272.264124) (xy 145.083022 -272.216372) (xy 144.883124 -272.216372) (xy 144.883124 -272.264124)
			(xy 144.982946 -272.3642)
		)
		(stroke
			(width 0)
			(type solid)
		)
		(fill yes)
		(layer "In6.Cu")
		(net "M_K_CPU1_SB_DQS_DP<4>")
	)
	(gr_poly
		(pts
			(xy 145.093944 -293.328344) (xy 145.130774 -293.191692) (xy 144.994122 -293.155116) (xy 144.955514 -293.177468)
			(xy 145.05559 -293.350696)
		)
		(stroke
			(width 0)
			(type solid)
		)
		(fill yes)
		(layer "In6.Cu")
		(net "M_K_CPU1_SB_DQ<28>")
	)
	(gr_poly
		(pts
			(xy 145.105374 -294.943276) (xy 145.14195 -294.806624) (xy 145.005298 -294.770048) (xy 144.96669 -294.792146)
			(xy 145.066766 -294.965374)
		)
		(stroke
			(width 0)
			(type solid)
		)
		(fill yes)
		(layer "In6.Cu")
		(net "M_K_CPU1_SB_DQ<29>")
	)
	(gr_poly
		(pts
			(xy 145.137886 -271.166844) (xy 145.089626 -271.034002) (xy 145.046446 -271.013936) (xy 144.961864 -271.195038)
			(xy 145.005044 -271.215358)
		)
		(stroke
			(width 0)
			(type solid)
		)
		(fill yes)
		(layer "In6.Cu")
		(net "M_K_CPU1_SB_DQS_DN<9>")
	)
	(gr_poly
		(pts
			(xy 145.204688 -236.189774) (xy 145.208498 -236.145578) (xy 145.009362 -236.128052) (xy 145.005298 -236.172502)
			(xy 145.09623 -236.280706)
		)
		(stroke
			(width 0)
			(type solid)
		)
		(fill yes)
		(layer "In6.Cu")
		(net "M_K_CPU1_SA_DQ<19>")
	)
	(gr_poly
		(pts
			(xy 145.233898 -247.522746) (xy 145.233898 -247.474994) (xy 145.034 -247.474994) (xy 145.034 -247.522746)
			(xy 145.134076 -247.622568)
		)
		(stroke
			(width 0)
			(type solid)
		)
		(fill yes)
		(layer "In6.Cu")
		(net "M_K_CPU1_SA_DQS_DP<9>")
	)
	(gr_poly
		(pts
			(xy 145.23593 -256.026158) (xy 145.136108 -255.926082) (xy 145.036032 -256.026158) (xy 145.036032 -256.073656)
			(xy 145.23593 -256.073656)
		)
		(stroke
			(width 0)
			(type solid)
		)
		(fill yes)
		(layer "In6.Cu")
		(net "M_K_CPU1_CLK_DP<0>")
	)
	(gr_poly
		(pts
			(xy 145.23593 -254.4064) (xy 145.136108 -254.306324) (xy 145.036032 -254.4064) (xy 145.036032 -254.45085)
			(xy 145.23593 -254.45085)
		)
		(stroke
			(width 0)
			(type solid)
		)
		(fill yes)
		(layer "In6.Cu")
		(net "M_K_CPU1_SA_CA<4>")
	)
	(gr_poly
		(pts
			(xy 145.23593 -252.786388) (xy 145.136108 -252.686312) (xy 145.036032 -252.786388) (xy 145.036032 -252.830838)
			(xy 145.23593 -252.830838)
		)
		(stroke
			(width 0)
			(type solid)
		)
		(fill yes)
		(layer "In6.Cu")
		(net "M_K_CPU1_SA_CA<0>")
	)
	(gr_poly
		(pts
			(xy 145.23593 -251.166376) (xy 145.136108 -251.0663) (xy 145.036032 -251.166376) (xy 145.036032 -251.210826)
			(xy 145.23593 -251.210826)
		)
		(stroke
			(width 0)
			(type solid)
		)
		(fill yes)
		(layer "In6.Cu")
		(net "M_K_CPU1_SA_CS_N<0>")
	)
	(gr_poly
		(pts
			(xy 145.23593 -247.926352) (xy 145.136108 -247.826276) (xy 145.036032 -247.926352) (xy 145.036032 -247.970802)
			(xy 145.23593 -247.970802)
		)
		(stroke
			(width 0)
			(type solid)
		)
		(fill yes)
		(layer "In6.Cu")
		(net "M_K_CPU1_SA_CB<4>")
	)
	(gr_poly
		(pts
			(xy 145.23593 -246.306086) (xy 145.136108 -246.20601) (xy 145.036032 -246.306086) (xy 145.036032 -246.353584)
			(xy 145.23593 -246.353584)
		)
		(stroke
			(width 0)
			(type solid)
		)
		(fill yes)
		(layer "In6.Cu")
		(net "M_K_CPU1_SA_DQS_DP<4>")
	)
	(gr_poly
		(pts
			(xy 145.23593 -244.686328) (xy 145.136108 -244.586252) (xy 145.036032 -244.686328) (xy 145.036032 -244.730778)
			(xy 145.23593 -244.730778)
		)
		(stroke
			(width 0)
			(type solid)
		)
		(fill yes)
		(layer "In6.Cu")
		(net "M_K_CPU1_SA_CB<0>")
	)
	(gr_poly
		(pts
			(xy 145.23593 -232.942638) (xy 145.23593 -232.89514) (xy 145.036032 -232.89514) (xy 145.036032 -232.942638)
			(xy 145.136108 -233.042714)
		)
		(stroke
			(width 0)
			(type solid)
		)
		(fill yes)
		(layer "In6.Cu")
		(net "M_K_CPU1_SA_DQS_DP<6>")
	)
	(gr_poly
		(pts
			(xy 145.237454 -254.00254) (xy 145.237454 -253.95809) (xy 145.037556 -253.95809) (xy 145.037556 -254.00254)
			(xy 145.137378 -254.102616)
		)
		(stroke
			(width 0)
			(type solid)
		)
		(fill yes)
		(layer "In6.Cu")
		(net "M_K_CPU1_SA_CA<3>")
	)
	(gr_poly
		(pts
			(xy 145.237454 -239.422432) (xy 145.237454 -239.377982) (xy 145.037556 -239.377982) (xy 145.037556 -239.422432)
			(xy 145.137378 -239.522508)
		)
		(stroke
			(width 0)
			(type solid)
		)
		(fill yes)
		(layer "In6.Cu")
		(net "M_K_CPU1_SA_DQ<23>")
	)
	(gr_poly
		(pts
			(xy 145.237454 -234.562396) (xy 145.237454 -234.517946) (xy 145.037556 -234.517946) (xy 145.037556 -234.562396)
			(xy 145.137378 -234.662472)
		)
		(stroke
			(width 0)
			(type solid)
		)
		(fill yes)
		(layer "In6.Cu")
		(net "M_K_CPU1_SA_DQ<15>")
	)
	(gr_poly
		(pts
			(xy 145.266664 -227.05568) (xy 145.242026 -226.916488) (xy 145.203164 -226.889056) (xy 145.088356 -227.052886)
			(xy 145.127472 -227.080318)
		)
		(stroke
			(width 0)
			(type solid)
		)
		(fill yes)
		(layer "In6.Cu")
		(net "M_K_CPU1_SA_DQS_DP<5>")
	)
	(gr_poly
		(pts
			(xy 145.32737 -237.790482) (xy 145.323306 -237.742984) (xy 145.12417 -237.76051) (xy 145.128234 -237.808008)
			(xy 145.236438 -237.898686)
		)
		(stroke
			(width 0)
			(type solid)
		)
		(fill yes)
		(layer "In6.Cu")
		(net "M_K_CPU1_SA_DQS_DP<7>")
	)
	(gr_poly
		(pts
			(xy 145.463768 -294.684958) (xy 145.363692 -294.51173) (xy 145.325338 -294.534082) (xy 145.288762 -294.670734)
			(xy 145.42516 -294.70731)
		)
		(stroke
			(width 0)
			(type solid)
		)
		(fill yes)
		(layer "In6.Cu")
		(net "M_K_CPU1_SB_DQ<30>")
	)
	(gr_poly
		(pts
			(xy 145.533872 -276.314662) (xy 145.533872 -276.26691) (xy 145.333974 -276.26691) (xy 145.333974 -276.314662)
			(xy 145.43405 -276.414484)
		)
		(stroke
			(width 0)
			(type solid)
		)
		(fill yes)
		(layer "In6.Cu")
		(net "M_K_CPU1_SB_DQS_DN<0>")
	)
	(gr_poly
		(pts
			(xy 145.563844 -294.13835) (xy 145.600674 -294.001698) (xy 145.464022 -293.965122) (xy 145.425414 -293.987474)
			(xy 145.52549 -294.160702)
		)
		(stroke
			(width 0)
			(type solid)
		)
		(fill yes)
		(layer "In6.Cu")
		(net "M_K_CPU1_SB_DQ<28>")
	)
	(gr_poly
		(pts
			(xy 145.636742 -223.886522) (xy 145.595594 -223.8629) (xy 145.458942 -223.899476) (xy 145.495518 -224.035874)
			(xy 145.53692 -224.05975)
		)
		(stroke
			(width 0)
			(type solid)
		)
		(fill yes)
		(layer "In6.Cu")
		(net "M_K_CPU1_SA_DQS_DN<5>")
	)
	(gr_poly
		(pts
			(xy 145.717514 -253.596394) (xy 145.617438 -253.496318) (xy 145.517362 -253.596394) (xy 145.517362 -253.640844)
			(xy 145.717514 -253.640844)
		)
		(stroke
			(width 0)
			(type solid)
		)
		(fill yes)
		(layer "In6.Cu")
		(net "M_K_CPU1_SA_CA<2>")
	)
	(gr_poly
		(pts
			(xy 145.722594 -247.116092) (xy 145.622518 -247.01627) (xy 145.522696 -247.116092) (xy 145.522696 -247.163844)
			(xy 145.722594 -247.163844)
		)
		(stroke
			(width 0)
			(type solid)
		)
		(fill yes)
		(layer "In6.Cu")
		(net "M_K_CPU1_SA_DQS_DN<9>")
	)
	(gr_poly
		(pts
			(xy 145.7706 -222.948754) (xy 145.734024 -222.812102) (xy 145.692622 -222.78848) (xy 145.5928 -222.961708)
			(xy 145.633948 -222.98533)
		)
		(stroke
			(width 0)
			(type solid)
		)
		(fill yes)
		(layer "In6.Cu")
		(net "M_K_CPU1_SA_DQS_DN<0>")
	)
	(gr_poly
		(pts
			(xy 146.2405 -223.759522) (xy 146.203924 -223.623124) (xy 146.162522 -223.599248) (xy 146.0627 -223.772476)
			(xy 146.103848 -223.796352)
		)
		(stroke
			(width 0)
			(type solid)
		)
		(fill yes)
		(layer "In6.Cu")
		(net "M_K_CPU1_SA_DQS_DP<5>")
	)
	(gr_poly
		(pts
			(xy 325.432674 -223.771206) (xy 325.333868 -223.60001) (xy 325.292466 -223.623632) (xy 325.255382 -223.759268)
			(xy 325.391526 -223.795082)
		)
		(stroke
			(width 0)
			(type solid)
		)
		(fill yes)
		(layer "In6.Cu")
		(net "M_E_CPU0_SA_DQS_DP<5>")
	)
	(gr_poly
		(pts
			(xy 325.980806 -253.595632) (xy 325.880984 -253.495556) (xy 325.780908 -253.595632) (xy 325.780908 -253.640082)
			(xy 325.980806 -253.640082)
		)
		(stroke
			(width 0)
			(type solid)
		)
		(fill yes)
		(layer "In6.Cu")
		(net "M_E_CPU0_SA_CA<2>")
	)
	(gr_poly
		(pts
			(xy 325.980806 -250.355608) (xy 325.880984 -250.255532) (xy 325.780908 -250.355608) (xy 325.780908 -250.400058)
			(xy 325.980806 -250.400058)
		)
		(stroke
			(width 0)
			(type solid)
		)
		(fill yes)
		(layer "In6.Cu")
		(net "M_E_CPU0_ALERT_R_N")
	)
	(gr_poly
		(pts
			(xy 325.999602 -224.034604) (xy 326.03694 -223.899222) (xy 325.900796 -223.863408) (xy 325.859648 -223.887284)
			(xy 325.958454 -224.05848)
		)
		(stroke
			(width 0)
			(type solid)
		)
		(fill yes)
		(layer "In6.Cu")
		(net "M_E_CPU0_SA_DQS_DN<5>")
	)
	(gr_poly
		(pts
			(xy 326.199754 -294.797734) (xy 326.161146 -294.775636) (xy 326.024494 -294.812212) (xy 326.061324 -294.948864)
			(xy 326.099678 -294.970962)
		)
		(stroke
			(width 0)
			(type solid)
		)
		(fill yes)
		(layer "In6.Cu")
		(net "M_E_CPU0_SB_DQ<28>")
	)
	(gr_poly
		(pts
			(xy 326.369934 -224.69602) (xy 326.331326 -224.673668) (xy 326.194674 -224.710498) (xy 326.231504 -224.846896)
			(xy 326.269858 -224.869248)
		)
		(stroke
			(width 0)
			(type solid)
		)
		(fill yes)
		(layer "In6.Cu")
		(net "M_E_CPU0_SA_DQS_DN<0>")
	)
	(gr_poly
		(pts
			(xy 326.370188 -225.392996) (xy 326.270112 -225.219768) (xy 326.231758 -225.24212) (xy 326.195182 -225.378772)
			(xy 326.33158 -225.415348)
		)
		(stroke
			(width 0)
			(type solid)
		)
		(fill yes)
		(layer "In6.Cu")
		(net "M_E_CPU0_SA_DQS_DN<0>")
	)
	(gr_poly
		(pts
			(xy 326.372982 -223.772222) (xy 326.27316 -223.598994) (xy 326.231758 -223.62287) (xy 326.195182 -223.759268)
			(xy 326.331834 -223.795844)
		)
		(stroke
			(width 0)
			(type solid)
		)
		(fill yes)
		(layer "In6.Cu")
		(net "M_E_CPU0_SA_DQS_DN<0>")
	)
	(gr_poly
		(pts
			(xy 326.379586 -232.94467) (xy 326.383904 -232.897426) (xy 326.184514 -232.8799) (xy 326.18045 -232.927398)
			(xy 326.271382 -233.035602)
		)
		(stroke
			(width 0)
			(type solid)
		)
		(fill yes)
		(layer "In6.Cu")
		(net "M_E_CPU0_SA_DQS_DP<6>")
	)
	(gr_poly
		(pts
			(xy 326.458326 -254.002286) (xy 326.458326 -253.957836) (xy 326.258428 -253.957836) (xy 326.258428 -254.002286)
			(xy 326.358504 -254.102362)
		)
		(stroke
			(width 0)
			(type solid)
		)
		(fill yes)
		(layer "In6.Cu")
		(net "M_E_CPU0_SA_CA<3>")
	)
	(gr_poly
		(pts
			(xy 326.458326 -252.382274) (xy 326.458326 -252.337824) (xy 326.258428 -252.337824) (xy 326.258428 -252.382274)
			(xy 326.358504 -252.48235)
		)
		(stroke
			(width 0)
			(type solid)
		)
		(fill yes)
		(layer "In6.Cu")
		(net "M_E_CPU0_SA_CS_N<1>")
	)
	(gr_poly
		(pts
			(xy 326.458326 -239.422178) (xy 326.458326 -239.377728) (xy 326.258428 -239.377728) (xy 326.258428 -239.422178)
			(xy 326.358504 -239.522254)
		)
		(stroke
			(width 0)
			(type solid)
		)
		(fill yes)
		(layer "In6.Cu")
		(net "M_E_CPU0_SA_DQ<23>")
	)
	(gr_poly
		(pts
			(xy 326.458326 -236.182154) (xy 326.458326 -236.137704) (xy 326.258428 -236.137704) (xy 326.258428 -236.182154)
			(xy 326.358504 -236.28223)
		)
		(stroke
			(width 0)
			(type solid)
		)
		(fill yes)
		(layer "In6.Cu")
		(net "M_E_CPU0_SA_DQ<19>")
	)
	(gr_poly
		(pts
			(xy 326.458326 -234.562142) (xy 326.458326 -234.517692) (xy 326.258428 -234.517692) (xy 326.258428 -234.562142)
			(xy 326.358504 -234.662218)
		)
		(stroke
			(width 0)
			(type solid)
		)
		(fill yes)
		(layer "In6.Cu")
		(net "M_E_CPU0_SA_DQ<15>")
	)
	(gr_poly
		(pts
			(xy 326.45985 -254.406146) (xy 326.359774 -254.30607) (xy 326.259952 -254.406146) (xy 326.259952 -254.450596)
			(xy 326.45985 -254.450596)
		)
		(stroke
			(width 0)
			(type solid)
		)
		(fill yes)
		(layer "In6.Cu")
		(net "M_E_CPU0_SA_CA<4>")
	)
	(gr_poly
		(pts
			(xy 326.45985 -252.786134) (xy 326.359774 -252.686058) (xy 326.259952 -252.786134) (xy 326.259952 -252.830584)
			(xy 326.45985 -252.830584)
		)
		(stroke
			(width 0)
			(type solid)
		)
		(fill yes)
		(layer "In6.Cu")
		(net "M_E_CPU0_SA_CA<0>")
	)
	(gr_poly
		(pts
			(xy 326.45985 -247.926098) (xy 326.359774 -247.826022) (xy 326.259952 -247.926098) (xy 326.259952 -247.970548)
			(xy 326.45985 -247.970548)
		)
		(stroke
			(width 0)
			(type solid)
		)
		(fill yes)
		(layer "In6.Cu")
		(net "M_E_CPU0_SA_CB<4>")
	)
	(gr_poly
		(pts
			(xy 326.45985 -244.686074) (xy 326.359774 -244.585998) (xy 326.259952 -244.686074) (xy 326.259952 -244.730524)
			(xy 326.45985 -244.730524)
		)
		(stroke
			(width 0)
			(type solid)
		)
		(fill yes)
		(layer "In6.Cu")
		(net "M_E_CPU0_SA_CB<0>")
	)
	(gr_poly
		(pts
			(xy 326.461882 -247.522492) (xy 326.461882 -247.47474) (xy 326.261984 -247.47474) (xy 326.261984 -247.522492)
			(xy 326.361806 -247.622568)
		)
		(stroke
			(width 0)
			(type solid)
		)
		(fill yes)
		(layer "In6.Cu")
		(net "M_E_CPU0_SA_DQS_DP<9>")
	)
	(gr_poly
		(pts
			(xy 326.461882 -242.662456) (xy 326.461882 -242.614704) (xy 326.261984 -242.614704) (xy 326.261984 -242.662456)
			(xy 326.361806 -242.762532)
		)
		(stroke
			(width 0)
			(type solid)
		)
		(fill yes)
		(layer "In6.Cu")
		(net "M_E_CPU0_SA_DQS_DP<8>")
	)
	(gr_poly
		(pts
			(xy 326.469502 -223.225106) (xy 326.506078 -223.088454) (xy 326.36968 -223.051878) (xy 326.328278 -223.075754)
			(xy 326.428354 -223.248982)
		)
		(stroke
			(width 0)
			(type solid)
		)
		(fill yes)
		(layer "In6.Cu")
		(net "M_E_CPU0_SA_DQS_DP<0>")
	)
	(gr_poly
		(pts
			(xy 326.50811 -237.79226) (xy 326.503792 -237.744762) (xy 326.304656 -237.762034) (xy 326.30872 -237.809532)
			(xy 326.417178 -237.900464)
		)
		(stroke
			(width 0)
			(type solid)
		)
		(fill yes)
		(layer "In6.Cu")
		(net "M_E_CPU0_SA_DQS_DP<7>")
	)
	(gr_poly
		(pts
			(xy 326.53097 -241.026696) (xy 326.51954 -240.98377) (xy 326.326246 -241.035586) (xy 326.33793 -241.078512)
			(xy 326.460358 -241.149124)
		)
		(stroke
			(width 0)
			(type solid)
		)
		(fill yes)
		(layer "In6.Cu")
		(net "M_E_CPU0_SA_DQ<27>")
	)
	(gr_poly
		(pts
			(xy 326.68083 -293.968932) (xy 326.642476 -293.94658) (xy 326.505824 -293.983156) (xy 326.5424 -294.119808)
			(xy 326.581008 -294.14216)
		)
		(stroke
			(width 0)
			(type solid)
		)
		(fill yes)
		(layer "In6.Cu")
		(net "M_E_CPU0_SB_DQ<28>")
	)
	(gr_poly
		(pts
			(xy 326.739758 -273.074384) (xy 326.739758 -273.029934) (xy 326.539606 -273.029934) (xy 326.539606 -273.074384)
			(xy 326.639682 -273.17446)
		)
		(stroke
			(width 0)
			(type solid)
		)
		(fill yes)
		(layer "In6.Cu")
		(net "M_E_CPU0_SB_CB<2>")
	)
	(gr_poly
		(pts
			(xy 326.759824 -281.174444) (xy 326.759824 -281.126946) (xy 326.559926 -281.126946) (xy 326.559926 -281.174444)
			(xy 326.659748 -281.27452)
		)
		(stroke
			(width 0)
			(type solid)
		)
		(fill yes)
		(layer "In6.Cu")
		(net "M_E_CPU0_SB_DQS_DN<1>")
	)
	(gr_poly
		(pts
			(xy 326.759824 -279.554178) (xy 326.759824 -279.509728) (xy 326.559926 -279.509728) (xy 326.559926 -279.554178)
			(xy 326.659748 -279.654254)
		)
		(stroke
			(width 0)
			(type solid)
		)
		(fill yes)
		(layer "In6.Cu")
		(net "M_E_CPU0_SB_DQ<10>")
	)
	(gr_poly
		(pts
			(xy 326.759824 -277.934166) (xy 326.759824 -277.889716) (xy 326.559926 -277.889716) (xy 326.559926 -277.934166)
			(xy 326.659748 -278.034242)
		)
		(stroke
			(width 0)
			(type solid)
		)
		(fill yes)
		(layer "In6.Cu")
		(net "M_E_CPU0_SB_DQ<6>")
	)
	(gr_poly
		(pts
			(xy 326.759824 -274.694142) (xy 326.759824 -274.649692) (xy 326.559926 -274.649692) (xy 326.559926 -274.694142)
			(xy 326.659748 -274.794218)
		)
		(stroke
			(width 0)
			(type solid)
		)
		(fill yes)
		(layer "In6.Cu")
		(net "M_E_CPU0_SB_DQ<2>")
	)
	(gr_poly
		(pts
			(xy 326.759824 -269.834106) (xy 326.759824 -269.789656) (xy 326.559926 -269.789656) (xy 326.559926 -269.834106)
			(xy 326.659748 -269.934182)
		)
		(stroke
			(width 0)
			(type solid)
		)
		(fill yes)
		(layer "In6.Cu")
		(net "M_E_CPU0_SB_CB<6>")
	)
	(gr_poly
		(pts
			(xy 326.759824 -264.97407) (xy 326.759824 -264.92962) (xy 326.559926 -264.92962) (xy 326.559926 -264.97407)
			(xy 326.659748 -265.074146)
		)
		(stroke
			(width 0)
			(type solid)
		)
		(fill yes)
		(layer "In6.Cu")
		(net "M_E_CPU0_SB_PAR")
	)
	(gr_poly
		(pts
			(xy 326.767952 -288.057844) (xy 326.667876 -287.957768) (xy 326.5678 -288.057844) (xy 326.5678 -288.102294)
			(xy 326.767952 -288.102294)
		)
		(stroke
			(width 0)
			(type solid)
		)
		(fill yes)
		(layer "In6.Cu")
		(net "M_E_CPU0_SB_DQ<21>")
	)
	(gr_poly
		(pts
			(xy 326.779636 -284.827218) (xy 326.688704 -284.719014) (xy 326.580246 -284.809946) (xy 326.576436 -284.854142)
			(xy 326.775826 -284.871668)
		)
		(stroke
			(width 0)
			(type solid)
		)
		(fill yes)
		(layer "In6.Cu")
		(net "M_E_CPU0_SB_DQ<17>")
	)
	(gr_poly
		(pts
			(xy 326.841866 -222.96501) (xy 326.74179 -222.791782) (xy 326.703436 -222.814134) (xy 326.66686 -222.950786)
			(xy 326.803258 -222.987362)
		)
		(stroke
			(width 0)
			(type solid)
		)
		(fill yes)
		(layer "In6.Cu")
		(net "M_E_CPU0_SA_DQ<3>")
	)
	(gr_poly
		(pts
			(xy 326.843136 -226.20224) (xy 326.743314 -226.029012) (xy 326.701912 -226.052888) (xy 326.665336 -226.189286)
			(xy 326.801988 -226.226116)
		)
		(stroke
			(width 0)
			(type solid)
		)
		(fill yes)
		(layer "In6.Cu")
		(net "M_E_CPU0_SA_DQS_DN<0>")
	)
	(gr_poly
		(pts
			(xy 326.905874 -289.22726) (xy 326.894444 -289.184334) (xy 326.70115 -289.23615) (xy 326.71258 -289.279076)
			(xy 326.835262 -289.349688)
		)
		(stroke
			(width 0)
			(type solid)
		)
		(fill yes)
		(layer "In6.Cu")
		(net "M_E_CPU0_SB_DQ<26>")
	)
	(gr_poly
		(pts
			(xy 326.905874 -287.607502) (xy 326.894444 -287.564576) (xy 326.70115 -287.616392) (xy 326.712834 -287.659064)
			(xy 326.835262 -287.72993)
		)
		(stroke
			(width 0)
			(type solid)
		)
		(fill yes)
		(layer "In6.Cu")
		(net "M_E_CPU0_SB_DQ<22>")
	)
	(gr_poly
		(pts
			(xy 326.912986 -237.396274) (xy 326.81291 -237.296198) (xy 326.712834 -237.396274) (xy 326.712834 -237.443772)
			(xy 326.912986 -237.443772)
		)
		(stroke
			(width 0)
			(type solid)
		)
		(fill yes)
		(layer "In6.Cu")
		(net "M_E_CPU0_SA_DQS_DN<7>")
	)
	(gr_poly
		(pts
			(xy 326.915526 -256.432558) (xy 326.915526 -256.38506) (xy 326.715374 -256.38506) (xy 326.715374 -256.432558)
			(xy 326.81545 -256.532634)
		)
		(stroke
			(width 0)
			(type solid)
		)
		(fill yes)
		(layer "In6.Cu")
		(net "M_E_CPU0_CLK_DN<0>")
	)
	(gr_poly
		(pts
			(xy 326.915526 -255.216152) (xy 326.815704 -255.116076) (xy 326.715628 -255.216152) (xy 326.715628 -255.260602)
			(xy 326.915526 -255.260602)
		)
		(stroke
			(width 0)
			(type solid)
		)
		(fill yes)
		(layer "In6.Cu")
		(net "M_E_CPU0_SA_CA<6>")
	)
	(gr_poly
		(pts
			(xy 326.915526 -254.812292) (xy 326.915526 -254.767842) (xy 326.715374 -254.767842) (xy 326.715374 -254.812292)
			(xy 326.81545 -254.912368)
		)
		(stroke
			(width 0)
			(type solid)
		)
		(fill yes)
		(layer "In6.Cu")
		(net "M_E_CPU0_SA_CA<5>")
	)
	(gr_poly
		(pts
			(xy 326.915526 -253.59614) (xy 326.815704 -253.496064) (xy 326.715628 -253.59614) (xy 326.715628 -253.64059)
			(xy 326.915526 -253.64059)
		)
		(stroke
			(width 0)
			(type solid)
		)
		(fill yes)
		(layer "In6.Cu")
		(net "M_E_CPU0_SA_CA<2>")
	)
	(gr_poly
		(pts
			(xy 326.915526 -253.19228) (xy 326.915526 -253.14783) (xy 326.715374 -253.14783) (xy 326.715374 -253.19228)
			(xy 326.81545 -253.292356)
		)
		(stroke
			(width 0)
			(type solid)
		)
		(fill yes)
		(layer "In6.Cu")
		(net "M_E_CPU0_SA_CA<1>")
	)
	(gr_poly
		(pts
			(xy 326.915526 -251.572268) (xy 326.915526 -251.527818) (xy 326.715374 -251.527818) (xy 326.715374 -251.572268)
			(xy 326.81545 -251.672344)
		)
		(stroke
			(width 0)
			(type solid)
		)
		(fill yes)
		(layer "In6.Cu")
		(net "M_E_CPU0_SA_CS_N<0>")
	)
	(gr_poly
		(pts
			(xy 326.915526 -250.356116) (xy 326.815704 -250.25604) (xy 326.715628 -250.356116) (xy 326.715628 -250.400566)
			(xy 326.915526 -250.400566)
		)
		(stroke
			(width 0)
			(type solid)
		)
		(fill yes)
		(layer "In6.Cu")
		(net "M_E_CPU0_ALERT_R_N")
	)
	(gr_poly
		(pts
			(xy 326.915526 -248.736104) (xy 326.815704 -248.636028) (xy 326.715628 -248.736104) (xy 326.715628 -248.780554)
			(xy 326.915526 -248.780554)
		)
		(stroke
			(width 0)
			(type solid)
		)
		(fill yes)
		(layer "In6.Cu")
		(net "M_E_CPU0_SA_CB<5>")
	)
	(gr_poly
		(pts
			(xy 326.915526 -248.332244) (xy 326.915526 -248.287794) (xy 326.715374 -248.287794) (xy 326.715374 -248.332244)
			(xy 326.81545 -248.43232)
		)
		(stroke
			(width 0)
			(type solid)
		)
		(fill yes)
		(layer "In6.Cu")
		(net "M_E_CPU0_SA_CB<6>")
	)
	(gr_poly
		(pts
			(xy 326.915526 -247.115838) (xy 326.815704 -247.015762) (xy 326.715628 -247.115838) (xy 326.715628 -247.163336)
			(xy 326.915526 -247.163336)
		)
		(stroke
			(width 0)
			(type solid)
		)
		(fill yes)
		(layer "In6.Cu")
		(net "M_E_CPU0_SA_DQS_DN<9>")
	)
	(gr_poly
		(pts
			(xy 326.915526 -246.712486) (xy 326.915526 -246.664988) (xy 326.715374 -246.664988) (xy 326.715374 -246.712486)
			(xy 326.81545 -246.812562)
		)
		(stroke
			(width 0)
			(type solid)
		)
		(fill yes)
		(layer "In6.Cu")
		(net "M_E_CPU0_SA_DQS_DN<4>")
	)
	(gr_poly
		(pts
			(xy 326.915526 -245.49608) (xy 326.815704 -245.396004) (xy 326.715628 -245.49608) (xy 326.715628 -245.54053)
			(xy 326.915526 -245.54053)
		)
		(stroke
			(width 0)
			(type solid)
		)
		(fill yes)
		(layer "In6.Cu")
		(net "M_E_CPU0_SA_CB<1>")
	)
	(gr_poly
		(pts
			(xy 326.915526 -245.09222) (xy 326.915526 -245.04777) (xy 326.715374 -245.04777) (xy 326.715374 -245.09222)
			(xy 326.81545 -245.192296)
		)
		(stroke
			(width 0)
			(type solid)
		)
		(fill yes)
		(layer "In6.Cu")
		(net "M_E_CPU0_SA_CB<2>")
	)
	(gr_poly
		(pts
			(xy 326.915526 -243.876068) (xy 326.815704 -243.775992) (xy 326.715628 -243.876068) (xy 326.715628 -243.920518)
			(xy 326.915526 -243.920518)
		)
		(stroke
			(width 0)
			(type solid)
		)
		(fill yes)
		(layer "In6.Cu")
		(net "M_E_CPU0_SA_DQ<29>")
	)
	(gr_poly
		(pts
			(xy 326.915526 -242.255802) (xy 326.815704 -242.155726) (xy 326.715628 -242.255802) (xy 326.715628 -242.3033)
			(xy 326.915526 -242.3033)
		)
		(stroke
			(width 0)
			(type solid)
		)
		(fill yes)
		(layer "In6.Cu")
		(net "M_E_CPU0_SA_DQS_DN<8>")
	)
	(gr_poly
		(pts
			(xy 326.915526 -241.85245) (xy 326.915526 -241.804952) (xy 326.715374 -241.804952) (xy 326.715374 -241.85245)
			(xy 326.81545 -241.952526)
		)
		(stroke
			(width 0)
			(type solid)
		)
		(fill yes)
		(layer "In6.Cu")
		(net "M_E_CPU0_SA_DQS_DN<3>")
	)
	(gr_poly
		(pts
			(xy 326.915526 -240.636044) (xy 326.815704 -240.535968) (xy 326.715628 -240.636044) (xy 326.715628 -240.680494)
			(xy 326.915526 -240.680494)
		)
		(stroke
			(width 0)
			(type solid)
		)
		(fill yes)
		(layer "In6.Cu")
		(net "M_E_CPU0_SA_DQ<25>")
	)
	(gr_poly
		(pts
			(xy 326.915526 -240.232184) (xy 326.915526 -240.187734) (xy 326.715374 -240.187734) (xy 326.715374 -240.232184)
			(xy 326.81545 -240.33226)
		)
		(stroke
			(width 0)
			(type solid)
		)
		(fill yes)
		(layer "In6.Cu")
		(net "M_E_CPU0_SA_DQ<26>")
	)
	(gr_poly
		(pts
			(xy 326.915526 -239.016032) (xy 326.815704 -238.915956) (xy 326.715628 -239.016032) (xy 326.715628 -239.060482)
			(xy 326.915526 -239.060482)
		)
		(stroke
			(width 0)
			(type solid)
		)
		(fill yes)
		(layer "In6.Cu")
		(net "M_E_CPU0_SA_DQ<21>")
	)
	(gr_poly
		(pts
			(xy 326.915526 -236.992414) (xy 326.915526 -236.944916) (xy 326.715374 -236.944916) (xy 326.715374 -236.992414)
			(xy 326.81545 -237.09249)
		)
		(stroke
			(width 0)
			(type solid)
		)
		(fill yes)
		(layer "In6.Cu")
		(net "M_E_CPU0_SA_DQS_DN<2>")
	)
	(gr_poly
		(pts
			(xy 326.915526 -235.776008) (xy 326.815704 -235.675932) (xy 326.715628 -235.776008) (xy 326.715628 -235.820458)
			(xy 326.915526 -235.820458)
		)
		(stroke
			(width 0)
			(type solid)
		)
		(fill yes)
		(layer "In6.Cu")
		(net "M_E_CPU0_SA_DQ<17>")
	)
	(gr_poly
		(pts
			(xy 326.915526 -234.155996) (xy 326.815704 -234.05592) (xy 326.715628 -234.155996) (xy 326.715628 -234.200446)
			(xy 326.915526 -234.200446)
		)
		(stroke
			(width 0)
			(type solid)
		)
		(fill yes)
		(layer "In6.Cu")
		(net "M_E_CPU0_SA_DQ<13>")
	)
	(gr_poly
		(pts
			(xy 326.915526 -233.752136) (xy 326.915526 -233.707686) (xy 326.715374 -233.707686) (xy 326.715374 -233.752136)
			(xy 326.81545 -233.852212)
		)
		(stroke
			(width 0)
			(type solid)
		)
		(fill yes)
		(layer "In6.Cu")
		(net "M_E_CPU0_SA_DQ<14>")
	)
	(gr_poly
		(pts
			(xy 326.915526 -232.53573) (xy 326.815704 -232.435654) (xy 326.715628 -232.53573) (xy 326.715628 -232.583228)
			(xy 326.915526 -232.583228)
		)
		(stroke
			(width 0)
			(type solid)
		)
		(fill yes)
		(layer "In6.Cu")
		(net "M_E_CPU0_SA_DQS_DN<6>")
	)
	(gr_poly
		(pts
			(xy 326.915526 -232.132378) (xy 326.915526 -232.08488) (xy 326.715628 -232.08488) (xy 326.715628 -232.132378)
			(xy 326.81545 -232.232454)
		)
		(stroke
			(width 0)
			(type solid)
		)
		(fill yes)
		(layer "In6.Cu")
		(net "M_E_CPU0_SA_DQS_DN<1>")
	)
	(gr_poly
		(pts
			(xy 326.923908 -243.472208) (xy 326.923908 -243.427758) (xy 326.723756 -243.427758) (xy 326.723756 -243.472208)
			(xy 326.823832 -243.572284)
		)
		(stroke
			(width 0)
			(type solid)
		)
		(fill yes)
		(layer "In6.Cu")
		(net "M_E_CPU0_SA_DQ<30>")
	)
	(gr_poly
		(pts
			(xy 326.923908 -238.612172) (xy 326.923908 -238.567722) (xy 326.723756 -238.567722) (xy 326.723756 -238.612172)
			(xy 326.823832 -238.712248)
		)
		(stroke
			(width 0)
			(type solid)
		)
		(fill yes)
		(layer "In6.Cu")
		(net "M_E_CPU0_SA_DQ<22>")
	)
	(gr_poly
		(pts
			(xy 326.923908 -235.372148) (xy 326.923908 -235.327698) (xy 326.723756 -235.327698) (xy 326.723756 -235.372148)
			(xy 326.823832 -235.472224)
		)
		(stroke
			(width 0)
			(type solid)
		)
		(fill yes)
		(layer "In6.Cu")
		(net "M_E_CPU0_SA_DQ<18>")
	)
	(gr_poly
		(pts
			(xy 326.93991 -224.035112) (xy 326.976486 -223.89846) (xy 326.839834 -223.861884) (xy 326.801226 -223.883982)
			(xy 326.901302 -224.05721)
		)
		(stroke
			(width 0)
			(type solid)
		)
		(fill yes)
		(layer "In6.Cu")
		(net "M_E_CPU0_SA_DQS_DP<0>")
	)
	(gr_poly
		(pts
			(xy 326.940418 -225.655632) (xy 326.976994 -225.519234) (xy 326.840342 -225.482404) (xy 326.799194 -225.50628)
			(xy 326.899016 -225.679508)
		)
		(stroke
			(width 0)
			(type solid)
		)
		(fill yes)
		(layer "In6.Cu")
		(net "M_E_CPU0_SA_DQS_DP<0>")
	)
	(gr_poly
		(pts
			(xy 326.940418 -222.415608) (xy 326.976994 -222.278956) (xy 326.840342 -222.24238) (xy 326.801988 -222.264732)
			(xy 326.90181 -222.43796)
		)
		(stroke
			(width 0)
			(type solid)
		)
		(fill yes)
		(layer "In6.Cu")
		(net "M_E_CPU0_SA_DQ<1>")
	)
	(gr_poly
		(pts
			(xy 326.97674 -224.569528) (xy 326.940164 -224.432876) (xy 326.901556 -224.410524) (xy 326.801734 -224.583752)
			(xy 326.840088 -224.606104)
		)
		(stroke
			(width 0)
			(type solid)
		)
		(fill yes)
		(layer "In6.Cu")
		(net "M_E_CPU0_SA_DQS_DP<0>")
	)
	(gr_poly
		(pts
			(xy 327.15073 -293.15918) (xy 327.112376 -293.136828) (xy 326.975724 -293.173404) (xy 327.0123 -293.310056)
			(xy 327.050908 -293.332408)
		)
		(stroke
			(width 0)
			(type solid)
		)
		(fill yes)
		(layer "In6.Cu")
		(net "M_E_CPU0_SB_DQ<28>")
	)
	(gr_poly
		(pts
			(xy 327.166224 -227.445316) (xy 327.16597 -227.303838) (xy 327.024492 -227.303584) (xy 326.99071 -227.337366)
			(xy 327.132442 -227.479098)
		)
		(stroke
			(width 0)
			(type solid)
		)
		(fill yes)
		(layer "In6.Cu")
		(net "M_E_CPU0_SA_DQS_DN<5>")
	)
	(gr_poly
		(pts
			(xy 327.212706 -269.42796) (xy 327.112884 -269.327884) (xy 327.012808 -269.42796) (xy 327.012808 -269.47241)
			(xy 327.212706 -269.47241)
		)
		(stroke
			(width 0)
			(type solid)
		)
		(fill yes)
		(layer "In6.Cu")
		(net "M_E_CPU0_SB_CB<4>")
	)
	(gr_poly
		(pts
			(xy 327.213468 -285.62808) (xy 327.113392 -285.528258) (xy 327.013316 -285.62808) (xy 327.013316 -285.675832)
			(xy 327.213468 -285.675832)
		)
		(stroke
			(width 0)
			(type solid)
		)
		(fill yes)
		(layer "In6.Cu")
		(net "M_E_CPU0_SB_DQS_DP<2>")
	)
	(gr_poly
		(pts
			(xy 327.215246 -288.86785) (xy 327.115424 -288.767774) (xy 327.015348 -288.86785) (xy 327.015348 -288.9123)
			(xy 327.215246 -288.9123)
		)
		(stroke
			(width 0)
			(type solid)
		)
		(fill yes)
		(layer "In6.Cu")
		(net "M_E_CPU0_SB_DQ<24>")
	)
	(gr_poly
		(pts
			(xy 327.215246 -287.247838) (xy 327.115424 -287.147762) (xy 327.015348 -287.247838) (xy 327.015348 -287.292288)
			(xy 327.215246 -287.292288)
		)
		(stroke
			(width 0)
			(type solid)
		)
		(fill yes)
		(layer "In6.Cu")
		(net "M_E_CPU0_SB_DQ<20>")
	)
	(gr_poly
		(pts
			(xy 327.215246 -280.76779) (xy 327.115424 -280.667714) (xy 327.015348 -280.76779) (xy 327.015348 -280.815288)
			(xy 327.215246 -280.815288)
		)
		(stroke
			(width 0)
			(type solid)
		)
		(fill yes)
		(layer "In6.Cu")
		(net "M_E_CPU0_SB_DQS_DP<1>")
	)
	(gr_poly
		(pts
			(xy 327.215246 -279.148032) (xy 327.115424 -279.047956) (xy 327.015348 -279.148032) (xy 327.015348 -279.192482)
			(xy 327.215246 -279.192482)
		)
		(stroke
			(width 0)
			(type solid)
		)
		(fill yes)
		(layer "In6.Cu")
		(net "M_E_CPU0_SB_DQ<8>")
	)
	(gr_poly
		(pts
			(xy 327.215246 -277.52802) (xy 327.115424 -277.427944) (xy 327.015348 -277.52802) (xy 327.015348 -277.57247)
			(xy 327.215246 -277.57247)
		)
		(stroke
			(width 0)
			(type solid)
		)
		(fill yes)
		(layer "In6.Cu")
		(net "M_E_CPU0_SB_DQ<4>")
	)
	(gr_poly
		(pts
			(xy 327.215246 -274.287996) (xy 327.115424 -274.18792) (xy 327.015348 -274.287996) (xy 327.015348 -274.332446)
			(xy 327.215246 -274.332446)
		)
		(stroke
			(width 0)
			(type solid)
		)
		(fill yes)
		(layer "In6.Cu")
		(net "M_E_CPU0_SB_DQ<0>")
	)
	(gr_poly
		(pts
			(xy 327.215246 -264.567924) (xy 327.115424 -264.467848) (xy 327.015348 -264.567924) (xy 327.015348 -264.612374)
			(xy 327.215246 -264.612374)
		)
		(stroke
			(width 0)
			(type solid)
		)
		(fill yes)
		(layer "In6.Cu")
		(net "M_E_CPU0_SB_CA<6>")
	)
	(gr_poly
		(pts
			(xy 327.215754 -288.464244) (xy 327.215754 -288.419794) (xy 327.015602 -288.419794) (xy 327.015602 -288.464244)
			(xy 327.115678 -288.56432)
		)
		(stroke
			(width 0)
			(type solid)
		)
		(fill yes)
		(layer "In6.Cu")
		(net "M_E_CPU0_SB_DQ<23>")
	)
	(gr_poly
		(pts
			(xy 327.215754 -285.22422) (xy 327.215754 -285.17977) (xy 327.015602 -285.17977) (xy 327.015602 -285.22422)
			(xy 327.115678 -285.324296)
		)
		(stroke
			(width 0)
			(type solid)
		)
		(fill yes)
		(layer "In6.Cu")
		(net "M_E_CPU0_SB_DQ<19>")
	)
	(gr_poly
		(pts
			(xy 327.215754 -283.604208) (xy 327.215754 -283.559758) (xy 327.015602 -283.559758) (xy 327.015602 -283.604208)
			(xy 327.115678 -283.704284)
		)
		(stroke
			(width 0)
			(type solid)
		)
		(fill yes)
		(layer "In6.Cu")
		(net "M_E_CPU0_SB_DQ<15>")
	)
	(gr_poly
		(pts
			(xy 327.221088 -286.844232) (xy 327.221088 -286.796734) (xy 327.02119 -286.796734) (xy 327.02119 -286.844232)
			(xy 327.121266 -286.944308)
		)
		(stroke
			(width 0)
			(type solid)
		)
		(fill yes)
		(layer "In6.Cu")
		(net "M_E_CPU0_SB_DQS_DP<7>")
	)
	(gr_poly
		(pts
			(xy 327.223882 -284.008068) (xy 327.123806 -283.907992) (xy 327.02373 -284.008068) (xy 327.02373 -284.052518)
			(xy 327.223882 -284.052518)
		)
		(stroke
			(width 0)
			(type solid)
		)
		(fill yes)
		(layer "In6.Cu")
		(net "M_E_CPU0_SB_DQ<16>")
	)
	(gr_poly
		(pts
			(xy 327.223882 -282.388056) (xy 327.123806 -282.28798) (xy 327.02373 -282.388056) (xy 327.02373 -282.432506)
			(xy 327.223882 -282.432506)
		)
		(stroke
			(width 0)
			(type solid)
		)
		(fill yes)
		(layer "In6.Cu")
		(net "M_E_CPU0_SB_DQ<12>")
	)
	(gr_poly
		(pts
			(xy 327.223882 -272.667984) (xy 327.123806 -272.567908) (xy 327.02373 -272.667984) (xy 327.02373 -272.712434)
			(xy 327.223882 -272.712434)
		)
		(stroke
			(width 0)
			(type solid)
		)
		(fill yes)
		(layer "In6.Cu")
		(net "M_E_CPU0_SB_CB<0>")
	)
	(gr_poly
		(pts
			(xy 327.22693 -290.084002) (xy 327.22693 -290.039552) (xy 327.027032 -290.039552) (xy 327.027032 -290.084002)
			(xy 327.127108 -290.183824)
		)
		(stroke
			(width 0)
			(type solid)
		)
		(fill yes)
		(layer "In6.Cu")
		(net "M_E_CPU0_SB_DQ<27>")
	)
	(gr_poly
		(pts
			(xy 327.227184 -267.795248) (xy 327.127362 -267.695172) (xy 327.027286 -267.795248) (xy 327.027286 -267.846048)
			(xy 327.227184 -267.846048)
		)
		(stroke
			(width 0)
			(type solid)
		)
		(fill yes)
		(layer "In6.Cu")
		(net "M_E_CPU0_SB_RSP<0>")
	)
	(gr_poly
		(pts
			(xy 327.23074 -290.487862) (xy 327.130918 -290.387786) (xy 327.030842 -290.487862) (xy 327.030842 -290.53536)
			(xy 327.23074 -290.53536)
		)
		(stroke
			(width 0)
			(type solid)
		)
		(fill yes)
		(layer "In6.Cu")
		(net "M_E_CPU0_SB_DQS_DP<3>")
	)
	(gr_poly
		(pts
			(xy 327.30948 -295.40835) (xy 327.24979 -295.28008) (xy 327.20788 -295.26484) (xy 327.139554 -295.4528)
			(xy 327.18121 -295.46804)
		)
		(stroke
			(width 0)
			(type solid)
		)
		(fill yes)
		(layer "In6.Cu")
		(net "M_E_CPU0_SB_DQ<30>")
	)
	(gr_poly
		(pts
			(xy 327.309988 -224.69602) (xy 327.27138 -224.673668) (xy 327.134982 -224.710498) (xy 327.171558 -224.846896)
			(xy 327.209912 -224.869248)
		)
		(stroke
			(width 0)
			(type solid)
		)
		(fill yes)
		(layer "In6.Cu")
		(net "M_E_CPU0_SA_DQ<3>")
	)
	(gr_poly
		(pts
			(xy 327.309988 -222.152464) (xy 327.209912 -221.979236) (xy 327.171558 -222.001334) (xy 327.134982 -222.137986)
			(xy 327.27138 -222.174816)
		)
		(stroke
			(width 0)
			(type solid)
		)
		(fill yes)
		(layer "In6.Cu")
		(net "M_E_CPU0_SA_DQ<2>")
	)
	(gr_poly
		(pts
			(xy 327.310242 -225.392996) (xy 327.210166 -225.219768) (xy 327.171812 -225.24212) (xy 327.134982 -225.378772)
			(xy 327.271634 -225.415348)
		)
		(stroke
			(width 0)
			(type solid)
		)
		(fill yes)
		(layer "In6.Cu")
		(net "M_E_CPU0_SA_DQ<3>")
	)
	(gr_poly
		(pts
			(xy 327.310496 -223.772984) (xy 327.21042 -223.599756) (xy 327.172066 -223.622108) (xy 327.13549 -223.75876)
			(xy 327.271888 -223.795336)
		)
		(stroke
			(width 0)
			(type solid)
		)
		(fill yes)
		(layer "In6.Cu")
		(net "M_E_CPU0_SA_DQ<3>")
	)
	(gr_poly
		(pts
			(xy 327.313036 -227.012246) (xy 327.213214 -226.839018) (xy 327.171812 -226.862894) (xy 327.135236 -226.999292)
			(xy 327.271888 -227.035868)
		)
		(stroke
			(width 0)
			(type solid)
		)
		(fill yes)
		(layer "In6.Cu")
		(net "M_E_CPU0_SA_DQS_DN<0>")
	)
	(gr_poly
		(pts
			(xy 327.385426 -256.025904) (xy 327.28535 -255.926082) (xy 327.185274 -256.025904) (xy 327.185274 -256.073656)
			(xy 327.385426 -256.073656)
		)
		(stroke
			(width 0)
			(type solid)
		)
		(fill yes)
		(layer "In6.Cu")
		(net "M_E_CPU0_CLK_DP<0>")
	)
	(gr_poly
		(pts
			(xy 327.385426 -255.622298) (xy 327.385426 -255.577848) (xy 327.185528 -255.577848) (xy 327.185528 -255.622298)
			(xy 327.285604 -255.722374)
		)
		(stroke
			(width 0)
			(type solid)
		)
		(fill yes)
		(layer "In6.Cu")
		(net "M_E_CPU0_SA_PAR")
	)
	(gr_poly
		(pts
			(xy 327.385426 -254.406146) (xy 327.28535 -254.30607) (xy 327.185274 -254.406146) (xy 327.185274 -254.450596)
			(xy 327.385426 -254.450596)
		)
		(stroke
			(width 0)
			(type solid)
		)
		(fill yes)
		(layer "In6.Cu")
		(net "M_E_CPU0_SA_CA<4>")
	)
	(gr_poly
		(pts
			(xy 327.385426 -254.002286) (xy 327.385426 -253.957836) (xy 327.185528 -253.957836) (xy 327.185528 -254.002286)
			(xy 327.285604 -254.102362)
		)
		(stroke
			(width 0)
			(type solid)
		)
		(fill yes)
		(layer "In6.Cu")
		(net "M_E_CPU0_SA_CA<3>")
	)
	(gr_poly
		(pts
			(xy 327.385426 -252.786134) (xy 327.28535 -252.686058) (xy 327.185274 -252.786134) (xy 327.185274 -252.830584)
			(xy 327.385426 -252.830584)
		)
		(stroke
			(width 0)
			(type solid)
		)
		(fill yes)
		(layer "In6.Cu")
		(net "M_E_CPU0_SA_CA<0>")
	)
	(gr_poly
		(pts
			(xy 327.385426 -252.382274) (xy 327.385426 -252.337824) (xy 327.185528 -252.337824) (xy 327.185528 -252.382274)
			(xy 327.285604 -252.48235)
		)
		(stroke
			(width 0)
			(type solid)
		)
		(fill yes)
		(layer "In6.Cu")
		(net "M_E_CPU0_SA_CS_N<1>")
	)
	(gr_poly
		(pts
			(xy 327.385426 -250.762262) (xy 327.385426 -250.717812) (xy 327.185528 -250.717812) (xy 327.185528 -250.762262)
			(xy 327.285604 -250.862338)
		)
		(stroke
			(width 0)
			(type solid)
		)
		(fill yes)
		(layer "In6.Cu")
		(net "M_E_CPU0_RESET_N")
	)
	(gr_poly
		(pts
			(xy 327.385426 -249.14225) (xy 327.385426 -249.0978) (xy 327.185528 -249.0978) (xy 327.185528 -249.14225)
			(xy 327.285604 -249.242326)
		)
		(stroke
			(width 0)
			(type solid)
		)
		(fill yes)
		(layer "In6.Cu")
		(net "M_E_CPU0_SA_CB<7>")
	)
	(gr_poly
		(pts
			(xy 327.385426 -247.926098) (xy 327.28535 -247.826022) (xy 327.185274 -247.926098) (xy 327.185274 -247.970548)
			(xy 327.385426 -247.970548)
		)
		(stroke
			(width 0)
			(type solid)
		)
		(fill yes)
		(layer "In6.Cu")
		(net "M_E_CPU0_SA_CB<4>")
	)
	(gr_poly
		(pts
			(xy 327.385426 -247.522492) (xy 327.385426 -247.47474) (xy 327.185528 -247.47474) (xy 327.185528 -247.522492)
			(xy 327.285604 -247.622314)
		)
		(stroke
			(width 0)
			(type solid)
		)
		(fill yes)
		(layer "In6.Cu")
		(net "M_E_CPU0_SA_DQS_DP<9>")
	)
	(gr_poly
		(pts
			(xy 327.385426 -246.305832) (xy 327.28535 -246.20601) (xy 327.185274 -246.305832) (xy 327.185274 -246.353584)
			(xy 327.385426 -246.353584)
		)
		(stroke
			(width 0)
			(type solid)
		)
		(fill yes)
		(layer "In6.Cu")
		(net "M_E_CPU0_SA_DQS_DP<4>")
	)
	(gr_poly
		(pts
			(xy 327.385426 -245.902226) (xy 327.385426 -245.857776) (xy 327.185528 -245.857776) (xy 327.185528 -245.902226)
			(xy 327.285604 -246.002302)
		)
		(stroke
			(width 0)
			(type solid)
		)
		(fill yes)
		(layer "In6.Cu")
		(net "M_E_CPU0_SA_CB<3>")
	)
	(gr_poly
		(pts
			(xy 327.385426 -244.686074) (xy 327.28535 -244.585998) (xy 327.185274 -244.686074) (xy 327.185274 -244.730524)
			(xy 327.385426 -244.730524)
		)
		(stroke
			(width 0)
			(type solid)
		)
		(fill yes)
		(layer "In6.Cu")
		(net "M_E_CPU0_SA_CB<0>")
	)
	(gr_poly
		(pts
			(xy 327.385426 -244.282214) (xy 327.385426 -244.237764) (xy 327.185528 -244.237764) (xy 327.185528 -244.282214)
			(xy 327.285604 -244.38229)
		)
		(stroke
			(width 0)
			(type solid)
		)
		(fill yes)
		(layer "In6.Cu")
		(net "M_E_CPU0_SA_DQ<31>")
	)
	(gr_poly
		(pts
			(xy 327.385426 -242.662456) (xy 327.385426 -242.614704) (xy 327.185528 -242.614704) (xy 327.185528 -242.662456)
			(xy 327.285604 -242.762278)
		)
		(stroke
			(width 0)
			(type solid)
		)
		(fill yes)
		(layer "In6.Cu")
		(net "M_E_CPU0_SA_DQS_DP<8>")
	)
	(gr_poly
		(pts
			(xy 327.385426 -241.445796) (xy 327.28535 -241.345974) (xy 327.185274 -241.445796) (xy 327.185274 -241.493548)
			(xy 327.385426 -241.493548)
		)
		(stroke
			(width 0)
			(type solid)
		)
		(fill yes)
		(layer "In6.Cu")
		(net "M_E_CPU0_SA_DQS_DP<3>")
	)
	(gr_poly
		(pts
			(xy 327.385426 -241.04219) (xy 327.385426 -240.99774) (xy 327.185528 -240.99774) (xy 327.185528 -241.04219)
			(xy 327.285604 -241.142266)
		)
		(stroke
			(width 0)
			(type solid)
		)
		(fill yes)
		(layer "In6.Cu")
		(net "M_E_CPU0_SA_DQ<27>")
	)
	(gr_poly
		(pts
			(xy 327.385426 -239.826038) (xy 327.28535 -239.725962) (xy 327.185274 -239.826038) (xy 327.185274 -239.870488)
			(xy 327.385426 -239.870488)
		)
		(stroke
			(width 0)
			(type solid)
		)
		(fill yes)
		(layer "In6.Cu")
		(net "M_E_CPU0_SA_DQ<24>")
	)
	(gr_poly
		(pts
			(xy 327.385426 -239.422178) (xy 327.385426 -239.377728) (xy 327.185528 -239.377728) (xy 327.185528 -239.422178)
			(xy 327.285604 -239.522254)
		)
		(stroke
			(width 0)
			(type solid)
		)
		(fill yes)
		(layer "In6.Cu")
		(net "M_E_CPU0_SA_DQ<23>")
	)
	(gr_poly
		(pts
			(xy 327.385426 -237.80242) (xy 327.385426 -237.754668) (xy 327.185528 -237.754668) (xy 327.185528 -237.80242)
			(xy 327.285604 -237.902242)
		)
		(stroke
			(width 0)
			(type solid)
		)
		(fill yes)
		(layer "In6.Cu")
		(net "M_E_CPU0_SA_DQS_DP<7>")
	)
	(gr_poly
		(pts
			(xy 327.385426 -236.58576) (xy 327.28535 -236.485938) (xy 327.185274 -236.58576) (xy 327.185274 -236.633512)
			(xy 327.385426 -236.633512)
		)
		(stroke
			(width 0)
			(type solid)
		)
		(fill yes)
		(layer "In6.Cu")
		(net "M_E_CPU0_SA_DQS_DP<2>")
	)
	(gr_poly
		(pts
			(xy 327.385426 -236.182154) (xy 327.385426 -236.137704) (xy 327.185528 -236.137704) (xy 327.185528 -236.182154)
			(xy 327.285604 -236.28223)
		)
		(stroke
			(width 0)
			(type solid)
		)
		(fill yes)
		(layer "In6.Cu")
		(net "M_E_CPU0_SA_DQ<19>")
	)
	(gr_poly
		(pts
			(xy 327.385426 -234.562142) (xy 327.385426 -234.517692) (xy 327.185528 -234.517692) (xy 327.185528 -234.562142)
			(xy 327.285604 -234.662218)
		)
		(stroke
			(width 0)
			(type solid)
		)
		(fill yes)
		(layer "In6.Cu")
		(net "M_E_CPU0_SA_DQ<15>")
	)
	(gr_poly
		(pts
			(xy 327.385426 -233.34599) (xy 327.28535 -233.245914) (xy 327.185274 -233.34599) (xy 327.185274 -233.39044)
			(xy 327.385426 -233.39044)
		)
		(stroke
			(width 0)
			(type solid)
		)
		(fill yes)
		(layer "In6.Cu")
		(net "M_E_CPU0_SA_DQ<12>")
	)
	(gr_poly
		(pts
			(xy 327.385426 -232.942384) (xy 327.385426 -232.894632) (xy 327.185528 -232.894632) (xy 327.185528 -232.942384)
			(xy 327.285604 -233.042206)
		)
		(stroke
			(width 0)
			(type solid)
		)
		(fill yes)
		(layer "In6.Cu")
		(net "M_E_CPU0_SA_DQS_DP<6>")
	)
	(gr_poly
		(pts
			(xy 327.385426 -231.725724) (xy 327.28535 -231.625902) (xy 327.185274 -231.725724) (xy 327.185274 -231.773476)
			(xy 327.385426 -231.773476)
		)
		(stroke
			(width 0)
			(type solid)
		)
		(fill yes)
		(layer "In6.Cu")
		(net "M_E_CPU0_SA_DQS_DP<1>")
	)
	(gr_poly
		(pts
			(xy 327.391268 -227.944172) (xy 327.411334 -227.900992) (xy 327.229978 -227.81641) (xy 327.209912 -227.85959)
			(xy 327.258172 -227.992432)
		)
		(stroke
			(width 0)
			(type solid)
		)
		(fill yes)
		(layer "In6.Cu")
		(net "M_E_CPU0_SA_DQS_DP<5>")
	)
	(gr_poly
		(pts
			(xy 327.396602 -243.066062) (xy 327.296526 -242.965986) (xy 327.19645 -243.066062) (xy 327.19645 -243.110512)
			(xy 327.396602 -243.110512)
		)
		(stroke
			(width 0)
			(type solid)
		)
		(fill yes)
		(layer "In6.Cu")
		(net "M_E_CPU0_SA_DQ<28>")
	)
	(gr_poly
		(pts
			(xy 327.396602 -238.206026) (xy 327.296526 -238.10595) (xy 327.19645 -238.206026) (xy 327.19645 -238.250476)
			(xy 327.396602 -238.250476)
		)
		(stroke
			(width 0)
			(type solid)
		)
		(fill yes)
		(layer "In6.Cu")
		(net "M_E_CPU0_SA_DQ<20>")
	)
	(gr_poly
		(pts
			(xy 327.396602 -234.966002) (xy 327.296526 -234.865926) (xy 327.19645 -234.966002) (xy 327.19645 -235.010452)
			(xy 327.396602 -235.010452)
		)
		(stroke
			(width 0)
			(type solid)
		)
		(fill yes)
		(layer "In6.Cu")
		(net "M_E_CPU0_SA_DQ<16>")
	)
	(gr_poly
		(pts
			(xy 327.410064 -223.225614) (xy 327.44664 -223.088962) (xy 327.309988 -223.052386) (xy 327.271634 -223.074738)
			(xy 327.371456 -223.247966)
		)
		(stroke
			(width 0)
			(type solid)
		)
		(fill yes)
		(layer "In6.Cu")
		(net "M_E_CPU0_SA_DQ<1>")
	)
	(gr_poly
		(pts
			(xy 327.410318 -226.465638) (xy 327.446894 -226.32924) (xy 327.310242 -226.292664) (xy 327.269094 -226.316286)
			(xy 327.368916 -226.489514)
		)
		(stroke
			(width 0)
			(type solid)
		)
		(fill yes)
		(layer "In6.Cu")
		(net "M_E_CPU0_SA_DQS_DP<0>")
	)
	(gr_poly
		(pts
			(xy 327.465436 -231.187498) (xy 327.480676 -231.145588) (xy 327.295002 -231.078024) (xy 327.279762 -231.11968)
			(xy 327.338436 -231.247442)
		)
		(stroke
			(width 0)
			(type solid)
		)
		(fill yes)
		(layer "In6.Cu")
		(net "M_E_CPU0_SA_DQ<11>")
	)
	(gr_poly
		(pts
			(xy 327.61047 -295.607232) (xy 327.571862 -295.58488) (xy 327.43521 -295.621456) (xy 327.47204 -295.758108)
			(xy 327.510394 -295.78046)
		)
		(stroke
			(width 0)
			(type solid)
		)
		(fill yes)
		(layer "In6.Cu")
		(net "M_E_CPU0_SB_DQ<29>")
	)
	(gr_poly
		(pts
			(xy 327.62063 -292.34892) (xy 327.582276 -292.326822) (xy 327.445624 -292.363398) (xy 327.4822 -292.50005)
			(xy 327.520808 -292.522148)
		)
		(stroke
			(width 0)
			(type solid)
		)
		(fill yes)
		(layer "In6.Cu")
		(net "M_E_CPU0_SB_DQ<28>")
	)
	(gr_poly
		(pts
			(xy 327.681336 -286.034734) (xy 327.681336 -285.987236) (xy 327.481438 -285.987236) (xy 327.481438 -286.034734)
			(xy 327.581514 -286.13481)
		)
		(stroke
			(width 0)
			(type solid)
		)
		(fill yes)
		(layer "In6.Cu")
		(net "M_E_CPU0_SB_DQS_DN<2>")
	)
	(gr_poly
		(pts
			(xy 327.685146 -289.273996) (xy 327.685146 -289.229546) (xy 327.485248 -289.229546) (xy 327.485248 -289.273996)
			(xy 327.585324 -289.374072)
		)
		(stroke
			(width 0)
			(type solid)
		)
		(fill yes)
		(layer "In6.Cu")
		(net "M_E_CPU0_SB_DQ<26>")
	)
	(gr_poly
		(pts
			(xy 327.685146 -287.654238) (xy 327.685146 -287.609788) (xy 327.485248 -287.609788) (xy 327.485248 -287.654238)
			(xy 327.585324 -287.75406)
		)
		(stroke
			(width 0)
			(type solid)
		)
		(fill yes)
		(layer "In6.Cu")
		(net "M_E_CPU0_SB_DQ<22>")
	)
	(gr_poly
		(pts
			(xy 327.685146 -281.174444) (xy 327.685146 -281.126692) (xy 327.485248 -281.126692) (xy 327.485248 -281.174444)
			(xy 327.585324 -281.274266)
		)
		(stroke
			(width 0)
			(type solid)
		)
		(fill yes)
		(layer "In6.Cu")
		(net "M_E_CPU0_SB_DQS_DN<1>")
	)
	(gr_poly
		(pts
			(xy 327.685146 -279.554178) (xy 327.685146 -279.509728) (xy 327.485248 -279.509728) (xy 327.485248 -279.554178)
			(xy 327.585324 -279.654254)
		)
		(stroke
			(width 0)
			(type solid)
		)
		(fill yes)
		(layer "In6.Cu")
		(net "M_E_CPU0_SB_DQ<10>")
	)
	(gr_poly
		(pts
			(xy 327.685146 -277.934166) (xy 327.685146 -277.889716) (xy 327.485248 -277.889716) (xy 327.485248 -277.934166)
			(xy 327.585324 -278.034242)
		)
		(stroke
			(width 0)
			(type solid)
		)
		(fill yes)
		(layer "In6.Cu")
		(net "M_E_CPU0_SB_DQ<6>")
	)
	(gr_poly
		(pts
			(xy 327.685146 -274.694142) (xy 327.685146 -274.649692) (xy 327.485248 -274.649692) (xy 327.485248 -274.694142)
			(xy 327.585324 -274.794218)
		)
		(stroke
			(width 0)
			(type solid)
		)
		(fill yes)
		(layer "In6.Cu")
		(net "M_E_CPU0_SB_DQ<2>")
	)
	(gr_poly
		(pts
			(xy 327.685146 -264.97407) (xy 327.685146 -264.92962) (xy 327.485248 -264.92962) (xy 327.485248 -264.97407)
			(xy 327.585324 -265.074146)
		)
		(stroke
			(width 0)
			(type solid)
		)
		(fill yes)
		(layer "In6.Cu")
		(net "M_E_CPU0_SB_PAR")
	)
	(gr_poly
		(pts
			(xy 327.685654 -288.057844) (xy 327.585578 -287.957768) (xy 327.485502 -288.057844) (xy 327.485502 -288.102294)
			(xy 327.685654 -288.102294)
		)
		(stroke
			(width 0)
			(type solid)
		)
		(fill yes)
		(layer "In6.Cu")
		(net "M_E_CPU0_SB_DQ<21>")
	)
	(gr_poly
		(pts
			(xy 327.685654 -284.818074) (xy 327.585578 -284.717998) (xy 327.485502 -284.818074) (xy 327.485502 -284.862524)
			(xy 327.685654 -284.862524)
		)
		(stroke
			(width 0)
			(type solid)
		)
		(fill yes)
		(layer "In6.Cu")
		(net "M_E_CPU0_SB_DQ<17>")
	)
	(gr_poly
		(pts
			(xy 327.685654 -283.198062) (xy 327.585578 -283.097986) (xy 327.485502 -283.198062) (xy 327.485502 -283.242512)
			(xy 327.685654 -283.242512)
		)
		(stroke
			(width 0)
			(type solid)
		)
		(fill yes)
		(layer "In6.Cu")
		(net "M_E_CPU0_SB_DQ<13>")
	)
	(gr_poly
		(pts
			(xy 327.691242 -286.437832) (xy 327.591166 -286.337756) (xy 327.49109 -286.437832) (xy 327.49109 -286.485584)
			(xy 327.691242 -286.485584)
		)
		(stroke
			(width 0)
			(type solid)
		)
		(fill yes)
		(layer "In6.Cu")
		(net "M_E_CPU0_SB_DQS_DN<7>")
	)
	(gr_poly
		(pts
			(xy 327.696576 -290.894262) (xy 327.696576 -290.846764) (xy 327.496678 -290.846764) (xy 327.496678 -290.894262)
			(xy 327.5965 -290.994338)
		)
		(stroke
			(width 0)
			(type solid)
		)
		(fill yes)
		(layer "In6.Cu")
		(net "M_E_CPU0_SB_DQS_DN<3>")
	)
	(gr_poly
		(pts
			(xy 327.696576 -284.414214) (xy 327.696576 -284.369764) (xy 327.496678 -284.369764) (xy 327.496678 -284.414214)
			(xy 327.5965 -284.51429)
		)
		(stroke
			(width 0)
			(type solid)
		)
		(fill yes)
		(layer "In6.Cu")
		(net "M_E_CPU0_SB_DQ<18>")
	)
	(gr_poly
		(pts
			(xy 327.696576 -282.794202) (xy 327.696576 -282.749752) (xy 327.496678 -282.749752) (xy 327.496678 -282.794202)
			(xy 327.5965 -282.894278)
		)
		(stroke
			(width 0)
			(type solid)
		)
		(fill yes)
		(layer "In6.Cu")
		(net "M_E_CPU0_SB_DQ<14>")
	)
	(gr_poly
		(pts
			(xy 327.696576 -273.07413) (xy 327.696576 -273.02968) (xy 327.496678 -273.02968) (xy 327.496678 -273.07413)
			(xy 327.5965 -273.174206)
		)
		(stroke
			(width 0)
			(type solid)
		)
		(fill yes)
		(layer "In6.Cu")
		(net "M_E_CPU0_SB_CB<2>")
	)
	(gr_poly
		(pts
			(xy 327.697338 -269.834106) (xy 327.697338 -269.789656) (xy 327.497186 -269.789656) (xy 327.497186 -269.834106)
			(xy 327.597262 -269.934182)
		)
		(stroke
			(width 0)
			(type solid)
		)
		(fill yes)
		(layer "In6.Cu")
		(net "M_E_CPU0_SB_CB<6>")
	)
	(gr_poly
		(pts
			(xy 327.746614 -294.67048) (xy 327.710038 -294.533828) (xy 327.671684 -294.511476) (xy 327.571608 -294.684704)
			(xy 327.610216 -294.707056)
		)
		(stroke
			(width 0)
			(type solid)
		)
		(fill yes)
		(layer "In6.Cu")
		(net "M_E_CPU0_SB_DQ<30>")
	)
	(gr_poly
		(pts
			(xy 327.780396 -226.203002) (xy 327.68032 -226.029774) (xy 327.641966 -226.052126) (xy 327.60539 -226.188778)
			(xy 327.741788 -226.225354)
		)
		(stroke
			(width 0)
			(type solid)
		)
		(fill yes)
		(layer "In6.Cu")
		(net "M_E_CPU0_SA_DQ<3>")
	)
	(gr_poly
		(pts
			(xy 327.781412 -222.964502) (xy 327.681336 -222.791274) (xy 327.642728 -222.813372) (xy 327.606152 -222.950024)
			(xy 327.742804 -222.9866)
		)
		(stroke
			(width 0)
			(type solid)
		)
		(fill yes)
		(layer "In6.Cu")
		(net "M_E_CPU0_SA_DQ<2>")
	)
	(gr_poly
		(pts
			(xy 327.854818 -243.472208) (xy 327.854818 -243.427758) (xy 327.65492 -243.427758) (xy 327.65492 -243.472208)
			(xy 327.754996 -243.572284)
		)
		(stroke
			(width 0)
			(type solid)
		)
		(fill yes)
		(layer "In6.Cu")
		(net "M_E_CPU0_SA_DQ<30>")
	)
	(gr_poly
		(pts
			(xy 327.854818 -238.612172) (xy 327.854818 -238.567722) (xy 327.65492 -238.567722) (xy 327.65492 -238.612172)
			(xy 327.754996 -238.712248)
		)
		(stroke
			(width 0)
			(type solid)
		)
		(fill yes)
		(layer "In6.Cu")
		(net "M_E_CPU0_SA_DQ<22>")
	)
	(gr_poly
		(pts
			(xy 327.854818 -235.372148) (xy 327.854818 -235.327698) (xy 327.65492 -235.327698) (xy 327.65492 -235.372148)
			(xy 327.754996 -235.472224)
		)
		(stroke
			(width 0)
			(type solid)
		)
		(fill yes)
		(layer "In6.Cu")
		(net "M_E_CPU0_SA_DQ<18>")
	)
	(gr_poly
		(pts
			(xy 327.867264 -256.432558) (xy 327.867264 -256.384806) (xy 327.667366 -256.384806) (xy 327.667366 -256.432558)
			(xy 327.767188 -256.53238)
		)
		(stroke
			(width 0)
			(type solid)
		)
		(fill yes)
		(layer "In6.Cu")
		(net "M_E_CPU0_CLK_DN<0>")
	)
	(gr_poly
		(pts
			(xy 327.867264 -255.216152) (xy 327.767188 -255.116076) (xy 327.667366 -255.216152) (xy 327.667366 -255.260602)
			(xy 327.867264 -255.260602)
		)
		(stroke
			(width 0)
			(type solid)
		)
		(fill yes)
		(layer "In6.Cu")
		(net "M_E_CPU0_SA_CA<6>")
	)
	(gr_poly
		(pts
			(xy 327.867264 -254.812292) (xy 327.867264 -254.767842) (xy 327.667366 -254.767842) (xy 327.667366 -254.812292)
			(xy 327.767188 -254.912368)
		)
		(stroke
			(width 0)
			(type solid)
		)
		(fill yes)
		(layer "In6.Cu")
		(net "M_E_CPU0_SA_CA<5>")
	)
	(gr_poly
		(pts
			(xy 327.867264 -253.59614) (xy 327.767188 -253.496064) (xy 327.667366 -253.59614) (xy 327.667366 -253.64059)
			(xy 327.867264 -253.64059)
		)
		(stroke
			(width 0)
			(type solid)
		)
		(fill yes)
		(layer "In6.Cu")
		(net "M_E_CPU0_SA_CA<2>")
	)
	(gr_poly
		(pts
			(xy 327.867264 -253.19228) (xy 327.867264 -253.14783) (xy 327.667366 -253.14783) (xy 327.667366 -253.19228)
			(xy 327.767188 -253.292356)
		)
		(stroke
			(width 0)
			(type solid)
		)
		(fill yes)
		(layer "In6.Cu")
		(net "M_E_CPU0_SA_CA<1>")
	)
	(gr_poly
		(pts
			(xy 327.867264 -251.572268) (xy 327.867264 -251.527818) (xy 327.667366 -251.527818) (xy 327.667366 -251.572268)
			(xy 327.767188 -251.672344)
		)
		(stroke
			(width 0)
			(type solid)
		)
		(fill yes)
		(layer "In6.Cu")
		(net "M_E_CPU0_SA_CS_N<0>")
	)
	(gr_poly
		(pts
			(xy 327.867264 -250.356116) (xy 327.767188 -250.25604) (xy 327.667366 -250.356116) (xy 327.667366 -250.400566)
			(xy 327.867264 -250.400566)
		)
		(stroke
			(width 0)
			(type solid)
		)
		(fill yes)
		(layer "In6.Cu")
		(net "M_E_CPU0_ALERT_R_N")
	)
	(gr_poly
		(pts
			(xy 327.867264 -248.736104) (xy 327.767188 -248.636028) (xy 327.667366 -248.736104) (xy 327.667366 -248.780554)
			(xy 327.867264 -248.780554)
		)
		(stroke
			(width 0)
			(type solid)
		)
		(fill yes)
		(layer "In6.Cu")
		(net "M_E_CPU0_SA_CB<5>")
	)
	(gr_poly
		(pts
			(xy 327.867264 -248.332244) (xy 327.867264 -248.287794) (xy 327.667366 -248.287794) (xy 327.667366 -248.332244)
			(xy 327.767188 -248.43232)
		)
		(stroke
			(width 0)
			(type solid)
		)
		(fill yes)
		(layer "In6.Cu")
		(net "M_E_CPU0_SA_CB<6>")
	)
	(gr_poly
		(pts
			(xy 327.867264 -247.115838) (xy 327.767188 -247.016016) (xy 327.667366 -247.115838) (xy 327.667366 -247.16359)
			(xy 327.867264 -247.16359)
		)
		(stroke
			(width 0)
			(type solid)
		)
		(fill yes)
		(layer "In6.Cu")
		(net "M_E_CPU0_SA_DQS_DN<9>")
	)
	(gr_poly
		(pts
			(xy 327.867264 -246.712486) (xy 327.867264 -246.664734) (xy 327.667366 -246.664734) (xy 327.667366 -246.712486)
			(xy 327.767188 -246.812308)
		)
		(stroke
			(width 0)
			(type solid)
		)
		(fill yes)
		(layer "In6.Cu")
		(net "M_E_CPU0_SA_DQS_DN<4>")
	)
	(gr_poly
		(pts
			(xy 327.867264 -245.49608) (xy 327.767188 -245.396004) (xy 327.667366 -245.49608) (xy 327.667366 -245.54053)
			(xy 327.867264 -245.54053)
		)
		(stroke
			(width 0)
			(type solid)
		)
		(fill yes)
		(layer "In6.Cu")
		(net "M_E_CPU0_SA_CB<1>")
	)
	(gr_poly
		(pts
			(xy 327.867264 -245.09222) (xy 327.867264 -245.04777) (xy 327.667366 -245.04777) (xy 327.667366 -245.09222)
			(xy 327.767188 -245.192296)
		)
		(stroke
			(width 0)
			(type solid)
		)
		(fill yes)
		(layer "In6.Cu")
		(net "M_E_CPU0_SA_CB<2>")
	)
	(gr_poly
		(pts
			(xy 327.867264 -243.876068) (xy 327.767188 -243.775992) (xy 327.667366 -243.876068) (xy 327.667366 -243.920518)
			(xy 327.867264 -243.920518)
		)
		(stroke
			(width 0)
			(type solid)
		)
		(fill yes)
		(layer "In6.Cu")
		(net "M_E_CPU0_SA_DQ<29>")
	)
	(gr_poly
		(pts
			(xy 327.867264 -242.255802) (xy 327.767188 -242.15598) (xy 327.667366 -242.255802) (xy 327.667366 -242.303554)
			(xy 327.867264 -242.303554)
		)
		(stroke
			(width 0)
			(type solid)
		)
		(fill yes)
		(layer "In6.Cu")
		(net "M_E_CPU0_SA_DQS_DN<8>")
	)
	(gr_poly
		(pts
			(xy 327.867264 -241.85245) (xy 327.867264 -241.804698) (xy 327.667366 -241.804698) (xy 327.667366 -241.85245)
			(xy 327.767188 -241.952272)
		)
		(stroke
			(width 0)
			(type solid)
		)
		(fill yes)
		(layer "In6.Cu")
		(net "M_E_CPU0_SA_DQS_DN<3>")
	)
	(gr_poly
		(pts
			(xy 327.867264 -240.636044) (xy 327.767188 -240.535968) (xy 327.667366 -240.636044) (xy 327.667366 -240.680494)
			(xy 327.867264 -240.680494)
		)
		(stroke
			(width 0)
			(type solid)
		)
		(fill yes)
		(layer "In6.Cu")
		(net "M_E_CPU0_SA_DQ<25>")
	)
	(gr_poly
		(pts
			(xy 327.867264 -240.232184) (xy 327.867264 -240.187734) (xy 327.667366 -240.187734) (xy 327.667366 -240.232184)
			(xy 327.767188 -240.33226)
		)
		(stroke
			(width 0)
			(type solid)
		)
		(fill yes)
		(layer "In6.Cu")
		(net "M_E_CPU0_SA_DQ<26>")
	)
	(gr_poly
		(pts
			(xy 327.867264 -239.016032) (xy 327.767188 -238.915956) (xy 327.667366 -239.016032) (xy 327.667366 -239.060482)
			(xy 327.867264 -239.060482)
		)
		(stroke
			(width 0)
			(type solid)
		)
		(fill yes)
		(layer "In6.Cu")
		(net "M_E_CPU0_SA_DQ<21>")
	)
	(gr_poly
		(pts
			(xy 327.867264 -237.395766) (xy 327.767188 -237.295944) (xy 327.667366 -237.395766) (xy 327.667366 -237.443518)
			(xy 327.867264 -237.443518)
		)
		(stroke
			(width 0)
			(type solid)
		)
		(fill yes)
		(layer "In6.Cu")
		(net "M_E_CPU0_SA_DQS_DN<7>")
	)
	(gr_poly
		(pts
			(xy 327.867264 -236.992414) (xy 327.867264 -236.944662) (xy 327.667366 -236.944662) (xy 327.667366 -236.992414)
			(xy 327.767188 -237.092236)
		)
		(stroke
			(width 0)
			(type solid)
		)
		(fill yes)
		(layer "In6.Cu")
		(net "M_E_CPU0_SA_DQS_DN<2>")
	)
	(gr_poly
		(pts
			(xy 327.867264 -235.776008) (xy 327.767188 -235.675932) (xy 327.667366 -235.776008) (xy 327.667366 -235.820458)
			(xy 327.867264 -235.820458)
		)
		(stroke
			(width 0)
			(type solid)
		)
		(fill yes)
		(layer "In6.Cu")
		(net "M_E_CPU0_SA_DQ<17>")
	)
	(gr_poly
		(pts
			(xy 327.867264 -234.155996) (xy 327.767188 -234.05592) (xy 327.667366 -234.155996) (xy 327.667366 -234.200446)
			(xy 327.867264 -234.200446)
		)
		(stroke
			(width 0)
			(type solid)
		)
		(fill yes)
		(layer "In6.Cu")
		(net "M_E_CPU0_SA_DQ<13>")
	)
	(gr_poly
		(pts
			(xy 327.867264 -233.752136) (xy 327.867264 -233.707686) (xy 327.667366 -233.707686) (xy 327.667366 -233.752136)
			(xy 327.767188 -233.852212)
		)
		(stroke
			(width 0)
			(type solid)
		)
		(fill yes)
		(layer "In6.Cu")
		(net "M_E_CPU0_SA_DQ<14>")
	)
	(gr_poly
		(pts
			(xy 327.867264 -232.53573) (xy 327.767188 -232.435908) (xy 327.667366 -232.53573) (xy 327.667366 -232.583482)
			(xy 327.867264 -232.583482)
		)
		(stroke
			(width 0)
			(type solid)
		)
		(fill yes)
		(layer "In6.Cu")
		(net "M_E_CPU0_SA_DQS_DN<6>")
	)
	(gr_poly
		(pts
			(xy 327.867264 -232.132378) (xy 327.867264 -232.084626) (xy 327.667366 -232.084626) (xy 327.667366 -232.132378)
			(xy 327.767188 -232.2322)
		)
		(stroke
			(width 0)
			(type solid)
		)
		(fill yes)
		(layer "In6.Cu")
		(net "M_E_CPU0_SA_DQS_DN<1>")
	)
	(gr_poly
		(pts
			(xy 327.867264 -230.512366) (xy 327.867264 -230.467916) (xy 327.667366 -230.467916) (xy 327.667366 -230.512366)
			(xy 327.767188 -230.612188)
		)
		(stroke
			(width 0)
			(type solid)
		)
		(fill yes)
		(layer "In6.Cu")
		(net "M_E_CPU0_SA_DQ<10>")
	)
	(gr_poly
		(pts
			(xy 327.867264 -227.272596) (xy 327.867264 -227.224844) (xy 327.667366 -227.224844) (xy 327.667366 -227.272596)
			(xy 327.767188 -227.372418)
		)
		(stroke
			(width 0)
			(type solid)
		)
		(fill yes)
		(layer "In6.Cu")
		(net "M_E_CPU0_SA_DQS_DN<0>")
	)
	(gr_poly
		(pts
			(xy 327.879964 -224.035112) (xy 327.91654 -223.89846) (xy 327.779888 -223.861884) (xy 327.74128 -223.883982)
			(xy 327.841356 -224.05721)
		)
		(stroke
			(width 0)
			(type solid)
		)
		(fill yes)
		(layer "In6.Cu")
		(net "M_E_CPU0_SA_DQ<1>")
	)
	(gr_poly
		(pts
			(xy 327.880218 -225.656394) (xy 327.916794 -225.519742) (xy 327.780396 -225.483166) (xy 327.741788 -225.505518)
			(xy 327.841864 -225.678746)
		)
		(stroke
			(width 0)
			(type solid)
		)
		(fill yes)
		(layer "In6.Cu")
		(net "M_E_CPU0_SA_DQ<1>")
	)
	(gr_poly
		(pts
			(xy 327.880218 -222.415608) (xy 327.916794 -222.278956) (xy 327.780142 -222.24238) (xy 327.741788 -222.264732)
			(xy 327.84161 -222.43796)
		)
		(stroke
			(width 0)
			(type solid)
		)
		(fill yes)
		(layer "In6.Cu")
		(net "M_E_CPU0_SA_DQ<0>")
	)
	(gr_poly
		(pts
			(xy 327.916794 -224.569528) (xy 327.880218 -224.432876) (xy 327.84161 -224.410524) (xy 327.741788 -224.583752)
			(xy 327.780142 -224.606104)
		)
		(stroke
			(width 0)
			(type solid)
		)
		(fill yes)
		(layer "In6.Cu")
		(net "M_E_CPU0_SA_DQ<1>")
	)
	(gr_poly
		(pts
			(xy 328.081386 -294.795702) (xy 328.042778 -294.773604) (xy 327.906126 -294.81018) (xy 327.942702 -294.946832)
			(xy 327.98131 -294.96893)
		)
		(stroke
			(width 0)
			(type solid)
		)
		(fill yes)
		(layer "In6.Cu")
		(net "M_E_CPU0_SB_DQ<29>")
	)
	(gr_poly
		(pts
			(xy 328.155046 -290.487608) (xy 328.05497 -290.387532) (xy 327.954894 -290.487608) (xy 327.954894 -290.535106)
			(xy 328.155046 -290.535106)
		)
		(stroke
			(width 0)
			(type solid)
		)
		(fill yes)
		(layer "In6.Cu")
		(net "M_E_CPU0_SB_DQS_DP<3>")
	)
	(gr_poly
		(pts
			(xy 328.155046 -284.008068) (xy 328.05497 -283.907992) (xy 327.954894 -284.008068) (xy 327.954894 -284.052518)
			(xy 328.155046 -284.052518)
		)
		(stroke
			(width 0)
			(type solid)
		)
		(fill yes)
		(layer "In6.Cu")
		(net "M_E_CPU0_SB_DQ<16>")
	)
	(gr_poly
		(pts
			(xy 328.155046 -282.388056) (xy 328.05497 -282.28798) (xy 327.954894 -282.388056) (xy 327.954894 -282.432506)
			(xy 328.155046 -282.432506)
		)
		(stroke
			(width 0)
			(type solid)
		)
		(fill yes)
		(layer "In6.Cu")
		(net "M_E_CPU0_SB_DQ<12>")
	)
	(gr_poly
		(pts
			(xy 328.155046 -272.667984) (xy 328.05497 -272.567908) (xy 327.954894 -272.667984) (xy 327.954894 -272.712434)
			(xy 328.155046 -272.712434)
		)
		(stroke
			(width 0)
			(type solid)
		)
		(fill yes)
		(layer "In6.Cu")
		(net "M_E_CPU0_SB_CB<0>")
	)
	(gr_poly
		(pts
			(xy 328.15911 -277.123906) (xy 328.15911 -277.076154) (xy 327.959212 -277.076154) (xy 327.959212 -277.123906)
			(xy 328.059034 -277.223728)
		)
		(stroke
			(width 0)
			(type solid)
		)
		(fill yes)
		(layer "In6.Cu")
		(net "M_E_CPU0_SB_DQS_DP<5>")
	)
	(gr_poly
		(pts
			(xy 328.161142 -292.107874) (xy 328.061066 -292.007798) (xy 327.96099 -292.107874) (xy 327.96099 -292.152324)
			(xy 328.161142 -292.152324)
		)
		(stroke
			(width 0)
			(type solid)
		)
		(fill yes)
		(layer "In6.Cu")
		(net "M_E_CPU0_SB_DQ<28>")
	)
	(gr_poly
		(pts
			(xy 328.161142 -286.844232) (xy 328.161142 -286.79648) (xy 327.96099 -286.79648) (xy 327.96099 -286.844232)
			(xy 328.061066 -286.944308)
		)
		(stroke
			(width 0)
			(type solid)
		)
		(fill yes)
		(layer "In6.Cu")
		(net "M_E_CPU0_SB_DQS_DP<7>")
	)
	(gr_poly
		(pts
			(xy 328.161142 -280.364184) (xy 328.161142 -280.319734) (xy 327.96099 -280.319734) (xy 327.96099 -280.364184)
			(xy 328.061066 -280.46426)
		)
		(stroke
			(width 0)
			(type solid)
		)
		(fill yes)
		(layer "In6.Cu")
		(net "M_E_CPU0_SB_DQ<11>")
	)
	(gr_poly
		(pts
			(xy 328.161142 -278.744172) (xy 328.161142 -278.699722) (xy 327.96099 -278.699722) (xy 327.96099 -278.744172)
			(xy 328.061066 -278.844248)
		)
		(stroke
			(width 0)
			(type solid)
		)
		(fill yes)
		(layer "In6.Cu")
		(net "M_E_CPU0_SB_DQ<7>")
	)
	(gr_poly
		(pts
			(xy 328.161142 -275.504148) (xy 328.161142 -275.459698) (xy 327.96099 -275.459698) (xy 327.96099 -275.504148)
			(xy 328.061066 -275.604224)
		)
		(stroke
			(width 0)
			(type solid)
		)
		(fill yes)
		(layer "In6.Cu")
		(net "M_E_CPU0_SB_DQ<3>")
	)
	(gr_poly
		(pts
			(xy 328.161142 -270.644112) (xy 328.161142 -270.599662) (xy 327.96099 -270.599662) (xy 327.96099 -270.644112)
			(xy 328.061066 -270.744188)
		)
		(stroke
			(width 0)
			(type solid)
		)
		(fill yes)
		(layer "In6.Cu")
		(net "M_E_CPU0_SB_CB<7>")
	)
	(gr_poly
		(pts
			(xy 328.161142 -269.42796) (xy 328.061066 -269.327884) (xy 327.96099 -269.42796) (xy 327.96099 -269.47241)
			(xy 328.161142 -269.47241)
		)
		(stroke
			(width 0)
			(type solid)
		)
		(fill yes)
		(layer "In6.Cu")
		(net "M_E_CPU0_SB_CB<4>")
	)
	(gr_poly
		(pts
			(xy 328.161142 -265.784076) (xy 328.161142 -265.739626) (xy 327.96099 -265.739626) (xy 327.96099 -265.784076)
			(xy 328.061066 -265.884152)
		)
		(stroke
			(width 0)
			(type solid)
		)
		(fill yes)
		(layer "In6.Cu")
		(net "M_E_CPU0_SB_CS_N<0>")
	)
	(gr_poly
		(pts
			(xy 328.161142 -262.947912) (xy 328.061066 -262.847836) (xy 327.96099 -262.947912) (xy 327.96099 -262.992362)
			(xy 328.161142 -262.992362)
		)
		(stroke
			(width 0)
			(type solid)
		)
		(fill yes)
		(layer "In6.Cu")
		(net "M_E_CPU0_SB_CA<2>")
	)
	(gr_poly
		(pts
			(xy 328.161142 -262.544052) (xy 328.161142 -262.499602) (xy 327.96099 -262.499602) (xy 327.96099 -262.544052)
			(xy 328.061066 -262.644128)
		)
		(stroke
			(width 0)
			(type solid)
		)
		(fill yes)
		(layer "In6.Cu")
		(net "M_E_CPU0_SB_CA<1>")
	)
	(gr_poly
		(pts
			(xy 328.167238 -288.86785) (xy 328.067162 -288.767774) (xy 327.967086 -288.86785) (xy 327.967086 -288.9123)
			(xy 328.167238 -288.9123)
		)
		(stroke
			(width 0)
			(type solid)
		)
		(fill yes)
		(layer "In6.Cu")
		(net "M_E_CPU0_SB_DQ<24>")
	)
	(gr_poly
		(pts
			(xy 328.167238 -288.464244) (xy 328.167238 -288.419794) (xy 327.967086 -288.419794) (xy 327.967086 -288.464244)
			(xy 328.067162 -288.56432)
		)
		(stroke
			(width 0)
			(type solid)
		)
		(fill yes)
		(layer "In6.Cu")
		(net "M_E_CPU0_SB_DQ<23>")
	)
	(gr_poly
		(pts
			(xy 328.167238 -287.247838) (xy 328.067162 -287.148016) (xy 327.967086 -287.247838) (xy 327.967086 -287.292288)
			(xy 328.167238 -287.292288)
		)
		(stroke
			(width 0)
			(type solid)
		)
		(fill yes)
		(layer "In6.Cu")
		(net "M_E_CPU0_SB_DQ<20>")
	)
	(gr_poly
		(pts
			(xy 328.167238 -285.22422) (xy 328.167238 -285.17977) (xy 327.967086 -285.17977) (xy 327.967086 -285.22422)
			(xy 328.067162 -285.324296)
		)
		(stroke
			(width 0)
			(type solid)
		)
		(fill yes)
		(layer "In6.Cu")
		(net "M_E_CPU0_SB_DQ<19>")
	)
	(gr_poly
		(pts
			(xy 328.167238 -283.604208) (xy 328.167238 -283.559758) (xy 327.967086 -283.559758) (xy 327.967086 -283.604208)
			(xy 328.067162 -283.704284)
		)
		(stroke
			(width 0)
			(type solid)
		)
		(fill yes)
		(layer "In6.Cu")
		(net "M_E_CPU0_SB_DQ<15>")
	)
	(gr_poly
		(pts
			(xy 328.167238 -281.98445) (xy 328.167238 -281.936698) (xy 327.967086 -281.936698) (xy 327.967086 -281.98445)
			(xy 328.067162 -282.084272)
		)
		(stroke
			(width 0)
			(type solid)
		)
		(fill yes)
		(layer "In6.Cu")
		(net "M_E_CPU0_SB_DQS_DP<6>")
	)
	(gr_poly
		(pts
			(xy 328.167238 -280.76779) (xy 328.067162 -280.667968) (xy 327.967086 -280.76779) (xy 327.967086 -280.815542)
			(xy 328.167238 -280.815542)
		)
		(stroke
			(width 0)
			(type solid)
		)
		(fill yes)
		(layer "In6.Cu")
		(net "M_E_CPU0_SB_DQS_DP<1>")
	)
	(gr_poly
		(pts
			(xy 328.167238 -279.148032) (xy 328.067162 -279.047956) (xy 327.967086 -279.148032) (xy 327.967086 -279.192482)
			(xy 328.167238 -279.192482)
		)
		(stroke
			(width 0)
			(type solid)
		)
		(fill yes)
		(layer "In6.Cu")
		(net "M_E_CPU0_SB_DQ<8>")
	)
	(gr_poly
		(pts
			(xy 328.167238 -277.52802) (xy 328.067162 -277.427944) (xy 327.967086 -277.52802) (xy 327.967086 -277.57247)
			(xy 328.167238 -277.57247)
		)
		(stroke
			(width 0)
			(type solid)
		)
		(fill yes)
		(layer "In6.Cu")
		(net "M_E_CPU0_SB_DQ<4>")
	)
	(gr_poly
		(pts
			(xy 328.167238 -275.907754) (xy 328.067162 -275.807932) (xy 327.967086 -275.907754) (xy 327.967086 -275.955506)
			(xy 328.167238 -275.955506)
		)
		(stroke
			(width 0)
			(type solid)
		)
		(fill yes)
		(layer "In6.Cu")
		(net "M_E_CPU0_SB_DQS_DP<0>")
	)
	(gr_poly
		(pts
			(xy 328.167238 -274.287996) (xy 328.067162 -274.18792) (xy 327.967086 -274.287996) (xy 327.967086 -274.332446)
			(xy 328.167238 -274.332446)
		)
		(stroke
			(width 0)
			(type solid)
		)
		(fill yes)
		(layer "In6.Cu")
		(net "M_E_CPU0_SB_DQ<0>")
	)
	(gr_poly
		(pts
			(xy 328.167238 -267.795248) (xy 328.067416 -267.695172) (xy 327.96734 -267.795248) (xy 327.96734 -267.846048)
			(xy 328.167238 -267.846048)
		)
		(stroke
			(width 0)
			(type solid)
		)
		(fill yes)
		(layer "In6.Cu")
		(net "M_E_CPU0_SB_RSP<0>")
	)
	(gr_poly
		(pts
			(xy 328.167238 -264.567924) (xy 328.067162 -264.467848) (xy 327.967086 -264.567924) (xy 327.967086 -264.612374)
			(xy 328.167238 -264.612374)
		)
		(stroke
			(width 0)
			(type solid)
		)
		(fill yes)
		(layer "In6.Cu")
		(net "M_E_CPU0_SB_CA<6>")
	)
	(gr_poly
		(pts
			(xy 328.168762 -272.264378) (xy 328.168762 -272.216626) (xy 327.96861 -272.216626) (xy 327.96861 -272.264378)
			(xy 328.068686 -272.364454)
		)
		(stroke
			(width 0)
			(type solid)
		)
		(fill yes)
		(layer "In6.Cu")
		(net "M_E_CPU0_SB_DQS_DP<4>")
	)
	(gr_poly
		(pts
			(xy 328.171048 -285.62808) (xy 328.070972 -285.528004) (xy 327.97115 -285.62808) (xy 327.97115 -285.675578)
			(xy 328.171048 -285.675578)
		)
		(stroke
			(width 0)
			(type solid)
		)
		(fill yes)
		(layer "In6.Cu")
		(net "M_E_CPU0_SB_DQS_DP<2>")
	)
	(gr_poly
		(pts
			(xy 328.178414 -273.883882) (xy 328.178414 -273.839432) (xy 327.978262 -273.839432) (xy 327.978262 -273.883882)
			(xy 328.078338 -273.983958)
		)
		(stroke
			(width 0)
			(type solid)
		)
		(fill yes)
		(layer "In6.Cu")
		(net "M_E_CPU0_SB_CB<3>")
	)
	(gr_poly
		(pts
			(xy 328.18197 -271.047972) (xy 328.081894 -270.94815) (xy 327.981818 -271.047972) (xy 327.981818 -271.095724)
			(xy 328.18197 -271.095724)
		)
		(stroke
			(width 0)
			(type solid)
		)
		(fill yes)
		(layer "In6.Cu")
		(net "M_E_CPU0_SB_DQS_DP<9>")
	)
	(gr_poly
		(pts
			(xy 328.18324 -264.163556) (xy 328.18324 -264.119106) (xy 327.983342 -264.119106) (xy 327.983342 -264.163556)
			(xy 328.083164 -264.263632)
		)
		(stroke
			(width 0)
			(type solid)
		)
		(fill yes)
		(layer "In6.Cu")
		(net "M_E_CPU0_SB_CA<5>")
	)
	(gr_poly
		(pts
			(xy 328.217022 -293.860474) (xy 328.180446 -293.723822) (xy 328.142092 -293.70147) (xy 328.042016 -293.874698)
			(xy 328.080624 -293.89705)
		)
		(stroke
			(width 0)
			(type solid)
		)
		(fill yes)
		(layer "In6.Cu")
		(net "M_E_CPU0_SB_DQ<30>")
	)
	(gr_poly
		(pts
			(xy 328.250042 -224.69602) (xy 328.211434 -224.673668) (xy 328.074782 -224.710498) (xy 328.111612 -224.846896)
			(xy 328.149966 -224.869248)
		)
		(stroke
			(width 0)
			(type solid)
		)
		(fill yes)
		(layer "In6.Cu")
		(net "M_E_CPU0_SA_DQ<2>")
	)
	(gr_poly
		(pts
			(xy 328.250296 -225.392996) (xy 328.15022 -225.219768) (xy 328.111866 -225.24212) (xy 328.07529 -225.378772)
			(xy 328.211688 -225.415348)
		)
		(stroke
			(width 0)
			(type solid)
		)
		(fill yes)
		(layer "In6.Cu")
		(net "M_E_CPU0_SA_DQ<2>")
	)
	(gr_poly
		(pts
			(xy 328.251312 -223.774508) (xy 328.151236 -223.60128) (xy 328.112628 -223.623378) (xy 328.076052 -223.76003)
			(xy 328.212704 -223.796606)
		)
		(stroke
			(width 0)
			(type solid)
		)
		(fill yes)
		(layer "In6.Cu")
		(net "M_E_CPU0_SA_DQ<2>")
	)
	(gr_poly
		(pts
			(xy 328.330052 -231.322372) (xy 328.330052 -231.277922) (xy 328.13244 -231.277922) (xy 328.13244 -231.322372)
			(xy 328.231246 -231.422448)
		)
		(stroke
			(width 0)
			(type solid)
		)
		(fill yes)
		(layer "In6.Cu")
		(net "M_E_CPU0_SA_DQ<11>")
	)
	(gr_poly
		(pts
			(xy 328.331322 -256.025904) (xy 328.231246 -255.926082) (xy 328.13117 -256.025904) (xy 328.13117 -256.073656)
			(xy 328.331322 -256.073656)
		)
		(stroke
			(width 0)
			(type solid)
		)
		(fill yes)
		(layer "In6.Cu")
		(net "M_E_CPU0_CLK_DP<0>")
	)
	(gr_poly
		(pts
			(xy 328.331322 -255.622298) (xy 328.331322 -255.577848) (xy 328.13117 -255.577848) (xy 328.13117 -255.622298)
			(xy 328.231246 -255.722374)
		)
		(stroke
			(width 0)
			(type solid)
		)
		(fill yes)
		(layer "In6.Cu")
		(net "M_E_CPU0_SA_PAR")
	)
	(gr_poly
		(pts
			(xy 328.331322 -254.406146) (xy 328.231246 -254.30607) (xy 328.13117 -254.406146) (xy 328.13117 -254.450596)
			(xy 328.331322 -254.450596)
		)
		(stroke
			(width 0)
			(type solid)
		)
		(fill yes)
		(layer "In6.Cu")
		(net "M_E_CPU0_SA_CA<4>")
	)
	(gr_poly
		(pts
			(xy 328.331322 -254.002286) (xy 328.331322 -253.957836) (xy 328.13117 -253.957836) (xy 328.13117 -254.002286)
			(xy 328.231246 -254.102362)
		)
		(stroke
			(width 0)
			(type solid)
		)
		(fill yes)
		(layer "In6.Cu")
		(net "M_E_CPU0_SA_CA<3>")
	)
	(gr_poly
		(pts
			(xy 328.331322 -252.786134) (xy 328.231246 -252.686058) (xy 328.13117 -252.786134) (xy 328.13117 -252.830584)
			(xy 328.331322 -252.830584)
		)
		(stroke
			(width 0)
			(type solid)
		)
		(fill yes)
		(layer "In6.Cu")
		(net "M_E_CPU0_SA_CA<0>")
	)
	(gr_poly
		(pts
			(xy 328.331322 -252.382274) (xy 328.331322 -252.337824) (xy 328.13117 -252.337824) (xy 328.13117 -252.382274)
			(xy 328.231246 -252.48235)
		)
		(stroke
			(width 0)
			(type solid)
		)
		(fill yes)
		(layer "In6.Cu")
		(net "M_E_CPU0_SA_CS_N<1>")
	)
	(gr_poly
		(pts
			(xy 328.331322 -250.762262) (xy 328.331322 -250.717812) (xy 328.13117 -250.717812) (xy 328.13117 -250.762262)
			(xy 328.231246 -250.862338)
		)
		(stroke
			(width 0)
			(type solid)
		)
		(fill yes)
		(layer "In6.Cu")
		(net "M_E_CPU0_RESET_N")
	)
	(gr_poly
		(pts
			(xy 328.331322 -249.14225) (xy 328.331322 -249.0978) (xy 328.13117 -249.0978) (xy 328.13117 -249.14225)
			(xy 328.231246 -249.242326)
		)
		(stroke
			(width 0)
			(type solid)
		)
		(fill yes)
		(layer "In6.Cu")
		(net "M_E_CPU0_SA_CB<7>")
	)
	(gr_poly
		(pts
			(xy 328.331322 -247.926098) (xy 328.231246 -247.826022) (xy 328.13117 -247.926098) (xy 328.13117 -247.970548)
			(xy 328.331322 -247.970548)
		)
		(stroke
			(width 0)
			(type solid)
		)
		(fill yes)
		(layer "In6.Cu")
		(net "M_E_CPU0_SA_CB<4>")
	)
	(gr_poly
		(pts
			(xy 328.331322 -247.522492) (xy 328.331322 -247.47474) (xy 328.13117 -247.47474) (xy 328.13117 -247.522492)
			(xy 328.231246 -247.622314)
		)
		(stroke
			(width 0)
			(type solid)
		)
		(fill yes)
		(layer "In6.Cu")
		(net "M_E_CPU0_SA_DQS_DP<9>")
	)
	(gr_poly
		(pts
			(xy 328.331322 -246.305832) (xy 328.231246 -246.20601) (xy 328.13117 -246.305832) (xy 328.13117 -246.353584)
			(xy 328.331322 -246.353584)
		)
		(stroke
			(width 0)
			(type solid)
		)
		(fill yes)
		(layer "In6.Cu")
		(net "M_E_CPU0_SA_DQS_DP<4>")
	)
	(gr_poly
		(pts
			(xy 328.331322 -245.902226) (xy 328.331322 -245.857776) (xy 328.13117 -245.857776) (xy 328.13117 -245.902226)
			(xy 328.231246 -246.002302)
		)
		(stroke
			(width 0)
			(type solid)
		)
		(fill yes)
		(layer "In6.Cu")
		(net "M_E_CPU0_SA_CB<3>")
	)
	(gr_poly
		(pts
			(xy 328.331322 -244.686074) (xy 328.231246 -244.585998) (xy 328.13117 -244.686074) (xy 328.13117 -244.730524)
			(xy 328.331322 -244.730524)
		)
		(stroke
			(width 0)
			(type solid)
		)
		(fill yes)
		(layer "In6.Cu")
		(net "M_E_CPU0_SA_CB<0>")
	)
	(gr_poly
		(pts
			(xy 328.331322 -244.282214) (xy 328.331322 -244.237764) (xy 328.13117 -244.237764) (xy 328.13117 -244.282214)
			(xy 328.231246 -244.38229)
		)
		(stroke
			(width 0)
			(type solid)
		)
		(fill yes)
		(layer "In6.Cu")
		(net "M_E_CPU0_SA_DQ<31>")
	)
	(gr_poly
		(pts
			(xy 328.331322 -243.066062) (xy 328.231246 -242.965986) (xy 328.13117 -243.066062) (xy 328.13117 -243.110512)
			(xy 328.331322 -243.110512)
		)
		(stroke
			(width 0)
			(type solid)
		)
		(fill yes)
		(layer "In6.Cu")
		(net "M_E_CPU0_SA_DQ<28>")
	)
	(gr_poly
		(pts
			(xy 328.331322 -242.662456) (xy 328.331322 -242.614704) (xy 328.13117 -242.614704) (xy 328.13117 -242.662456)
			(xy 328.231246 -242.762278)
		)
		(stroke
			(width 0)
			(type solid)
		)
		(fill yes)
		(layer "In6.Cu")
		(net "M_E_CPU0_SA_DQS_DP<8>")
	)
	(gr_poly
		(pts
			(xy 328.331322 -241.445796) (xy 328.231246 -241.345974) (xy 328.13117 -241.445796) (xy 328.13117 -241.493548)
			(xy 328.331322 -241.493548)
		)
		(stroke
			(width 0)
			(type solid)
		)
		(fill yes)
		(layer "In6.Cu")
		(net "M_E_CPU0_SA_DQS_DP<3>")
	)
	(gr_poly
		(pts
			(xy 328.331322 -241.04219) (xy 328.331322 -240.99774) (xy 328.13117 -240.99774) (xy 328.13117 -241.04219)
			(xy 328.231246 -241.142266)
		)
		(stroke
			(width 0)
			(type solid)
		)
		(fill yes)
		(layer "In6.Cu")
		(net "M_E_CPU0_SA_DQ<27>")
	)
	(gr_poly
		(pts
			(xy 328.331322 -239.826038) (xy 328.231246 -239.725962) (xy 328.13117 -239.826038) (xy 328.13117 -239.870488)
			(xy 328.331322 -239.870488)
		)
		(stroke
			(width 0)
			(type solid)
		)
		(fill yes)
		(layer "In6.Cu")
		(net "M_E_CPU0_SA_DQ<24>")
	)
	(gr_poly
		(pts
			(xy 328.331322 -239.422178) (xy 328.331322 -239.377728) (xy 328.13117 -239.377728) (xy 328.13117 -239.422178)
			(xy 328.231246 -239.522254)
		)
		(stroke
			(width 0)
			(type solid)
		)
		(fill yes)
		(layer "In6.Cu")
		(net "M_E_CPU0_SA_DQ<23>")
	)
	(gr_poly
		(pts
			(xy 328.331322 -238.206026) (xy 328.231246 -238.10595) (xy 328.13117 -238.206026) (xy 328.13117 -238.250476)
			(xy 328.331322 -238.250476)
		)
		(stroke
			(width 0)
			(type solid)
		)
		(fill yes)
		(layer "In6.Cu")
		(net "M_E_CPU0_SA_DQ<20>")
	)
	(gr_poly
		(pts
			(xy 328.331322 -237.80242) (xy 328.331322 -237.754668) (xy 328.13117 -237.754668) (xy 328.13117 -237.80242)
			(xy 328.231246 -237.902242)
		)
		(stroke
			(width 0)
			(type solid)
		)
		(fill yes)
		(layer "In6.Cu")
		(net "M_E_CPU0_SA_DQS_DP<7>")
	)
	(gr_poly
		(pts
			(xy 328.331322 -236.58576) (xy 328.231246 -236.485938) (xy 328.13117 -236.58576) (xy 328.13117 -236.633512)
			(xy 328.331322 -236.633512)
		)
		(stroke
			(width 0)
			(type solid)
		)
		(fill yes)
		(layer "In6.Cu")
		(net "M_E_CPU0_SA_DQS_DP<2>")
	)
	(gr_poly
		(pts
			(xy 328.331322 -236.182154) (xy 328.331322 -236.137704) (xy 328.13117 -236.137704) (xy 328.13117 -236.182154)
			(xy 328.231246 -236.28223)
		)
		(stroke
			(width 0)
			(type solid)
		)
		(fill yes)
		(layer "In6.Cu")
		(net "M_E_CPU0_SA_DQ<19>")
	)
	(gr_poly
		(pts
			(xy 328.331322 -234.966002) (xy 328.231246 -234.865926) (xy 328.13117 -234.966002) (xy 328.13117 -235.010452)
			(xy 328.331322 -235.010452)
		)
		(stroke
			(width 0)
			(type solid)
		)
		(fill yes)
		(layer "In6.Cu")
		(net "M_E_CPU0_SA_DQ<16>")
	)
	(gr_poly
		(pts
			(xy 328.331322 -234.562142) (xy 328.331322 -234.517692) (xy 328.13117 -234.517692) (xy 328.13117 -234.562142)
			(xy 328.231246 -234.662218)
		)
		(stroke
			(width 0)
			(type solid)
		)
		(fill yes)
		(layer "In6.Cu")
		(net "M_E_CPU0_SA_DQ<15>")
	)
	(gr_poly
		(pts
			(xy 328.331322 -233.34599) (xy 328.231246 -233.245914) (xy 328.13117 -233.34599) (xy 328.13117 -233.39044)
			(xy 328.331322 -233.39044)
		)
		(stroke
			(width 0)
			(type solid)
		)
		(fill yes)
		(layer "In6.Cu")
		(net "M_E_CPU0_SA_DQ<12>")
	)
	(gr_poly
		(pts
			(xy 328.331322 -232.942384) (xy 328.331322 -232.894632) (xy 328.13117 -232.894632) (xy 328.13117 -232.942384)
			(xy 328.231246 -233.042206)
		)
		(stroke
			(width 0)
			(type solid)
		)
		(fill yes)
		(layer "In6.Cu")
		(net "M_E_CPU0_SA_DQS_DP<6>")
	)
	(gr_poly
		(pts
			(xy 328.331322 -231.725724) (xy 328.231246 -231.625902) (xy 328.13117 -231.725724) (xy 328.13117 -231.773476)
			(xy 328.331322 -231.773476)
		)
		(stroke
			(width 0)
			(type solid)
		)
		(fill yes)
		(layer "In6.Cu")
		(net "M_E_CPU0_SA_DQS_DP<1>")
	)
	(gr_poly
		(pts
			(xy 328.331322 -230.105966) (xy 328.231246 -230.006144) (xy 328.13117 -230.105966) (xy 328.13117 -230.150416)
			(xy 328.331322 -230.150416)
		)
		(stroke
			(width 0)
			(type solid)
		)
		(fill yes)
		(layer "In6.Cu")
		(net "M_E_CPU0_SA_DQ<8>")
	)
	(gr_poly
		(pts
			(xy 328.331322 -229.70236) (xy 328.331322 -229.65791) (xy 328.13117 -229.65791) (xy 328.13117 -229.70236)
			(xy 328.231246 -229.802436)
		)
		(stroke
			(width 0)
			(type solid)
		)
		(fill yes)
		(layer "In6.Cu")
		(net "M_E_CPU0_SA_DQ<7>")
	)
	(gr_poly
		(pts
			(xy 328.331322 -228.486208) (xy 328.231246 -228.386132) (xy 328.13117 -228.486208) (xy 328.13117 -228.530658)
			(xy 328.331322 -228.530658)
		)
		(stroke
			(width 0)
			(type solid)
		)
		(fill yes)
		(layer "In6.Cu")
		(net "M_E_CPU0_SA_DQ<4>")
	)
	(gr_poly
		(pts
			(xy 328.331322 -228.082602) (xy 328.331322 -228.03485) (xy 328.13117 -228.03485) (xy 328.13117 -228.082602)
			(xy 328.231246 -228.182424)
		)
		(stroke
			(width 0)
			(type solid)
		)
		(fill yes)
		(layer "In6.Cu")
		(net "M_E_CPU0_SA_DQS_DP<5>")
	)
	(gr_poly
		(pts
			(xy 328.331322 -226.865942) (xy 328.231246 -226.76612) (xy 328.13117 -226.865942) (xy 328.13117 -226.913694)
			(xy 328.331322 -226.913694)
		)
		(stroke
			(width 0)
			(type solid)
		)
		(fill yes)
		(layer "In6.Cu")
		(net "M_E_CPU0_SA_DQS_DP<0>")
	)
	(gr_poly
		(pts
			(xy 328.331322 -226.462336) (xy 328.331322 -226.417886) (xy 328.13117 -226.417886) (xy 328.13117 -226.462336)
			(xy 328.231246 -226.562412)
		)
		(stroke
			(width 0)
			(type solid)
		)
		(fill yes)
		(layer "In6.Cu")
		(net "M_E_CPU0_SA_DQ<3>")
	)
	(gr_poly
		(pts
			(xy 328.349864 -223.225106) (xy 328.38644 -223.088454) (xy 328.249788 -223.051878) (xy 328.21118 -223.073976)
			(xy 328.311256 -223.247204)
		)
		(stroke
			(width 0)
			(type solid)
		)
		(fill yes)
		(layer "In6.Cu")
		(net "M_E_CPU0_SA_DQ<0>")
	)
	(gr_poly
		(pts
			(xy 328.55027 -293.98722) (xy 328.511662 -293.964868) (xy 328.37501 -294.001444) (xy 328.41184 -294.138096)
			(xy 328.450194 -294.160448)
		)
		(stroke
			(width 0)
			(type solid)
		)
		(fill yes)
		(layer "In6.Cu")
		(net "M_E_CPU0_SB_DQ<29>")
	)
	(gr_poly
		(pts
			(xy 328.631296 -291.297614) (xy 328.53122 -291.197792) (xy 328.431144 -291.297614) (xy 328.431144 -291.345366)
			(xy 328.631296 -291.345366)
		)
		(stroke
			(width 0)
			(type solid)
		)
		(fill yes)
		(layer "In6.Cu")
		(net "M_E_CPU0_SB_DQS_DN<8>")
	)
	(gr_poly
		(pts
			(xy 328.631296 -290.894262) (xy 328.631296 -290.84651) (xy 328.431144 -290.84651) (xy 328.431144 -290.894262)
			(xy 328.53122 -290.994084)
		)
		(stroke
			(width 0)
			(type solid)
		)
		(fill yes)
		(layer "In6.Cu")
		(net "M_E_CPU0_SB_DQS_DN<3>")
	)
	(gr_poly
		(pts
			(xy 328.631296 -289.677856) (xy 328.53122 -289.57778) (xy 328.431144 -289.677856) (xy 328.431144 -289.722306)
			(xy 328.631296 -289.722306)
		)
		(stroke
			(width 0)
			(type solid)
		)
		(fill yes)
		(layer "In6.Cu")
		(net "M_E_CPU0_SB_DQ<25>")
	)
	(gr_poly
		(pts
			(xy 328.631296 -289.273996) (xy 328.631296 -289.229546) (xy 328.431144 -289.229546) (xy 328.431144 -289.273996)
			(xy 328.53122 -289.374072)
		)
		(stroke
			(width 0)
			(type solid)
		)
		(fill yes)
		(layer "In6.Cu")
		(net "M_E_CPU0_SB_DQ<26>")
	)
	(gr_poly
		(pts
			(xy 328.631296 -288.057844) (xy 328.53122 -287.957768) (xy 328.431144 -288.057844) (xy 328.431144 -288.102294)
			(xy 328.631296 -288.102294)
		)
		(stroke
			(width 0)
			(type solid)
		)
		(fill yes)
		(layer "In6.Cu")
		(net "M_E_CPU0_SB_DQ<21>")
	)
	(gr_poly
		(pts
			(xy 328.631296 -287.654238) (xy 328.631296 -287.609788) (xy 328.431144 -287.609788) (xy 328.431144 -287.654238)
			(xy 328.53122 -287.75406)
		)
		(stroke
			(width 0)
			(type solid)
		)
		(fill yes)
		(layer "In6.Cu")
		(net "M_E_CPU0_SB_DQ<22>")
	)
	(gr_poly
		(pts
			(xy 328.631296 -286.437832) (xy 328.53122 -286.337756) (xy 328.431144 -286.437832) (xy 328.431144 -286.485584)
			(xy 328.631296 -286.485584)
		)
		(stroke
			(width 0)
			(type solid)
		)
		(fill yes)
		(layer "In6.Cu")
		(net "M_E_CPU0_SB_DQS_DN<7>")
	)
	(gr_poly
		(pts
			(xy 328.631296 -286.03448) (xy 328.631296 -285.986728) (xy 328.431144 -285.986728) (xy 328.431144 -286.03448)
			(xy 328.53122 -286.134302)
		)
		(stroke
			(width 0)
			(type solid)
		)
		(fill yes)
		(layer "In6.Cu")
		(net "M_E_CPU0_SB_DQS_DN<2>")
	)
	(gr_poly
		(pts
			(xy 328.631296 -284.818074) (xy 328.53122 -284.717998) (xy 328.431144 -284.818074) (xy 328.431144 -284.862524)
			(xy 328.631296 -284.862524)
		)
		(stroke
			(width 0)
			(type solid)
		)
		(fill yes)
		(layer "In6.Cu")
		(net "M_E_CPU0_SB_DQ<17>")
	)
	(gr_poly
		(pts
			(xy 328.631296 -284.414214) (xy 328.631296 -284.369764) (xy 328.431144 -284.369764) (xy 328.431144 -284.414214)
			(xy 328.53122 -284.51429)
		)
		(stroke
			(width 0)
			(type solid)
		)
		(fill yes)
		(layer "In6.Cu")
		(net "M_E_CPU0_SB_DQ<18>")
	)
	(gr_poly
		(pts
			(xy 328.631296 -283.198062) (xy 328.53122 -283.097986) (xy 328.431144 -283.198062) (xy 328.431144 -283.242512)
			(xy 328.631296 -283.242512)
		)
		(stroke
			(width 0)
			(type solid)
		)
		(fill yes)
		(layer "In6.Cu")
		(net "M_E_CPU0_SB_DQ<13>")
	)
	(gr_poly
		(pts
			(xy 328.631296 -282.794202) (xy 328.631296 -282.749752) (xy 328.431144 -282.749752) (xy 328.431144 -282.794202)
			(xy 328.53122 -282.894278)
		)
		(stroke
			(width 0)
			(type solid)
		)
		(fill yes)
		(layer "In6.Cu")
		(net "M_E_CPU0_SB_DQ<14>")
	)
	(gr_poly
		(pts
			(xy 328.631296 -281.577796) (xy 328.53122 -281.477974) (xy 328.431144 -281.577796) (xy 328.431144 -281.625548)
			(xy 328.631296 -281.625548)
		)
		(stroke
			(width 0)
			(type solid)
		)
		(fill yes)
		(layer "In6.Cu")
		(net "M_E_CPU0_SB_DQS_DN<6>")
	)
	(gr_poly
		(pts
			(xy 328.631296 -281.174444) (xy 328.631296 -281.126692) (xy 328.431144 -281.126692) (xy 328.431144 -281.174444)
			(xy 328.53122 -281.274266)
		)
		(stroke
			(width 0)
			(type solid)
		)
		(fill yes)
		(layer "In6.Cu")
		(net "M_E_CPU0_SB_DQS_DN<1>")
	)
	(gr_poly
		(pts
			(xy 328.631296 -279.958038) (xy 328.53122 -279.857962) (xy 328.431144 -279.958038) (xy 328.431144 -280.002488)
			(xy 328.631296 -280.002488)
		)
		(stroke
			(width 0)
			(type solid)
		)
		(fill yes)
		(layer "In6.Cu")
		(net "M_E_CPU0_SB_DQ<9>")
	)
	(gr_poly
		(pts
			(xy 328.631296 -279.554178) (xy 328.631296 -279.509728) (xy 328.431144 -279.509728) (xy 328.431144 -279.554178)
			(xy 328.53122 -279.654254)
		)
		(stroke
			(width 0)
			(type solid)
		)
		(fill yes)
		(layer "In6.Cu")
		(net "M_E_CPU0_SB_DQ<10>")
	)
	(gr_poly
		(pts
			(xy 328.631296 -278.338026) (xy 328.53122 -278.23795) (xy 328.431144 -278.338026) (xy 328.431144 -278.382476)
			(xy 328.631296 -278.382476)
		)
		(stroke
			(width 0)
			(type solid)
		)
		(fill yes)
		(layer "In6.Cu")
		(net "M_E_CPU0_SB_DQ<5>")
	)
	(gr_poly
		(pts
			(xy 328.631296 -277.934166) (xy 328.631296 -277.889716) (xy 328.431144 -277.889716) (xy 328.431144 -277.934166)
			(xy 328.53122 -278.034242)
		)
		(stroke
			(width 0)
			(type solid)
		)
		(fill yes)
		(layer "In6.Cu")
		(net "M_E_CPU0_SB_DQ<6>")
	)
	(gr_poly
		(pts
			(xy 328.631296 -276.71776) (xy 328.53122 -276.617938) (xy 328.431144 -276.71776) (xy 328.431144 -276.765512)
			(xy 328.631296 -276.765512)
		)
		(stroke
			(width 0)
			(type solid)
		)
		(fill yes)
		(layer "In6.Cu")
		(net "M_E_CPU0_SB_DQS_DN<5>")
	)
	(gr_poly
		(pts
			(xy 328.631296 -276.314408) (xy 328.631296 -276.266656) (xy 328.431144 -276.266656) (xy 328.431144 -276.314408)
			(xy 328.53122 -276.41423)
		)
		(stroke
			(width 0)
			(type solid)
		)
		(fill yes)
		(layer "In6.Cu")
		(net "M_E_CPU0_SB_DQS_DN<0>")
	)
	(gr_poly
		(pts
			(xy 328.631296 -275.098002) (xy 328.53122 -274.997926) (xy 328.431144 -275.098002) (xy 328.431144 -275.142452)
			(xy 328.631296 -275.142452)
		)
		(stroke
			(width 0)
			(type solid)
		)
		(fill yes)
		(layer "In6.Cu")
		(net "M_E_CPU0_SB_DQ<1>")
	)
	(gr_poly
		(pts
			(xy 328.631296 -274.694142) (xy 328.631296 -274.649692) (xy 328.431144 -274.649692) (xy 328.431144 -274.694142)
			(xy 328.53122 -274.794218)
		)
		(stroke
			(width 0)
			(type solid)
		)
		(fill yes)
		(layer "In6.Cu")
		(net "M_E_CPU0_SB_DQ<2>")
	)
	(gr_poly
		(pts
			(xy 328.631296 -273.47799) (xy 328.53122 -273.377914) (xy 328.431144 -273.47799) (xy 328.431144 -273.52244)
			(xy 328.631296 -273.52244)
		)
		(stroke
			(width 0)
			(type solid)
		)
		(fill yes)
		(layer "In6.Cu")
		(net "M_E_CPU0_SB_CB<1>")
	)
	(gr_poly
		(pts
			(xy 328.631296 -273.07413) (xy 328.631296 -273.02968) (xy 328.431144 -273.02968) (xy 328.431144 -273.07413)
			(xy 328.53122 -273.174206)
		)
		(stroke
			(width 0)
			(type solid)
		)
		(fill yes)
		(layer "In6.Cu")
		(net "M_E_CPU0_SB_CB<2>")
	)
	(gr_poly
		(pts
			(xy 328.631296 -271.857724) (xy 328.53122 -271.757902) (xy 328.431144 -271.857724) (xy 328.431144 -271.905476)
			(xy 328.631296 -271.905476)
		)
		(stroke
			(width 0)
			(type solid)
		)
		(fill yes)
		(layer "In6.Cu")
		(net "M_E_CPU0_SB_DQS_DN<4>")
	)
	(gr_poly
		(pts
			(xy 328.631296 -271.454372) (xy 328.631296 -271.40662) (xy 328.431144 -271.40662) (xy 328.431144 -271.454372)
			(xy 328.53122 -271.554194)
		)
		(stroke
			(width 0)
			(type solid)
		)
		(fill yes)
		(layer "In6.Cu")
		(net "M_E_CPU0_SB_DQS_DN<9>")
	)
	(gr_poly
		(pts
			(xy 328.631296 -270.237966) (xy 328.53122 -270.13789) (xy 328.431144 -270.237966) (xy 328.431144 -270.282416)
			(xy 328.631296 -270.282416)
		)
		(stroke
			(width 0)
			(type solid)
		)
		(fill yes)
		(layer "In6.Cu")
		(net "M_E_CPU0_SB_CB<5>")
	)
	(gr_poly
		(pts
			(xy 328.631296 -269.834106) (xy 328.631296 -269.789656) (xy 328.431144 -269.789656) (xy 328.431144 -269.834106)
			(xy 328.53122 -269.934182)
		)
		(stroke
			(width 0)
			(type solid)
		)
		(fill yes)
		(layer "In6.Cu")
		(net "M_E_CPU0_SB_CB<6>")
	)
	(gr_poly
		(pts
			(xy 328.631296 -266.997942) (xy 328.53122 -266.897866) (xy 328.431144 -266.997942) (xy 328.431144 -267.042392)
			(xy 328.631296 -267.042392)
		)
		(stroke
			(width 0)
			(type solid)
		)
		(fill yes)
		(layer "In6.Cu")
		(net "M_E_CPU0_SA_RSP<0>")
	)
	(gr_poly
		(pts
			(xy 328.631296 -266.594082) (xy 328.631296 -266.549632) (xy 328.431144 -266.549632) (xy 328.431144 -266.594082)
			(xy 328.53122 -266.694158)
		)
		(stroke
			(width 0)
			(type solid)
		)
		(fill yes)
		(layer "In6.Cu")
		(net "M_E_CPU0_SB_CS_N<1>")
	)
	(gr_poly
		(pts
			(xy 328.631296 -264.97407) (xy 328.631296 -264.92962) (xy 328.431144 -264.92962) (xy 328.431144 -264.97407)
			(xy 328.53122 -265.074146)
		)
		(stroke
			(width 0)
			(type solid)
		)
		(fill yes)
		(layer "In6.Cu")
		(net "M_E_CPU0_SB_PAR")
	)
	(gr_poly
		(pts
			(xy 328.631296 -263.757918) (xy 328.53122 -263.657842) (xy 328.431144 -263.757918) (xy 328.431144 -263.802368)
			(xy 328.631296 -263.802368)
		)
		(stroke
			(width 0)
			(type solid)
		)
		(fill yes)
		(layer "In6.Cu")
		(net "M_E_CPU0_SB_CA<4>")
	)
	(gr_poly
		(pts
			(xy 328.631296 -263.354058) (xy 328.631296 -263.309608) (xy 328.431144 -263.309608) (xy 328.431144 -263.354058)
			(xy 328.53122 -263.454134)
		)
		(stroke
			(width 0)
			(type solid)
		)
		(fill yes)
		(layer "In6.Cu")
		(net "M_E_CPU0_SB_CA<3>")
	)
	(gr_poly
		(pts
			(xy 328.631296 -262.137906) (xy 328.53122 -262.03783) (xy 328.431144 -262.137906) (xy 328.431144 -262.182356)
			(xy 328.631296 -262.182356)
		)
		(stroke
			(width 0)
			(type solid)
		)
		(fill yes)
		(layer "In6.Cu")
		(net "M_E_CPU0_SB_CA<0>")
	)
	(gr_poly
		(pts
			(xy 328.676508 -293.068502) (xy 328.639932 -292.93185) (xy 328.601324 -292.909498) (xy 328.501502 -293.082726)
			(xy 328.539856 -293.105078)
		)
		(stroke
			(width 0)
			(type solid)
		)
		(fill yes)
		(layer "In6.Cu")
		(net "M_E_CPU0_SB_DQ<30>")
	)
	(gr_poly
		(pts
			(xy 328.748898 -256.439162) (xy 328.753216 -256.391664) (xy 328.553826 -256.374138) (xy 328.549762 -256.421636)
			(xy 328.640694 -256.530094)
		)
		(stroke
			(width 0)
			(type solid)
		)
		(fill yes)
		(layer "In6.Cu")
		(net "M_E_CPU0_CLK_DN<0>")
	)
	(gr_poly
		(pts
			(xy 328.748898 -246.71909) (xy 328.753216 -246.671592) (xy 328.553826 -246.65432) (xy 328.549762 -246.701564)
			(xy 328.640694 -246.810022)
		)
		(stroke
			(width 0)
			(type solid)
		)
		(fill yes)
		(layer "In6.Cu")
		(net "M_E_CPU0_SA_DQS_DN<4>")
	)
	(gr_poly
		(pts
			(xy 328.748898 -241.859054) (xy 328.753216 -241.811556) (xy 328.553826 -241.794284) (xy 328.549762 -241.841528)
			(xy 328.640694 -241.949986)
		)
		(stroke
			(width 0)
			(type solid)
		)
		(fill yes)
		(layer "In6.Cu")
		(net "M_E_CPU0_SA_DQS_DN<3>")
	)
	(gr_poly
		(pts
			(xy 328.748898 -236.999018) (xy 328.753216 -236.95152) (xy 328.553826 -236.934248) (xy 328.549762 -236.981492)
			(xy 328.640694 -237.08995)
		)
		(stroke
			(width 0)
			(type solid)
		)
		(fill yes)
		(layer "In6.Cu")
		(net "M_E_CPU0_SA_DQS_DN<2>")
	)
	(gr_poly
		(pts
			(xy 328.748898 -232.138982) (xy 328.753216 -232.091484) (xy 328.553826 -232.074212) (xy 328.549762 -232.121456)
			(xy 328.640694 -232.229914)
		)
		(stroke
			(width 0)
			(type solid)
		)
		(fill yes)
		(layer "In6.Cu")
		(net "M_E_CPU0_SA_DQS_DN<1>")
	)
	(gr_poly
		(pts
			(xy 328.757026 -296.170096) (xy 328.697336 -296.041826) (xy 328.65568 -296.026586) (xy 328.5871 -296.214546)
			(xy 328.62901 -296.229786)
		)
		(stroke
			(width 0)
			(type solid)
		)
		(fill yes)
		(layer "In6.Cu")
		(net "M_E_CPU0_SB_DQ<31>")
	)
	(gr_poly
		(pts
			(xy 328.759566 -227.279962) (xy 328.76363 -227.232464) (xy 328.564494 -227.214938) (xy 328.56043 -227.262436)
			(xy 328.651362 -227.370894)
		)
		(stroke
			(width 0)
			(type solid)
		)
		(fill yes)
		(layer "In6.Cu")
		(net "M_E_CPU0_SA_DQS_DN<0>")
	)
	(gr_poly
		(pts
			(xy 328.761598 -254.819912) (xy 328.765662 -254.775462) (xy 328.566272 -254.75819) (xy 328.562462 -254.802386)
			(xy 328.653394 -254.910844)
		)
		(stroke
			(width 0)
			(type solid)
		)
		(fill yes)
		(layer "In6.Cu")
		(net "M_E_CPU0_SA_CA<5>")
	)
	(gr_poly
		(pts
			(xy 328.761598 -253.1999) (xy 328.765662 -253.15545) (xy 328.566272 -253.138178) (xy 328.562462 -253.182374)
			(xy 328.653394 -253.290832)
		)
		(stroke
			(width 0)
			(type solid)
		)
		(fill yes)
		(layer "In6.Cu")
		(net "M_E_CPU0_SA_CA<1>")
	)
	(gr_poly
		(pts
			(xy 328.761598 -251.579888) (xy 328.765662 -251.535438) (xy 328.566272 -251.518166) (xy 328.562462 -251.562362)
			(xy 328.653394 -251.67082)
		)
		(stroke
			(width 0)
			(type solid)
		)
		(fill yes)
		(layer "In6.Cu")
		(net "M_E_CPU0_SA_CS_N<0>")
	)
	(gr_poly
		(pts
			(xy 328.761598 -248.339864) (xy 328.765662 -248.295414) (xy 328.566272 -248.278142) (xy 328.562462 -248.322338)
			(xy 328.653394 -248.430796)
		)
		(stroke
			(width 0)
			(type solid)
		)
		(fill yes)
		(layer "In6.Cu")
		(net "M_E_CPU0_SA_CB<6>")
	)
	(gr_poly
		(pts
			(xy 328.761598 -245.09984) (xy 328.765662 -245.05539) (xy 328.566272 -245.038118) (xy 328.562462 -245.082314)
			(xy 328.653394 -245.190772)
		)
		(stroke
			(width 0)
			(type solid)
		)
		(fill yes)
		(layer "In6.Cu")
		(net "M_E_CPU0_SA_CB<2>")
	)
	(gr_poly
		(pts
			(xy 328.761598 -243.479828) (xy 328.765662 -243.435378) (xy 328.566272 -243.418106) (xy 328.562462 -243.462302)
			(xy 328.653394 -243.57076)
		)
		(stroke
			(width 0)
			(type solid)
		)
		(fill yes)
		(layer "In6.Cu")
		(net "M_E_CPU0_SA_DQ<30>")
	)
	(gr_poly
		(pts
			(xy 328.761598 -240.239804) (xy 328.765662 -240.195354) (xy 328.566272 -240.178082) (xy 328.562462 -240.222278)
			(xy 328.653394 -240.330736)
		)
		(stroke
			(width 0)
			(type solid)
		)
		(fill yes)
		(layer "In6.Cu")
		(net "M_E_CPU0_SA_DQ<26>")
	)
	(gr_poly
		(pts
			(xy 328.761598 -238.619792) (xy 328.765662 -238.575342) (xy 328.566272 -238.55807) (xy 328.562462 -238.602266)
			(xy 328.653394 -238.710724)
		)
		(stroke
			(width 0)
			(type solid)
		)
		(fill yes)
		(layer "In6.Cu")
		(net "M_E_CPU0_SA_DQ<22>")
	)
	(gr_poly
		(pts
			(xy 328.761598 -235.379768) (xy 328.765662 -235.335318) (xy 328.566272 -235.318046) (xy 328.562462 -235.362242)
			(xy 328.653394 -235.4707)
		)
		(stroke
			(width 0)
			(type solid)
		)
		(fill yes)
		(layer "In6.Cu")
		(net "M_E_CPU0_SA_DQ<18>")
	)
	(gr_poly
		(pts
			(xy 328.761598 -233.759756) (xy 328.765662 -233.715306) (xy 328.566272 -233.698034) (xy 328.562462 -233.74223)
			(xy 328.653394 -233.850688)
		)
		(stroke
			(width 0)
			(type solid)
		)
		(fill yes)
		(layer "In6.Cu")
		(net "M_E_CPU0_SA_DQ<14>")
	)
	(gr_poly
		(pts
			(xy 328.761598 -230.519986) (xy 328.765662 -230.475536) (xy 328.566272 -230.458264) (xy 328.562462 -230.50246)
			(xy 328.653394 -230.610664)
		)
		(stroke
			(width 0)
			(type solid)
		)
		(fill yes)
		(layer "In6.Cu")
		(net "M_E_CPU0_SA_DQ<10>")
	)
	(gr_poly
		(pts
			(xy 328.761598 -228.899974) (xy 328.765662 -228.855524) (xy 328.566272 -228.838252) (xy 328.562462 -228.882448)
			(xy 328.653394 -228.990906)
		)
		(stroke
			(width 0)
			(type solid)
		)
		(fill yes)
		(layer "In6.Cu")
		(net "M_E_CPU0_SA_DQ<6>")
	)
	(gr_poly
		(pts
			(xy 328.761598 -225.65995) (xy 328.765662 -225.6155) (xy 328.566272 -225.598228) (xy 328.562462 -225.642424)
			(xy 328.653394 -225.750882)
		)
		(stroke
			(width 0)
			(type solid)
		)
		(fill yes)
		(layer "In6.Cu")
		(net "M_E_CPU0_SA_DQ<2>")
	)
	(gr_poly
		(pts
			(xy 328.799952 -230.915972) (xy 328.701146 -230.815896) (xy 328.60234 -230.915972) (xy 328.60234 -230.960422)
			(xy 328.799952 -230.960422)
		)
		(stroke
			(width 0)
			(type solid)
		)
		(fill yes)
		(layer "In6.Cu")
		(net "M_E_CPU0_SA_DQ<9>")
	)
	(gr_poly
		(pts
			(xy 328.801222 -255.216152) (xy 328.701146 -255.116076) (xy 328.60107 -255.216152) (xy 328.60107 -255.260602)
			(xy 328.801222 -255.260602)
		)
		(stroke
			(width 0)
			(type solid)
		)
		(fill yes)
		(layer "In6.Cu")
		(net "M_E_CPU0_SA_CA<6>")
	)
	(gr_poly
		(pts
			(xy 328.801222 -253.59614) (xy 328.701146 -253.496064) (xy 328.60107 -253.59614) (xy 328.60107 -253.64059)
			(xy 328.801222 -253.64059)
		)
		(stroke
			(width 0)
			(type solid)
		)
		(fill yes)
		(layer "In6.Cu")
		(net "M_E_CPU0_SA_CA<2>")
	)
	(gr_poly
		(pts
			(xy 328.801222 -250.356116) (xy 328.701146 -250.25604) (xy 328.60107 -250.356116) (xy 328.60107 -250.400566)
			(xy 328.801222 -250.400566)
		)
		(stroke
			(width 0)
			(type solid)
		)
		(fill yes)
		(layer "In6.Cu")
		(net "M_E_CPU0_ALERT_R_N")
	)
	(gr_poly
		(pts
			(xy 328.801222 -248.736104) (xy 328.701146 -248.636028) (xy 328.60107 -248.736104) (xy 328.60107 -248.780554)
			(xy 328.801222 -248.780554)
		)
		(stroke
			(width 0)
			(type solid)
		)
		(fill yes)
		(layer "In6.Cu")
		(net "M_E_CPU0_SA_CB<5>")
	)
	(gr_poly
		(pts
			(xy 328.801222 -247.115838) (xy 328.701146 -247.016016) (xy 328.60107 -247.115838) (xy 328.60107 -247.16359)
			(xy 328.801222 -247.16359)
		)
		(stroke
			(width 0)
			(type solid)
		)
		(fill yes)
		(layer "In6.Cu")
		(net "M_E_CPU0_SA_DQS_DN<9>")
	)
	(gr_poly
		(pts
			(xy 328.801222 -245.49608) (xy 328.701146 -245.396004) (xy 328.60107 -245.49608) (xy 328.60107 -245.54053)
			(xy 328.801222 -245.54053)
		)
		(stroke
			(width 0)
			(type solid)
		)
		(fill yes)
		(layer "In6.Cu")
		(net "M_E_CPU0_SA_CB<1>")
	)
	(gr_poly
		(pts
			(xy 328.801222 -243.876068) (xy 328.701146 -243.775992) (xy 328.60107 -243.876068) (xy 328.60107 -243.920518)
			(xy 328.801222 -243.920518)
		)
		(stroke
			(width 0)
			(type solid)
		)
		(fill yes)
		(layer "In6.Cu")
		(net "M_E_CPU0_SA_DQ<29>")
	)
	(gr_poly
		(pts
			(xy 328.801222 -242.255802) (xy 328.701146 -242.15598) (xy 328.60107 -242.255802) (xy 328.60107 -242.303554)
			(xy 328.801222 -242.303554)
		)
		(stroke
			(width 0)
			(type solid)
		)
		(fill yes)
		(layer "In6.Cu")
		(net "M_E_CPU0_SA_DQS_DN<8>")
	)
	(gr_poly
		(pts
			(xy 328.801222 -240.636044) (xy 328.701146 -240.535968) (xy 328.60107 -240.636044) (xy 328.60107 -240.680494)
			(xy 328.801222 -240.680494)
		)
		(stroke
			(width 0)
			(type solid)
		)
		(fill yes)
		(layer "In6.Cu")
		(net "M_E_CPU0_SA_DQ<25>")
	)
	(gr_poly
		(pts
			(xy 328.801222 -239.016032) (xy 328.701146 -238.915956) (xy 328.60107 -239.016032) (xy 328.60107 -239.060482)
			(xy 328.801222 -239.060482)
		)
		(stroke
			(width 0)
			(type solid)
		)
		(fill yes)
		(layer "In6.Cu")
		(net "M_E_CPU0_SA_DQ<21>")
	)
	(gr_poly
		(pts
			(xy 328.801222 -237.395766) (xy 328.701146 -237.295944) (xy 328.60107 -237.395766) (xy 328.60107 -237.443518)
			(xy 328.801222 -237.443518)
		)
		(stroke
			(width 0)
			(type solid)
		)
		(fill yes)
		(layer "In6.Cu")
		(net "M_E_CPU0_SA_DQS_DN<7>")
	)
	(gr_poly
		(pts
			(xy 328.801222 -235.776008) (xy 328.701146 -235.675932) (xy 328.60107 -235.776008) (xy 328.60107 -235.820458)
			(xy 328.801222 -235.820458)
		)
		(stroke
			(width 0)
			(type solid)
		)
		(fill yes)
		(layer "In6.Cu")
		(net "M_E_CPU0_SA_DQ<17>")
	)
	(gr_poly
		(pts
			(xy 328.801222 -234.155996) (xy 328.701146 -234.05592) (xy 328.60107 -234.155996) (xy 328.60107 -234.200446)
			(xy 328.801222 -234.200446)
		)
		(stroke
			(width 0)
			(type solid)
		)
		(fill yes)
		(layer "In6.Cu")
		(net "M_E_CPU0_SA_DQ<13>")
	)
	(gr_poly
		(pts
			(xy 328.801222 -232.53573) (xy 328.701146 -232.435908) (xy 328.60107 -232.53573) (xy 328.60107 -232.583482)
			(xy 328.801222 -232.583482)
		)
		(stroke
			(width 0)
			(type solid)
		)
		(fill yes)
		(layer "In6.Cu")
		(net "M_E_CPU0_SA_DQS_DN<6>")
	)
	(gr_poly
		(pts
			(xy 328.801222 -229.29596) (xy 328.701146 -229.195884) (xy 328.60107 -229.29596) (xy 328.60107 -229.34041)
			(xy 328.801222 -229.34041)
		)
		(stroke
			(width 0)
			(type solid)
		)
		(fill yes)
		(layer "In6.Cu")
		(net "M_E_CPU0_SA_DQ<5>")
	)
	(gr_poly
		(pts
			(xy 328.801222 -227.675948) (xy 328.701146 -227.576126) (xy 328.60107 -227.675948) (xy 328.60107 -227.7237)
			(xy 328.801222 -227.7237)
		)
		(stroke
			(width 0)
			(type solid)
		)
		(fill yes)
		(layer "In6.Cu")
		(net "M_E_CPU0_SA_DQS_DN<5>")
	)
	(gr_poly
		(pts
			(xy 328.801222 -226.05619) (xy 328.701146 -225.956114) (xy 328.60107 -226.05619) (xy 328.60107 -226.10064)
			(xy 328.801222 -226.10064)
		)
		(stroke
			(width 0)
			(type solid)
		)
		(fill yes)
		(layer "In6.Cu")
		(net "M_E_CPU0_SA_DQ<1>")
	)
	(gr_poly
		(pts
			(xy 328.820018 -224.035112) (xy 328.856594 -223.89846) (xy 328.719942 -223.861884) (xy 328.681334 -223.883982)
			(xy 328.78141 -224.05721)
		)
		(stroke
			(width 0)
			(type solid)
		)
		(fill yes)
		(layer "In6.Cu")
		(net "M_E_CPU0_SA_DQ<0>")
	)
	(gr_poly
		(pts
			(xy 328.856848 -224.569528) (xy 328.820272 -224.432876) (xy 328.781664 -224.410524) (xy 328.681842 -224.583752)
			(xy 328.720196 -224.606104)
		)
		(stroke
			(width 0)
			(type solid)
		)
		(fill yes)
		(layer "In6.Cu")
		(net "M_E_CPU0_SA_DQ<0>")
	)
	(gr_poly
		(pts
			(xy 329.030838 -293.158672) (xy 328.992484 -293.136574) (xy 328.855832 -293.17315) (xy 328.892408 -293.309802)
			(xy 328.931016 -293.3319)
		)
		(stroke
			(width 0)
			(type solid)
		)
		(fill yes)
		(layer "In6.Cu")
		(net "M_E_CPU0_SB_DQ<29>")
	)
	(gr_poly
		(pts
			(xy 329.05319 -290.528502) (xy 329.048872 -290.481004) (xy 328.940668 -290.390072) (xy 328.849736 -290.49853)
			(xy 328.8538 -290.546028)
		)
		(stroke
			(width 0)
			(type solid)
		)
		(fill yes)
		(layer "In6.Cu")
		(net "M_E_CPU0_SB_DQS_DP<3>")
	)
	(gr_poly
		(pts
			(xy 329.05319 -285.66872) (xy 329.048872 -285.621222) (xy 328.940668 -285.53029) (xy 328.849736 -285.638748)
			(xy 328.8538 -285.685992)
		)
		(stroke
			(width 0)
			(type solid)
		)
		(fill yes)
		(layer "In6.Cu")
		(net "M_E_CPU0_SB_DQS_DP<2>")
	)
	(gr_poly
		(pts
			(xy 329.05319 -275.948648) (xy 329.048872 -275.90115) (xy 328.940668 -275.810218) (xy 328.849736 -275.918676)
			(xy 328.8538 -275.96592)
		)
		(stroke
			(width 0)
			(type solid)
		)
		(fill yes)
		(layer "In6.Cu")
		(net "M_E_CPU0_SB_DQS_DP<0>")
	)
	(gr_poly
		(pts
			(xy 329.05319 -271.088612) (xy 329.048872 -271.041114) (xy 328.940668 -270.950182) (xy 328.849736 -271.05864)
			(xy 328.8538 -271.105884)
		)
		(stroke
			(width 0)
			(type solid)
		)
		(fill yes)
		(layer "In6.Cu")
		(net "M_E_CPU0_SB_DQS_DP<9>")
	)
	(gr_poly
		(pts
			(xy 329.063096 -267.838428) (xy 329.058524 -267.787882) (xy 328.95032 -267.69695) (xy 328.859388 -267.805408)
			(xy 328.863706 -267.855954)
		)
		(stroke
			(width 0)
			(type solid)
		)
		(fill yes)
		(layer "In6.Cu")
		(net "M_E_CPU0_SB_RSP<0>")
	)
	(gr_poly
		(pts
			(xy 329.063858 -280.807922) (xy 329.05954 -280.760424) (xy 328.951336 -280.669492) (xy 328.860404 -280.77795)
			(xy 328.864468 -280.825448)
		)
		(stroke
			(width 0)
			(type solid)
		)
		(fill yes)
		(layer "In6.Cu")
		(net "M_E_CPU0_SB_DQS_DP<1>")
	)
	(gr_poly
		(pts
			(xy 329.065382 -292.144704) (xy 329.061572 -292.100254) (xy 328.953368 -292.009322) (xy 328.862436 -292.11778)
			(xy 328.866246 -292.161976)
		)
		(stroke
			(width 0)
			(type solid)
		)
		(fill yes)
		(layer "In6.Cu")
		(net "M_E_CPU0_SB_DQ<28>")
	)
	(gr_poly
		(pts
			(xy 329.065382 -288.90468) (xy 329.061572 -288.86023) (xy 328.953368 -288.769298) (xy 328.862436 -288.877756)
			(xy 328.866246 -288.921952)
		)
		(stroke
			(width 0)
			(type solid)
		)
		(fill yes)
		(layer "In6.Cu")
		(net "M_E_CPU0_SB_DQ<24>")
	)
	(gr_poly
		(pts
			(xy 329.065382 -287.284668) (xy 329.061572 -287.240218) (xy 328.953368 -287.14954) (xy 328.862436 -287.257744)
			(xy 328.866246 -287.30194)
		)
		(stroke
			(width 0)
			(type solid)
		)
		(fill yes)
		(layer "In6.Cu")
		(net "M_E_CPU0_SB_DQ<20>")
	)
	(gr_poly
		(pts
			(xy 329.065382 -284.044898) (xy 329.061572 -284.000448) (xy 328.953368 -283.909516) (xy 328.862436 -284.017974)
			(xy 328.866246 -284.06217)
		)
		(stroke
			(width 0)
			(type solid)
		)
		(fill yes)
		(layer "In6.Cu")
		(net "M_E_CPU0_SB_DQ<16>")
	)
	(gr_poly
		(pts
			(xy 329.065382 -282.424886) (xy 329.061572 -282.380436) (xy 328.953368 -282.289504) (xy 328.862436 -282.397962)
			(xy 328.866246 -282.442158)
		)
		(stroke
			(width 0)
			(type solid)
		)
		(fill yes)
		(layer "In6.Cu")
		(net "M_E_CPU0_SB_DQ<12>")
	)
	(gr_poly
		(pts
			(xy 329.065382 -279.184862) (xy 329.061572 -279.140412) (xy 328.953368 -279.04948) (xy 328.862436 -279.157938)
			(xy 328.866246 -279.202134)
		)
		(stroke
			(width 0)
			(type solid)
		)
		(fill yes)
		(layer "In6.Cu")
		(net "M_E_CPU0_SB_DQ<8>")
	)
	(gr_poly
		(pts
			(xy 329.065382 -277.56485) (xy 329.061572 -277.5204) (xy 328.953368 -277.429468) (xy 328.862436 -277.537926)
			(xy 328.866246 -277.582122)
		)
		(stroke
			(width 0)
			(type solid)
		)
		(fill yes)
		(layer "In6.Cu")
		(net "M_E_CPU0_SB_DQ<4>")
	)
	(gr_poly
		(pts
			(xy 329.065382 -274.324826) (xy 329.061572 -274.280376) (xy 328.953368 -274.189444) (xy 328.862436 -274.297902)
			(xy 328.866246 -274.342098)
		)
		(stroke
			(width 0)
			(type solid)
		)
		(fill yes)
		(layer "In6.Cu")
		(net "M_E_CPU0_SB_DQ<0>")
	)
	(gr_poly
		(pts
			(xy 329.065382 -272.704814) (xy 329.061572 -272.660364) (xy 328.953368 -272.569432) (xy 328.862436 -272.67789)
			(xy 328.866246 -272.722086)
		)
		(stroke
			(width 0)
			(type solid)
		)
		(fill yes)
		(layer "In6.Cu")
		(net "M_E_CPU0_SB_CB<0>")
	)
	(gr_poly
		(pts
			(xy 329.065382 -269.46479) (xy 329.061572 -269.42034) (xy 328.953368 -269.329408) (xy 328.862436 -269.437866)
			(xy 328.866246 -269.482062)
		)
		(stroke
			(width 0)
			(type solid)
		)
		(fill yes)
		(layer "In6.Cu")
		(net "M_E_CPU0_SB_CB<4>")
	)
	(gr_poly
		(pts
			(xy 329.065382 -264.604754) (xy 329.061572 -264.560304) (xy 328.953368 -264.469372) (xy 328.862436 -264.57783)
			(xy 328.866246 -264.622026)
		)
		(stroke
			(width 0)
			(type solid)
		)
		(fill yes)
		(layer "In6.Cu")
		(net "M_E_CPU0_SB_CA<6>")
	)
	(gr_poly
		(pts
			(xy 329.065382 -262.984742) (xy 329.061572 -262.940292) (xy 328.953368 -262.84936) (xy 328.862436 -262.957818)
			(xy 328.866246 -263.002014)
		)
		(stroke
			(width 0)
			(type solid)
		)
		(fill yes)
		(layer "In6.Cu")
		(net "M_E_CPU0_SB_CA<2>")
	)
	(gr_poly
		(pts
			(xy 329.101196 -291.704268) (xy 329.101196 -291.656516) (xy 328.901044 -291.656516) (xy 328.901044 -291.704268)
			(xy 329.00112 -291.80409)
		)
		(stroke
			(width 0)
			(type solid)
		)
		(fill yes)
		(layer "In6.Cu")
		(net "M_E_CPU0_SB_DQS_DP<8>")
	)
	(gr_poly
		(pts
			(xy 329.101196 -290.084002) (xy 329.101196 -290.039552) (xy 328.901044 -290.039552) (xy 328.901044 -290.084002)
			(xy 329.00112 -290.184078)
		)
		(stroke
			(width 0)
			(type solid)
		)
		(fill yes)
		(layer "In6.Cu")
		(net "M_E_CPU0_SB_DQ<27>")
	)
	(gr_poly
		(pts
			(xy 329.101196 -288.464244) (xy 329.101196 -288.419794) (xy 328.901044 -288.419794) (xy 328.901044 -288.464244)
			(xy 329.00112 -288.56432)
		)
		(stroke
			(width 0)
			(type solid)
		)
		(fill yes)
		(layer "In6.Cu")
		(net "M_E_CPU0_SB_DQ<23>")
	)
	(gr_poly
		(pts
			(xy 329.101196 -286.844232) (xy 329.101196 -286.79648) (xy 328.901044 -286.79648) (xy 328.901044 -286.844232)
			(xy 329.00112 -286.944308)
		)
		(stroke
			(width 0)
			(type solid)
		)
		(fill yes)
		(layer "In6.Cu")
		(net "M_E_CPU0_SB_DQS_DP<7>")
	)
	(gr_poly
		(pts
			(xy 329.101196 -285.22422) (xy 329.101196 -285.17977) (xy 328.901044 -285.17977) (xy 328.901044 -285.22422)
			(xy 329.00112 -285.324296)
		)
		(stroke
			(width 0)
			(type solid)
		)
		(fill yes)
		(layer "In6.Cu")
		(net "M_E_CPU0_SB_DQ<19>")
	)
	(gr_poly
		(pts
			(xy 329.101196 -283.604208) (xy 329.101196 -283.559758) (xy 328.901044 -283.559758) (xy 328.901044 -283.604208)
			(xy 329.00112 -283.704284)
		)
		(stroke
			(width 0)
			(type solid)
		)
		(fill yes)
		(layer "In6.Cu")
		(net "M_E_CPU0_SB_DQ<15>")
	)
	(gr_poly
		(pts
			(xy 329.101196 -281.98445) (xy 329.101196 -281.936698) (xy 328.901044 -281.936698) (xy 328.901044 -281.98445)
			(xy 329.00112 -282.084272)
		)
		(stroke
			(width 0)
			(type solid)
		)
		(fill yes)
		(layer "In6.Cu")
		(net "M_E_CPU0_SB_DQS_DP<6>")
	)
	(gr_poly
		(pts
			(xy 329.101196 -280.364184) (xy 329.101196 -280.319734) (xy 328.901044 -280.319734) (xy 328.901044 -280.364184)
			(xy 329.00112 -280.46426)
		)
		(stroke
			(width 0)
			(type solid)
		)
		(fill yes)
		(layer "In6.Cu")
		(net "M_E_CPU0_SB_DQ<11>")
	)
	(gr_poly
		(pts
			(xy 329.101196 -278.744172) (xy 329.101196 -278.699722) (xy 328.901044 -278.699722) (xy 328.901044 -278.744172)
			(xy 329.00112 -278.844248)
		)
		(stroke
			(width 0)
			(type solid)
		)
		(fill yes)
		(layer "In6.Cu")
		(net "M_E_CPU0_SB_DQ<7>")
	)
	(gr_poly
		(pts
			(xy 329.101196 -277.124414) (xy 329.101196 -277.076662) (xy 328.901044 -277.076662) (xy 328.901044 -277.124414)
			(xy 329.00112 -277.224236)
		)
		(stroke
			(width 0)
			(type solid)
		)
		(fill yes)
		(layer "In6.Cu")
		(net "M_E_CPU0_SB_DQS_DP<5>")
	)
	(gr_poly
		(pts
			(xy 329.101196 -275.504148) (xy 329.101196 -275.459698) (xy 328.901044 -275.459698) (xy 328.901044 -275.504148)
			(xy 329.00112 -275.604224)
		)
		(stroke
			(width 0)
			(type solid)
		)
		(fill yes)
		(layer "In6.Cu")
		(net "M_E_CPU0_SB_DQ<3>")
	)
	(gr_poly
		(pts
			(xy 329.101196 -273.884136) (xy 329.101196 -273.839686) (xy 328.901044 -273.839686) (xy 328.901044 -273.884136)
			(xy 329.00112 -273.984212)
		)
		(stroke
			(width 0)
			(type solid)
		)
		(fill yes)
		(layer "In6.Cu")
		(net "M_E_CPU0_SB_CB<3>")
	)
	(gr_poly
		(pts
			(xy 329.101196 -272.264378) (xy 329.101196 -272.216626) (xy 328.901044 -272.216626) (xy 328.901044 -272.264378)
			(xy 329.00112 -272.3642)
		)
		(stroke
			(width 0)
			(type solid)
		)
		(fill yes)
		(layer "In6.Cu")
		(net "M_E_CPU0_SB_DQS_DP<4>")
	)
	(gr_poly
		(pts
			(xy 329.101196 -270.644112) (xy 329.101196 -270.599662) (xy 328.901044 -270.599662) (xy 328.901044 -270.644112)
			(xy 329.00112 -270.744188)
		)
		(stroke
			(width 0)
			(type solid)
		)
		(fill yes)
		(layer "In6.Cu")
		(net "M_E_CPU0_SB_CB<7>")
	)
	(gr_poly
		(pts
			(xy 329.101196 -265.784076) (xy 329.101196 -265.739626) (xy 328.901044 -265.739626) (xy 328.901044 -265.784076)
			(xy 329.00112 -265.884152)
		)
		(stroke
			(width 0)
			(type solid)
		)
		(fill yes)
		(layer "In6.Cu")
		(net "M_E_CPU0_SB_CS_N<0>")
	)
	(gr_poly
		(pts
			(xy 329.101196 -264.164064) (xy 329.101196 -264.119614) (xy 328.901044 -264.119614) (xy 328.901044 -264.164064)
			(xy 329.00112 -264.26414)
		)
		(stroke
			(width 0)
			(type solid)
		)
		(fill yes)
		(layer "In6.Cu")
		(net "M_E_CPU0_SB_CA<5>")
	)
	(gr_poly
		(pts
			(xy 329.101196 -262.544052) (xy 329.101196 -262.499602) (xy 328.901044 -262.499602) (xy 328.901044 -262.544052)
			(xy 329.00112 -262.644128)
		)
		(stroke
			(width 0)
			(type solid)
		)
		(fill yes)
		(layer "In6.Cu")
		(net "M_E_CPU0_SB_CA<1>")
	)
	(gr_poly
		(pts
			(xy 329.198224 -295.386252) (xy 329.138534 -295.257982) (xy 329.096878 -295.242996) (xy 329.028298 -295.430956)
			(xy 329.070208 -295.445942)
		)
		(stroke
			(width 0)
			(type solid)
		)
		(fill yes)
		(layer "In6.Cu")
		(net "M_E_CPU0_SB_DQ<31>")
	)
	(gr_poly
		(pts
			(xy 329.269852 -231.322372) (xy 329.269852 -231.277922) (xy 329.07224 -231.277922) (xy 329.07224 -231.322372)
			(xy 329.171046 -231.422448)
		)
		(stroke
			(width 0)
			(type solid)
		)
		(fill yes)
		(layer "In6.Cu")
		(net "M_E_CPU0_SA_DQ<11>")
	)
	(gr_poly
		(pts
			(xy 329.271122 -255.622298) (xy 329.271122 -255.577848) (xy 329.07097 -255.577848) (xy 329.07097 -255.622298)
			(xy 329.171046 -255.722374)
		)
		(stroke
			(width 0)
			(type solid)
		)
		(fill yes)
		(layer "In6.Cu")
		(net "M_E_CPU0_SA_PAR")
	)
	(gr_poly
		(pts
			(xy 329.271122 -254.002286) (xy 329.271122 -253.957836) (xy 329.07097 -253.957836) (xy 329.07097 -254.002286)
			(xy 329.171046 -254.102362)
		)
		(stroke
			(width 0)
			(type solid)
		)
		(fill yes)
		(layer "In6.Cu")
		(net "M_E_CPU0_SA_CA<3>")
	)
	(gr_poly
		(pts
			(xy 329.271122 -252.382274) (xy 329.271122 -252.337824) (xy 329.07097 -252.337824) (xy 329.07097 -252.382274)
			(xy 329.171046 -252.48235)
		)
		(stroke
			(width 0)
			(type solid)
		)
		(fill yes)
		(layer "In6.Cu")
		(net "M_E_CPU0_SA_CS_N<1>")
	)
	(gr_poly
		(pts
			(xy 329.271122 -250.762262) (xy 329.271122 -250.717812) (xy 329.07097 -250.717812) (xy 329.07097 -250.762262)
			(xy 329.171046 -250.862338)
		)
		(stroke
			(width 0)
			(type solid)
		)
		(fill yes)
		(layer "In6.Cu")
		(net "M_E_CPU0_RESET_N")
	)
	(gr_poly
		(pts
			(xy 329.271122 -249.14225) (xy 329.271122 -249.0978) (xy 329.07097 -249.0978) (xy 329.07097 -249.14225)
			(xy 329.171046 -249.242326)
		)
		(stroke
			(width 0)
			(type solid)
		)
		(fill yes)
		(layer "In6.Cu")
		(net "M_E_CPU0_SA_CB<7>")
	)
	(gr_poly
		(pts
			(xy 329.271122 -247.522492) (xy 329.271122 -247.47474) (xy 329.07097 -247.47474) (xy 329.07097 -247.522492)
			(xy 329.171046 -247.622314)
		)
		(stroke
			(width 0)
			(type solid)
		)
		(fill yes)
		(layer "In6.Cu")
		(net "M_E_CPU0_SA_DQS_DP<9>")
	)
	(gr_poly
		(pts
			(xy 329.271122 -245.902226) (xy 329.271122 -245.857776) (xy 329.07097 -245.857776) (xy 329.07097 -245.902226)
			(xy 329.171046 -246.002302)
		)
		(stroke
			(width 0)
			(type solid)
		)
		(fill yes)
		(layer "In6.Cu")
		(net "M_E_CPU0_SA_CB<3>")
	)
	(gr_poly
		(pts
			(xy 329.271122 -244.282214) (xy 329.271122 -244.237764) (xy 329.07097 -244.237764) (xy 329.07097 -244.282214)
			(xy 329.171046 -244.38229)
		)
		(stroke
			(width 0)
			(type solid)
		)
		(fill yes)
		(layer "In6.Cu")
		(net "M_E_CPU0_SA_DQ<31>")
	)
	(gr_poly
		(pts
			(xy 329.271122 -242.662456) (xy 329.271122 -242.614704) (xy 329.07097 -242.614704) (xy 329.07097 -242.662456)
			(xy 329.171046 -242.762278)
		)
		(stroke
			(width 0)
			(type solid)
		)
		(fill yes)
		(layer "In6.Cu")
		(net "M_E_CPU0_SA_DQS_DP<8>")
	)
	(gr_poly
		(pts
			(xy 329.271122 -241.04219) (xy 329.271122 -240.99774) (xy 329.07097 -240.99774) (xy 329.07097 -241.04219)
			(xy 329.171046 -241.142266)
		)
		(stroke
			(width 0)
			(type solid)
		)
		(fill yes)
		(layer "In6.Cu")
		(net "M_E_CPU0_SA_DQ<27>")
	)
	(gr_poly
		(pts
			(xy 329.271122 -239.422178) (xy 329.271122 -239.377728) (xy 329.07097 -239.377728) (xy 329.07097 -239.422178)
			(xy 329.171046 -239.522254)
		)
		(stroke
			(width 0)
			(type solid)
		)
		(fill yes)
		(layer "In6.Cu")
		(net "M_E_CPU0_SA_DQ<23>")
	)
	(gr_poly
		(pts
			(xy 329.271122 -237.80242) (xy 329.271122 -237.754668) (xy 329.07097 -237.754668) (xy 329.07097 -237.80242)
			(xy 329.171046 -237.902242)
		)
		(stroke
			(width 0)
			(type solid)
		)
		(fill yes)
		(layer "In6.Cu")
		(net "M_E_CPU0_SA_DQS_DP<7>")
	)
	(gr_poly
		(pts
			(xy 329.271122 -236.182154) (xy 329.271122 -236.137704) (xy 329.07097 -236.137704) (xy 329.07097 -236.182154)
			(xy 329.171046 -236.28223)
		)
		(stroke
			(width 0)
			(type solid)
		)
		(fill yes)
		(layer "In6.Cu")
		(net "M_E_CPU0_SA_DQ<19>")
	)
	(gr_poly
		(pts
			(xy 329.271122 -234.562142) (xy 329.271122 -234.517692) (xy 329.07097 -234.517692) (xy 329.07097 -234.562142)
			(xy 329.171046 -234.662218)
		)
		(stroke
			(width 0)
			(type solid)
		)
		(fill yes)
		(layer "In6.Cu")
		(net "M_E_CPU0_SA_DQ<15>")
	)
	(gr_poly
		(pts
			(xy 329.271122 -232.942384) (xy 329.271122 -232.894632) (xy 329.07097 -232.894632) (xy 329.07097 -232.942384)
			(xy 329.171046 -233.042206)
		)
		(stroke
			(width 0)
			(type solid)
		)
		(fill yes)
		(layer "In6.Cu")
		(net "M_E_CPU0_SA_DQS_DP<6>")
	)
	(gr_poly
		(pts
			(xy 329.271122 -229.70236) (xy 329.271122 -229.65791) (xy 329.07097 -229.65791) (xy 329.07097 -229.70236)
			(xy 329.171046 -229.802436)
		)
		(stroke
			(width 0)
			(type solid)
		)
		(fill yes)
		(layer "In6.Cu")
		(net "M_E_CPU0_SA_DQ<7>")
	)
	(gr_poly
		(pts
			(xy 329.271122 -228.082602) (xy 329.271122 -228.03485) (xy 329.07097 -228.03485) (xy 329.07097 -228.082602)
			(xy 329.171046 -228.182424)
		)
		(stroke
			(width 0)
			(type solid)
		)
		(fill yes)
		(layer "In6.Cu")
		(net "M_E_CPU0_SA_DQS_DP<5>")
	)
	(gr_poly
		(pts
			(xy 329.271122 -226.462336) (xy 329.271122 -226.417886) (xy 329.07097 -226.417886) (xy 329.07097 -226.462336)
			(xy 329.171046 -226.562412)
		)
		(stroke
			(width 0)
			(type solid)
		)
		(fill yes)
		(layer "In6.Cu")
		(net "M_E_CPU0_SA_DQ<3>")
	)
	(gr_poly
		(pts
			(xy 329.571096 -292.91788) (xy 329.47102 -292.817804) (xy 329.370944 -292.91788) (xy 329.370944 -292.96233)
			(xy 329.571096 -292.96233)
		)
		(stroke
			(width 0)
			(type solid)
		)
		(fill yes)
		(layer "In6.Cu")
		(net "M_E_CPU0_SB_DQ<29>")
	)
	(gr_poly
		(pts
			(xy 329.571096 -291.297614) (xy 329.47102 -291.197792) (xy 329.370944 -291.297614) (xy 329.370944 -291.345366)
			(xy 329.571096 -291.345366)
		)
		(stroke
			(width 0)
			(type solid)
		)
		(fill yes)
		(layer "In6.Cu")
		(net "M_E_CPU0_SB_DQS_DN<8>")
	)
	(gr_poly
		(pts
			(xy 329.571096 -289.677856) (xy 329.47102 -289.57778) (xy 329.370944 -289.677856) (xy 329.370944 -289.722306)
			(xy 329.571096 -289.722306)
		)
		(stroke
			(width 0)
			(type solid)
		)
		(fill yes)
		(layer "In6.Cu")
		(net "M_E_CPU0_SB_DQ<25>")
	)
	(gr_poly
		(pts
			(xy 329.571096 -288.057844) (xy 329.47102 -287.957768) (xy 329.370944 -288.057844) (xy 329.370944 -288.102294)
			(xy 329.571096 -288.102294)
		)
		(stroke
			(width 0)
			(type solid)
		)
		(fill yes)
		(layer "In6.Cu")
		(net "M_E_CPU0_SB_DQ<21>")
	)
	(gr_poly
		(pts
			(xy 329.571096 -286.437832) (xy 329.47102 -286.337756) (xy 329.370944 -286.437832) (xy 329.370944 -286.485584)
			(xy 329.571096 -286.485584)
		)
		(stroke
			(width 0)
			(type solid)
		)
		(fill yes)
		(layer "In6.Cu")
		(net "M_E_CPU0_SB_DQS_DN<7>")
	)
	(gr_poly
		(pts
			(xy 329.571096 -284.818074) (xy 329.47102 -284.717998) (xy 329.370944 -284.818074) (xy 329.370944 -284.862524)
			(xy 329.571096 -284.862524)
		)
		(stroke
			(width 0)
			(type solid)
		)
		(fill yes)
		(layer "In6.Cu")
		(net "M_E_CPU0_SB_DQ<17>")
	)
	(gr_poly
		(pts
			(xy 329.571096 -283.198062) (xy 329.47102 -283.097986) (xy 329.370944 -283.198062) (xy 329.370944 -283.242512)
			(xy 329.571096 -283.242512)
		)
		(stroke
			(width 0)
			(type solid)
		)
		(fill yes)
		(layer "In6.Cu")
		(net "M_E_CPU0_SB_DQ<13>")
	)
	(gr_poly
		(pts
			(xy 329.571096 -281.577796) (xy 329.47102 -281.477974) (xy 329.370944 -281.577796) (xy 329.370944 -281.625548)
			(xy 329.571096 -281.625548)
		)
		(stroke
			(width 0)
			(type solid)
		)
		(fill yes)
		(layer "In6.Cu")
		(net "M_E_CPU0_SB_DQS_DN<6>")
	)
	(gr_poly
		(pts
			(xy 329.571096 -279.958038) (xy 329.47102 -279.857962) (xy 329.370944 -279.958038) (xy 329.370944 -280.002488)
			(xy 329.571096 -280.002488)
		)
		(stroke
			(width 0)
			(type solid)
		)
		(fill yes)
		(layer "In6.Cu")
		(net "M_E_CPU0_SB_DQ<9>")
	)
	(gr_poly
		(pts
			(xy 329.571096 -278.338026) (xy 329.47102 -278.23795) (xy 329.370944 -278.338026) (xy 329.370944 -278.382476)
			(xy 329.571096 -278.382476)
		)
		(stroke
			(width 0)
			(type solid)
		)
		(fill yes)
		(layer "In6.Cu")
		(net "M_E_CPU0_SB_DQ<5>")
	)
	(gr_poly
		(pts
			(xy 329.571096 -276.71776) (xy 329.47102 -276.617938) (xy 329.370944 -276.71776) (xy 329.370944 -276.765512)
			(xy 329.571096 -276.765512)
		)
		(stroke
			(width 0)
			(type solid)
		)
		(fill yes)
		(layer "In6.Cu")
		(net "M_E_CPU0_SB_DQS_DN<5>")
	)
	(gr_poly
		(pts
			(xy 329.571096 -275.098002) (xy 329.47102 -274.997926) (xy 329.370944 -275.098002) (xy 329.370944 -275.142452)
			(xy 329.571096 -275.142452)
		)
		(stroke
			(width 0)
			(type solid)
		)
		(fill yes)
		(layer "In6.Cu")
		(net "M_E_CPU0_SB_DQ<1>")
	)
	(gr_poly
		(pts
			(xy 329.571096 -273.47799) (xy 329.47102 -273.377914) (xy 329.370944 -273.47799) (xy 329.370944 -273.52244)
			(xy 329.571096 -273.52244)
		)
		(stroke
			(width 0)
			(type solid)
		)
		(fill yes)
		(layer "In6.Cu")
		(net "M_E_CPU0_SB_CB<1>")
	)
	(gr_poly
		(pts
			(xy 329.571096 -271.857724) (xy 329.47102 -271.757902) (xy 329.370944 -271.857724) (xy 329.370944 -271.905476)
			(xy 329.571096 -271.905476)
		)
		(stroke
			(width 0)
			(type solid)
		)
		(fill yes)
		(layer "In6.Cu")
		(net "M_E_CPU0_SB_DQS_DN<4>")
	)
	(gr_poly
		(pts
			(xy 329.571096 -270.237966) (xy 329.47102 -270.13789) (xy 329.370944 -270.237966) (xy 329.370944 -270.282416)
			(xy 329.571096 -270.282416)
		)
		(stroke
			(width 0)
			(type solid)
		)
		(fill yes)
		(layer "In6.Cu")
		(net "M_E_CPU0_SB_CB<5>")
	)
	(gr_poly
		(pts
			(xy 329.571096 -266.997942) (xy 329.47102 -266.897866) (xy 329.370944 -266.997942) (xy 329.370944 -267.042392)
			(xy 329.571096 -267.042392)
		)
		(stroke
			(width 0)
			(type solid)
		)
		(fill yes)
		(layer "In6.Cu")
		(net "M_E_CPU0_SA_RSP<0>")
	)
	(gr_poly
		(pts
			(xy 329.571096 -263.757918) (xy 329.47102 -263.657842) (xy 329.370944 -263.757918) (xy 329.370944 -263.802368)
			(xy 329.571096 -263.802368)
		)
		(stroke
			(width 0)
			(type solid)
		)
		(fill yes)
		(layer "In6.Cu")
		(net "M_E_CPU0_SB_CA<4>")
	)
	(gr_poly
		(pts
			(xy 329.571096 -262.137906) (xy 329.47102 -262.03783) (xy 329.370944 -262.137906) (xy 329.370944 -262.182356)
			(xy 329.571096 -262.182356)
		)
		(stroke
			(width 0)
			(type solid)
		)
		(fill yes)
		(layer "In6.Cu")
		(net "M_E_CPU0_SB_CA<0>")
	)
	(gr_poly
		(pts
			(xy 329.62723 -294.67048) (xy 329.5904 -294.533828) (xy 329.552046 -294.511476) (xy 329.45197 -294.684704)
			(xy 329.490578 -294.707056)
		)
		(stroke
			(width 0)
			(type solid)
		)
		(fill yes)
		(layer "In6.Cu")
		(net "M_E_CPU0_SB_DQ<31>")
	)
	(gr_poly
		(pts
			(xy 329.740006 -230.915972) (xy 329.6412 -230.815896) (xy 329.542394 -230.915972) (xy 329.542394 -230.960422)
			(xy 329.740006 -230.960422)
		)
		(stroke
			(width 0)
			(type solid)
		)
		(fill yes)
		(layer "In6.Cu")
		(net "M_E_CPU0_SA_DQ<9>")
	)
	(gr_poly
		(pts
			(xy 329.741276 -255.216152) (xy 329.6412 -255.116076) (xy 329.541124 -255.216152) (xy 329.541124 -255.260602)
			(xy 329.741276 -255.260602)
		)
		(stroke
			(width 0)
			(type solid)
		)
		(fill yes)
		(layer "In6.Cu")
		(net "M_E_CPU0_SA_CA<6>")
	)
	(gr_poly
		(pts
			(xy 329.741276 -253.59614) (xy 329.6412 -253.496064) (xy 329.541124 -253.59614) (xy 329.541124 -253.64059)
			(xy 329.741276 -253.64059)
		)
		(stroke
			(width 0)
			(type solid)
		)
		(fill yes)
		(layer "In6.Cu")
		(net "M_E_CPU0_SA_CA<2>")
	)
	(gr_poly
		(pts
			(xy 329.741276 -250.356116) (xy 329.6412 -250.25604) (xy 329.541124 -250.356116) (xy 329.541124 -250.400566)
			(xy 329.741276 -250.400566)
		)
		(stroke
			(width 0)
			(type solid)
		)
		(fill yes)
		(layer "In6.Cu")
		(net "M_E_CPU0_ALERT_R_N")
	)
	(gr_poly
		(pts
			(xy 329.741276 -248.736104) (xy 329.6412 -248.636028) (xy 329.541124 -248.736104) (xy 329.541124 -248.780554)
			(xy 329.741276 -248.780554)
		)
		(stroke
			(width 0)
			(type solid)
		)
		(fill yes)
		(layer "In6.Cu")
		(net "M_E_CPU0_SA_CB<5>")
	)
	(gr_poly
		(pts
			(xy 329.741276 -247.115838) (xy 329.6412 -247.016016) (xy 329.541124 -247.115838) (xy 329.541124 -247.16359)
			(xy 329.741276 -247.16359)
		)
		(stroke
			(width 0)
			(type solid)
		)
		(fill yes)
		(layer "In6.Cu")
		(net "M_E_CPU0_SA_DQS_DN<9>")
	)
	(gr_poly
		(pts
			(xy 329.741276 -245.49608) (xy 329.6412 -245.396004) (xy 329.541124 -245.49608) (xy 329.541124 -245.54053)
			(xy 329.741276 -245.54053)
		)
		(stroke
			(width 0)
			(type solid)
		)
		(fill yes)
		(layer "In6.Cu")
		(net "M_E_CPU0_SA_CB<1>")
	)
	(gr_poly
		(pts
			(xy 329.741276 -243.876068) (xy 329.6412 -243.775992) (xy 329.541124 -243.876068) (xy 329.541124 -243.920518)
			(xy 329.741276 -243.920518)
		)
		(stroke
			(width 0)
			(type solid)
		)
		(fill yes)
		(layer "In6.Cu")
		(net "M_E_CPU0_SA_DQ<29>")
	)
	(gr_poly
		(pts
			(xy 329.741276 -242.255802) (xy 329.6412 -242.15598) (xy 329.541124 -242.255802) (xy 329.541124 -242.303554)
			(xy 329.741276 -242.303554)
		)
		(stroke
			(width 0)
			(type solid)
		)
		(fill yes)
		(layer "In6.Cu")
		(net "M_E_CPU0_SA_DQS_DN<8>")
	)
	(gr_poly
		(pts
			(xy 329.741276 -240.636044) (xy 329.6412 -240.535968) (xy 329.541124 -240.636044) (xy 329.541124 -240.680494)
			(xy 329.741276 -240.680494)
		)
		(stroke
			(width 0)
			(type solid)
		)
		(fill yes)
		(layer "In6.Cu")
		(net "M_E_CPU0_SA_DQ<25>")
	)
	(gr_poly
		(pts
			(xy 329.741276 -239.016032) (xy 329.6412 -238.915956) (xy 329.541124 -239.016032) (xy 329.541124 -239.060482)
			(xy 329.741276 -239.060482)
		)
		(stroke
			(width 0)
			(type solid)
		)
		(fill yes)
		(layer "In6.Cu")
		(net "M_E_CPU0_SA_DQ<21>")
	)
	(gr_poly
		(pts
			(xy 329.741276 -237.395766) (xy 329.6412 -237.295944) (xy 329.541124 -237.395766) (xy 329.541124 -237.443518)
			(xy 329.741276 -237.443518)
		)
		(stroke
			(width 0)
			(type solid)
		)
		(fill yes)
		(layer "In6.Cu")
		(net "M_E_CPU0_SA_DQS_DN<7>")
	)
	(gr_poly
		(pts
			(xy 329.741276 -235.776008) (xy 329.6412 -235.675932) (xy 329.541124 -235.776008) (xy 329.541124 -235.820458)
			(xy 329.741276 -235.820458)
		)
		(stroke
			(width 0)
			(type solid)
		)
		(fill yes)
		(layer "In6.Cu")
		(net "M_E_CPU0_SA_DQ<17>")
	)
	(gr_poly
		(pts
			(xy 329.741276 -234.155996) (xy 329.6412 -234.05592) (xy 329.541124 -234.155996) (xy 329.541124 -234.200446)
			(xy 329.741276 -234.200446)
		)
		(stroke
			(width 0)
			(type solid)
		)
		(fill yes)
		(layer "In6.Cu")
		(net "M_E_CPU0_SA_DQ<13>")
	)
	(gr_poly
		(pts
			(xy 329.741276 -232.53573) (xy 329.6412 -232.435908) (xy 329.541124 -232.53573) (xy 329.541124 -232.583482)
			(xy 329.741276 -232.583482)
		)
		(stroke
			(width 0)
			(type solid)
		)
		(fill yes)
		(layer "In6.Cu")
		(net "M_E_CPU0_SA_DQS_DN<6>")
	)
	(gr_poly
		(pts
			(xy 329.741276 -229.29596) (xy 329.6412 -229.195884) (xy 329.541124 -229.29596) (xy 329.541124 -229.34041)
			(xy 329.741276 -229.34041)
		)
		(stroke
			(width 0)
			(type solid)
		)
		(fill yes)
		(layer "In6.Cu")
		(net "M_E_CPU0_SA_DQ<5>")
	)
	(gr_poly
		(pts
			(xy 329.741276 -227.675948) (xy 329.6412 -227.576126) (xy 329.541124 -227.675948) (xy 329.541124 -227.7237)
			(xy 329.741276 -227.7237)
		)
		(stroke
			(width 0)
			(type solid)
		)
		(fill yes)
		(layer "In6.Cu")
		(net "M_E_CPU0_SA_DQS_DN<5>")
	)
	(gr_poly
		(pts
			(xy 329.741276 -226.05619) (xy 329.6412 -225.956114) (xy 329.541124 -226.05619) (xy 329.541124 -226.10064)
			(xy 329.741276 -226.10064)
		)
		(stroke
			(width 0)
			(type solid)
		)
		(fill yes)
		(layer "In6.Cu")
		(net "M_E_CPU0_SA_DQ<1>")
	)
	(gr_poly
		(pts
			(xy 330.04125 -291.704268) (xy 330.04125 -291.656516) (xy 329.841098 -291.656516) (xy 329.841098 -291.704268)
			(xy 329.941174 -291.80409)
		)
		(stroke
			(width 0)
			(type solid)
		)
		(fill yes)
		(layer "In6.Cu")
		(net "M_E_CPU0_SB_DQS_DP<8>")
	)
	(gr_poly
		(pts
			(xy 330.04125 -290.084002) (xy 330.04125 -290.039552) (xy 329.841098 -290.039552) (xy 329.841098 -290.084002)
			(xy 329.941174 -290.184078)
		)
		(stroke
			(width 0)
			(type solid)
		)
		(fill yes)
		(layer "In6.Cu")
		(net "M_E_CPU0_SB_DQ<27>")
	)
	(gr_poly
		(pts
			(xy 330.04125 -288.464244) (xy 330.04125 -288.419794) (xy 329.841098 -288.419794) (xy 329.841098 -288.464244)
			(xy 329.941174 -288.56432)
		)
		(stroke
			(width 0)
			(type solid)
		)
		(fill yes)
		(layer "In6.Cu")
		(net "M_E_CPU0_SB_DQ<23>")
	)
	(gr_poly
		(pts
			(xy 330.04125 -286.844232) (xy 330.04125 -286.79648) (xy 329.841098 -286.79648) (xy 329.841098 -286.844232)
			(xy 329.941174 -286.944308)
		)
		(stroke
			(width 0)
			(type solid)
		)
		(fill yes)
		(layer "In6.Cu")
		(net "M_E_CPU0_SB_DQS_DP<7>")
	)
	(gr_poly
		(pts
			(xy 330.04125 -285.22422) (xy 330.04125 -285.17977) (xy 329.841098 -285.17977) (xy 329.841098 -285.22422)
			(xy 329.941174 -285.324296)
		)
		(stroke
			(width 0)
			(type solid)
		)
		(fill yes)
		(layer "In6.Cu")
		(net "M_E_CPU0_SB_DQ<19>")
	)
	(gr_poly
		(pts
			(xy 330.04125 -283.604208) (xy 330.04125 -283.559758) (xy 329.841098 -283.559758) (xy 329.841098 -283.604208)
			(xy 329.941174 -283.704284)
		)
		(stroke
			(width 0)
			(type solid)
		)
		(fill yes)
		(layer "In6.Cu")
		(net "M_E_CPU0_SB_DQ<15>")
	)
	(gr_poly
		(pts
			(xy 330.04125 -281.98445) (xy 330.04125 -281.936698) (xy 329.841098 -281.936698) (xy 329.841098 -281.98445)
			(xy 329.941174 -282.084272)
		)
		(stroke
			(width 0)
			(type solid)
		)
		(fill yes)
		(layer "In6.Cu")
		(net "M_E_CPU0_SB_DQS_DP<6>")
	)
	(gr_poly
		(pts
			(xy 330.04125 -280.364184) (xy 330.04125 -280.319734) (xy 329.841098 -280.319734) (xy 329.841098 -280.364184)
			(xy 329.941174 -280.46426)
		)
		(stroke
			(width 0)
			(type solid)
		)
		(fill yes)
		(layer "In6.Cu")
		(net "M_E_CPU0_SB_DQ<11>")
	)
	(gr_poly
		(pts
			(xy 330.04125 -278.744172) (xy 330.04125 -278.699722) (xy 329.841098 -278.699722) (xy 329.841098 -278.744172)
			(xy 329.941174 -278.844248)
		)
		(stroke
			(width 0)
			(type solid)
		)
		(fill yes)
		(layer "In6.Cu")
		(net "M_E_CPU0_SB_DQ<7>")
	)
	(gr_poly
		(pts
			(xy 330.04125 -277.124414) (xy 330.04125 -277.076662) (xy 329.841098 -277.076662) (xy 329.841098 -277.124414)
			(xy 329.941174 -277.224236)
		)
		(stroke
			(width 0)
			(type solid)
		)
		(fill yes)
		(layer "In6.Cu")
		(net "M_E_CPU0_SB_DQS_DP<5>")
	)
	(gr_poly
		(pts
			(xy 330.04125 -275.504148) (xy 330.04125 -275.459698) (xy 329.841098 -275.459698) (xy 329.841098 -275.504148)
			(xy 329.941174 -275.604224)
		)
		(stroke
			(width 0)
			(type solid)
		)
		(fill yes)
		(layer "In6.Cu")
		(net "M_E_CPU0_SB_DQ<3>")
	)
	(gr_poly
		(pts
			(xy 330.04125 -273.884136) (xy 330.04125 -273.839686) (xy 329.841098 -273.839686) (xy 329.841098 -273.884136)
			(xy 329.941174 -273.984212)
		)
		(stroke
			(width 0)
			(type solid)
		)
		(fill yes)
		(layer "In6.Cu")
		(net "M_E_CPU0_SB_CB<3>")
	)
	(gr_poly
		(pts
			(xy 330.04125 -272.264378) (xy 330.04125 -272.216626) (xy 329.841098 -272.216626) (xy 329.841098 -272.264378)
			(xy 329.941174 -272.3642)
		)
		(stroke
			(width 0)
			(type solid)
		)
		(fill yes)
		(layer "In6.Cu")
		(net "M_E_CPU0_SB_DQS_DP<4>")
	)
	(gr_poly
		(pts
			(xy 330.04125 -270.644112) (xy 330.04125 -270.599662) (xy 329.841098 -270.599662) (xy 329.841098 -270.644112)
			(xy 329.941174 -270.744188)
		)
		(stroke
			(width 0)
			(type solid)
		)
		(fill yes)
		(layer "In6.Cu")
		(net "M_E_CPU0_SB_CB<7>")
	)
	(gr_poly
		(pts
			(xy 330.04125 -265.784076) (xy 330.04125 -265.739626) (xy 329.841098 -265.739626) (xy 329.841098 -265.784076)
			(xy 329.941174 -265.884152)
		)
		(stroke
			(width 0)
			(type solid)
		)
		(fill yes)
		(layer "In6.Cu")
		(net "M_E_CPU0_SB_CS_N<0>")
	)
	(gr_poly
		(pts
			(xy 330.04125 -264.164064) (xy 330.04125 -264.119614) (xy 329.841098 -264.119614) (xy 329.841098 -264.164064)
			(xy 329.941174 -264.26414)
		)
		(stroke
			(width 0)
			(type solid)
		)
		(fill yes)
		(layer "In6.Cu")
		(net "M_E_CPU0_SB_CA<5>")
	)
	(gr_poly
		(pts
			(xy 330.04125 -262.544052) (xy 330.04125 -262.499602) (xy 329.841098 -262.499602) (xy 329.841098 -262.544052)
			(xy 329.941174 -262.644128)
		)
		(stroke
			(width 0)
			(type solid)
		)
		(fill yes)
		(layer "In6.Cu")
		(net "M_E_CPU0_SB_CA<1>")
	)
	(gr_poly
		(pts
			(xy 330.09713 -293.860474) (xy 330.0603 -293.723822) (xy 330.021946 -293.70147) (xy 329.92187 -293.874698)
			(xy 329.960478 -293.89705)
		)
		(stroke
			(width 0)
			(type solid)
		)
		(fill yes)
		(layer "In6.Cu")
		(net "M_E_CPU0_SB_DQ<31>")
	)
	(gr_poly
		(pts
			(xy 330.158852 -247.529096) (xy 330.16317 -247.481598) (xy 329.96378 -247.464072) (xy 329.959716 -247.51157)
			(xy 330.050648 -247.620028)
		)
		(stroke
			(width 0)
			(type solid)
		)
		(fill yes)
		(layer "In6.Cu")
		(net "M_E_CPU0_SA_DQS_DP<9>")
	)
	(gr_poly
		(pts
			(xy 330.158852 -242.66906) (xy 330.16317 -242.621562) (xy 329.96378 -242.604036) (xy 329.959716 -242.651534)
			(xy 330.050648 -242.759992)
		)
		(stroke
			(width 0)
			(type solid)
		)
		(fill yes)
		(layer "In6.Cu")
		(net "M_E_CPU0_SA_DQS_DP<8>")
	)
	(gr_poly
		(pts
			(xy 330.158852 -237.809024) (xy 330.16317 -237.761526) (xy 329.96378 -237.744) (xy 329.959716 -237.791498)
			(xy 330.050648 -237.899956)
		)
		(stroke
			(width 0)
			(type solid)
		)
		(fill yes)
		(layer "In6.Cu")
		(net "M_E_CPU0_SA_DQS_DP<7>")
	)
	(gr_poly
		(pts
			(xy 330.158852 -232.948988) (xy 330.16317 -232.90149) (xy 329.96378 -232.883964) (xy 329.959716 -232.931462)
			(xy 330.050648 -233.03992)
		)
		(stroke
			(width 0)
			(type solid)
		)
		(fill yes)
		(layer "In6.Cu")
		(net "M_E_CPU0_SA_DQS_DP<6>")
	)
	(gr_poly
		(pts
			(xy 330.158852 -228.089206) (xy 330.16317 -228.041708) (xy 329.96378 -228.024436) (xy 329.959716 -228.07168)
			(xy 330.050648 -228.180138)
		)
		(stroke
			(width 0)
			(type solid)
		)
		(fill yes)
		(layer "In6.Cu")
		(net "M_E_CPU0_SA_DQS_DP<5>")
	)
	(gr_poly
		(pts
			(xy 330.170536 -231.329738) (xy 330.1746 -231.285542) (xy 329.977496 -231.26827) (xy 329.973686 -231.312466)
			(xy 330.063348 -231.42067)
		)
		(stroke
			(width 0)
			(type solid)
		)
		(fill yes)
		(layer "In6.Cu")
		(net "M_E_CPU0_SA_DQ<11>")
	)
	(gr_poly
		(pts
			(xy 330.171552 -255.629918) (xy 330.175362 -255.585468) (xy 329.976226 -255.568196) (xy 329.972416 -255.612392)
			(xy 330.063348 -255.72085)
		)
		(stroke
			(width 0)
			(type solid)
		)
		(fill yes)
		(layer "In6.Cu")
		(net "M_E_CPU0_SA_PAR")
	)
	(gr_poly
		(pts
			(xy 330.171552 -254.009906) (xy 330.175362 -253.965456) (xy 329.976226 -253.948184) (xy 329.972416 -253.99238)
			(xy 330.063348 -254.100838)
		)
		(stroke
			(width 0)
			(type solid)
		)
		(fill yes)
		(layer "In6.Cu")
		(net "M_E_CPU0_SA_CA<3>")
	)
	(gr_poly
		(pts
			(xy 330.171552 -252.389894) (xy 330.175362 -252.345444) (xy 329.976226 -252.328172) (xy 329.972416 -252.372368)
			(xy 330.063348 -252.480826)
		)
		(stroke
			(width 0)
			(type solid)
		)
		(fill yes)
		(layer "In6.Cu")
		(net "M_E_CPU0_SA_CS_N<1>")
	)
	(gr_poly
		(pts
			(xy 330.171552 -250.769882) (xy 330.175362 -250.725432) (xy 329.976226 -250.70816) (xy 329.972416 -250.752356)
			(xy 330.063348 -250.860814)
		)
		(stroke
			(width 0)
			(type solid)
		)
		(fill yes)
		(layer "In6.Cu")
		(net "M_E_CPU0_RESET_N")
	)
	(gr_poly
		(pts
			(xy 330.171552 -249.14987) (xy 330.175362 -249.10542) (xy 329.976226 -249.088148) (xy 329.972416 -249.132344)
			(xy 330.063348 -249.240802)
		)
		(stroke
			(width 0)
			(type solid)
		)
		(fill yes)
		(layer "In6.Cu")
		(net "M_E_CPU0_SA_CB<7>")
	)
	(gr_poly
		(pts
			(xy 330.171552 -245.909846) (xy 330.175362 -245.865396) (xy 329.976226 -245.848124) (xy 329.972416 -245.89232)
			(xy 330.063348 -246.000778)
		)
		(stroke
			(width 0)
			(type solid)
		)
		(fill yes)
		(layer "In6.Cu")
		(net "M_E_CPU0_SA_CB<3>")
	)
	(gr_poly
		(pts
			(xy 330.171552 -244.289834) (xy 330.175362 -244.245384) (xy 329.976226 -244.228112) (xy 329.972416 -244.272308)
			(xy 330.063348 -244.380766)
		)
		(stroke
			(width 0)
			(type solid)
		)
		(fill yes)
		(layer "In6.Cu")
		(net "M_E_CPU0_SA_DQ<31>")
	)
	(gr_poly
		(pts
			(xy 330.171552 -241.04981) (xy 330.175362 -241.00536) (xy 329.976226 -240.988088) (xy 329.972416 -241.032284)
			(xy 330.063348 -241.140742)
		)
		(stroke
			(width 0)
			(type solid)
		)
		(fill yes)
		(layer "In6.Cu")
		(net "M_E_CPU0_SA_DQ<27>")
	)
	(gr_poly
		(pts
			(xy 330.171552 -239.429798) (xy 330.175362 -239.385348) (xy 329.976226 -239.368076) (xy 329.972416 -239.412272)
			(xy 330.063348 -239.52073)
		)
		(stroke
			(width 0)
			(type solid)
		)
		(fill yes)
		(layer "In6.Cu")
		(net "M_E_CPU0_SA_DQ<23>")
	)
	(gr_poly
		(pts
			(xy 330.171552 -236.189774) (xy 330.175362 -236.145324) (xy 329.976226 -236.128052) (xy 329.972416 -236.172248)
			(xy 330.063348 -236.280706)
		)
		(stroke
			(width 0)
			(type solid)
		)
		(fill yes)
		(layer "In6.Cu")
		(net "M_E_CPU0_SA_DQ<19>")
	)
	(gr_poly
		(pts
			(xy 330.171552 -234.569762) (xy 330.175362 -234.525312) (xy 329.976226 -234.50804) (xy 329.972416 -234.552236)
			(xy 330.063348 -234.660694)
		)
		(stroke
			(width 0)
			(type solid)
		)
		(fill yes)
		(layer "In6.Cu")
		(net "M_E_CPU0_SA_DQ<15>")
	)
	(gr_poly
		(pts
			(xy 330.171552 -226.469956) (xy 330.175362 -226.425506) (xy 329.976226 -226.408234) (xy 329.972416 -226.45243)
			(xy 330.063348 -226.560888)
		)
		(stroke
			(width 0)
			(type solid)
		)
		(fill yes)
		(layer "In6.Cu")
		(net "M_E_CPU0_SA_DQ<3>")
	)
	(gr_poly
		(pts
			(xy 330.171806 -229.70998) (xy 330.175616 -229.66553) (xy 329.97648 -229.648258) (xy 329.972416 -229.692454)
			(xy 330.063348 -229.800658)
		)
		(stroke
			(width 0)
			(type solid)
		)
		(fill yes)
		(layer "In6.Cu")
		(net "M_E_CPU0_SA_DQ<7>")
	)
	(gr_poly
		(pts
			(xy 330.463144 -281.61869) (xy 330.458826 -281.571192) (xy 330.350622 -281.48026) (xy 330.25969 -281.588718)
			(xy 330.263754 -281.636216)
		)
		(stroke
			(width 0)
			(type solid)
		)
		(fill yes)
		(layer "In6.Cu")
		(net "M_E_CPU0_SB_DQS_DN<6>")
	)
	(gr_poly
		(pts
			(xy 330.473558 -291.337746) (xy 330.469494 -291.290248) (xy 330.36129 -291.199316) (xy 330.270358 -291.307774)
			(xy 330.274422 -291.355272)
		)
		(stroke
			(width 0)
			(type solid)
		)
		(fill yes)
		(layer "In6.Cu")
		(net "M_E_CPU0_SB_DQS_DN<8>")
	)
	(gr_poly
		(pts
			(xy 330.473558 -286.477964) (xy 330.469494 -286.430466) (xy 330.36129 -286.339534) (xy 330.270358 -286.447992)
			(xy 330.274422 -286.495236)
		)
		(stroke
			(width 0)
			(type solid)
		)
		(fill yes)
		(layer "In6.Cu")
		(net "M_E_CPU0_SB_DQS_DN<7>")
	)
	(gr_poly
		(pts
			(xy 330.473558 -276.757892) (xy 330.469494 -276.710394) (xy 330.36129 -276.619462) (xy 330.270358 -276.72792)
			(xy 330.274422 -276.775164)
		)
		(stroke
			(width 0)
			(type solid)
		)
		(fill yes)
		(layer "In6.Cu")
		(net "M_E_CPU0_SB_DQS_DN<5>")
	)
	(gr_poly
		(pts
			(xy 330.473558 -271.897856) (xy 330.469494 -271.850358) (xy 330.36129 -271.759426) (xy 330.270358 -271.867884)
			(xy 330.274422 -271.915128)
		)
		(stroke
			(width 0)
			(type solid)
		)
		(fill yes)
		(layer "In6.Cu")
		(net "M_E_CPU0_SB_DQS_DN<4>")
	)
	(gr_poly
		(pts
			(xy 330.47559 -292.95471) (xy 330.471526 -292.91026) (xy 330.363322 -292.819328) (xy 330.27239 -292.927786)
			(xy 330.2762 -292.971982)
		)
		(stroke
			(width 0)
			(type solid)
		)
		(fill yes)
		(layer "In6.Cu")
		(net "M_E_CPU0_SB_DQ<29>")
	)
	(gr_poly
		(pts
			(xy 330.47559 -289.714686) (xy 330.471526 -289.670236) (xy 330.363322 -289.579304) (xy 330.27239 -289.687762)
			(xy 330.2762 -289.731958)
		)
		(stroke
			(width 0)
			(type solid)
		)
		(fill yes)
		(layer "In6.Cu")
		(net "M_E_CPU0_SB_DQ<25>")
	)
	(gr_poly
		(pts
			(xy 330.47559 -288.094674) (xy 330.47178 -288.050224) (xy 330.363322 -287.959546) (xy 330.27239 -288.06775)
			(xy 330.276454 -288.111946)
		)
		(stroke
			(width 0)
			(type solid)
		)
		(fill yes)
		(layer "In6.Cu")
		(net "M_E_CPU0_SB_DQ<21>")
	)
	(gr_poly
		(pts
			(xy 330.47559 -284.854904) (xy 330.471526 -284.810454) (xy 330.363322 -284.719522) (xy 330.27239 -284.82798)
			(xy 330.2762 -284.872176)
		)
		(stroke
			(width 0)
			(type solid)
		)
		(fill yes)
		(layer "In6.Cu")
		(net "M_E_CPU0_SB_DQ<17>")
	)
	(gr_poly
		(pts
			(xy 330.47559 -283.234892) (xy 330.471526 -283.190442) (xy 330.363322 -283.09951) (xy 330.27239 -283.207968)
			(xy 330.2762 -283.252164)
		)
		(stroke
			(width 0)
			(type solid)
		)
		(fill yes)
		(layer "In6.Cu")
		(net "M_E_CPU0_SB_DQ<13>")
	)
	(gr_poly
		(pts
			(xy 330.47559 -279.994868) (xy 330.471526 -279.950418) (xy 330.363322 -279.859486) (xy 330.27239 -279.967944)
			(xy 330.2762 -280.01214)
		)
		(stroke
			(width 0)
			(type solid)
		)
		(fill yes)
		(layer "In6.Cu")
		(net "M_E_CPU0_SB_DQ<9>")
	)
	(gr_poly
		(pts
			(xy 330.47559 -278.374856) (xy 330.471526 -278.330406) (xy 330.363322 -278.239474) (xy 330.27239 -278.347932)
			(xy 330.2762 -278.392128)
		)
		(stroke
			(width 0)
			(type solid)
		)
		(fill yes)
		(layer "In6.Cu")
		(net "M_E_CPU0_SB_DQ<5>")
	)
	(gr_poly
		(pts
			(xy 330.47559 -275.134832) (xy 330.471526 -275.090382) (xy 330.363322 -274.99945) (xy 330.27239 -275.107908)
			(xy 330.2762 -275.152104)
		)
		(stroke
			(width 0)
			(type solid)
		)
		(fill yes)
		(layer "In6.Cu")
		(net "M_E_CPU0_SB_DQ<1>")
	)
	(gr_poly
		(pts
			(xy 330.47559 -273.51482) (xy 330.471526 -273.47037) (xy 330.363322 -273.379438) (xy 330.27239 -273.487896)
			(xy 330.2762 -273.532092)
		)
		(stroke
			(width 0)
			(type solid)
		)
		(fill yes)
		(layer "In6.Cu")
		(net "M_E_CPU0_SB_CB<1>")
	)
	(gr_poly
		(pts
			(xy 330.47559 -270.274796) (xy 330.471526 -270.230346) (xy 330.363322 -270.139414) (xy 330.27239 -270.247872)
			(xy 330.2762 -270.292068)
		)
		(stroke
			(width 0)
			(type solid)
		)
		(fill yes)
		(layer "In6.Cu")
		(net "M_E_CPU0_SB_CB<5>")
	)
	(gr_poly
		(pts
			(xy 330.47559 -267.034772) (xy 330.471526 -266.990322) (xy 330.363322 -266.89939) (xy 330.27239 -267.007848)
			(xy 330.2762 -267.052044)
		)
		(stroke
			(width 0)
			(type solid)
		)
		(fill yes)
		(layer "In6.Cu")
		(net "M_E_CPU0_SA_RSP<0>")
	)
	(gr_poly
		(pts
			(xy 330.47559 -263.794748) (xy 330.471526 -263.750298) (xy 330.363322 -263.659366) (xy 330.27239 -263.767824)
			(xy 330.2762 -263.81202)
		)
		(stroke
			(width 0)
			(type solid)
		)
		(fill yes)
		(layer "In6.Cu")
		(net "M_E_CPU0_SB_CA<4>")
	)
	(gr_poly
		(pts
			(xy 330.47559 -262.174736) (xy 330.471526 -262.130286) (xy 330.363322 -262.039354) (xy 330.27239 -262.147812)
			(xy 330.2762 -262.192008)
		)
		(stroke
			(width 0)
			(type solid)
		)
		(fill yes)
		(layer "In6.Cu")
		(net "M_E_CPU0_SB_CA<0>")
	)
	(gr_poly
		(pts
			(xy 389.463534 -255.612392) (xy 389.459724 -255.568196) (xy 389.260334 -255.585468) (xy 389.264398 -255.629918)
			(xy 389.372602 -255.72085)
		)
		(stroke
			(width 0)
			(type solid)
		)
		(fill yes)
		(layer "In6.Cu")
		(net "M_K_CPU0_SA_PAR")
	)
	(gr_poly
		(pts
			(xy 389.463534 -253.99238) (xy 389.459724 -253.948184) (xy 389.260334 -253.965456) (xy 389.264398 -254.009906)
			(xy 389.372602 -254.100838)
		)
		(stroke
			(width 0)
			(type solid)
		)
		(fill yes)
		(layer "In6.Cu")
		(net "M_K_CPU0_SA_CA<3>")
	)
	(gr_poly
		(pts
			(xy 389.463534 -250.752356) (xy 389.459724 -250.70816) (xy 389.260334 -250.725432) (xy 389.264398 -250.769882)
			(xy 389.372602 -250.860814)
		)
		(stroke
			(width 0)
			(type solid)
		)
		(fill yes)
		(layer "In6.Cu")
		(net "M_K_CPU0_RESET_N")
	)
	(gr_poly
		(pts
			(xy 389.463534 -249.132344) (xy 389.459724 -249.088148) (xy 389.260334 -249.10542) (xy 389.264398 -249.14987)
			(xy 389.372602 -249.240802)
		)
		(stroke
			(width 0)
			(type solid)
		)
		(fill yes)
		(layer "In6.Cu")
		(net "M_K_CPU0_SA_CB<7>")
	)
	(gr_poly
		(pts
			(xy 389.463534 -245.89232) (xy 389.459724 -245.848124) (xy 389.260334 -245.865396) (xy 389.264398 -245.909846)
			(xy 389.372602 -246.000778)
		)
		(stroke
			(width 0)
			(type solid)
		)
		(fill yes)
		(layer "In6.Cu")
		(net "M_K_CPU0_SA_CB<3>")
	)
	(gr_poly
		(pts
			(xy 389.463534 -244.272308) (xy 389.459724 -244.228112) (xy 389.260334 -244.245384) (xy 389.264398 -244.289834)
			(xy 389.372602 -244.380766)
		)
		(stroke
			(width 0)
			(type solid)
		)
		(fill yes)
		(layer "In6.Cu")
		(net "M_K_CPU0_SA_DQ<31>")
	)
	(gr_poly
		(pts
			(xy 389.463534 -241.032284) (xy 389.459724 -240.988088) (xy 389.260334 -241.00536) (xy 389.264398 -241.04981)
			(xy 389.372602 -241.140742)
		)
		(stroke
			(width 0)
			(type solid)
		)
		(fill yes)
		(layer "In6.Cu")
		(net "M_K_CPU0_SA_DQ<27>")
	)
	(gr_poly
		(pts
			(xy 389.463534 -239.412272) (xy 389.459724 -239.368076) (xy 389.260334 -239.385348) (xy 389.264398 -239.429798)
			(xy 389.372602 -239.52073)
		)
		(stroke
			(width 0)
			(type solid)
		)
		(fill yes)
		(layer "In6.Cu")
		(net "M_K_CPU0_SA_DQ<23>")
	)
	(gr_poly
		(pts
			(xy 389.463534 -236.172248) (xy 389.459724 -236.128052) (xy 389.260334 -236.145324) (xy 389.264398 -236.189774)
			(xy 389.372602 -236.280706)
		)
		(stroke
			(width 0)
			(type solid)
		)
		(fill yes)
		(layer "In6.Cu")
		(net "M_K_CPU0_SA_DQ<19>")
	)
	(gr_poly
		(pts
			(xy 389.463534 -234.552236) (xy 389.459724 -234.50804) (xy 389.260334 -234.525312) (xy 389.264398 -234.569762)
			(xy 389.372602 -234.660694)
		)
		(stroke
			(width 0)
			(type solid)
		)
		(fill yes)
		(layer "In6.Cu")
		(net "M_K_CPU0_SA_DQ<15>")
	)
	(gr_poly
		(pts
			(xy 389.463534 -231.312466) (xy 389.45947 -231.26827) (xy 389.260334 -231.285542) (xy 389.264144 -231.329738)
			(xy 389.372602 -231.42067)
		)
		(stroke
			(width 0)
			(type solid)
		)
		(fill yes)
		(layer "In6.Cu")
		(net "M_K_CPU0_SA_DQ<11>")
	)
	(gr_poly
		(pts
			(xy 389.463534 -229.692454) (xy 389.45947 -229.648258) (xy 389.260334 -229.66553) (xy 389.264144 -229.70998)
			(xy 389.372602 -229.800658)
		)
		(stroke
			(width 0)
			(type solid)
		)
		(fill yes)
		(layer "In6.Cu")
		(net "M_K_CPU0_SA_DQ<7>")
	)
	(gr_poly
		(pts
			(xy 389.463534 -226.45243) (xy 389.459724 -226.408234) (xy 389.260334 -226.425506) (xy 389.264398 -226.469956)
			(xy 389.372602 -226.560888)
		)
		(stroke
			(width 0)
			(type solid)
		)
		(fill yes)
		(layer "In6.Cu")
		(net "M_K_CPU0_SA_DQ<3>")
	)
	(gr_poly
		(pts
			(xy 389.465566 -237.79226) (xy 389.461502 -237.745016) (xy 389.262366 -237.762288) (xy 389.26643 -237.809786)
			(xy 389.374634 -237.900718)
		)
		(stroke
			(width 0)
			(type solid)
		)
		(fill yes)
		(layer "In6.Cu")
		(net "M_K_CPU0_SA_DQS_DP<7>")
	)
	(gr_poly
		(pts
			(xy 389.465566 -232.932224) (xy 389.461502 -232.88498) (xy 389.262366 -232.902252) (xy 389.26643 -232.94975)
			(xy 389.374634 -233.040682)
		)
		(stroke
			(width 0)
			(type solid)
		)
		(fill yes)
		(layer "In6.Cu")
		(net "M_K_CPU0_SA_DQS_DP<6>")
	)
	(gr_poly
		(pts
			(xy 389.476234 -247.51157) (xy 389.47217 -247.464072) (xy 389.27278 -247.481598) (xy 389.277098 -247.529096)
			(xy 389.385302 -247.620028)
		)
		(stroke
			(width 0)
			(type solid)
		)
		(fill yes)
		(layer "In6.Cu")
		(net "M_K_CPU0_SA_DQS_DP<9>")
	)
	(gr_poly
		(pts
			(xy 389.476234 -242.651534) (xy 389.47217 -242.604036) (xy 389.27278 -242.621562) (xy 389.277098 -242.66906)
			(xy 389.385302 -242.759992)
		)
		(stroke
			(width 0)
			(type solid)
		)
		(fill yes)
		(layer "In6.Cu")
		(net "M_K_CPU0_SA_DQS_DP<8>")
	)
	(gr_poly
		(pts
			(xy 389.476234 -228.07168) (xy 389.47217 -228.024436) (xy 389.27278 -228.041708) (xy 389.277098 -228.089206)
			(xy 389.385302 -228.180138)
		)
		(stroke
			(width 0)
			(type solid)
		)
		(fill yes)
		(layer "In6.Cu")
		(net "M_K_CPU0_SA_DQS_DP<5>")
	)
	(gr_poly
		(pts
			(xy 389.763508 -292.927786) (xy 389.672576 -292.819328) (xy 389.564372 -292.91026) (xy 389.560562 -292.95471)
			(xy 389.759698 -292.971982)
		)
		(stroke
			(width 0)
			(type solid)
		)
		(fill yes)
		(layer "In6.Cu")
		(net "M_K_CPU0_SB_DQ<29>")
	)
	(gr_poly
		(pts
			(xy 389.763508 -289.687762) (xy 389.672576 -289.579304) (xy 389.564372 -289.670236) (xy 389.560562 -289.714686)
			(xy 389.759698 -289.731958)
		)
		(stroke
			(width 0)
			(type solid)
		)
		(fill yes)
		(layer "In6.Cu")
		(net "M_K_CPU0_SB_DQ<25>")
	)
	(gr_poly
		(pts
			(xy 389.763508 -288.06775) (xy 389.672576 -287.959546) (xy 389.564118 -288.050224) (xy 389.560308 -288.094674)
			(xy 389.759444 -288.111946)
		)
		(stroke
			(width 0)
			(type solid)
		)
		(fill yes)
		(layer "In6.Cu")
		(net "M_K_CPU0_SB_DQ<21>")
	)
	(gr_poly
		(pts
			(xy 389.763508 -284.82798) (xy 389.672576 -284.719522) (xy 389.564372 -284.810454) (xy 389.560562 -284.854904)
			(xy 389.759698 -284.872176)
		)
		(stroke
			(width 0)
			(type solid)
		)
		(fill yes)
		(layer "In6.Cu")
		(net "M_K_CPU0_SB_DQ<17>")
	)
	(gr_poly
		(pts
			(xy 389.763508 -283.207968) (xy 389.672576 -283.09951) (xy 389.564372 -283.190442) (xy 389.560562 -283.234892)
			(xy 389.759698 -283.252164)
		)
		(stroke
			(width 0)
			(type solid)
		)
		(fill yes)
		(layer "In6.Cu")
		(net "M_K_CPU0_SB_DQ<13>")
	)
	(gr_poly
		(pts
			(xy 389.763508 -279.967944) (xy 389.672576 -279.859486) (xy 389.564372 -279.950418) (xy 389.560562 -279.994868)
			(xy 389.759698 -280.01214)
		)
		(stroke
			(width 0)
			(type solid)
		)
		(fill yes)
		(layer "In6.Cu")
		(net "M_K_CPU0_SB_DQ<9>")
	)
	(gr_poly
		(pts
			(xy 389.763508 -278.347932) (xy 389.672576 -278.239474) (xy 389.564372 -278.330406) (xy 389.560562 -278.374856)
			(xy 389.759698 -278.392128)
		)
		(stroke
			(width 0)
			(type solid)
		)
		(fill yes)
		(layer "In6.Cu")
		(net "M_K_CPU0_SB_DQ<5>")
	)
	(gr_poly
		(pts
			(xy 389.763508 -275.107908) (xy 389.672576 -274.99945) (xy 389.564372 -275.090382) (xy 389.560562 -275.134832)
			(xy 389.759698 -275.152104)
		)
		(stroke
			(width 0)
			(type solid)
		)
		(fill yes)
		(layer "In6.Cu")
		(net "M_K_CPU0_SB_DQ<1>")
	)
	(gr_poly
		(pts
			(xy 389.763508 -273.487896) (xy 389.672576 -273.379438) (xy 389.564372 -273.47037) (xy 389.560562 -273.51482)
			(xy 389.759698 -273.532092)
		)
		(stroke
			(width 0)
			(type solid)
		)
		(fill yes)
		(layer "In6.Cu")
		(net "M_K_CPU0_SB_CB<1>")
	)
	(gr_poly
		(pts
			(xy 389.763508 -270.247872) (xy 389.672576 -270.139414) (xy 389.564372 -270.230346) (xy 389.560562 -270.274796)
			(xy 389.759698 -270.292068)
		)
		(stroke
			(width 0)
			(type solid)
		)
		(fill yes)
		(layer "In6.Cu")
		(net "M_K_CPU0_SB_CB<5>")
	)
	(gr_poly
		(pts
			(xy 389.763508 -267.007848) (xy 389.672576 -266.89939) (xy 389.564372 -266.990322) (xy 389.560562 -267.034772)
			(xy 389.759698 -267.052044)
		)
		(stroke
			(width 0)
			(type solid)
		)
		(fill yes)
		(layer "In6.Cu")
		(net "M_K_CPU0_SA_RSP<0>")
	)
	(gr_poly
		(pts
			(xy 389.763508 -265.387836) (xy 389.672576 -265.279378) (xy 389.564372 -265.37031) (xy 389.560562 -265.41476)
			(xy 389.759698 -265.432032)
		)
		(stroke
			(width 0)
			(type solid)
		)
		(fill yes)
		(layer "In6.Cu")
		(net "M_K_CPU0_SB_PAR")
	)
	(gr_poly
		(pts
			(xy 389.763508 -263.767824) (xy 389.672576 -263.659366) (xy 389.564372 -263.750298) (xy 389.560562 -263.794748)
			(xy 389.759698 -263.81202)
		)
		(stroke
			(width 0)
			(type solid)
		)
		(fill yes)
		(layer "In6.Cu")
		(net "M_K_CPU0_SB_CA<4>")
	)
	(gr_poly
		(pts
			(xy 389.763508 -262.147812) (xy 389.672576 -262.039354) (xy 389.564372 -262.130286) (xy 389.560562 -262.174736)
			(xy 389.759698 -262.192008)
		)
		(stroke
			(width 0)
			(type solid)
		)
		(fill yes)
		(layer "In6.Cu")
		(net "M_K_CPU0_SB_CA<0>")
	)
	(gr_poly
		(pts
			(xy 389.76554 -286.447992) (xy 389.674608 -286.339534) (xy 389.566404 -286.430466) (xy 389.562086 -286.477964)
			(xy 389.761476 -286.495236)
		)
		(stroke
			(width 0)
			(type solid)
		)
		(fill yes)
		(layer "In6.Cu")
		(net "M_K_CPU0_SB_DQS_DN<7>")
	)
	(gr_poly
		(pts
			(xy 389.76554 -281.587956) (xy 389.674608 -281.479498) (xy 389.566404 -281.57043) (xy 389.562086 -281.617928)
			(xy 389.761476 -281.6352)
		)
		(stroke
			(width 0)
			(type solid)
		)
		(fill yes)
		(layer "In6.Cu")
		(net "M_K_CPU0_SB_DQS_DN<6>")
	)
	(gr_poly
		(pts
			(xy 389.76554 -276.72792) (xy 389.674608 -276.619462) (xy 389.566404 -276.710394) (xy 389.562086 -276.757892)
			(xy 389.761476 -276.775164)
		)
		(stroke
			(width 0)
			(type solid)
		)
		(fill yes)
		(layer "In6.Cu")
		(net "M_K_CPU0_SB_DQS_DN<5>")
	)
	(gr_poly
		(pts
			(xy 389.776208 -291.308536) (xy 389.685276 -291.200078) (xy 389.577072 -291.29101) (xy 389.572754 -291.338508)
			(xy 389.772144 -291.35578)
		)
		(stroke
			(width 0)
			(type solid)
		)
		(fill yes)
		(layer "In6.Cu")
		(net "M_K_CPU0_SB_DQS_DN<8>")
	)
	(gr_poly
		(pts
			(xy 389.776208 -271.868646) (xy 389.685276 -271.760188) (xy 389.577072 -271.85112) (xy 389.572754 -271.898618)
			(xy 389.772144 -271.916144)
		)
		(stroke
			(width 0)
			(type solid)
		)
		(fill yes)
		(layer "In6.Cu")
		(net "M_K_CPU0_SB_DQS_DN<4>")
	)
	(gr_poly
		(pts
			(xy 389.894572 -251.976128) (xy 389.794496 -251.876052) (xy 389.69442 -251.976128) (xy 389.69442 -252.020578)
			(xy 389.894572 -252.020578)
		)
		(stroke
			(width 0)
			(type solid)
		)
		(fill yes)
		(layer "In6.Cu")
		(net "M_K_CPU0_SA_CS_N<1>")
	)
	(gr_poly
		(pts
			(xy 389.894826 -255.216152) (xy 389.79475 -255.116076) (xy 389.694674 -255.216152) (xy 389.694674 -255.260602)
			(xy 389.894826 -255.260602)
		)
		(stroke
			(width 0)
			(type solid)
		)
		(fill yes)
		(layer "In6.Cu")
		(net "M_K_CPU0_SA_CA<6>")
	)
	(gr_poly
		(pts
			(xy 389.894826 -253.59614) (xy 389.79475 -253.496064) (xy 389.694674 -253.59614) (xy 389.694674 -253.64059)
			(xy 389.894826 -253.64059)
		)
		(stroke
			(width 0)
			(type solid)
		)
		(fill yes)
		(layer "In6.Cu")
		(net "M_K_CPU0_SA_CA<2>")
	)
	(gr_poly
		(pts
			(xy 389.894826 -250.356116) (xy 389.79475 -250.25604) (xy 389.694674 -250.356116) (xy 389.694674 -250.400566)
			(xy 389.894826 -250.400566)
		)
		(stroke
			(width 0)
			(type solid)
		)
		(fill yes)
		(layer "In6.Cu")
		(net "M_K_CPU0_ALERT_R_N")
	)
	(gr_poly
		(pts
			(xy 389.894826 -248.736104) (xy 389.79475 -248.636028) (xy 389.694674 -248.736104) (xy 389.694674 -248.780554)
			(xy 389.894826 -248.780554)
		)
		(stroke
			(width 0)
			(type solid)
		)
		(fill yes)
		(layer "In6.Cu")
		(net "M_K_CPU0_SA_CB<5>")
	)
	(gr_poly
		(pts
			(xy 389.894826 -247.115838) (xy 389.79475 -247.016016) (xy 389.694674 -247.115838) (xy 389.694674 -247.16359)
			(xy 389.894826 -247.16359)
		)
		(stroke
			(width 0)
			(type solid)
		)
		(fill yes)
		(layer "In6.Cu")
		(net "M_K_CPU0_SA_DQS_DN<9>")
	)
	(gr_poly
		(pts
			(xy 389.894826 -245.49608) (xy 389.79475 -245.396004) (xy 389.694674 -245.49608) (xy 389.694674 -245.54053)
			(xy 389.894826 -245.54053)
		)
		(stroke
			(width 0)
			(type solid)
		)
		(fill yes)
		(layer "In6.Cu")
		(net "M_K_CPU0_SA_CB<1>")
	)
	(gr_poly
		(pts
			(xy 389.894826 -243.876068) (xy 389.79475 -243.775992) (xy 389.694674 -243.876068) (xy 389.694674 -243.920518)
			(xy 389.894826 -243.920518)
		)
		(stroke
			(width 0)
			(type solid)
		)
		(fill yes)
		(layer "In6.Cu")
		(net "M_K_CPU0_SA_DQ<29>")
	)
	(gr_poly
		(pts
			(xy 389.894826 -242.255802) (xy 389.79475 -242.15598) (xy 389.694674 -242.255802) (xy 389.694674 -242.303554)
			(xy 389.894826 -242.303554)
		)
		(stroke
			(width 0)
			(type solid)
		)
		(fill yes)
		(layer "In6.Cu")
		(net "M_K_CPU0_SA_DQS_DN<8>")
	)
	(gr_poly
		(pts
			(xy 389.894826 -240.636044) (xy 389.79475 -240.535968) (xy 389.694674 -240.636044) (xy 389.694674 -240.680494)
			(xy 389.894826 -240.680494)
		)
		(stroke
			(width 0)
			(type solid)
		)
		(fill yes)
		(layer "In6.Cu")
		(net "M_K_CPU0_SA_DQ<25>")
	)
	(gr_poly
		(pts
			(xy 389.894826 -239.016032) (xy 389.79475 -238.915956) (xy 389.694674 -239.016032) (xy 389.694674 -239.060482)
			(xy 389.894826 -239.060482)
		)
		(stroke
			(width 0)
			(type solid)
		)
		(fill yes)
		(layer "In6.Cu")
		(net "M_K_CPU0_SA_DQ<21>")
	)
	(gr_poly
		(pts
			(xy 389.894826 -237.395766) (xy 389.79475 -237.295944) (xy 389.694674 -237.395766) (xy 389.694674 -237.443518)
			(xy 389.894826 -237.443518)
		)
		(stroke
			(width 0)
			(type solid)
		)
		(fill yes)
		(layer "In6.Cu")
		(net "M_K_CPU0_SA_DQS_DN<7>")
	)
	(gr_poly
		(pts
			(xy 389.894826 -235.776008) (xy 389.79475 -235.675932) (xy 389.694674 -235.776008) (xy 389.694674 -235.820458)
			(xy 389.894826 -235.820458)
		)
		(stroke
			(width 0)
			(type solid)
		)
		(fill yes)
		(layer "In6.Cu")
		(net "M_K_CPU0_SA_DQ<17>")
	)
	(gr_poly
		(pts
			(xy 389.894826 -234.155996) (xy 389.79475 -234.05592) (xy 389.694674 -234.155996) (xy 389.694674 -234.200446)
			(xy 389.894826 -234.200446)
		)
		(stroke
			(width 0)
			(type solid)
		)
		(fill yes)
		(layer "In6.Cu")
		(net "M_K_CPU0_SA_DQ<13>")
	)
	(gr_poly
		(pts
			(xy 389.894826 -232.53573) (xy 389.79475 -232.435908) (xy 389.694674 -232.53573) (xy 389.694674 -232.583482)
			(xy 389.894826 -232.583482)
		)
		(stroke
			(width 0)
			(type solid)
		)
		(fill yes)
		(layer "In6.Cu")
		(net "M_K_CPU0_SA_DQS_DN<6>")
	)
	(gr_poly
		(pts
			(xy 389.894826 -230.915972) (xy 389.79475 -230.815896) (xy 389.694674 -230.915972) (xy 389.694674 -230.960422)
			(xy 389.894826 -230.960422)
		)
		(stroke
			(width 0)
			(type solid)
		)
		(fill yes)
		(layer "In6.Cu")
		(net "M_K_CPU0_SA_DQ<9>")
	)
	(gr_poly
		(pts
			(xy 389.894826 -229.29596) (xy 389.79475 -229.195884) (xy 389.694674 -229.29596) (xy 389.694674 -229.34041)
			(xy 389.894826 -229.34041)
		)
		(stroke
			(width 0)
			(type solid)
		)
		(fill yes)
		(layer "In6.Cu")
		(net "M_K_CPU0_SA_DQ<5>")
	)
	(gr_poly
		(pts
			(xy 389.894826 -227.675948) (xy 389.79475 -227.576126) (xy 389.694674 -227.675948) (xy 389.694674 -227.7237)
			(xy 389.894826 -227.7237)
		)
		(stroke
			(width 0)
			(type solid)
		)
		(fill yes)
		(layer "In6.Cu")
		(net "M_K_CPU0_SA_DQS_DN<5>")
	)
	(gr_poly
		(pts
			(xy 389.894826 -226.05619) (xy 389.79475 -225.956114) (xy 389.694674 -226.05619) (xy 389.694674 -226.10064)
			(xy 389.894826 -226.10064)
		)
		(stroke
			(width 0)
			(type solid)
		)
		(fill yes)
		(layer "In6.Cu")
		(net "M_K_CPU0_SA_DQ<1>")
	)
	(gr_poly
		(pts
			(xy 390.1948 -293.324026) (xy 390.1948 -293.279576) (xy 389.994648 -293.279576) (xy 389.994648 -293.324026)
			(xy 390.094724 -293.424102)
		)
		(stroke
			(width 0)
			(type solid)
		)
		(fill yes)
		(layer "In6.Cu")
		(net "M_K_CPU0_SB_DQ<31>")
	)
	(gr_poly
		(pts
			(xy 390.1948 -291.704268) (xy 390.1948 -291.656516) (xy 389.994648 -291.656516) (xy 389.994648 -291.704268)
			(xy 390.094724 -291.80409)
		)
		(stroke
			(width 0)
			(type solid)
		)
		(fill yes)
		(layer "In6.Cu")
		(net "M_K_CPU0_SB_DQS_DP<8>")
	)
	(gr_poly
		(pts
			(xy 390.1948 -290.084002) (xy 390.1948 -290.039552) (xy 389.994648 -290.039552) (xy 389.994648 -290.084002)
			(xy 390.094724 -290.184078)
		)
		(stroke
			(width 0)
			(type solid)
		)
		(fill yes)
		(layer "In6.Cu")
		(net "M_K_CPU0_SB_DQ<27>")
	)
	(gr_poly
		(pts
			(xy 390.1948 -288.464244) (xy 390.1948 -288.419794) (xy 389.994648 -288.419794) (xy 389.994648 -288.464244)
			(xy 390.094724 -288.56432)
		)
		(stroke
			(width 0)
			(type solid)
		)
		(fill yes)
		(layer "In6.Cu")
		(net "M_K_CPU0_SB_DQ<23>")
	)
	(gr_poly
		(pts
			(xy 390.1948 -286.844232) (xy 390.1948 -286.79648) (xy 389.994648 -286.79648) (xy 389.994648 -286.844232)
			(xy 390.094724 -286.944308)
		)
		(stroke
			(width 0)
			(type solid)
		)
		(fill yes)
		(layer "In6.Cu")
		(net "M_K_CPU0_SB_DQS_DP<7>")
	)
	(gr_poly
		(pts
			(xy 390.1948 -285.22422) (xy 390.1948 -285.17977) (xy 389.994648 -285.17977) (xy 389.994648 -285.22422)
			(xy 390.094724 -285.324296)
		)
		(stroke
			(width 0)
			(type solid)
		)
		(fill yes)
		(layer "In6.Cu")
		(net "M_K_CPU0_SB_DQ<19>")
	)
	(gr_poly
		(pts
			(xy 390.1948 -283.604208) (xy 390.1948 -283.559758) (xy 389.994648 -283.559758) (xy 389.994648 -283.604208)
			(xy 390.094724 -283.704284)
		)
		(stroke
			(width 0)
			(type solid)
		)
		(fill yes)
		(layer "In6.Cu")
		(net "M_K_CPU0_SB_DQ<15>")
	)
	(gr_poly
		(pts
			(xy 390.1948 -281.98445) (xy 390.1948 -281.936698) (xy 389.994648 -281.936698) (xy 389.994648 -281.98445)
			(xy 390.094724 -282.084272)
		)
		(stroke
			(width 0)
			(type solid)
		)
		(fill yes)
		(layer "In6.Cu")
		(net "M_K_CPU0_SB_DQS_DP<6>")
	)
	(gr_poly
		(pts
			(xy 390.1948 -280.364184) (xy 390.1948 -280.319734) (xy 389.994648 -280.319734) (xy 389.994648 -280.364184)
			(xy 390.094724 -280.46426)
		)
		(stroke
			(width 0)
			(type solid)
		)
		(fill yes)
		(layer "In6.Cu")
		(net "M_K_CPU0_SB_DQ<11>")
	)
	(gr_poly
		(pts
			(xy 390.1948 -278.744172) (xy 390.1948 -278.699722) (xy 389.994648 -278.699722) (xy 389.994648 -278.744172)
			(xy 390.094724 -278.844248)
		)
		(stroke
			(width 0)
			(type solid)
		)
		(fill yes)
		(layer "In6.Cu")
		(net "M_K_CPU0_SB_DQ<7>")
	)
	(gr_poly
		(pts
			(xy 390.1948 -277.124414) (xy 390.1948 -277.076662) (xy 389.994648 -277.076662) (xy 389.994648 -277.124414)
			(xy 390.094724 -277.224236)
		)
		(stroke
			(width 0)
			(type solid)
		)
		(fill yes)
		(layer "In6.Cu")
		(net "M_K_CPU0_SB_DQS_DP<5>")
	)
	(gr_poly
		(pts
			(xy 390.1948 -275.504148) (xy 390.1948 -275.459698) (xy 389.994648 -275.459698) (xy 389.994648 -275.504148)
			(xy 390.094724 -275.604224)
		)
		(stroke
			(width 0)
			(type solid)
		)
		(fill yes)
		(layer "In6.Cu")
		(net "M_K_CPU0_SB_DQ<3>")
	)
	(gr_poly
		(pts
			(xy 390.1948 -273.884136) (xy 390.1948 -273.839686) (xy 389.994648 -273.839686) (xy 389.994648 -273.884136)
			(xy 390.094724 -273.984212)
		)
		(stroke
			(width 0)
			(type solid)
		)
		(fill yes)
		(layer "In6.Cu")
		(net "M_K_CPU0_SB_CB<3>")
	)
	(gr_poly
		(pts
			(xy 390.1948 -272.264378) (xy 390.1948 -272.216626) (xy 389.994648 -272.216626) (xy 389.994648 -272.264378)
			(xy 390.094724 -272.3642)
		)
		(stroke
			(width 0)
			(type solid)
		)
		(fill yes)
		(layer "In6.Cu")
		(net "M_K_CPU0_SB_DQS_DP<4>")
	)
	(gr_poly
		(pts
			(xy 390.1948 -270.644112) (xy 390.1948 -270.599662) (xy 389.994648 -270.599662) (xy 389.994648 -270.644112)
			(xy 390.094724 -270.744188)
		)
		(stroke
			(width 0)
			(type solid)
		)
		(fill yes)
		(layer "In6.Cu")
		(net "M_K_CPU0_SB_CB<7>")
	)
	(gr_poly
		(pts
			(xy 390.1948 -265.784076) (xy 390.1948 -265.739626) (xy 389.994648 -265.739626) (xy 389.994648 -265.784076)
			(xy 390.094724 -265.884152)
		)
		(stroke
			(width 0)
			(type solid)
		)
		(fill yes)
		(layer "In6.Cu")
		(net "M_K_CPU0_SB_CS_N<0>")
	)
	(gr_poly
		(pts
			(xy 390.1948 -264.164064) (xy 390.1948 -264.119614) (xy 389.994648 -264.119614) (xy 389.994648 -264.164064)
			(xy 390.094724 -264.26414)
		)
		(stroke
			(width 0)
			(type solid)
		)
		(fill yes)
		(layer "In6.Cu")
		(net "M_K_CPU0_SB_CA<5>")
	)
	(gr_poly
		(pts
			(xy 390.1948 -262.544052) (xy 390.1948 -262.499602) (xy 389.994648 -262.499602) (xy 389.994648 -262.544052)
			(xy 390.094724 -262.644128)
		)
		(stroke
			(width 0)
			(type solid)
		)
		(fill yes)
		(layer "In6.Cu")
		(net "M_K_CPU0_SB_CA<1>")
	)
	(gr_poly
		(pts
			(xy 390.36498 -255.622298) (xy 390.36498 -255.577848) (xy 390.164828 -255.577848) (xy 390.164828 -255.622298)
			(xy 390.264904 -255.722374)
		)
		(stroke
			(width 0)
			(type solid)
		)
		(fill yes)
		(layer "In6.Cu")
		(net "M_K_CPU0_SA_PAR")
	)
	(gr_poly
		(pts
			(xy 390.36498 -254.002286) (xy 390.36498 -253.957836) (xy 390.164828 -253.957836) (xy 390.164828 -254.002286)
			(xy 390.264904 -254.102362)
		)
		(stroke
			(width 0)
			(type solid)
		)
		(fill yes)
		(layer "In6.Cu")
		(net "M_K_CPU0_SA_CA<3>")
	)
	(gr_poly
		(pts
			(xy 390.36498 -250.762262) (xy 390.36498 -250.717812) (xy 390.164828 -250.717812) (xy 390.164828 -250.762262)
			(xy 390.264904 -250.862338)
		)
		(stroke
			(width 0)
			(type solid)
		)
		(fill yes)
		(layer "In6.Cu")
		(net "M_K_CPU0_RESET_N")
	)
	(gr_poly
		(pts
			(xy 390.36498 -249.14225) (xy 390.36498 -249.0978) (xy 390.164828 -249.0978) (xy 390.164828 -249.14225)
			(xy 390.264904 -249.242326)
		)
		(stroke
			(width 0)
			(type solid)
		)
		(fill yes)
		(layer "In6.Cu")
		(net "M_K_CPU0_SA_CB<7>")
	)
	(gr_poly
		(pts
			(xy 390.36498 -247.522492) (xy 390.36498 -247.47474) (xy 390.164828 -247.47474) (xy 390.164828 -247.522492)
			(xy 390.264904 -247.622314)
		)
		(stroke
			(width 0)
			(type solid)
		)
		(fill yes)
		(layer "In6.Cu")
		(net "M_K_CPU0_SA_DQS_DP<9>")
	)
	(gr_poly
		(pts
			(xy 390.36498 -245.902226) (xy 390.36498 -245.857776) (xy 390.164828 -245.857776) (xy 390.164828 -245.902226)
			(xy 390.264904 -246.002302)
		)
		(stroke
			(width 0)
			(type solid)
		)
		(fill yes)
		(layer "In6.Cu")
		(net "M_K_CPU0_SA_CB<3>")
	)
	(gr_poly
		(pts
			(xy 390.36498 -244.282214) (xy 390.36498 -244.237764) (xy 390.164828 -244.237764) (xy 390.164828 -244.282214)
			(xy 390.264904 -244.38229)
		)
		(stroke
			(width 0)
			(type solid)
		)
		(fill yes)
		(layer "In6.Cu")
		(net "M_K_CPU0_SA_DQ<31>")
	)
	(gr_poly
		(pts
			(xy 390.36498 -242.662456) (xy 390.36498 -242.614704) (xy 390.164828 -242.614704) (xy 390.164828 -242.662456)
			(xy 390.264904 -242.762278)
		)
		(stroke
			(width 0)
			(type solid)
		)
		(fill yes)
		(layer "In6.Cu")
		(net "M_K_CPU0_SA_DQS_DP<8>")
	)
	(gr_poly
		(pts
			(xy 390.36498 -241.04219) (xy 390.36498 -240.99774) (xy 390.164828 -240.99774) (xy 390.164828 -241.04219)
			(xy 390.264904 -241.142266)
		)
		(stroke
			(width 0)
			(type solid)
		)
		(fill yes)
		(layer "In6.Cu")
		(net "M_K_CPU0_SA_DQ<27>")
	)
	(gr_poly
		(pts
			(xy 390.36498 -239.422178) (xy 390.36498 -239.377728) (xy 390.164828 -239.377728) (xy 390.164828 -239.422178)
			(xy 390.264904 -239.522254)
		)
		(stroke
			(width 0)
			(type solid)
		)
		(fill yes)
		(layer "In6.Cu")
		(net "M_K_CPU0_SA_DQ<23>")
	)
	(gr_poly
		(pts
			(xy 390.36498 -237.80242) (xy 390.36498 -237.754668) (xy 390.164828 -237.754668) (xy 390.164828 -237.80242)
			(xy 390.264904 -237.902242)
		)
		(stroke
			(width 0)
			(type solid)
		)
		(fill yes)
		(layer "In6.Cu")
		(net "M_K_CPU0_SA_DQS_DP<7>")
	)
	(gr_poly
		(pts
			(xy 390.36498 -236.182154) (xy 390.36498 -236.137704) (xy 390.164828 -236.137704) (xy 390.164828 -236.182154)
			(xy 390.264904 -236.28223)
		)
		(stroke
			(width 0)
			(type solid)
		)
		(fill yes)
		(layer "In6.Cu")
		(net "M_K_CPU0_SA_DQ<19>")
	)
	(gr_poly
		(pts
			(xy 390.36498 -234.562142) (xy 390.36498 -234.517692) (xy 390.164828 -234.517692) (xy 390.164828 -234.562142)
			(xy 390.264904 -234.662218)
		)
		(stroke
			(width 0)
			(type solid)
		)
		(fill yes)
		(layer "In6.Cu")
		(net "M_K_CPU0_SA_DQ<15>")
	)
	(gr_poly
		(pts
			(xy 390.36498 -232.942384) (xy 390.36498 -232.894632) (xy 390.164828 -232.894632) (xy 390.164828 -232.942384)
			(xy 390.264904 -233.042206)
		)
		(stroke
			(width 0)
			(type solid)
		)
		(fill yes)
		(layer "In6.Cu")
		(net "M_K_CPU0_SA_DQS_DP<6>")
	)
	(gr_poly
		(pts
			(xy 390.36498 -231.322372) (xy 390.36498 -231.277922) (xy 390.164828 -231.277922) (xy 390.164828 -231.322372)
			(xy 390.264904 -231.422448)
		)
		(stroke
			(width 0)
			(type solid)
		)
		(fill yes)
		(layer "In6.Cu")
		(net "M_K_CPU0_SA_DQ<11>")
	)
	(gr_poly
		(pts
			(xy 390.36498 -229.70236) (xy 390.36498 -229.65791) (xy 390.164828 -229.65791) (xy 390.164828 -229.70236)
			(xy 390.264904 -229.802436)
		)
		(stroke
			(width 0)
			(type solid)
		)
		(fill yes)
		(layer "In6.Cu")
		(net "M_K_CPU0_SA_DQ<7>")
	)
	(gr_poly
		(pts
			(xy 390.36498 -228.082602) (xy 390.36498 -228.03485) (xy 390.164828 -228.03485) (xy 390.164828 -228.082602)
			(xy 390.264904 -228.182424)
		)
		(stroke
			(width 0)
			(type solid)
		)
		(fill yes)
		(layer "In6.Cu")
		(net "M_K_CPU0_SA_DQS_DP<5>")
	)
	(gr_poly
		(pts
			(xy 390.36498 -226.462336) (xy 390.36498 -226.417886) (xy 390.164828 -226.417886) (xy 390.164828 -226.462336)
			(xy 390.264904 -226.562412)
		)
		(stroke
			(width 0)
			(type solid)
		)
		(fill yes)
		(layer "In6.Cu")
		(net "M_K_CPU0_SA_DQ<3>")
	)
	(gr_poly
		(pts
			(xy 390.664954 -292.91788) (xy 390.564878 -292.817804) (xy 390.464802 -292.91788) (xy 390.464802 -292.96233)
			(xy 390.664954 -292.96233)
		)
		(stroke
			(width 0)
			(type solid)
		)
		(fill yes)
		(layer "In6.Cu")
		(net "M_K_CPU0_SB_DQ<29>")
	)
	(gr_poly
		(pts
			(xy 390.664954 -291.297614) (xy 390.564878 -291.197792) (xy 390.464802 -291.297614) (xy 390.464802 -291.345366)
			(xy 390.664954 -291.345366)
		)
		(stroke
			(width 0)
			(type solid)
		)
		(fill yes)
		(layer "In6.Cu")
		(net "M_K_CPU0_SB_DQS_DN<8>")
	)
	(gr_poly
		(pts
			(xy 390.664954 -289.677856) (xy 390.564878 -289.57778) (xy 390.464802 -289.677856) (xy 390.464802 -289.722306)
			(xy 390.664954 -289.722306)
		)
		(stroke
			(width 0)
			(type solid)
		)
		(fill yes)
		(layer "In6.Cu")
		(net "M_K_CPU0_SB_DQ<25>")
	)
	(gr_poly
		(pts
			(xy 390.664954 -288.057844) (xy 390.564878 -287.957768) (xy 390.464802 -288.057844) (xy 390.464802 -288.102294)
			(xy 390.664954 -288.102294)
		)
		(stroke
			(width 0)
			(type solid)
		)
		(fill yes)
		(layer "In6.Cu")
		(net "M_K_CPU0_SB_DQ<21>")
	)
	(gr_poly
		(pts
			(xy 390.664954 -286.437832) (xy 390.564878 -286.337756) (xy 390.464802 -286.437832) (xy 390.464802 -286.485584)
			(xy 390.664954 -286.485584)
		)
		(stroke
			(width 0)
			(type solid)
		)
		(fill yes)
		(layer "In6.Cu")
		(net "M_K_CPU0_SB_DQS_DN<7>")
	)
	(gr_poly
		(pts
			(xy 390.664954 -284.818074) (xy 390.564878 -284.717998) (xy 390.464802 -284.818074) (xy 390.464802 -284.862524)
			(xy 390.664954 -284.862524)
		)
		(stroke
			(width 0)
			(type solid)
		)
		(fill yes)
		(layer "In6.Cu")
		(net "M_K_CPU0_SB_DQ<17>")
	)
	(gr_poly
		(pts
			(xy 390.664954 -283.198062) (xy 390.564878 -283.097986) (xy 390.464802 -283.198062) (xy 390.464802 -283.242512)
			(xy 390.664954 -283.242512)
		)
		(stroke
			(width 0)
			(type solid)
		)
		(fill yes)
		(layer "In6.Cu")
		(net "M_K_CPU0_SB_DQ<13>")
	)
	(gr_poly
		(pts
			(xy 390.664954 -281.577796) (xy 390.564878 -281.477974) (xy 390.464802 -281.577796) (xy 390.464802 -281.625548)
			(xy 390.664954 -281.625548)
		)
		(stroke
			(width 0)
			(type solid)
		)
		(fill yes)
		(layer "In6.Cu")
		(net "M_K_CPU0_SB_DQS_DN<6>")
	)
	(gr_poly
		(pts
			(xy 390.664954 -279.958038) (xy 390.564878 -279.857962) (xy 390.464802 -279.958038) (xy 390.464802 -280.002488)
			(xy 390.664954 -280.002488)
		)
		(stroke
			(width 0)
			(type solid)
		)
		(fill yes)
		(layer "In6.Cu")
		(net "M_K_CPU0_SB_DQ<9>")
	)
	(gr_poly
		(pts
			(xy 390.664954 -278.338026) (xy 390.564878 -278.23795) (xy 390.464802 -278.338026) (xy 390.464802 -278.382476)
			(xy 390.664954 -278.382476)
		)
		(stroke
			(width 0)
			(type solid)
		)
		(fill yes)
		(layer "In6.Cu")
		(net "M_K_CPU0_SB_DQ<5>")
	)
	(gr_poly
		(pts
			(xy 390.664954 -276.71776) (xy 390.564878 -276.617938) (xy 390.464802 -276.71776) (xy 390.464802 -276.765512)
			(xy 390.664954 -276.765512)
		)
		(stroke
			(width 0)
			(type solid)
		)
		(fill yes)
		(layer "In6.Cu")
		(net "M_K_CPU0_SB_DQS_DN<5>")
	)
	(gr_poly
		(pts
			(xy 390.664954 -275.098002) (xy 390.564878 -274.997926) (xy 390.464802 -275.098002) (xy 390.464802 -275.142452)
			(xy 390.664954 -275.142452)
		)
		(stroke
			(width 0)
			(type solid)
		)
		(fill yes)
		(layer "In6.Cu")
		(net "M_K_CPU0_SB_DQ<1>")
	)
	(gr_poly
		(pts
			(xy 390.664954 -273.47799) (xy 390.564878 -273.377914) (xy 390.464802 -273.47799) (xy 390.464802 -273.52244)
			(xy 390.664954 -273.52244)
		)
		(stroke
			(width 0)
			(type solid)
		)
		(fill yes)
		(layer "In6.Cu")
		(net "M_K_CPU0_SB_CB<1>")
	)
	(gr_poly
		(pts
			(xy 390.664954 -271.857724) (xy 390.564878 -271.757902) (xy 390.464802 -271.857724) (xy 390.464802 -271.905476)
			(xy 390.664954 -271.905476)
		)
		(stroke
			(width 0)
			(type solid)
		)
		(fill yes)
		(layer "In6.Cu")
		(net "M_K_CPU0_SB_DQS_DN<4>")
	)
	(gr_poly
		(pts
			(xy 390.664954 -270.237966) (xy 390.564878 -270.13789) (xy 390.464802 -270.237966) (xy 390.464802 -270.282416)
			(xy 390.664954 -270.282416)
		)
		(stroke
			(width 0)
			(type solid)
		)
		(fill yes)
		(layer "In6.Cu")
		(net "M_K_CPU0_SB_CB<5>")
	)
	(gr_poly
		(pts
			(xy 390.664954 -266.997942) (xy 390.564878 -266.897866) (xy 390.464802 -266.997942) (xy 390.464802 -267.042392)
			(xy 390.664954 -267.042392)
		)
		(stroke
			(width 0)
			(type solid)
		)
		(fill yes)
		(layer "In6.Cu")
		(net "M_K_CPU0_SA_RSP<0>")
	)
	(gr_poly
		(pts
			(xy 390.664954 -265.37793) (xy 390.564878 -265.277854) (xy 390.464802 -265.37793) (xy 390.464802 -265.42238)
			(xy 390.664954 -265.42238)
		)
		(stroke
			(width 0)
			(type solid)
		)
		(fill yes)
		(layer "In6.Cu")
		(net "M_K_CPU0_SB_PAR")
	)
	(gr_poly
		(pts
			(xy 390.664954 -263.757918) (xy 390.564878 -263.657842) (xy 390.464802 -263.757918) (xy 390.464802 -263.802368)
			(xy 390.664954 -263.802368)
		)
		(stroke
			(width 0)
			(type solid)
		)
		(fill yes)
		(layer "In6.Cu")
		(net "M_K_CPU0_SB_CA<4>")
	)
	(gr_poly
		(pts
			(xy 390.664954 -262.137906) (xy 390.564878 -262.03783) (xy 390.464802 -262.137906) (xy 390.464802 -262.182356)
			(xy 390.664954 -262.182356)
		)
		(stroke
			(width 0)
			(type solid)
		)
		(fill yes)
		(layer "In6.Cu")
		(net "M_K_CPU0_SB_CA<0>")
	)
	(gr_poly
		(pts
			(xy 390.834626 -251.976128) (xy 390.73455 -251.876052) (xy 390.634474 -251.976128) (xy 390.634474 -252.020578)
			(xy 390.834626 -252.020578)
		)
		(stroke
			(width 0)
			(type solid)
		)
		(fill yes)
		(layer "In6.Cu")
		(net "M_K_CPU0_SA_CS_N<1>")
	)
	(gr_poly
		(pts
			(xy 390.83488 -255.216152) (xy 390.734804 -255.116076) (xy 390.634728 -255.216152) (xy 390.634728 -255.260602)
			(xy 390.83488 -255.260602)
		)
		(stroke
			(width 0)
			(type solid)
		)
		(fill yes)
		(layer "In6.Cu")
		(net "M_K_CPU0_SA_CA<6>")
	)
	(gr_poly
		(pts
			(xy 390.83488 -253.59614) (xy 390.734804 -253.496064) (xy 390.634728 -253.59614) (xy 390.634728 -253.64059)
			(xy 390.83488 -253.64059)
		)
		(stroke
			(width 0)
			(type solid)
		)
		(fill yes)
		(layer "In6.Cu")
		(net "M_K_CPU0_SA_CA<2>")
	)
	(gr_poly
		(pts
			(xy 390.83488 -250.356116) (xy 390.734804 -250.25604) (xy 390.634728 -250.356116) (xy 390.634728 -250.400566)
			(xy 390.83488 -250.400566)
		)
		(stroke
			(width 0)
			(type solid)
		)
		(fill yes)
		(layer "In6.Cu")
		(net "M_K_CPU0_ALERT_R_N")
	)
	(gr_poly
		(pts
			(xy 390.83488 -248.736104) (xy 390.734804 -248.636028) (xy 390.634728 -248.736104) (xy 390.634728 -248.780554)
			(xy 390.83488 -248.780554)
		)
		(stroke
			(width 0)
			(type solid)
		)
		(fill yes)
		(layer "In6.Cu")
		(net "M_K_CPU0_SA_CB<5>")
	)
	(gr_poly
		(pts
			(xy 390.83488 -247.115838) (xy 390.734804 -247.016016) (xy 390.634728 -247.115838) (xy 390.634728 -247.16359)
			(xy 390.83488 -247.16359)
		)
		(stroke
			(width 0)
			(type solid)
		)
		(fill yes)
		(layer "In6.Cu")
		(net "M_K_CPU0_SA_DQS_DN<9>")
	)
	(gr_poly
		(pts
			(xy 390.83488 -245.49608) (xy 390.734804 -245.396004) (xy 390.634728 -245.49608) (xy 390.634728 -245.54053)
			(xy 390.83488 -245.54053)
		)
		(stroke
			(width 0)
			(type solid)
		)
		(fill yes)
		(layer "In6.Cu")
		(net "M_K_CPU0_SA_CB<1>")
	)
	(gr_poly
		(pts
			(xy 390.83488 -243.876068) (xy 390.734804 -243.775992) (xy 390.634728 -243.876068) (xy 390.634728 -243.920518)
			(xy 390.83488 -243.920518)
		)
		(stroke
			(width 0)
			(type solid)
		)
		(fill yes)
		(layer "In6.Cu")
		(net "M_K_CPU0_SA_DQ<29>")
	)
	(gr_poly
		(pts
			(xy 390.83488 -242.255802) (xy 390.734804 -242.15598) (xy 390.634728 -242.255802) (xy 390.634728 -242.303554)
			(xy 390.83488 -242.303554)
		)
		(stroke
			(width 0)
			(type solid)
		)
		(fill yes)
		(layer "In6.Cu")
		(net "M_K_CPU0_SA_DQS_DN<8>")
	)
	(gr_poly
		(pts
			(xy 390.83488 -240.636044) (xy 390.734804 -240.535968) (xy 390.634728 -240.636044) (xy 390.634728 -240.680494)
			(xy 390.83488 -240.680494)
		)
		(stroke
			(width 0)
			(type solid)
		)
		(fill yes)
		(layer "In6.Cu")
		(net "M_K_CPU0_SA_DQ<25>")
	)
	(gr_poly
		(pts
			(xy 390.83488 -239.016032) (xy 390.734804 -238.915956) (xy 390.634728 -239.016032) (xy 390.634728 -239.060482)
			(xy 390.83488 -239.060482)
		)
		(stroke
			(width 0)
			(type solid)
		)
		(fill yes)
		(layer "In6.Cu")
		(net "M_K_CPU0_SA_DQ<21>")
	)
	(gr_poly
		(pts
			(xy 390.83488 -237.395766) (xy 390.734804 -237.295944) (xy 390.634728 -237.395766) (xy 390.634728 -237.443518)
			(xy 390.83488 -237.443518)
		)
		(stroke
			(width 0)
			(type solid)
		)
		(fill yes)
		(layer "In6.Cu")
		(net "M_K_CPU0_SA_DQS_DN<7>")
	)
	(gr_poly
		(pts
			(xy 390.83488 -235.776008) (xy 390.734804 -235.675932) (xy 390.634728 -235.776008) (xy 390.634728 -235.820458)
			(xy 390.83488 -235.820458)
		)
		(stroke
			(width 0)
			(type solid)
		)
		(fill yes)
		(layer "In6.Cu")
		(net "M_K_CPU0_SA_DQ<17>")
	)
	(gr_poly
		(pts
			(xy 390.83488 -234.155996) (xy 390.734804 -234.05592) (xy 390.634728 -234.155996) (xy 390.634728 -234.200446)
			(xy 390.83488 -234.200446)
		)
		(stroke
			(width 0)
			(type solid)
		)
		(fill yes)
		(layer "In6.Cu")
		(net "M_K_CPU0_SA_DQ<13>")
	)
	(gr_poly
		(pts
			(xy 390.83488 -232.53573) (xy 390.734804 -232.435908) (xy 390.634728 -232.53573) (xy 390.634728 -232.583482)
			(xy 390.83488 -232.583482)
		)
		(stroke
			(width 0)
			(type solid)
		)
		(fill yes)
		(layer "In6.Cu")
		(net "M_K_CPU0_SA_DQS_DN<6>")
	)
	(gr_poly
		(pts
			(xy 390.83488 -230.915972) (xy 390.734804 -230.815896) (xy 390.634728 -230.915972) (xy 390.634728 -230.960422)
			(xy 390.83488 -230.960422)
		)
		(stroke
			(width 0)
			(type solid)
		)
		(fill yes)
		(layer "In6.Cu")
		(net "M_K_CPU0_SA_DQ<9>")
	)
	(gr_poly
		(pts
			(xy 390.83488 -229.29596) (xy 390.734804 -229.195884) (xy 390.634728 -229.29596) (xy 390.634728 -229.34041)
			(xy 390.83488 -229.34041)
		)
		(stroke
			(width 0)
			(type solid)
		)
		(fill yes)
		(layer "In6.Cu")
		(net "M_K_CPU0_SA_DQ<5>")
	)
	(gr_poly
		(pts
			(xy 390.83488 -227.675948) (xy 390.734804 -227.576126) (xy 390.634728 -227.675948) (xy 390.634728 -227.7237)
			(xy 390.83488 -227.7237)
		)
		(stroke
			(width 0)
			(type solid)
		)
		(fill yes)
		(layer "In6.Cu")
		(net "M_K_CPU0_SA_DQS_DN<5>")
	)
	(gr_poly
		(pts
			(xy 390.83488 -226.05619) (xy 390.734804 -225.956114) (xy 390.634728 -226.05619) (xy 390.634728 -226.10064)
			(xy 390.83488 -226.10064)
		)
		(stroke
			(width 0)
			(type solid)
		)
		(fill yes)
		(layer "In6.Cu")
		(net "M_K_CPU0_SA_DQ<1>")
	)
	(gr_poly
		(pts
			(xy 390.873488 -254.802386) (xy 390.869678 -254.75819) (xy 390.670542 -254.775462) (xy 390.674352 -254.819912)
			(xy 390.782556 -254.910844)
		)
		(stroke
			(width 0)
			(type solid)
		)
		(fill yes)
		(layer "In6.Cu")
		(net "M_K_CPU0_SA_CA<5>")
	)
	(gr_poly
		(pts
			(xy 390.873488 -253.182374) (xy 390.869678 -253.138178) (xy 390.670542 -253.15545) (xy 390.674352 -253.1999)
			(xy 390.782556 -253.290832)
		)
		(stroke
			(width 0)
			(type solid)
		)
		(fill yes)
		(layer "In6.Cu")
		(net "M_K_CPU0_SA_CA<1>")
	)
	(gr_poly
		(pts
			(xy 390.873488 -248.322338) (xy 390.869678 -248.278142) (xy 390.670542 -248.295414) (xy 390.674352 -248.339864)
			(xy 390.782556 -248.430796)
		)
		(stroke
			(width 0)
			(type solid)
		)
		(fill yes)
		(layer "In6.Cu")
		(net "M_K_CPU0_SA_CB<6>")
	)
	(gr_poly
		(pts
			(xy 390.873488 -245.082314) (xy 390.869678 -245.038118) (xy 390.670542 -245.05539) (xy 390.674352 -245.09984)
			(xy 390.782556 -245.190772)
		)
		(stroke
			(width 0)
			(type solid)
		)
		(fill yes)
		(layer "In6.Cu")
		(net "M_K_CPU0_SA_CB<2>")
	)
	(gr_poly
		(pts
			(xy 390.873488 -243.462302) (xy 390.869678 -243.418106) (xy 390.670542 -243.435378) (xy 390.674352 -243.479828)
			(xy 390.782556 -243.57076)
		)
		(stroke
			(width 0)
			(type solid)
		)
		(fill yes)
		(layer "In6.Cu")
		(net "M_K_CPU0_SA_DQ<30>")
	)
	(gr_poly
		(pts
			(xy 390.873488 -240.222278) (xy 390.869678 -240.178082) (xy 390.670542 -240.195354) (xy 390.674352 -240.239804)
			(xy 390.782556 -240.330736)
		)
		(stroke
			(width 0)
			(type solid)
		)
		(fill yes)
		(layer "In6.Cu")
		(net "M_K_CPU0_SA_DQ<26>")
	)
	(gr_poly
		(pts
			(xy 390.873488 -238.602266) (xy 390.869678 -238.55807) (xy 390.670542 -238.575342) (xy 390.674352 -238.619792)
			(xy 390.782556 -238.710724)
		)
		(stroke
			(width 0)
			(type solid)
		)
		(fill yes)
		(layer "In6.Cu")
		(net "M_K_CPU0_SA_DQ<22>")
	)
	(gr_poly
		(pts
			(xy 390.873488 -235.362242) (xy 390.869678 -235.318046) (xy 390.670542 -235.335318) (xy 390.674352 -235.379768)
			(xy 390.782556 -235.4707)
		)
		(stroke
			(width 0)
			(type solid)
		)
		(fill yes)
		(layer "In6.Cu")
		(net "M_K_CPU0_SA_DQ<18>")
	)
	(gr_poly
		(pts
			(xy 390.873488 -233.74223) (xy 390.869678 -233.698034) (xy 390.670542 -233.715306) (xy 390.674352 -233.759756)
			(xy 390.782556 -233.850688)
		)
		(stroke
			(width 0)
			(type solid)
		)
		(fill yes)
		(layer "In6.Cu")
		(net "M_K_CPU0_SA_DQ<14>")
	)
	(gr_poly
		(pts
			(xy 390.873488 -230.50246) (xy 390.869678 -230.458264) (xy 390.670542 -230.475536) (xy 390.674352 -230.519986)
			(xy 390.782556 -230.610664)
		)
		(stroke
			(width 0)
			(type solid)
		)
		(fill yes)
		(layer "In6.Cu")
		(net "M_K_CPU0_SA_DQ<10>")
	)
	(gr_poly
		(pts
			(xy 390.873488 -228.882448) (xy 390.869678 -228.838252) (xy 390.670542 -228.855524) (xy 390.674352 -228.899974)
			(xy 390.782556 -228.990906)
		)
		(stroke
			(width 0)
			(type solid)
		)
		(fill yes)
		(layer "In6.Cu")
		(net "M_K_CPU0_SA_DQ<6>")
	)
	(gr_poly
		(pts
			(xy 390.873488 -225.642424) (xy 390.869678 -225.598228) (xy 390.670542 -225.6155) (xy 390.674352 -225.65995)
			(xy 390.782556 -225.750882)
		)
		(stroke
			(width 0)
			(type solid)
		)
		(fill yes)
		(layer "In6.Cu")
		(net "M_K_CPU0_SA_DQ<2>")
	)
	(gr_poly
		(pts
			(xy 390.87552 -256.422398) (xy 390.871456 -256.3749) (xy 390.672066 -256.392426) (xy 390.676384 -256.439924)
			(xy 390.784588 -256.530856)
		)
		(stroke
			(width 0)
			(type solid)
		)
		(fill yes)
		(layer "In6.Cu")
		(net "M_K_CPU0_CLK_DN<0>")
	)
	(gr_poly
		(pts
			(xy 390.87552 -241.84229) (xy 390.871456 -241.794792) (xy 390.672066 -241.812318) (xy 390.676384 -241.859816)
			(xy 390.784588 -241.950748)
		)
		(stroke
			(width 0)
			(type solid)
		)
		(fill yes)
		(layer "In6.Cu")
		(net "M_K_CPU0_SA_DQS_DN<3>")
	)
	(gr_poly
		(pts
			(xy 390.87552 -236.982254) (xy 390.871456 -236.934756) (xy 390.672066 -236.952282) (xy 390.676384 -236.99978)
			(xy 390.784588 -237.090712)
		)
		(stroke
			(width 0)
			(type solid)
		)
		(fill yes)
		(layer "In6.Cu")
		(net "M_K_CPU0_SA_DQS_DN<2>")
	)
	(gr_poly
		(pts
			(xy 390.87552 -232.122218) (xy 390.871456 -232.07472) (xy 390.672066 -232.092246) (xy 390.676384 -232.139744)
			(xy 390.784588 -232.230676)
		)
		(stroke
			(width 0)
			(type solid)
		)
		(fill yes)
		(layer "In6.Cu")
		(net "M_K_CPU0_SA_DQS_DN<1>")
	)
	(gr_poly
		(pts
			(xy 390.886188 -246.701564) (xy 390.882124 -246.65432) (xy 390.682734 -246.671592) (xy 390.687052 -246.71909)
			(xy 390.795256 -246.810022)
		)
		(stroke
			(width 0)
			(type solid)
		)
		(fill yes)
		(layer "In6.Cu")
		(net "M_K_CPU0_SA_DQS_DN<4>")
	)
	(gr_poly
		(pts
			(xy 390.886188 -227.261674) (xy 390.882124 -227.214176) (xy 390.682734 -227.231702) (xy 390.687052 -227.2792)
			(xy 390.795256 -227.370132)
		)
		(stroke
			(width 0)
			(type solid)
		)
		(fill yes)
		(layer "In6.Cu")
		(net "M_K_CPU0_SA_DQS_DN<0>")
	)
	(gr_poly
		(pts
			(xy 391.134854 -293.324026) (xy 391.134854 -293.279576) (xy 390.934702 -293.279576) (xy 390.934702 -293.324026)
			(xy 391.034778 -293.424102)
		)
		(stroke
			(width 0)
			(type solid)
		)
		(fill yes)
		(layer "In6.Cu")
		(net "M_K_CPU0_SB_DQ<31>")
	)
	(gr_poly
		(pts
			(xy 391.134854 -291.704268) (xy 391.134854 -291.656516) (xy 390.934702 -291.656516) (xy 390.934702 -291.704268)
			(xy 391.034778 -291.80409)
		)
		(stroke
			(width 0)
			(type solid)
		)
		(fill yes)
		(layer "In6.Cu")
		(net "M_K_CPU0_SB_DQS_DP<8>")
	)
	(gr_poly
		(pts
			(xy 391.134854 -290.084002) (xy 391.134854 -290.039552) (xy 390.934702 -290.039552) (xy 390.934702 -290.084002)
			(xy 391.034778 -290.184078)
		)
		(stroke
			(width 0)
			(type solid)
		)
		(fill yes)
		(layer "In6.Cu")
		(net "M_K_CPU0_SB_DQ<27>")
	)
	(gr_poly
		(pts
			(xy 391.134854 -288.464244) (xy 391.134854 -288.419794) (xy 390.934702 -288.419794) (xy 390.934702 -288.464244)
			(xy 391.034778 -288.56432)
		)
		(stroke
			(width 0)
			(type solid)
		)
		(fill yes)
		(layer "In6.Cu")
		(net "M_K_CPU0_SB_DQ<23>")
	)
	(gr_poly
		(pts
			(xy 391.134854 -286.844232) (xy 391.134854 -286.79648) (xy 390.934702 -286.79648) (xy 390.934702 -286.844232)
			(xy 391.034778 -286.944308)
		)
		(stroke
			(width 0)
			(type solid)
		)
		(fill yes)
		(layer "In6.Cu")
		(net "M_K_CPU0_SB_DQS_DP<7>")
	)
	(gr_poly
		(pts
			(xy 391.134854 -285.22422) (xy 391.134854 -285.17977) (xy 390.934702 -285.17977) (xy 390.934702 -285.22422)
			(xy 391.034778 -285.324296)
		)
		(stroke
			(width 0)
			(type solid)
		)
		(fill yes)
		(layer "In6.Cu")
		(net "M_K_CPU0_SB_DQ<19>")
	)
	(gr_poly
		(pts
			(xy 391.134854 -283.604208) (xy 391.134854 -283.559758) (xy 390.934702 -283.559758) (xy 390.934702 -283.604208)
			(xy 391.034778 -283.704284)
		)
		(stroke
			(width 0)
			(type solid)
		)
		(fill yes)
		(layer "In6.Cu")
		(net "M_K_CPU0_SB_DQ<15>")
	)
	(gr_poly
		(pts
			(xy 391.134854 -281.98445) (xy 391.134854 -281.936698) (xy 390.934702 -281.936698) (xy 390.934702 -281.98445)
			(xy 391.034778 -282.084272)
		)
		(stroke
			(width 0)
			(type solid)
		)
		(fill yes)
		(layer "In6.Cu")
		(net "M_K_CPU0_SB_DQS_DP<6>")
	)
	(gr_poly
		(pts
			(xy 391.134854 -280.364184) (xy 391.134854 -280.319734) (xy 390.934702 -280.319734) (xy 390.934702 -280.364184)
			(xy 391.034778 -280.46426)
		)
		(stroke
			(width 0)
			(type solid)
		)
		(fill yes)
		(layer "In6.Cu")
		(net "M_K_CPU0_SB_DQ<11>")
	)
	(gr_poly
		(pts
			(xy 391.134854 -278.744172) (xy 391.134854 -278.699722) (xy 390.934702 -278.699722) (xy 390.934702 -278.744172)
			(xy 391.034778 -278.844248)
		)
		(stroke
			(width 0)
			(type solid)
		)
		(fill yes)
		(layer "In6.Cu")
		(net "M_K_CPU0_SB_DQ<7>")
	)
	(gr_poly
		(pts
			(xy 391.134854 -277.124414) (xy 391.134854 -277.076662) (xy 390.934702 -277.076662) (xy 390.934702 -277.124414)
			(xy 391.034778 -277.224236)
		)
		(stroke
			(width 0)
			(type solid)
		)
		(fill yes)
		(layer "In6.Cu")
		(net "M_K_CPU0_SB_DQS_DP<5>")
	)
	(gr_poly
		(pts
			(xy 391.134854 -275.504148) (xy 391.134854 -275.459698) (xy 390.934702 -275.459698) (xy 390.934702 -275.504148)
			(xy 391.034778 -275.604224)
		)
		(stroke
			(width 0)
			(type solid)
		)
		(fill yes)
		(layer "In6.Cu")
		(net "M_K_CPU0_SB_DQ<3>")
	)
	(gr_poly
		(pts
			(xy 391.134854 -273.884136) (xy 391.134854 -273.839686) (xy 390.934702 -273.839686) (xy 390.934702 -273.884136)
			(xy 391.034778 -273.984212)
		)
		(stroke
			(width 0)
			(type solid)
		)
		(fill yes)
		(layer "In6.Cu")
		(net "M_K_CPU0_SB_CB<3>")
	)
	(gr_poly
		(pts
			(xy 391.134854 -272.264378) (xy 391.134854 -272.216626) (xy 390.934702 -272.216626) (xy 390.934702 -272.264378)
			(xy 391.034778 -272.3642)
		)
		(stroke
			(width 0)
			(type solid)
		)
		(fill yes)
		(layer "In6.Cu")
		(net "M_K_CPU0_SB_DQS_DP<4>")
	)
	(gr_poly
		(pts
			(xy 391.134854 -270.644112) (xy 391.134854 -270.599662) (xy 390.934702 -270.599662) (xy 390.934702 -270.644112)
			(xy 391.034778 -270.744188)
		)
		(stroke
			(width 0)
			(type solid)
		)
		(fill yes)
		(layer "In6.Cu")
		(net "M_K_CPU0_SB_CB<7>")
	)
	(gr_poly
		(pts
			(xy 391.134854 -265.784076) (xy 391.134854 -265.739626) (xy 390.934702 -265.739626) (xy 390.934702 -265.784076)
			(xy 391.034778 -265.884152)
		)
		(stroke
			(width 0)
			(type solid)
		)
		(fill yes)
		(layer "In6.Cu")
		(net "M_K_CPU0_SB_CS_N<0>")
	)
	(gr_poly
		(pts
			(xy 391.134854 -264.164064) (xy 391.134854 -264.119614) (xy 390.934702 -264.119614) (xy 390.934702 -264.164064)
			(xy 391.034778 -264.26414)
		)
		(stroke
			(width 0)
			(type solid)
		)
		(fill yes)
		(layer "In6.Cu")
		(net "M_K_CPU0_SB_CA<5>")
	)
	(gr_poly
		(pts
			(xy 391.134854 -262.544052) (xy 391.134854 -262.499602) (xy 390.934702 -262.499602) (xy 390.934702 -262.544052)
			(xy 391.034778 -262.644128)
		)
		(stroke
			(width 0)
			(type solid)
		)
		(fill yes)
		(layer "In6.Cu")
		(net "M_K_CPU0_SB_CA<1>")
	)
	(gr_poly
		(pts
			(xy 391.173462 -292.11778) (xy 391.08253 -292.009322) (xy 390.974326 -292.100254) (xy 390.970262 -292.144704)
			(xy 391.169652 -292.161976)
		)
		(stroke
			(width 0)
			(type solid)
		)
		(fill yes)
		(layer "In6.Cu")
		(net "M_K_CPU0_SB_DQ<28>")
	)
	(gr_poly
		(pts
			(xy 391.173462 -288.877756) (xy 391.08253 -288.769298) (xy 390.974326 -288.86023) (xy 390.970262 -288.90468)
			(xy 391.169652 -288.921952)
		)
		(stroke
			(width 0)
			(type solid)
		)
		(fill yes)
		(layer "In6.Cu")
		(net "M_K_CPU0_SB_DQ<24>")
	)
	(gr_poly
		(pts
			(xy 391.173462 -287.257744) (xy 391.08253 -287.14954) (xy 390.974326 -287.240218) (xy 390.970262 -287.284668)
			(xy 391.169652 -287.30194)
		)
		(stroke
			(width 0)
			(type solid)
		)
		(fill yes)
		(layer "In6.Cu")
		(net "M_K_CPU0_SB_DQ<20>")
	)
	(gr_poly
		(pts
			(xy 391.173462 -284.017974) (xy 391.08253 -283.909516) (xy 390.974326 -284.000448) (xy 390.970262 -284.044898)
			(xy 391.169652 -284.06217)
		)
		(stroke
			(width 0)
			(type solid)
		)
		(fill yes)
		(layer "In6.Cu")
		(net "M_K_CPU0_SB_DQ<16>")
	)
	(gr_poly
		(pts
			(xy 391.173462 -282.397962) (xy 391.08253 -282.289504) (xy 390.974326 -282.380436) (xy 390.970262 -282.424886)
			(xy 391.169652 -282.442158)
		)
		(stroke
			(width 0)
			(type solid)
		)
		(fill yes)
		(layer "In6.Cu")
		(net "M_K_CPU0_SB_DQ<12>")
	)
	(gr_poly
		(pts
			(xy 391.173462 -279.157938) (xy 391.08253 -279.04948) (xy 390.974326 -279.140412) (xy 390.970262 -279.184862)
			(xy 391.169652 -279.202134)
		)
		(stroke
			(width 0)
			(type solid)
		)
		(fill yes)
		(layer "In6.Cu")
		(net "M_K_CPU0_SB_DQ<8>")
	)
	(gr_poly
		(pts
			(xy 391.173462 -277.537926) (xy 391.08253 -277.429468) (xy 390.974326 -277.5204) (xy 390.970262 -277.56485)
			(xy 391.169652 -277.582122)
		)
		(stroke
			(width 0)
			(type solid)
		)
		(fill yes)
		(layer "In6.Cu")
		(net "M_K_CPU0_SB_DQ<4>")
	)
	(gr_poly
		(pts
			(xy 391.173462 -274.297902) (xy 391.08253 -274.189444) (xy 390.974326 -274.280376) (xy 390.970262 -274.324826)
			(xy 391.169652 -274.342098)
		)
		(stroke
			(width 0)
			(type solid)
		)
		(fill yes)
		(layer "In6.Cu")
		(net "M_K_CPU0_SB_DQ<0>")
	)
	(gr_poly
		(pts
			(xy 391.173462 -272.67789) (xy 391.08253 -272.569432) (xy 390.974326 -272.660364) (xy 390.970262 -272.704814)
			(xy 391.169652 -272.722086)
		)
		(stroke
			(width 0)
			(type solid)
		)
		(fill yes)
		(layer "In6.Cu")
		(net "M_K_CPU0_SB_CB<0>")
	)
	(gr_poly
		(pts
			(xy 391.173462 -269.437866) (xy 391.08253 -269.329408) (xy 390.974326 -269.42034) (xy 390.970262 -269.46479)
			(xy 391.169652 -269.482062)
		)
		(stroke
			(width 0)
			(type solid)
		)
		(fill yes)
		(layer "In6.Cu")
		(net "M_K_CPU0_SB_CB<4>")
	)
	(gr_poly
		(pts
			(xy 391.173462 -267.817854) (xy 391.08253 -267.709396) (xy 390.974326 -267.800328) (xy 390.970262 -267.844778)
			(xy 391.169652 -267.86205)
		)
		(stroke
			(width 0)
			(type solid)
		)
		(fill yes)
		(layer "In6.Cu")
		(net "M_K_CPU0_SB_RSP<0>")
	)
	(gr_poly
		(pts
			(xy 391.173462 -264.57783) (xy 391.08253 -264.469372) (xy 390.974326 -264.560304) (xy 390.970262 -264.604754)
			(xy 391.169652 -264.622026)
		)
		(stroke
			(width 0)
			(type solid)
		)
		(fill yes)
		(layer "In6.Cu")
		(net "M_K_CPU0_SB_CA<6>")
	)
	(gr_poly
		(pts
			(xy 391.173462 -262.957818) (xy 391.08253 -262.84936) (xy 390.974326 -262.940292) (xy 390.970262 -262.984742)
			(xy 391.169652 -263.002014)
		)
		(stroke
			(width 0)
			(type solid)
		)
		(fill yes)
		(layer "In6.Cu")
		(net "M_K_CPU0_SB_CA<2>")
	)
	(gr_poly
		(pts
			(xy 391.175494 -285.637986) (xy 391.084562 -285.529528) (xy 390.976358 -285.62046) (xy 390.972294 -285.667958)
			(xy 391.17143 -285.685484)
		)
		(stroke
			(width 0)
			(type solid)
		)
		(fill yes)
		(layer "In6.Cu")
		(net "M_K_CPU0_SB_DQS_DP<2>")
	)
	(gr_poly
		(pts
			(xy 391.175494 -280.77795) (xy 391.084562 -280.669492) (xy 390.976358 -280.760424) (xy 390.972294 -280.807922)
			(xy 391.17143 -280.825448)
		)
		(stroke
			(width 0)
			(type solid)
		)
		(fill yes)
		(layer "In6.Cu")
		(net "M_K_CPU0_SB_DQS_DP<1>")
	)
	(gr_poly
		(pts
			(xy 391.175494 -271.057878) (xy 391.084562 -270.94942) (xy 390.976358 -271.040352) (xy 390.972294 -271.08785)
			(xy 391.17143 -271.105376)
		)
		(stroke
			(width 0)
			(type solid)
		)
		(fill yes)
		(layer "In6.Cu")
		(net "M_K_CPU0_SB_DQS_DP<9>")
	)
	(gr_poly
		(pts
			(xy 391.186162 -290.49853) (xy 391.09523 -290.390072) (xy 390.987026 -290.481004) (xy 390.982708 -290.528502)
			(xy 391.182098 -290.546028)
		)
		(stroke
			(width 0)
			(type solid)
		)
		(fill yes)
		(layer "In6.Cu")
		(net "M_K_CPU0_SB_DQS_DP<3>")
	)
	(gr_poly
		(pts
			(xy 391.186162 -275.918676) (xy 391.09523 -275.810218) (xy 390.987026 -275.90115) (xy 390.982708 -275.948648)
			(xy 391.182098 -275.96592)
		)
		(stroke
			(width 0)
			(type solid)
		)
		(fill yes)
		(layer "In6.Cu")
		(net "M_K_CPU0_SB_DQS_DP<0>")
	)
	(gr_poly
		(pts
			(xy 391.224008 -223.0755) (xy 391.1854 -223.053148) (xy 391.049002 -223.089724) (xy 391.085578 -223.226376)
			(xy 391.123932 -223.248728)
		)
		(stroke
			(width 0)
			(type solid)
		)
		(fill yes)
		(layer "In6.Cu")
		(net "M_K_CPU0_SA_DQ<0>")
	)
	(gr_poly
		(pts
			(xy 391.30478 -256.025904) (xy 391.204704 -255.926082) (xy 391.104628 -256.025904) (xy 391.104628 -256.073656)
			(xy 391.30478 -256.073656)
		)
		(stroke
			(width 0)
			(type solid)
		)
		(fill yes)
		(layer "In6.Cu")
		(net "M_K_CPU0_CLK_DP<0>")
	)
	(gr_poly
		(pts
			(xy 391.30478 -255.622298) (xy 391.30478 -255.577848) (xy 391.104628 -255.577848) (xy 391.104628 -255.622298)
			(xy 391.204704 -255.722374)
		)
		(stroke
			(width 0)
			(type solid)
		)
		(fill yes)
		(layer "In6.Cu")
		(net "M_K_CPU0_SA_PAR")
	)
	(gr_poly
		(pts
			(xy 391.30478 -254.406146) (xy 391.204704 -254.30607) (xy 391.104628 -254.406146) (xy 391.104628 -254.450596)
			(xy 391.30478 -254.450596)
		)
		(stroke
			(width 0)
			(type solid)
		)
		(fill yes)
		(layer "In6.Cu")
		(net "M_K_CPU0_SA_CA<4>")
	)
	(gr_poly
		(pts
			(xy 391.30478 -254.002286) (xy 391.30478 -253.957836) (xy 391.104628 -253.957836) (xy 391.104628 -254.002286)
			(xy 391.204704 -254.102362)
		)
		(stroke
			(width 0)
			(type solid)
		)
		(fill yes)
		(layer "In6.Cu")
		(net "M_K_CPU0_SA_CA<3>")
	)
	(gr_poly
		(pts
			(xy 391.30478 -252.786134) (xy 391.204704 -252.686058) (xy 391.104628 -252.786134) (xy 391.104628 -252.830584)
			(xy 391.30478 -252.830584)
		)
		(stroke
			(width 0)
			(type solid)
		)
		(fill yes)
		(layer "In6.Cu")
		(net "M_K_CPU0_SA_CA<0>")
	)
	(gr_poly
		(pts
			(xy 391.30478 -251.166122) (xy 391.204704 -251.066046) (xy 391.104628 -251.166122) (xy 391.104628 -251.210572)
			(xy 391.30478 -251.210572)
		)
		(stroke
			(width 0)
			(type solid)
		)
		(fill yes)
		(layer "In6.Cu")
		(net "M_K_CPU0_SA_CS_N<0>")
	)
	(gr_poly
		(pts
			(xy 391.30478 -250.762262) (xy 391.30478 -250.717812) (xy 391.104628 -250.717812) (xy 391.104628 -250.762262)
			(xy 391.204704 -250.862338)
		)
		(stroke
			(width 0)
			(type solid)
		)
		(fill yes)
		(layer "In6.Cu")
		(net "M_K_CPU0_RESET_N")
	)
	(gr_poly
		(pts
			(xy 391.30478 -249.14225) (xy 391.30478 -249.0978) (xy 391.104628 -249.0978) (xy 391.104628 -249.14225)
			(xy 391.204704 -249.242326)
		)
		(stroke
			(width 0)
			(type solid)
		)
		(fill yes)
		(layer "In6.Cu")
		(net "M_K_CPU0_SA_CB<7>")
	)
	(gr_poly
		(pts
			(xy 391.30478 -247.926098) (xy 391.204704 -247.826022) (xy 391.104628 -247.926098) (xy 391.104628 -247.970548)
			(xy 391.30478 -247.970548)
		)
		(stroke
			(width 0)
			(type solid)
		)
		(fill yes)
		(layer "In6.Cu")
		(net "M_K_CPU0_SA_CB<4>")
	)
	(gr_poly
		(pts
			(xy 391.30478 -247.522492) (xy 391.30478 -247.47474) (xy 391.104628 -247.47474) (xy 391.104628 -247.522492)
			(xy 391.204704 -247.622314)
		)
		(stroke
			(width 0)
			(type solid)
		)
		(fill yes)
		(layer "In6.Cu")
		(net "M_K_CPU0_SA_DQS_DP<9>")
	)
	(gr_poly
		(pts
			(xy 391.30478 -246.305832) (xy 391.204704 -246.20601) (xy 391.104628 -246.305832) (xy 391.104628 -246.353584)
			(xy 391.30478 -246.353584)
		)
		(stroke
			(width 0)
			(type solid)
		)
		(fill yes)
		(layer "In6.Cu")
		(net "M_K_CPU0_SA_DQS_DP<4>")
	)
	(gr_poly
		(pts
			(xy 391.30478 -245.902226) (xy 391.30478 -245.857776) (xy 391.104628 -245.857776) (xy 391.104628 -245.902226)
			(xy 391.204704 -246.002302)
		)
		(stroke
			(width 0)
			(type solid)
		)
		(fill yes)
		(layer "In6.Cu")
		(net "M_K_CPU0_SA_CB<3>")
	)
	(gr_poly
		(pts
			(xy 391.30478 -244.686074) (xy 391.204704 -244.585998) (xy 391.104628 -244.686074) (xy 391.104628 -244.730524)
			(xy 391.30478 -244.730524)
		)
		(stroke
			(width 0)
			(type solid)
		)
		(fill yes)
		(layer "In6.Cu")
		(net "M_K_CPU0_SA_CB<0>")
	)
	(gr_poly
		(pts
			(xy 391.30478 -244.282214) (xy 391.30478 -244.237764) (xy 391.104628 -244.237764) (xy 391.104628 -244.282214)
			(xy 391.204704 -244.38229)
		)
		(stroke
			(width 0)
			(type solid)
		)
		(fill yes)
		(layer "In6.Cu")
		(net "M_K_CPU0_SA_DQ<31>")
	)
	(gr_poly
		(pts
			(xy 391.30478 -243.066062) (xy 391.204704 -242.965986) (xy 391.104628 -243.066062) (xy 391.104628 -243.110512)
			(xy 391.30478 -243.110512)
		)
		(stroke
			(width 0)
			(type solid)
		)
		(fill yes)
		(layer "In6.Cu")
		(net "M_K_CPU0_SA_DQ<28>")
	)
	(gr_poly
		(pts
			(xy 391.30478 -242.662456) (xy 391.30478 -242.614704) (xy 391.104628 -242.614704) (xy 391.104628 -242.662456)
			(xy 391.204704 -242.762278)
		)
		(stroke
			(width 0)
			(type solid)
		)
		(fill yes)
		(layer "In6.Cu")
		(net "M_K_CPU0_SA_DQS_DP<8>")
	)
	(gr_poly
		(pts
			(xy 391.30478 -241.445796) (xy 391.204704 -241.345974) (xy 391.104628 -241.445796) (xy 391.104628 -241.493548)
			(xy 391.30478 -241.493548)
		)
		(stroke
			(width 0)
			(type solid)
		)
		(fill yes)
		(layer "In6.Cu")
		(net "M_K_CPU0_SA_DQS_DP<3>")
	)
	(gr_poly
		(pts
			(xy 391.30478 -241.04219) (xy 391.30478 -240.99774) (xy 391.104628 -240.99774) (xy 391.104628 -241.04219)
			(xy 391.204704 -241.142266)
		)
		(stroke
			(width 0)
			(type solid)
		)
		(fill yes)
		(layer "In6.Cu")
		(net "M_K_CPU0_SA_DQ<27>")
	)
	(gr_poly
		(pts
			(xy 391.30478 -239.826038) (xy 391.204704 -239.725962) (xy 391.104628 -239.826038) (xy 391.104628 -239.870488)
			(xy 391.30478 -239.870488)
		)
		(stroke
			(width 0)
			(type solid)
		)
		(fill yes)
		(layer "In6.Cu")
		(net "M_K_CPU0_SA_DQ<24>")
	)
	(gr_poly
		(pts
			(xy 391.30478 -239.422178) (xy 391.30478 -239.377728) (xy 391.104628 -239.377728) (xy 391.104628 -239.422178)
			(xy 391.204704 -239.522254)
		)
		(stroke
			(width 0)
			(type solid)
		)
		(fill yes)
		(layer "In6.Cu")
		(net "M_K_CPU0_SA_DQ<23>")
	)
	(gr_poly
		(pts
			(xy 391.30478 -238.206026) (xy 391.204704 -238.10595) (xy 391.104628 -238.206026) (xy 391.104628 -238.250476)
			(xy 391.30478 -238.250476)
		)
		(stroke
			(width 0)
			(type solid)
		)
		(fill yes)
		(layer "In6.Cu")
		(net "M_K_CPU0_SA_DQ<20>")
	)
	(gr_poly
		(pts
			(xy 391.30478 -237.80242) (xy 391.30478 -237.754668) (xy 391.104628 -237.754668) (xy 391.104628 -237.80242)
			(xy 391.204704 -237.902242)
		)
		(stroke
			(width 0)
			(type solid)
		)
		(fill yes)
		(layer "In6.Cu")
		(net "M_K_CPU0_SA_DQS_DP<7>")
	)
	(gr_poly
		(pts
			(xy 391.30478 -236.58576) (xy 391.204704 -236.485938) (xy 391.104628 -236.58576) (xy 391.104628 -236.633512)
			(xy 391.30478 -236.633512)
		)
		(stroke
			(width 0)
			(type solid)
		)
		(fill yes)
		(layer "In6.Cu")
		(net "M_K_CPU0_SA_DQS_DP<2>")
	)
	(gr_poly
		(pts
			(xy 391.30478 -236.182154) (xy 391.30478 -236.137704) (xy 391.104628 -236.137704) (xy 391.104628 -236.182154)
			(xy 391.204704 -236.28223)
		)
		(stroke
			(width 0)
			(type solid)
		)
		(fill yes)
		(layer "In6.Cu")
		(net "M_K_CPU0_SA_DQ<19>")
	)
	(gr_poly
		(pts
			(xy 391.30478 -234.966002) (xy 391.204704 -234.865926) (xy 391.104628 -234.966002) (xy 391.104628 -235.010452)
			(xy 391.30478 -235.010452)
		)
		(stroke
			(width 0)
			(type solid)
		)
		(fill yes)
		(layer "In6.Cu")
		(net "M_K_CPU0_SA_DQ<16>")
	)
	(gr_poly
		(pts
			(xy 391.30478 -234.562142) (xy 391.30478 -234.517692) (xy 391.104628 -234.517692) (xy 391.104628 -234.562142)
			(xy 391.204704 -234.662218)
		)
		(stroke
			(width 0)
			(type solid)
		)
		(fill yes)
		(layer "In6.Cu")
		(net "M_K_CPU0_SA_DQ<15>")
	)
	(gr_poly
		(pts
			(xy 391.30478 -233.34599) (xy 391.204704 -233.245914) (xy 391.104628 -233.34599) (xy 391.104628 -233.39044)
			(xy 391.30478 -233.39044)
		)
		(stroke
			(width 0)
			(type solid)
		)
		(fill yes)
		(layer "In6.Cu")
		(net "M_K_CPU0_SA_DQ<12>")
	)
	(gr_poly
		(pts
			(xy 391.30478 -232.942384) (xy 391.30478 -232.894632) (xy 391.104628 -232.894632) (xy 391.104628 -232.942384)
			(xy 391.204704 -233.042206)
		)
		(stroke
			(width 0)
			(type solid)
		)
		(fill yes)
		(layer "In6.Cu")
		(net "M_K_CPU0_SA_DQS_DP<6>")
	)
	(gr_poly
		(pts
			(xy 391.30478 -231.725724) (xy 391.204704 -231.625902) (xy 391.104628 -231.725724) (xy 391.104628 -231.773476)
			(xy 391.30478 -231.773476)
		)
		(stroke
			(width 0)
			(type solid)
		)
		(fill yes)
		(layer "In6.Cu")
		(net "M_K_CPU0_SA_DQS_DP<1>")
	)
	(gr_poly
		(pts
			(xy 391.30478 -231.322372) (xy 391.30478 -231.277922) (xy 391.104628 -231.277922) (xy 391.104628 -231.322372)
			(xy 391.204704 -231.422448)
		)
		(stroke
			(width 0)
			(type solid)
		)
		(fill yes)
		(layer "In6.Cu")
		(net "M_K_CPU0_SA_DQ<11>")
	)
	(gr_poly
		(pts
			(xy 391.30478 -230.105966) (xy 391.204704 -230.006144) (xy 391.104628 -230.105966) (xy 391.104628 -230.150416)
			(xy 391.30478 -230.150416)
		)
		(stroke
			(width 0)
			(type solid)
		)
		(fill yes)
		(layer "In6.Cu")
		(net "M_K_CPU0_SA_DQ<8>")
	)
	(gr_poly
		(pts
			(xy 391.30478 -229.70236) (xy 391.30478 -229.65791) (xy 391.104628 -229.65791) (xy 391.104628 -229.70236)
			(xy 391.204704 -229.802436)
		)
		(stroke
			(width 0)
			(type solid)
		)
		(fill yes)
		(layer "In6.Cu")
		(net "M_K_CPU0_SA_DQ<7>")
	)
	(gr_poly
		(pts
			(xy 391.30478 -228.486208) (xy 391.204704 -228.386132) (xy 391.104628 -228.486208) (xy 391.104628 -228.530658)
			(xy 391.30478 -228.530658)
		)
		(stroke
			(width 0)
			(type solid)
		)
		(fill yes)
		(layer "In6.Cu")
		(net "M_K_CPU0_SA_DQ<4>")
	)
	(gr_poly
		(pts
			(xy 391.30478 -228.082602) (xy 391.30478 -228.03485) (xy 391.104628 -228.03485) (xy 391.104628 -228.082602)
			(xy 391.204704 -228.182424)
		)
		(stroke
			(width 0)
			(type solid)
		)
		(fill yes)
		(layer "In6.Cu")
		(net "M_K_CPU0_SA_DQS_DP<5>")
	)
	(gr_poly
		(pts
			(xy 391.30478 -226.865942) (xy 391.204704 -226.76612) (xy 391.104628 -226.865942) (xy 391.104628 -226.913694)
			(xy 391.30478 -226.913694)
		)
		(stroke
			(width 0)
			(type solid)
		)
		(fill yes)
		(layer "In6.Cu")
		(net "M_K_CPU0_SA_DQS_DP<0>")
	)
	(gr_poly
		(pts
			(xy 391.30478 -226.462336) (xy 391.30478 -226.417886) (xy 391.104628 -226.417886) (xy 391.104628 -226.462336)
			(xy 391.204704 -226.562412)
		)
		(stroke
			(width 0)
			(type solid)
		)
		(fill yes)
		(layer "In6.Cu")
		(net "M_K_CPU0_SA_DQ<3>")
	)
	(gr_poly
		(pts
			(xy 391.360914 -223.75876) (xy 391.324084 -223.622108) (xy 391.28573 -223.599756) (xy 391.185654 -223.772984)
			(xy 391.224262 -223.795336)
		)
		(stroke
			(width 0)
			(type solid)
		)
		(fill yes)
		(layer "In6.Cu")
		(net "M_K_CPU0_SA_DQ<2>")
	)
	(gr_poly
		(pts
			(xy 391.604754 -292.91788) (xy 391.504678 -292.817804) (xy 391.404602 -292.91788) (xy 391.404602 -292.96233)
			(xy 391.604754 -292.96233)
		)
		(stroke
			(width 0)
			(type solid)
		)
		(fill yes)
		(layer "In6.Cu")
		(net "M_K_CPU0_SB_DQ<29>")
	)
	(gr_poly
		(pts
			(xy 391.604754 -292.51402) (xy 391.604754 -292.46957) (xy 391.404602 -292.46957) (xy 391.404602 -292.51402)
			(xy 391.504678 -292.614096)
		)
		(stroke
			(width 0)
			(type solid)
		)
		(fill yes)
		(layer "In6.Cu")
		(net "M_K_CPU0_SB_DQ<30>")
	)
	(gr_poly
		(pts
			(xy 391.604754 -291.297614) (xy 391.504678 -291.197792) (xy 391.404602 -291.297614) (xy 391.404602 -291.345366)
			(xy 391.604754 -291.345366)
		)
		(stroke
			(width 0)
			(type solid)
		)
		(fill yes)
		(layer "In6.Cu")
		(net "M_K_CPU0_SB_DQS_DN<8>")
	)
	(gr_poly
		(pts
			(xy 391.604754 -290.894262) (xy 391.604754 -290.84651) (xy 391.404602 -290.84651) (xy 391.404602 -290.894262)
			(xy 391.504678 -290.994084)
		)
		(stroke
			(width 0)
			(type solid)
		)
		(fill yes)
		(layer "In6.Cu")
		(net "M_K_CPU0_SB_DQS_DN<3>")
	)
	(gr_poly
		(pts
			(xy 391.604754 -289.677856) (xy 391.504678 -289.57778) (xy 391.404602 -289.677856) (xy 391.404602 -289.722306)
			(xy 391.604754 -289.722306)
		)
		(stroke
			(width 0)
			(type solid)
		)
		(fill yes)
		(layer "In6.Cu")
		(net "M_K_CPU0_SB_DQ<25>")
	)
	(gr_poly
		(pts
			(xy 391.604754 -289.273996) (xy 391.604754 -289.229546) (xy 391.404602 -289.229546) (xy 391.404602 -289.273996)
			(xy 391.504678 -289.374072)
		)
		(stroke
			(width 0)
			(type solid)
		)
		(fill yes)
		(layer "In6.Cu")
		(net "M_K_CPU0_SB_DQ<26>")
	)
	(gr_poly
		(pts
			(xy 391.604754 -288.057844) (xy 391.504678 -287.957768) (xy 391.404602 -288.057844) (xy 391.404602 -288.102294)
			(xy 391.604754 -288.102294)
		)
		(stroke
			(width 0)
			(type solid)
		)
		(fill yes)
		(layer "In6.Cu")
		(net "M_K_CPU0_SB_DQ<21>")
	)
	(gr_poly
		(pts
			(xy 391.604754 -287.654238) (xy 391.604754 -287.609788) (xy 391.404602 -287.609788) (xy 391.404602 -287.654238)
			(xy 391.504678 -287.75406)
		)
		(stroke
			(width 0)
			(type solid)
		)
		(fill yes)
		(layer "In6.Cu")
		(net "M_K_CPU0_SB_DQ<22>")
	)
	(gr_poly
		(pts
			(xy 391.604754 -286.437832) (xy 391.504678 -286.337756) (xy 391.404602 -286.437832) (xy 391.404602 -286.485584)
			(xy 391.604754 -286.485584)
		)
		(stroke
			(width 0)
			(type solid)
		)
		(fill yes)
		(layer "In6.Cu")
		(net "M_K_CPU0_SB_DQS_DN<7>")
	)
	(gr_poly
		(pts
			(xy 391.604754 -286.03448) (xy 391.604754 -285.986728) (xy 391.404602 -285.986728) (xy 391.404602 -286.03448)
			(xy 391.504678 -286.134302)
		)
		(stroke
			(width 0)
			(type solid)
		)
		(fill yes)
		(layer "In6.Cu")
		(net "M_K_CPU0_SB_DQS_DN<2>")
	)
	(gr_poly
		(pts
			(xy 391.604754 -284.818074) (xy 391.504678 -284.717998) (xy 391.404602 -284.818074) (xy 391.404602 -284.862524)
			(xy 391.604754 -284.862524)
		)
		(stroke
			(width 0)
			(type solid)
		)
		(fill yes)
		(layer "In6.Cu")
		(net "M_K_CPU0_SB_DQ<17>")
	)
	(gr_poly
		(pts
			(xy 391.604754 -284.414214) (xy 391.604754 -284.369764) (xy 391.404602 -284.369764) (xy 391.404602 -284.414214)
			(xy 391.504678 -284.51429)
		)
		(stroke
			(width 0)
			(type solid)
		)
		(fill yes)
		(layer "In6.Cu")
		(net "M_K_CPU0_SB_DQ<18>")
	)
	(gr_poly
		(pts
			(xy 391.604754 -283.198062) (xy 391.504678 -283.097986) (xy 391.404602 -283.198062) (xy 391.404602 -283.242512)
			(xy 391.604754 -283.242512)
		)
		(stroke
			(width 0)
			(type solid)
		)
		(fill yes)
		(layer "In6.Cu")
		(net "M_K_CPU0_SB_DQ<13>")
	)
	(gr_poly
		(pts
			(xy 391.604754 -282.794202) (xy 391.604754 -282.749752) (xy 391.404602 -282.749752) (xy 391.404602 -282.794202)
			(xy 391.504678 -282.894278)
		)
		(stroke
			(width 0)
			(type solid)
		)
		(fill yes)
		(layer "In6.Cu")
		(net "M_K_CPU0_SB_DQ<14>")
	)
	(gr_poly
		(pts
			(xy 391.604754 -281.577796) (xy 391.504678 -281.477974) (xy 391.404602 -281.577796) (xy 391.404602 -281.625548)
			(xy 391.604754 -281.625548)
		)
		(stroke
			(width 0)
			(type solid)
		)
		(fill yes)
		(layer "In6.Cu")
		(net "M_K_CPU0_SB_DQS_DN<6>")
	)
	(gr_poly
		(pts
			(xy 391.604754 -281.174444) (xy 391.604754 -281.126692) (xy 391.404602 -281.126692) (xy 391.404602 -281.174444)
			(xy 391.504678 -281.274266)
		)
		(stroke
			(width 0)
			(type solid)
		)
		(fill yes)
		(layer "In6.Cu")
		(net "M_K_CPU0_SB_DQS_DN<1>")
	)
	(gr_poly
		(pts
			(xy 391.604754 -279.958038) (xy 391.504678 -279.857962) (xy 391.404602 -279.958038) (xy 391.404602 -280.002488)
			(xy 391.604754 -280.002488)
		)
		(stroke
			(width 0)
			(type solid)
		)
		(fill yes)
		(layer "In6.Cu")
		(net "M_K_CPU0_SB_DQ<9>")
	)
	(gr_poly
		(pts
			(xy 391.604754 -279.554178) (xy 391.604754 -279.509728) (xy 391.404602 -279.509728) (xy 391.404602 -279.554178)
			(xy 391.504678 -279.654254)
		)
		(stroke
			(width 0)
			(type solid)
		)
		(fill yes)
		(layer "In6.Cu")
		(net "M_K_CPU0_SB_DQ<10>")
	)
	(gr_poly
		(pts
			(xy 391.604754 -278.338026) (xy 391.504678 -278.23795) (xy 391.404602 -278.338026) (xy 391.404602 -278.382476)
			(xy 391.604754 -278.382476)
		)
		(stroke
			(width 0)
			(type solid)
		)
		(fill yes)
		(layer "In6.Cu")
		(net "M_K_CPU0_SB_DQ<5>")
	)
	(gr_poly
		(pts
			(xy 391.604754 -277.934166) (xy 391.604754 -277.889716) (xy 391.404602 -277.889716) (xy 391.404602 -277.934166)
			(xy 391.504678 -278.034242)
		)
		(stroke
			(width 0)
			(type solid)
		)
		(fill yes)
		(layer "In6.Cu")
		(net "M_K_CPU0_SB_DQ<6>")
	)
	(gr_poly
		(pts
			(xy 391.604754 -276.71776) (xy 391.504678 -276.617938) (xy 391.404602 -276.71776) (xy 391.404602 -276.765512)
			(xy 391.604754 -276.765512)
		)
		(stroke
			(width 0)
			(type solid)
		)
		(fill yes)
		(layer "In6.Cu")
		(net "M_K_CPU0_SB_DQS_DN<5>")
	)
	(gr_poly
		(pts
			(xy 391.604754 -276.314408) (xy 391.604754 -276.266656) (xy 391.404602 -276.266656) (xy 391.404602 -276.314408)
			(xy 391.504678 -276.41423)
		)
		(stroke
			(width 0)
			(type solid)
		)
		(fill yes)
		(layer "In6.Cu")
		(net "M_K_CPU0_SB_DQS_DN<0>")
	)
	(gr_poly
		(pts
			(xy 391.604754 -275.098002) (xy 391.504678 -274.997926) (xy 391.404602 -275.098002) (xy 391.404602 -275.142452)
			(xy 391.604754 -275.142452)
		)
		(stroke
			(width 0)
			(type solid)
		)
		(fill yes)
		(layer "In6.Cu")
		(net "M_K_CPU0_SB_DQ<1>")
	)
	(gr_poly
		(pts
			(xy 391.604754 -274.694142) (xy 391.604754 -274.649692) (xy 391.404602 -274.649692) (xy 391.404602 -274.694142)
			(xy 391.504678 -274.794218)
		)
		(stroke
			(width 0)
			(type solid)
		)
		(fill yes)
		(layer "In6.Cu")
		(net "M_K_CPU0_SB_DQ<2>")
	)
	(gr_poly
		(pts
			(xy 391.604754 -273.47799) (xy 391.504678 -273.377914) (xy 391.404602 -273.47799) (xy 391.404602 -273.52244)
			(xy 391.604754 -273.52244)
		)
		(stroke
			(width 0)
			(type solid)
		)
		(fill yes)
		(layer "In6.Cu")
		(net "M_K_CPU0_SB_CB<1>")
	)
	(gr_poly
		(pts
			(xy 391.604754 -273.07413) (xy 391.604754 -273.02968) (xy 391.404602 -273.02968) (xy 391.404602 -273.07413)
			(xy 391.504678 -273.174206)
		)
		(stroke
			(width 0)
			(type solid)
		)
		(fill yes)
		(layer "In6.Cu")
		(net "M_K_CPU0_SB_CB<2>")
	)
	(gr_poly
		(pts
			(xy 391.604754 -271.857724) (xy 391.504678 -271.757902) (xy 391.404602 -271.857724) (xy 391.404602 -271.905476)
			(xy 391.604754 -271.905476)
		)
		(stroke
			(width 0)
			(type solid)
		)
		(fill yes)
		(layer "In6.Cu")
		(net "M_K_CPU0_SB_DQS_DN<4>")
	)
	(gr_poly
		(pts
			(xy 391.604754 -270.237966) (xy 391.504678 -270.13789) (xy 391.404602 -270.237966) (xy 391.404602 -270.282416)
			(xy 391.604754 -270.282416)
		)
		(stroke
			(width 0)
			(type solid)
		)
		(fill yes)
		(layer "In6.Cu")
		(net "M_K_CPU0_SB_CB<5>")
	)
	(gr_poly
		(pts
			(xy 391.604754 -269.834106) (xy 391.604754 -269.789656) (xy 391.404602 -269.789656) (xy 391.404602 -269.834106)
			(xy 391.504678 -269.934182)
		)
		(stroke
			(width 0)
			(type solid)
		)
		(fill yes)
		(layer "In6.Cu")
		(net "M_K_CPU0_SB_CB<6>")
	)
	(gr_poly
		(pts
			(xy 391.604754 -266.997942) (xy 391.504678 -266.897866) (xy 391.404602 -266.997942) (xy 391.404602 -267.042392)
			(xy 391.604754 -267.042392)
		)
		(stroke
			(width 0)
			(type solid)
		)
		(fill yes)
		(layer "In6.Cu")
		(net "M_K_CPU0_SA_RSP<0>")
	)
	(gr_poly
		(pts
			(xy 391.604754 -266.594082) (xy 391.604754 -266.549632) (xy 391.404602 -266.549632) (xy 391.404602 -266.594082)
			(xy 391.504678 -266.694158)
		)
		(stroke
			(width 0)
			(type solid)
		)
		(fill yes)
		(layer "In6.Cu")
		(net "M_K_CPU0_SB_CS_N<1>")
	)
	(gr_poly
		(pts
			(xy 391.604754 -265.37793) (xy 391.504678 -265.277854) (xy 391.404602 -265.37793) (xy 391.404602 -265.42238)
			(xy 391.604754 -265.42238)
		)
		(stroke
			(width 0)
			(type solid)
		)
		(fill yes)
		(layer "In6.Cu")
		(net "M_K_CPU0_SB_PAR")
	)
	(gr_poly
		(pts
			(xy 391.604754 -263.757918) (xy 391.504678 -263.657842) (xy 391.404602 -263.757918) (xy 391.404602 -263.802368)
			(xy 391.604754 -263.802368)
		)
		(stroke
			(width 0)
			(type solid)
		)
		(fill yes)
		(layer "In6.Cu")
		(net "M_K_CPU0_SB_CA<4>")
	)
	(gr_poly
		(pts
			(xy 391.604754 -263.354058) (xy 391.604754 -263.309608) (xy 391.404602 -263.309608) (xy 391.404602 -263.354058)
			(xy 391.504678 -263.454134)
		)
		(stroke
			(width 0)
			(type solid)
		)
		(fill yes)
		(layer "In6.Cu")
		(net "M_K_CPU0_SB_CA<3>")
	)
	(gr_poly
		(pts
			(xy 391.604754 -262.137906) (xy 391.504678 -262.03783) (xy 391.404602 -262.137906) (xy 391.404602 -262.182356)
			(xy 391.604754 -262.182356)
		)
		(stroke
			(width 0)
			(type solid)
		)
		(fill yes)
		(layer "In6.Cu")
		(net "M_K_CPU0_SB_CA<0>")
	)
	(gr_poly
		(pts
			(xy 391.693908 -225.505518) (xy 391.6553 -225.483166) (xy 391.518902 -225.519742) (xy 391.555478 -225.656394)
			(xy 391.593832 -225.678746)
		)
		(stroke
			(width 0)
			(type solid)
		)
		(fill yes)
		(layer "In6.Cu")
		(net "M_K_CPU0_SA_DQ<1>")
	)
	(gr_poly
		(pts
			(xy 391.693908 -222.265494) (xy 391.6553 -222.243142) (xy 391.518902 -222.279718) (xy 391.555478 -222.41637)
			(xy 391.593832 -222.438722)
		)
		(stroke
			(width 0)
			(type solid)
		)
		(fill yes)
		(layer "In6.Cu")
		(net "M_K_CPU0_SA_DQ<0>")
	)
	(gr_poly
		(pts
			(xy 391.697972 -224.583498) (xy 391.597896 -224.41027) (xy 391.556748 -224.434146) (xy 391.519918 -224.570544)
			(xy 391.65657 -224.607374)
		)
		(stroke
			(width 0)
			(type solid)
		)
		(fill yes)
		(layer "In6.Cu")
		(net "M_K_CPU0_SA_DQ<1>")
	)
	(gr_poly
		(pts
			(xy 391.697972 -223.884998) (xy 391.65657 -223.861122) (xy 391.519918 -223.897952) (xy 391.556748 -224.03435)
			(xy 391.597896 -224.058226)
		)
		(stroke
			(width 0)
			(type solid)
		)
		(fill yes)
		(layer "In6.Cu")
		(net "M_K_CPU0_SA_DQ<1>")
	)
	(gr_poly
		(pts
			(xy 391.76833 -251.976128) (xy 391.668508 -251.876052) (xy 391.568432 -251.976128) (xy 391.568432 -252.020578)
			(xy 391.76833 -252.020578)
		)
		(stroke
			(width 0)
			(type solid)
		)
		(fill yes)
		(layer "In6.Cu")
		(net "M_K_CPU0_SA_CS_N<1>")
	)
	(gr_poly
		(pts
			(xy 391.768838 -255.216152) (xy 391.668762 -255.116076) (xy 391.568686 -255.216152) (xy 391.568686 -255.260602)
			(xy 391.768838 -255.260602)
		)
		(stroke
			(width 0)
			(type solid)
		)
		(fill yes)
		(layer "In6.Cu")
		(net "M_K_CPU0_SA_CA<6>")
	)
	(gr_poly
		(pts
			(xy 391.768838 -254.812292) (xy 391.768838 -254.767842) (xy 391.568686 -254.767842) (xy 391.568686 -254.812292)
			(xy 391.668762 -254.912368)
		)
		(stroke
			(width 0)
			(type solid)
		)
		(fill yes)
		(layer "In6.Cu")
		(net "M_K_CPU0_SA_CA<5>")
	)
	(gr_poly
		(pts
			(xy 391.768838 -253.59614) (xy 391.668762 -253.496064) (xy 391.568686 -253.59614) (xy 391.568686 -253.64059)
			(xy 391.768838 -253.64059)
		)
		(stroke
			(width 0)
			(type solid)
		)
		(fill yes)
		(layer "In6.Cu")
		(net "M_K_CPU0_SA_CA<2>")
	)
	(gr_poly
		(pts
			(xy 391.768838 -253.19228) (xy 391.768838 -253.14783) (xy 391.568686 -253.14783) (xy 391.568686 -253.19228)
			(xy 391.668762 -253.292356)
		)
		(stroke
			(width 0)
			(type solid)
		)
		(fill yes)
		(layer "In6.Cu")
		(net "M_K_CPU0_SA_CA<1>")
	)
	(gr_poly
		(pts
			(xy 391.768838 -250.356116) (xy 391.668762 -250.25604) (xy 391.568686 -250.356116) (xy 391.568686 -250.400566)
			(xy 391.768838 -250.400566)
		)
		(stroke
			(width 0)
			(type solid)
		)
		(fill yes)
		(layer "In6.Cu")
		(net "M_K_CPU0_ALERT_R_N")
	)
	(gr_poly
		(pts
			(xy 391.768838 -248.736104) (xy 391.668762 -248.636028) (xy 391.568686 -248.736104) (xy 391.568686 -248.780554)
			(xy 391.768838 -248.780554)
		)
		(stroke
			(width 0)
			(type solid)
		)
		(fill yes)
		(layer "In6.Cu")
		(net "M_K_CPU0_SA_CB<5>")
	)
	(gr_poly
		(pts
			(xy 391.768838 -248.332244) (xy 391.768838 -248.287794) (xy 391.568686 -248.287794) (xy 391.568686 -248.332244)
			(xy 391.668762 -248.43232)
		)
		(stroke
			(width 0)
			(type solid)
		)
		(fill yes)
		(layer "In6.Cu")
		(net "M_K_CPU0_SA_CB<6>")
	)
	(gr_poly
		(pts
			(xy 391.768838 -247.115838) (xy 391.668762 -247.016016) (xy 391.568686 -247.115838) (xy 391.568686 -247.16359)
			(xy 391.768838 -247.16359)
		)
		(stroke
			(width 0)
			(type solid)
		)
		(fill yes)
		(layer "In6.Cu")
		(net "M_K_CPU0_SA_DQS_DN<9>")
	)
	(gr_poly
		(pts
			(xy 391.768838 -246.712486) (xy 391.768838 -246.664734) (xy 391.568686 -246.664734) (xy 391.568686 -246.712486)
			(xy 391.668762 -246.812308)
		)
		(stroke
			(width 0)
			(type solid)
		)
		(fill yes)
		(layer "In6.Cu")
		(net "M_K_CPU0_SA_DQS_DN<4>")
	)
	(gr_poly
		(pts
			(xy 391.768838 -245.49608) (xy 391.668762 -245.396004) (xy 391.568686 -245.49608) (xy 391.568686 -245.54053)
			(xy 391.768838 -245.54053)
		)
		(stroke
			(width 0)
			(type solid)
		)
		(fill yes)
		(layer "In6.Cu")
		(net "M_K_CPU0_SA_CB<1>")
	)
	(gr_poly
		(pts
			(xy 391.768838 -245.09222) (xy 391.768838 -245.04777) (xy 391.568686 -245.04777) (xy 391.568686 -245.09222)
			(xy 391.668762 -245.192296)
		)
		(stroke
			(width 0)
			(type solid)
		)
		(fill yes)
		(layer "In6.Cu")
		(net "M_K_CPU0_SA_CB<2>")
	)
	(gr_poly
		(pts
			(xy 391.768838 -243.876068) (xy 391.668762 -243.775992) (xy 391.568686 -243.876068) (xy 391.568686 -243.920518)
			(xy 391.768838 -243.920518)
		)
		(stroke
			(width 0)
			(type solid)
		)
		(fill yes)
		(layer "In6.Cu")
		(net "M_K_CPU0_SA_DQ<29>")
	)
	(gr_poly
		(pts
			(xy 391.768838 -243.472208) (xy 391.768838 -243.427758) (xy 391.568686 -243.427758) (xy 391.568686 -243.472208)
			(xy 391.668762 -243.572284)
		)
		(stroke
			(width 0)
			(type solid)
		)
		(fill yes)
		(layer "In6.Cu")
		(net "M_K_CPU0_SA_DQ<30>")
	)
	(gr_poly
		(pts
			(xy 391.768838 -242.255802) (xy 391.668762 -242.15598) (xy 391.568686 -242.255802) (xy 391.568686 -242.303554)
			(xy 391.768838 -242.303554)
		)
		(stroke
			(width 0)
			(type solid)
		)
		(fill yes)
		(layer "In6.Cu")
		(net "M_K_CPU0_SA_DQS_DN<8>")
	)
	(gr_poly
		(pts
			(xy 391.768838 -241.85245) (xy 391.768838 -241.804698) (xy 391.568686 -241.804698) (xy 391.568686 -241.85245)
			(xy 391.668762 -241.952272)
		)
		(stroke
			(width 0)
			(type solid)
		)
		(fill yes)
		(layer "In6.Cu")
		(net "M_K_CPU0_SA_DQS_DN<3>")
	)
	(gr_poly
		(pts
			(xy 391.768838 -240.636044) (xy 391.668762 -240.535968) (xy 391.568686 -240.636044) (xy 391.568686 -240.680494)
			(xy 391.768838 -240.680494)
		)
		(stroke
			(width 0)
			(type solid)
		)
		(fill yes)
		(layer "In6.Cu")
		(net "M_K_CPU0_SA_DQ<25>")
	)
	(gr_poly
		(pts
			(xy 391.768838 -240.232184) (xy 391.768838 -240.187734) (xy 391.568686 -240.187734) (xy 391.568686 -240.232184)
			(xy 391.668762 -240.33226)
		)
		(stroke
			(width 0)
			(type solid)
		)
		(fill yes)
		(layer "In6.Cu")
		(net "M_K_CPU0_SA_DQ<26>")
	)
	(gr_poly
		(pts
			(xy 391.768838 -239.016032) (xy 391.668762 -238.915956) (xy 391.568686 -239.016032) (xy 391.568686 -239.060482)
			(xy 391.768838 -239.060482)
		)
		(stroke
			(width 0)
			(type solid)
		)
		(fill yes)
		(layer "In6.Cu")
		(net "M_K_CPU0_SA_DQ<21>")
	)
	(gr_poly
		(pts
			(xy 391.768838 -238.612172) (xy 391.768838 -238.567722) (xy 391.568686 -238.567722) (xy 391.568686 -238.612172)
			(xy 391.668762 -238.712248)
		)
		(stroke
			(width 0)
			(type solid)
		)
		(fill yes)
		(layer "In6.Cu")
		(net "M_K_CPU0_SA_DQ<22>")
	)
	(gr_poly
		(pts
			(xy 391.768838 -237.395766) (xy 391.668762 -237.295944) (xy 391.568686 -237.395766) (xy 391.568686 -237.443518)
			(xy 391.768838 -237.443518)
		)
		(stroke
			(width 0)
			(type solid)
		)
		(fill yes)
		(layer "In6.Cu")
		(net "M_K_CPU0_SA_DQS_DN<7>")
	)
	(gr_poly
		(pts
			(xy 391.768838 -236.992414) (xy 391.768838 -236.944662) (xy 391.568686 -236.944662) (xy 391.568686 -236.992414)
			(xy 391.668762 -237.092236)
		)
		(stroke
			(width 0)
			(type solid)
		)
		(fill yes)
		(layer "In6.Cu")
		(net "M_K_CPU0_SA_DQS_DN<2>")
	)
	(gr_poly
		(pts
			(xy 391.768838 -235.776008) (xy 391.668762 -235.675932) (xy 391.568686 -235.776008) (xy 391.568686 -235.820458)
			(xy 391.768838 -235.820458)
		)
		(stroke
			(width 0)
			(type solid)
		)
		(fill yes)
		(layer "In6.Cu")
		(net "M_K_CPU0_SA_DQ<17>")
	)
	(gr_poly
		(pts
			(xy 391.768838 -235.372148) (xy 391.768838 -235.327698) (xy 391.568686 -235.327698) (xy 391.568686 -235.372148)
			(xy 391.668762 -235.472224)
		)
		(stroke
			(width 0)
			(type solid)
		)
		(fill yes)
		(layer "In6.Cu")
		(net "M_K_CPU0_SA_DQ<18>")
	)
	(gr_poly
		(pts
			(xy 391.768838 -234.155996) (xy 391.668762 -234.05592) (xy 391.568686 -234.155996) (xy 391.568686 -234.200446)
			(xy 391.768838 -234.200446)
		)
		(stroke
			(width 0)
			(type solid)
		)
		(fill yes)
		(layer "In6.Cu")
		(net "M_K_CPU0_SA_DQ<13>")
	)
	(gr_poly
		(pts
			(xy 391.768838 -233.752136) (xy 391.768838 -233.707686) (xy 391.568686 -233.707686) (xy 391.568686 -233.752136)
			(xy 391.668762 -233.852212)
		)
		(stroke
			(width 0)
			(type solid)
		)
		(fill yes)
		(layer "In6.Cu")
		(net "M_K_CPU0_SA_DQ<14>")
	)
	(gr_poly
		(pts
			(xy 391.768838 -232.53573) (xy 391.668762 -232.435908) (xy 391.568686 -232.53573) (xy 391.568686 -232.583482)
			(xy 391.768838 -232.583482)
		)
		(stroke
			(width 0)
			(type solid)
		)
		(fill yes)
		(layer "In6.Cu")
		(net "M_K_CPU0_SA_DQS_DN<6>")
	)
	(gr_poly
		(pts
			(xy 391.768838 -232.132378) (xy 391.768838 -232.084626) (xy 391.568686 -232.084626) (xy 391.568686 -232.132378)
			(xy 391.668762 -232.2322)
		)
		(stroke
			(width 0)
			(type solid)
		)
		(fill yes)
		(layer "In6.Cu")
		(net "M_K_CPU0_SA_DQS_DN<1>")
	)
	(gr_poly
		(pts
			(xy 391.768838 -230.512366) (xy 391.768838 -230.467916) (xy 391.568686 -230.467916) (xy 391.568686 -230.512366)
			(xy 391.668762 -230.612188)
		)
		(stroke
			(width 0)
			(type solid)
		)
		(fill yes)
		(layer "In6.Cu")
		(net "M_K_CPU0_SA_DQ<10>")
	)
	(gr_poly
		(pts
			(xy 391.774934 -256.432558) (xy 391.774934 -256.384806) (xy 391.574782 -256.384806) (xy 391.574782 -256.432558)
			(xy 391.674858 -256.53238)
		)
		(stroke
			(width 0)
			(type solid)
		)
		(fill yes)
		(layer "In6.Cu")
		(net "M_K_CPU0_CLK_DN<0>")
	)
	(gr_poly
		(pts
			(xy 391.774934 -227.272596) (xy 391.774934 -227.224844) (xy 391.574782 -227.224844) (xy 391.574782 -227.272596)
			(xy 391.674858 -227.372418)
		)
		(stroke
			(width 0)
			(type solid)
		)
		(fill yes)
		(layer "In6.Cu")
		(net "M_K_CPU0_SA_DQS_DN<0>")
	)
	(gr_poly
		(pts
			(xy 391.830814 -226.188778) (xy 391.793984 -226.052126) (xy 391.75563 -226.029774) (xy 391.655554 -226.203002)
			(xy 391.694162 -226.225354)
		)
		(stroke
			(width 0)
			(type solid)
		)
		(fill yes)
		(layer "In6.Cu")
		(net "M_K_CPU0_SA_DQ<3>")
	)
	(gr_poly
		(pts
			(xy 391.830814 -222.948754) (xy 391.793984 -222.812102) (xy 391.75563 -222.78975) (xy 391.655554 -222.962978)
			(xy 391.694162 -222.98533)
		)
		(stroke
			(width 0)
			(type solid)
		)
		(fill yes)
		(layer "In6.Cu")
		(net "M_K_CPU0_SA_DQ<2>")
	)
	(gr_poly
		(pts
			(xy 391.993882 -293.874698) (xy 391.893806 -293.70147) (xy 391.855452 -293.723822) (xy 391.818622 -293.860474)
			(xy 391.955274 -293.89705)
		)
		(stroke
			(width 0)
			(type solid)
		)
		(fill yes)
		(layer "In6.Cu")
		(net "M_K_CPU0_SB_DQ<31>")
	)
	(gr_poly
		(pts
			(xy 391.993882 -268.877288) (xy 391.955274 -268.854936) (xy 391.818622 -268.891512) (xy 391.855452 -269.028164)
			(xy 391.893806 -269.050516)
		)
		(stroke
			(width 0)
			(type solid)
		)
		(fill yes)
		(layer "In6.Cu")
		(net "M_K_CPU0_SB_CB<4>")
	)
	(gr_poly
		(pts
			(xy 392.068558 -291.704268) (xy 392.068558 -291.656516) (xy 391.86866 -291.656516) (xy 391.86866 -291.704268)
			(xy 391.968736 -291.80409)
		)
		(stroke
			(width 0)
			(type solid)
		)
		(fill yes)
		(layer "In6.Cu")
		(net "M_K_CPU0_SB_DQS_DP<8>")
	)
	(gr_poly
		(pts
			(xy 392.068558 -290.084002) (xy 392.068558 -290.039552) (xy 391.86866 -290.039552) (xy 391.86866 -290.084002)
			(xy 391.968736 -290.184078)
		)
		(stroke
			(width 0)
			(type solid)
		)
		(fill yes)
		(layer "In6.Cu")
		(net "M_K_CPU0_SB_DQ<27>")
	)
	(gr_poly
		(pts
			(xy 392.068558 -288.86785) (xy 391.968736 -288.767774) (xy 391.86866 -288.86785) (xy 391.86866 -288.9123)
			(xy 392.068558 -288.9123)
		)
		(stroke
			(width 0)
			(type solid)
		)
		(fill yes)
		(layer "In6.Cu")
		(net "M_K_CPU0_SB_DQ<24>")
	)
	(gr_poly
		(pts
			(xy 392.068558 -288.464244) (xy 392.068558 -288.419794) (xy 391.86866 -288.419794) (xy 391.86866 -288.464244)
			(xy 391.968736 -288.56432)
		)
		(stroke
			(width 0)
			(type solid)
		)
		(fill yes)
		(layer "In6.Cu")
		(net "M_K_CPU0_SB_DQ<23>")
	)
	(gr_poly
		(pts
			(xy 392.068558 -287.247838) (xy 391.968736 -287.148016) (xy 391.86866 -287.247838) (xy 391.86866 -287.292288)
			(xy 392.068558 -287.292288)
		)
		(stroke
			(width 0)
			(type solid)
		)
		(fill yes)
		(layer "In6.Cu")
		(net "M_K_CPU0_SB_DQ<20>")
	)
	(gr_poly
		(pts
			(xy 392.068558 -285.22422) (xy 392.068558 -285.17977) (xy 391.86866 -285.17977) (xy 391.86866 -285.22422)
			(xy 391.968736 -285.324296)
		)
		(stroke
			(width 0)
			(type solid)
		)
		(fill yes)
		(layer "In6.Cu")
		(net "M_K_CPU0_SB_DQ<19>")
	)
	(gr_poly
		(pts
			(xy 392.068558 -284.008068) (xy 391.968736 -283.907992) (xy 391.86866 -284.008068) (xy 391.86866 -284.052518)
			(xy 392.068558 -284.052518)
		)
		(stroke
			(width 0)
			(type solid)
		)
		(fill yes)
		(layer "In6.Cu")
		(net "M_K_CPU0_SB_DQ<16>")
	)
	(gr_poly
		(pts
			(xy 392.068558 -283.604208) (xy 392.068558 -283.559758) (xy 391.86866 -283.559758) (xy 391.86866 -283.604208)
			(xy 391.968736 -283.704284)
		)
		(stroke
			(width 0)
			(type solid)
		)
		(fill yes)
		(layer "In6.Cu")
		(net "M_K_CPU0_SB_DQ<15>")
	)
	(gr_poly
		(pts
			(xy 392.068558 -282.388056) (xy 391.968736 -282.28798) (xy 391.86866 -282.388056) (xy 391.86866 -282.432506)
			(xy 392.068558 -282.432506)
		)
		(stroke
			(width 0)
			(type solid)
		)
		(fill yes)
		(layer "In6.Cu")
		(net "M_K_CPU0_SB_DQ<12>")
	)
	(gr_poly
		(pts
			(xy 392.068558 -281.98445) (xy 392.068558 -281.936698) (xy 391.86866 -281.936698) (xy 391.86866 -281.98445)
			(xy 391.968736 -282.084272)
		)
		(stroke
			(width 0)
			(type solid)
		)
		(fill yes)
		(layer "In6.Cu")
		(net "M_K_CPU0_SB_DQS_DP<6>")
	)
	(gr_poly
		(pts
			(xy 392.068558 -280.364184) (xy 392.068558 -280.319734) (xy 391.86866 -280.319734) (xy 391.86866 -280.364184)
			(xy 391.968736 -280.46426)
		)
		(stroke
			(width 0)
			(type solid)
		)
		(fill yes)
		(layer "In6.Cu")
		(net "M_K_CPU0_SB_DQ<11>")
	)
	(gr_poly
		(pts
			(xy 392.068558 -279.148032) (xy 391.968736 -279.047956) (xy 391.86866 -279.148032) (xy 391.86866 -279.192482)
			(xy 392.068558 -279.192482)
		)
		(stroke
			(width 0)
			(type solid)
		)
		(fill yes)
		(layer "In6.Cu")
		(net "M_K_CPU0_SB_DQ<8>")
	)
	(gr_poly
		(pts
			(xy 392.068558 -278.744172) (xy 392.068558 -278.699722) (xy 391.86866 -278.699722) (xy 391.86866 -278.744172)
			(xy 391.968736 -278.844248)
		)
		(stroke
			(width 0)
			(type solid)
		)
		(fill yes)
		(layer "In6.Cu")
		(net "M_K_CPU0_SB_DQ<7>")
	)
	(gr_poly
		(pts
			(xy 392.068558 -277.52802) (xy 391.968736 -277.427944) (xy 391.86866 -277.52802) (xy 391.86866 -277.57247)
			(xy 392.068558 -277.57247)
		)
		(stroke
			(width 0)
			(type solid)
		)
		(fill yes)
		(layer "In6.Cu")
		(net "M_K_CPU0_SB_DQ<4>")
	)
	(gr_poly
		(pts
			(xy 392.068558 -277.124414) (xy 392.068558 -277.076662) (xy 391.86866 -277.076662) (xy 391.86866 -277.124414)
			(xy 391.968736 -277.224236)
		)
		(stroke
			(width 0)
			(type solid)
		)
		(fill yes)
		(layer "In6.Cu")
		(net "M_K_CPU0_SB_DQS_DP<5>")
	)
	(gr_poly
		(pts
			(xy 392.068558 -275.504148) (xy 392.068558 -275.459698) (xy 391.86866 -275.459698) (xy 391.86866 -275.504148)
			(xy 391.968736 -275.604224)
		)
		(stroke
			(width 0)
			(type solid)
		)
		(fill yes)
		(layer "In6.Cu")
		(net "M_K_CPU0_SB_DQ<3>")
	)
	(gr_poly
		(pts
			(xy 392.068558 -274.287996) (xy 391.968736 -274.18792) (xy 391.86866 -274.287996) (xy 391.86866 -274.332446)
			(xy 392.068558 -274.332446)
		)
		(stroke
			(width 0)
			(type solid)
		)
		(fill yes)
		(layer "In6.Cu")
		(net "M_K_CPU0_SB_DQ<0>")
	)
	(gr_poly
		(pts
			(xy 392.068558 -273.884136) (xy 392.068558 -273.839686) (xy 391.86866 -273.839686) (xy 391.86866 -273.884136)
			(xy 391.968736 -273.984212)
		)
		(stroke
			(width 0)
			(type solid)
		)
		(fill yes)
		(layer "In6.Cu")
		(net "M_K_CPU0_SB_CB<3>")
	)
	(gr_poly
		(pts
			(xy 392.068558 -272.667984) (xy 391.968736 -272.567908) (xy 391.86866 -272.667984) (xy 391.86866 -272.712434)
			(xy 392.068558 -272.712434)
		)
		(stroke
			(width 0)
			(type solid)
		)
		(fill yes)
		(layer "In6.Cu")
		(net "M_K_CPU0_SB_CB<0>")
	)
	(gr_poly
		(pts
			(xy 392.068558 -272.264378) (xy 392.068558 -272.216626) (xy 391.86866 -272.216626) (xy 391.86866 -272.264378)
			(xy 391.968736 -272.3642)
		)
		(stroke
			(width 0)
			(type solid)
		)
		(fill yes)
		(layer "In6.Cu")
		(net "M_K_CPU0_SB_DQS_DP<4>")
	)
	(gr_poly
		(pts
			(xy 392.068558 -267.807948) (xy 391.968736 -267.707872) (xy 391.86866 -267.807948) (xy 391.86866 -267.852398)
			(xy 392.068558 -267.852398)
		)
		(stroke
			(width 0)
			(type solid)
		)
		(fill yes)
		(layer "In6.Cu")
		(net "M_K_CPU0_SB_RSP<0>")
	)
	(gr_poly
		(pts
			(xy 392.068558 -265.784076) (xy 392.068558 -265.739626) (xy 391.86866 -265.739626) (xy 391.86866 -265.784076)
			(xy 391.968736 -265.884152)
		)
		(stroke
			(width 0)
			(type solid)
		)
		(fill yes)
		(layer "In6.Cu")
		(net "M_K_CPU0_SB_CS_N<0>")
	)
	(gr_poly
		(pts
			(xy 392.068558 -264.567924) (xy 391.968736 -264.467848) (xy 391.86866 -264.567924) (xy 391.86866 -264.612374)
			(xy 392.068558 -264.612374)
		)
		(stroke
			(width 0)
			(type solid)
		)
		(fill yes)
		(layer "In6.Cu")
		(net "M_K_CPU0_SB_CA<6>")
	)
	(gr_poly
		(pts
			(xy 392.068558 -264.164064) (xy 392.068558 -264.119614) (xy 391.86866 -264.119614) (xy 391.86866 -264.164064)
			(xy 391.968736 -264.26414)
		)
		(stroke
			(width 0)
			(type solid)
		)
		(fill yes)
		(layer "In6.Cu")
		(net "M_K_CPU0_SB_CA<5>")
	)
	(gr_poly
		(pts
			(xy 392.068558 -262.947912) (xy 391.968736 -262.847836) (xy 391.86866 -262.947912) (xy 391.86866 -262.992362)
			(xy 392.068558 -262.992362)
		)
		(stroke
			(width 0)
			(type solid)
		)
		(fill yes)
		(layer "In6.Cu")
		(net "M_K_CPU0_SB_CA<2>")
	)
	(gr_poly
		(pts
			(xy 392.068558 -262.544052) (xy 392.068558 -262.499602) (xy 391.86866 -262.499602) (xy 391.86866 -262.544052)
			(xy 391.968736 -262.644128)
		)
		(stroke
			(width 0)
			(type solid)
		)
		(fill yes)
		(layer "In6.Cu")
		(net "M_K_CPU0_SB_CA<1>")
	)
	(gr_poly
		(pts
			(xy 392.074908 -292.107874) (xy 391.974832 -292.007798) (xy 391.874756 -292.107874) (xy 391.874756 -292.152324)
			(xy 392.074908 -292.152324)
		)
		(stroke
			(width 0)
			(type solid)
		)
		(fill yes)
		(layer "In6.Cu")
		(net "M_K_CPU0_SB_DQ<28>")
	)
	(gr_poly
		(pts
			(xy 392.074908 -290.487608) (xy 391.974832 -290.387786) (xy 391.874756 -290.487608) (xy 391.874756 -290.53536)
			(xy 392.074908 -290.53536)
		)
		(stroke
			(width 0)
			(type solid)
		)
		(fill yes)
		(layer "In6.Cu")
		(net "M_K_CPU0_SB_DQS_DP<3>")
	)
	(gr_poly
		(pts
			(xy 392.074908 -285.627826) (xy 391.974832 -285.528004) (xy 391.874756 -285.627826) (xy 391.874756 -285.675578)
			(xy 392.074908 -285.675578)
		)
		(stroke
			(width 0)
			(type solid)
		)
		(fill yes)
		(layer "In6.Cu")
		(net "M_K_CPU0_SB_DQS_DP<2>")
	)
	(gr_poly
		(pts
			(xy 392.074908 -280.76779) (xy 391.974832 -280.667968) (xy 391.874756 -280.76779) (xy 391.874756 -280.815542)
			(xy 392.074908 -280.815542)
		)
		(stroke
			(width 0)
			(type solid)
		)
		(fill yes)
		(layer "In6.Cu")
		(net "M_K_CPU0_SB_DQS_DP<1>")
	)
	(gr_poly
		(pts
			(xy 392.074908 -275.907754) (xy 391.974832 -275.807932) (xy 391.874756 -275.907754) (xy 391.874756 -275.955506)
			(xy 392.074908 -275.955506)
		)
		(stroke
			(width 0)
			(type solid)
		)
		(fill yes)
		(layer "In6.Cu")
		(net "M_K_CPU0_SB_DQS_DP<0>")
	)
	(gr_poly
		(pts
			(xy 392.074908 -271.047718) (xy 391.974832 -270.947896) (xy 391.874756 -271.047718) (xy 391.874756 -271.09547)
			(xy 392.074908 -271.09547)
		)
		(stroke
			(width 0)
			(type solid)
		)
		(fill yes)
		(layer "In6.Cu")
		(net "M_K_CPU0_SB_DQS_DP<9>")
	)
	(gr_poly
		(pts
			(xy 392.074908 -270.644112) (xy 392.074908 -270.599662) (xy 391.874756 -270.599662) (xy 391.874756 -270.644112)
			(xy 391.974832 -270.744188)
		)
		(stroke
			(width 0)
			(type solid)
		)
		(fill yes)
		(layer "In6.Cu")
		(net "M_K_CPU0_SB_CB<7>")
	)
	(gr_poly
		(pts
			(xy 392.093958 -293.32809) (xy 392.130534 -293.191438) (xy 391.994136 -293.154862) (xy 391.955528 -293.177214)
			(xy 392.055604 -293.350442)
		)
		(stroke
			(width 0)
			(type solid)
		)
		(fill yes)
		(layer "In6.Cu")
		(net "M_K_CPU0_SB_DQ<29>")
	)
	(gr_poly
		(pts
			(xy 392.130534 -269.560548) (xy 392.093958 -269.423896) (xy 392.055604 -269.401544) (xy 391.955528 -269.574772)
			(xy 391.994136 -269.597124)
		)
		(stroke
			(width 0)
			(type solid)
		)
		(fill yes)
		(layer "In6.Cu")
		(net "M_K_CPU0_SB_CB<6>")
	)
	(gr_poly
		(pts
			(xy 392.164062 -223.0755) (xy 392.125454 -223.053148) (xy 391.988802 -223.089724) (xy 392.025632 -223.226376)
			(xy 392.063986 -223.248728)
		)
		(stroke
			(width 0)
			(type solid)
		)
		(fill yes)
		(layer "In6.Cu")
		(net "M_K_CPU0_SA_DQ<1>")
	)
	(gr_poly
		(pts
			(xy 392.166856 -226.316286) (xy 392.125708 -226.292664) (xy 391.989056 -226.32924) (xy 392.025632 -226.465638)
			(xy 392.067034 -226.489514)
		)
		(stroke
			(width 0)
			(type solid)
		)
		(fill yes)
		(layer "In6.Cu")
		(net "M_K_CPU0_SA_DQS_DP<0>")
	)
	(gr_poly
		(pts
			(xy 392.238738 -256.025904) (xy 392.138662 -255.926082) (xy 392.038586 -256.025904) (xy 392.038586 -256.073656)
			(xy 392.238738 -256.073656)
		)
		(stroke
			(width 0)
			(type solid)
		)
		(fill yes)
		(layer "In6.Cu")
		(net "M_K_CPU0_CLK_DP<0>")
	)
	(gr_poly
		(pts
			(xy 392.250422 -255.622298) (xy 392.250422 -255.577848) (xy 392.05027 -255.577848) (xy 392.05027 -255.622298)
			(xy 392.150346 -255.722374)
		)
		(stroke
			(width 0)
			(type solid)
		)
		(fill yes)
		(layer "In6.Cu")
		(net "M_K_CPU0_SA_PAR")
	)
	(gr_poly
		(pts
			(xy 392.250422 -254.002286) (xy 392.250422 -253.957836) (xy 392.05027 -253.957836) (xy 392.05027 -254.002286)
			(xy 392.150346 -254.102362)
		)
		(stroke
			(width 0)
			(type solid)
		)
		(fill yes)
		(layer "In6.Cu")
		(net "M_K_CPU0_SA_CA<3>")
	)
	(gr_poly
		(pts
			(xy 392.250422 -250.762262) (xy 392.250422 -250.717812) (xy 392.05027 -250.717812) (xy 392.05027 -250.762262)
			(xy 392.150346 -250.862338)
		)
		(stroke
			(width 0)
			(type solid)
		)
		(fill yes)
		(layer "In6.Cu")
		(net "M_K_CPU0_RESET_N")
	)
	(gr_poly
		(pts
			(xy 392.250422 -249.14225) (xy 392.250422 -249.0978) (xy 392.05027 -249.0978) (xy 392.05027 -249.14225)
			(xy 392.150346 -249.242326)
		)
		(stroke
			(width 0)
			(type solid)
		)
		(fill yes)
		(layer "In6.Cu")
		(net "M_K_CPU0_SA_CB<7>")
	)
	(gr_poly
		(pts
			(xy 392.250422 -247.522492) (xy 392.250422 -247.47474) (xy 392.05027 -247.47474) (xy 392.05027 -247.522492)
			(xy 392.150346 -247.622314)
		)
		(stroke
			(width 0)
			(type solid)
		)
		(fill yes)
		(layer "In6.Cu")
		(net "M_K_CPU0_SA_DQS_DP<9>")
	)
	(gr_poly
		(pts
			(xy 392.250422 -244.282214) (xy 392.250422 -244.237764) (xy 392.05027 -244.237764) (xy 392.05027 -244.282214)
			(xy 392.150346 -244.38229)
		)
		(stroke
			(width 0)
			(type solid)
		)
		(fill yes)
		(layer "In6.Cu")
		(net "M_K_CPU0_SA_DQ<31>")
	)
	(gr_poly
		(pts
			(xy 392.250422 -242.662456) (xy 392.250422 -242.614704) (xy 392.05027 -242.614704) (xy 392.05027 -242.662456)
			(xy 392.150346 -242.762278)
		)
		(stroke
			(width 0)
			(type solid)
		)
		(fill yes)
		(layer "In6.Cu")
		(net "M_K_CPU0_SA_DQS_DP<8>")
	)
	(gr_poly
		(pts
			(xy 392.250422 -241.04219) (xy 392.250422 -240.99774) (xy 392.05027 -240.99774) (xy 392.05027 -241.04219)
			(xy 392.150346 -241.142266)
		)
		(stroke
			(width 0)
			(type solid)
		)
		(fill yes)
		(layer "In6.Cu")
		(net "M_K_CPU0_SA_DQ<27>")
	)
	(gr_poly
		(pts
			(xy 392.250422 -239.422178) (xy 392.250422 -239.377728) (xy 392.05027 -239.377728) (xy 392.05027 -239.422178)
			(xy 392.150346 -239.522254)
		)
		(stroke
			(width 0)
			(type solid)
		)
		(fill yes)
		(layer "In6.Cu")
		(net "M_K_CPU0_SA_DQ<23>")
	)
	(gr_poly
		(pts
			(xy 392.250422 -237.80242) (xy 392.250422 -237.754668) (xy 392.05027 -237.754668) (xy 392.05027 -237.80242)
			(xy 392.150346 -237.902242)
		)
		(stroke
			(width 0)
			(type solid)
		)
		(fill yes)
		(layer "In6.Cu")
		(net "M_K_CPU0_SA_DQS_DP<7>")
	)
	(gr_poly
		(pts
			(xy 392.250422 -236.182154) (xy 392.250422 -236.137704) (xy 392.05027 -236.137704) (xy 392.05027 -236.182154)
			(xy 392.150346 -236.28223)
		)
		(stroke
			(width 0)
			(type solid)
		)
		(fill yes)
		(layer "In6.Cu")
		(net "M_K_CPU0_SA_DQ<19>")
	)
	(gr_poly
		(pts
			(xy 392.250422 -234.562142) (xy 392.250422 -234.517692) (xy 392.05027 -234.517692) (xy 392.05027 -234.562142)
			(xy 392.150346 -234.662218)
		)
		(stroke
			(width 0)
			(type solid)
		)
		(fill yes)
		(layer "In6.Cu")
		(net "M_K_CPU0_SA_DQ<15>")
	)
	(gr_poly
		(pts
			(xy 392.250422 -231.322372) (xy 392.250422 -231.277922) (xy 392.05027 -231.277922) (xy 392.05027 -231.322372)
			(xy 392.150346 -231.422448)
		)
		(stroke
			(width 0)
			(type solid)
		)
		(fill yes)
		(layer "In6.Cu")
		(net "M_K_CPU0_SA_DQ<11>")
	)
	(gr_poly
		(pts
			(xy 392.250676 -254.406146) (xy 392.1506 -254.30607) (xy 392.050778 -254.406146) (xy 392.050778 -254.450596)
			(xy 392.250676 -254.450596)
		)
		(stroke
			(width 0)
			(type solid)
		)
		(fill yes)
		(layer "In6.Cu")
		(net "M_K_CPU0_SA_CA<4>")
	)
	(gr_poly
		(pts
			(xy 392.250676 -252.786134) (xy 392.1506 -252.686058) (xy 392.050778 -252.786134) (xy 392.050778 -252.830584)
			(xy 392.250676 -252.830584)
		)
		(stroke
			(width 0)
			(type solid)
		)
		(fill yes)
		(layer "In6.Cu")
		(net "M_K_CPU0_SA_CA<0>")
	)
	(gr_poly
		(pts
			(xy 392.250676 -251.166122) (xy 392.1506 -251.066046) (xy 392.050778 -251.166122) (xy 392.050778 -251.210572)
			(xy 392.250676 -251.210572)
		)
		(stroke
			(width 0)
			(type solid)
		)
		(fill yes)
		(layer "In6.Cu")
		(net "M_K_CPU0_SA_CS_N<0>")
	)
	(gr_poly
		(pts
			(xy 392.250676 -247.926098) (xy 392.1506 -247.826022) (xy 392.050778 -247.926098) (xy 392.050778 -247.970548)
			(xy 392.250676 -247.970548)
		)
		(stroke
			(width 0)
			(type solid)
		)
		(fill yes)
		(layer "In6.Cu")
		(net "M_K_CPU0_SA_CB<4>")
	)
	(gr_poly
		(pts
			(xy 392.250676 -246.305832) (xy 392.1506 -246.20601) (xy 392.050778 -246.305832) (xy 392.050778 -246.353584)
			(xy 392.250676 -246.353584)
		)
		(stroke
			(width 0)
			(type solid)
		)
		(fill yes)
		(layer "In6.Cu")
		(net "M_K_CPU0_SA_DQS_DP<4>")
	)
	(gr_poly
		(pts
			(xy 392.250676 -245.902226) (xy 392.250676 -245.857776) (xy 392.050778 -245.857776) (xy 392.050778 -245.902226)
			(xy 392.1506 -246.002302)
		)
		(stroke
			(width 0)
			(type solid)
		)
		(fill yes)
		(layer "In6.Cu")
		(net "M_K_CPU0_SA_CB<3>")
	)
	(gr_poly
		(pts
			(xy 392.250676 -244.686074) (xy 392.1506 -244.585998) (xy 392.050778 -244.686074) (xy 392.050778 -244.730524)
			(xy 392.250676 -244.730524)
		)
		(stroke
			(width 0)
			(type solid)
		)
		(fill yes)
		(layer "In6.Cu")
		(net "M_K_CPU0_SA_CB<0>")
	)
	(gr_poly
		(pts
			(xy 392.250676 -243.066062) (xy 392.1506 -242.965986) (xy 392.050778 -243.066062) (xy 392.050778 -243.110512)
			(xy 392.250676 -243.110512)
		)
		(stroke
			(width 0)
			(type solid)
		)
		(fill yes)
		(layer "In6.Cu")
		(net "M_K_CPU0_SA_DQ<28>")
	)
	(gr_poly
		(pts
			(xy 392.250676 -241.445796) (xy 392.1506 -241.345974) (xy 392.050778 -241.445796) (xy 392.050778 -241.493548)
			(xy 392.250676 -241.493548)
		)
		(stroke
			(width 0)
			(type solid)
		)
		(fill yes)
		(layer "In6.Cu")
		(net "M_K_CPU0_SA_DQS_DP<3>")
	)
	(gr_poly
		(pts
			(xy 392.250676 -239.826038) (xy 392.1506 -239.725962) (xy 392.050778 -239.826038) (xy 392.050778 -239.870488)
			(xy 392.250676 -239.870488)
		)
		(stroke
			(width 0)
			(type solid)
		)
		(fill yes)
		(layer "In6.Cu")
		(net "M_K_CPU0_SA_DQ<24>")
	)
	(gr_poly
		(pts
			(xy 392.250676 -238.206026) (xy 392.1506 -238.10595) (xy 392.050778 -238.206026) (xy 392.050778 -238.250476)
			(xy 392.250676 -238.250476)
		)
		(stroke
			(width 0)
			(type solid)
		)
		(fill yes)
		(layer "In6.Cu")
		(net "M_K_CPU0_SA_DQ<20>")
	)
	(gr_poly
		(pts
			(xy 392.250676 -236.58576) (xy 392.1506 -236.485938) (xy 392.050778 -236.58576) (xy 392.050778 -236.633512)
			(xy 392.250676 -236.633512)
		)
		(stroke
			(width 0)
			(type solid)
		)
		(fill yes)
		(layer "In6.Cu")
		(net "M_K_CPU0_SA_DQS_DP<2>")
	)
	(gr_poly
		(pts
			(xy 392.250676 -234.966002) (xy 392.1506 -234.865926) (xy 392.050778 -234.966002) (xy 392.050778 -235.010452)
			(xy 392.250676 -235.010452)
		)
		(stroke
			(width 0)
			(type solid)
		)
		(fill yes)
		(layer "In6.Cu")
		(net "M_K_CPU0_SA_DQ<16>")
	)
	(gr_poly
		(pts
			(xy 392.250676 -233.34599) (xy 392.1506 -233.245914) (xy 392.050778 -233.34599) (xy 392.050778 -233.39044)
			(xy 392.250676 -233.39044)
		)
		(stroke
			(width 0)
			(type solid)
		)
		(fill yes)
		(layer "In6.Cu")
		(net "M_K_CPU0_SA_DQ<12>")
	)
	(gr_poly
		(pts
			(xy 392.250676 -232.942384) (xy 392.250676 -232.894632) (xy 392.050778 -232.894632) (xy 392.050778 -232.942384)
			(xy 392.1506 -233.042206)
		)
		(stroke
			(width 0)
			(type solid)
		)
		(fill yes)
		(layer "In6.Cu")
		(net "M_K_CPU0_SA_DQS_DP<6>")
	)
	(gr_poly
		(pts
			(xy 392.250676 -231.725724) (xy 392.1506 -231.625902) (xy 392.050778 -231.725724) (xy 392.050778 -231.773476)
			(xy 392.250676 -231.773476)
		)
		(stroke
			(width 0)
			(type solid)
		)
		(fill yes)
		(layer "In6.Cu")
		(net "M_K_CPU0_SA_DQS_DP<1>")
	)
	(gr_poly
		(pts
			(xy 392.262868 -224.844356) (xy 392.299698 -224.707704) (xy 392.163046 -224.671128) (xy 392.121644 -224.695004)
			(xy 392.22172 -224.868232)
		)
		(stroke
			(width 0)
			(type solid)
		)
		(fill yes)
		(layer "In6.Cu")
		(net "M_K_CPU0_SA_DQ<3>")
	)
	(gr_poly
		(pts
			(xy 392.299698 -225.380804) (xy 392.262868 -225.244152) (xy 392.22172 -225.220276) (xy 392.121644 -225.393504)
			(xy 392.163046 -225.41738)
		)
		(stroke
			(width 0)
			(type solid)
		)
		(fill yes)
		(layer "In6.Cu")
		(net "M_K_CPU0_SA_DQ<3>")
	)
	(gr_poly
		(pts
			(xy 392.300714 -226.999292) (xy 392.264138 -226.862894) (xy 392.222736 -226.839018) (xy 392.122914 -227.012246)
			(xy 392.164062 -227.035868)
		)
		(stroke
			(width 0)
			(type solid)
		)
		(fill yes)
		(layer "In6.Cu")
		(net "M_K_CPU0_SA_DQS_DN<0>")
	)
	(gr_poly
		(pts
			(xy 392.300714 -223.75876) (xy 392.264138 -223.622108) (xy 392.225784 -223.599756) (xy 392.125708 -223.772984)
			(xy 392.164316 -223.795336)
		)
		(stroke
			(width 0)
			(type solid)
		)
		(fill yes)
		(layer "In6.Cu")
		(net "M_K_CPU0_SA_DQ<3>")
	)
	(gr_poly
		(pts
			(xy 392.300714 -222.138748) (xy 392.263884 -222.002096) (xy 392.22553 -221.979744) (xy 392.125454 -222.152972)
			(xy 392.164062 -222.175324)
		)
		(stroke
			(width 0)
			(type solid)
		)
		(fill yes)
		(layer "In6.Cu")
		(net "M_K_CPU0_SA_DQ<2>")
	)
	(gr_poly
		(pts
			(xy 392.463782 -294.684704) (xy 392.363706 -294.511476) (xy 392.325352 -294.533828) (xy 392.288522 -294.67048)
			(xy 392.425174 -294.707056)
		)
		(stroke
			(width 0)
			(type solid)
		)
		(fill yes)
		(layer "In6.Cu")
		(net "M_K_CPU0_SB_DQ<31>")
	)
	(gr_poly
		(pts
			(xy 392.464036 -293.064692) (xy 392.36396 -292.891464) (xy 392.325606 -292.913816) (xy 392.28903 -293.050468)
			(xy 392.425428 -293.087044)
		)
		(stroke
			(width 0)
			(type solid)
		)
		(fill yes)
		(layer "In6.Cu")
		(net "M_K_CPU0_SB_DQ<30>")
	)
	(gr_poly
		(pts
			(xy 392.464036 -269.687294) (xy 392.425428 -269.664942) (xy 392.28903 -269.701518) (xy 392.325606 -269.83817)
			(xy 392.36396 -269.860522)
		)
		(stroke
			(width 0)
			(type solid)
		)
		(fill yes)
		(layer "In6.Cu")
		(net "M_K_CPU0_SB_CB<5>")
	)
	(gr_poly
		(pts
			(xy 392.532108 -271.454118) (xy 392.532108 -271.40662) (xy 392.33221 -271.40662) (xy 392.33221 -271.454118)
			(xy 392.432032 -271.554194)
		)
		(stroke
			(width 0)
			(type solid)
		)
		(fill yes)
		(layer "In6.Cu")
		(net "M_K_CPU0_SB_DQS_DN<9>")
	)
	(gr_poly
		(pts
			(xy 392.538458 -290.894262) (xy 392.538458 -290.84651) (xy 392.33856 -290.84651) (xy 392.33856 -290.894262)
			(xy 392.438636 -290.994084)
		)
		(stroke
			(width 0)
			(type solid)
		)
		(fill yes)
		(layer "In6.Cu")
		(net "M_K_CPU0_SB_DQS_DN<3>")
	)
	(gr_poly
		(pts
			(xy 392.538458 -286.03448) (xy 392.538458 -285.986728) (xy 392.33856 -285.986728) (xy 392.33856 -286.03448)
			(xy 392.438636 -286.134302)
		)
		(stroke
			(width 0)
			(type solid)
		)
		(fill yes)
		(layer "In6.Cu")
		(net "M_K_CPU0_SB_DQS_DN<2>")
	)
	(gr_poly
		(pts
			(xy 392.538458 -281.174444) (xy 392.538458 -281.126692) (xy 392.33856 -281.126692) (xy 392.33856 -281.174444)
			(xy 392.438636 -281.274266)
		)
		(stroke
			(width 0)
			(type solid)
		)
		(fill yes)
		(layer "In6.Cu")
		(net "M_K_CPU0_SB_DQS_DN<1>")
	)
	(gr_poly
		(pts
			(xy 392.538458 -276.314408) (xy 392.538458 -276.266656) (xy 392.33856 -276.266656) (xy 392.33856 -276.314408)
			(xy 392.438636 -276.41423)
		)
		(stroke
			(width 0)
			(type solid)
		)
		(fill yes)
		(layer "In6.Cu")
		(net "M_K_CPU0_SB_DQS_DN<0>")
	)
	(gr_poly
		(pts
			(xy 392.544808 -268.617954) (xy 392.444732 -268.517878) (xy 392.344656 -268.617954) (xy 392.344656 -268.662404)
			(xy 392.544808 -268.662404)
		)
		(stroke
			(width 0)
			(type solid)
		)
		(fill yes)
		(layer "In6.Cu")
		(net "M_K_CPU0_SB_CB<4>")
	)
	(gr_poly
		(pts
			(xy 392.550396 -291.297614) (xy 392.45032 -291.197792) (xy 392.350498 -291.297614) (xy 392.350498 -291.345366)
			(xy 392.550396 -291.345366)
		)
		(stroke
			(width 0)
			(type solid)
		)
		(fill yes)
		(layer "In6.Cu")
		(net "M_K_CPU0_SB_DQS_DN<8>")
	)
	(gr_poly
		(pts
			(xy 392.550396 -284.818074) (xy 392.45032 -284.717998) (xy 392.350498 -284.818074) (xy 392.350498 -284.862524)
			(xy 392.550396 -284.862524)
		)
		(stroke
			(width 0)
			(type solid)
		)
		(fill yes)
		(layer "In6.Cu")
		(net "M_K_CPU0_SB_DQ<17>")
	)
	(gr_poly
		(pts
			(xy 392.550396 -283.198062) (xy 392.45032 -283.097986) (xy 392.350498 -283.198062) (xy 392.350498 -283.242512)
			(xy 392.550396 -283.242512)
		)
		(stroke
			(width 0)
			(type solid)
		)
		(fill yes)
		(layer "In6.Cu")
		(net "M_K_CPU0_SB_DQ<13>")
	)
	(gr_poly
		(pts
			(xy 392.550396 -281.577796) (xy 392.45032 -281.477974) (xy 392.350498 -281.577796) (xy 392.350498 -281.625548)
			(xy 392.550396 -281.625548)
		)
		(stroke
			(width 0)
			(type solid)
		)
		(fill yes)
		(layer "In6.Cu")
		(net "M_K_CPU0_SB_DQS_DN<6>")
	)
	(gr_poly
		(pts
			(xy 392.550396 -279.958038) (xy 392.45032 -279.857962) (xy 392.350498 -279.958038) (xy 392.350498 -280.002488)
			(xy 392.550396 -280.002488)
		)
		(stroke
			(width 0)
			(type solid)
		)
		(fill yes)
		(layer "In6.Cu")
		(net "M_K_CPU0_SB_DQ<9>")
	)
	(gr_poly
		(pts
			(xy 392.550396 -278.338026) (xy 392.45032 -278.23795) (xy 392.350498 -278.338026) (xy 392.350498 -278.382476)
			(xy 392.550396 -278.382476)
		)
		(stroke
			(width 0)
			(type solid)
		)
		(fill yes)
		(layer "In6.Cu")
		(net "M_K_CPU0_SB_DQ<5>")
	)
	(gr_poly
		(pts
			(xy 392.550396 -276.71776) (xy 392.45032 -276.617938) (xy 392.350498 -276.71776) (xy 392.350498 -276.765512)
			(xy 392.550396 -276.765512)
		)
		(stroke
			(width 0)
			(type solid)
		)
		(fill yes)
		(layer "In6.Cu")
		(net "M_K_CPU0_SB_DQS_DN<5>")
	)
	(gr_poly
		(pts
			(xy 392.550396 -275.098002) (xy 392.45032 -274.997926) (xy 392.350498 -275.098002) (xy 392.350498 -275.142452)
			(xy 392.550396 -275.142452)
		)
		(stroke
			(width 0)
			(type solid)
		)
		(fill yes)
		(layer "In6.Cu")
		(net "M_K_CPU0_SB_DQ<1>")
	)
	(gr_poly
		(pts
			(xy 392.550396 -273.47799) (xy 392.45032 -273.377914) (xy 392.350498 -273.47799) (xy 392.350498 -273.52244)
			(xy 392.550396 -273.52244)
		)
		(stroke
			(width 0)
			(type solid)
		)
		(fill yes)
		(layer "In6.Cu")
		(net "M_K_CPU0_SB_CB<1>")
	)
	(gr_poly
		(pts
			(xy 392.550396 -266.997942) (xy 392.45032 -266.897866) (xy 392.350498 -266.997942) (xy 392.350498 -267.042392)
			(xy 392.550396 -267.042392)
		)
		(stroke
			(width 0)
			(type solid)
		)
		(fill yes)
		(layer "In6.Cu")
		(net "M_K_CPU0_SA_RSP<0>")
	)
	(gr_poly
		(pts
			(xy 392.550396 -265.37793) (xy 392.45032 -265.277854) (xy 392.350498 -265.37793) (xy 392.350498 -265.42238)
			(xy 392.550396 -265.42238)
		)
		(stroke
			(width 0)
			(type solid)
		)
		(fill yes)
		(layer "In6.Cu")
		(net "M_K_CPU0_SB_PAR")
	)
	(gr_poly
		(pts
			(xy 392.550396 -263.757918) (xy 392.45032 -263.657842) (xy 392.350498 -263.757918) (xy 392.350498 -263.802368)
			(xy 392.550396 -263.802368)
		)
		(stroke
			(width 0)
			(type solid)
		)
		(fill yes)
		(layer "In6.Cu")
		(net "M_K_CPU0_SB_CA<4>")
	)
	(gr_poly
		(pts
			(xy 392.550396 -262.137906) (xy 392.45032 -262.03783) (xy 392.350498 -262.137906) (xy 392.350498 -262.182356)
			(xy 392.550396 -262.182356)
		)
		(stroke
			(width 0)
			(type solid)
		)
		(fill yes)
		(layer "In6.Cu")
		(net "M_K_CPU0_SB_CA<0>")
	)
	(gr_poly
		(pts
			(xy 392.55065 -284.414214) (xy 392.55065 -284.369764) (xy 392.350498 -284.369764) (xy 392.350498 -284.414214)
			(xy 392.450574 -284.51429)
		)
		(stroke
			(width 0)
			(type solid)
		)
		(fill yes)
		(layer "In6.Cu")
		(net "M_K_CPU0_SB_DQ<18>")
	)
	(gr_poly
		(pts
			(xy 392.55065 -282.794202) (xy 392.55065 -282.749752) (xy 392.350498 -282.749752) (xy 392.350498 -282.794202)
			(xy 392.450574 -282.894278)
		)
		(stroke
			(width 0)
			(type solid)
		)
		(fill yes)
		(layer "In6.Cu")
		(net "M_K_CPU0_SB_DQ<14>")
	)
	(gr_poly
		(pts
			(xy 392.55065 -279.554178) (xy 392.55065 -279.509728) (xy 392.350498 -279.509728) (xy 392.350498 -279.554178)
			(xy 392.450574 -279.654254)
		)
		(stroke
			(width 0)
			(type solid)
		)
		(fill yes)
		(layer "In6.Cu")
		(net "M_K_CPU0_SB_DQ<10>")
	)
	(gr_poly
		(pts
			(xy 392.55065 -277.934166) (xy 392.55065 -277.889716) (xy 392.350498 -277.889716) (xy 392.350498 -277.934166)
			(xy 392.450574 -278.034242)
		)
		(stroke
			(width 0)
			(type solid)
		)
		(fill yes)
		(layer "In6.Cu")
		(net "M_K_CPU0_SB_DQ<6>")
	)
	(gr_poly
		(pts
			(xy 392.55065 -274.694142) (xy 392.55065 -274.649692) (xy 392.350498 -274.649692) (xy 392.350498 -274.694142)
			(xy 392.450574 -274.794218)
		)
		(stroke
			(width 0)
			(type solid)
		)
		(fill yes)
		(layer "In6.Cu")
		(net "M_K_CPU0_SB_DQ<2>")
	)
	(gr_poly
		(pts
			(xy 392.55065 -273.07413) (xy 392.55065 -273.02968) (xy 392.350498 -273.02968) (xy 392.350498 -273.07413)
			(xy 392.450574 -273.174206)
		)
		(stroke
			(width 0)
			(type solid)
		)
		(fill yes)
		(layer "In6.Cu")
		(net "M_K_CPU0_SB_CB<2>")
	)
	(gr_poly
		(pts
			(xy 392.55065 -266.594082) (xy 392.55065 -266.549632) (xy 392.350498 -266.549632) (xy 392.350498 -266.594082)
			(xy 392.450574 -266.694158)
		)
		(stroke
			(width 0)
			(type solid)
		)
		(fill yes)
		(layer "In6.Cu")
		(net "M_K_CPU0_SB_CS_N<1>")
	)
	(gr_poly
		(pts
			(xy 392.55065 -263.354058) (xy 392.55065 -263.309608) (xy 392.350498 -263.309608) (xy 392.350498 -263.354058)
			(xy 392.450574 -263.454134)
		)
		(stroke
			(width 0)
			(type solid)
		)
		(fill yes)
		(layer "In6.Cu")
		(net "M_K_CPU0_SB_CA<3>")
	)
	(gr_poly
		(pts
			(xy 392.555476 -271.857724) (xy 392.4554 -271.757648) (xy 392.355578 -271.857724) (xy 392.355578 -271.905222)
			(xy 392.555476 -271.905222)
		)
		(stroke
			(width 0)
			(type solid)
		)
		(fill yes)
		(layer "In6.Cu")
		(net "M_K_CPU0_SB_DQS_DN<4>")
	)
	(gr_poly
		(pts
			(xy 392.563858 -294.138096) (xy 392.600434 -294.001444) (xy 392.464036 -293.964868) (xy 392.425428 -293.98722)
			(xy 392.525504 -294.160448)
		)
		(stroke
			(width 0)
			(type solid)
		)
		(fill yes)
		(layer "In6.Cu")
		(net "M_K_CPU0_SB_DQ<29>")
	)
	(gr_poly
		(pts
			(xy 392.564112 -292.518084) (xy 392.600942 -292.381432) (xy 392.46429 -292.344856) (xy 392.425682 -292.367208)
			(xy 392.525758 -292.540436)
		)
		(stroke
			(width 0)
			(type solid)
		)
		(fill yes)
		(layer "In6.Cu")
		(net "M_K_CPU0_SB_DQ<28>")
	)
	(gr_poly
		(pts
			(xy 392.600942 -270.370554) (xy 392.564112 -270.233902) (xy 392.525758 -270.21155) (xy 392.425682 -270.384778)
			(xy 392.46429 -270.40713)
		)
		(stroke
			(width 0)
			(type solid)
		)
		(fill yes)
		(layer "In6.Cu")
		(net "M_K_CPU0_SB_CB<7>")
	)
	(gr_poly
		(pts
			(xy 392.634216 -222.265494) (xy 392.595608 -222.243142) (xy 392.45921 -222.279718) (xy 392.495786 -222.41637)
			(xy 392.53414 -222.438722)
		)
		(stroke
			(width 0)
			(type solid)
		)
		(fill yes)
		(layer "In6.Cu")
		(net "M_K_CPU0_SA_DQ<1>")
	)
	(gr_poly
		(pts
			(xy 392.636756 -225.50628) (xy 392.595608 -225.482404) (xy 392.458956 -225.519234) (xy 392.495532 -225.655632)
			(xy 392.536934 -225.679508)
		)
		(stroke
			(width 0)
			(type solid)
		)
		(fill yes)
		(layer "In6.Cu")
		(net "M_K_CPU0_SA_DQS_DP<0>")
	)
	(gr_poly
		(pts
			(xy 392.720068 -251.976128) (xy 392.619992 -251.876052) (xy 392.52017 -251.976128) (xy 392.52017 -252.020578)
			(xy 392.720068 -252.020578)
		)
		(stroke
			(width 0)
			(type solid)
		)
		(fill yes)
		(layer "In6.Cu")
		(net "M_K_CPU0_SA_CS_N<1>")
	)
	(gr_poly
		(pts
			(xy 392.720322 -255.216152) (xy 392.620246 -255.116076) (xy 392.52017 -255.216152) (xy 392.52017 -255.260602)
			(xy 392.720322 -255.260602)
		)
		(stroke
			(width 0)
			(type solid)
		)
		(fill yes)
		(layer "In6.Cu")
		(net "M_K_CPU0_SA_CA<6>")
	)
	(gr_poly
		(pts
			(xy 392.720322 -253.59614) (xy 392.620246 -253.496064) (xy 392.52017 -253.59614) (xy 392.52017 -253.64059)
			(xy 392.720322 -253.64059)
		)
		(stroke
			(width 0)
			(type solid)
		)
		(fill yes)
		(layer "In6.Cu")
		(net "M_K_CPU0_SA_CA<2>")
	)
	(gr_poly
		(pts
			(xy 392.720322 -250.356116) (xy 392.620246 -250.25604) (xy 392.52017 -250.356116) (xy 392.52017 -250.400566)
			(xy 392.720322 -250.400566)
		)
		(stroke
			(width 0)
			(type solid)
		)
		(fill yes)
		(layer "In6.Cu")
		(net "M_K_CPU0_ALERT_R_N")
	)
	(gr_poly
		(pts
			(xy 392.720322 -248.736104) (xy 392.620246 -248.636028) (xy 392.52017 -248.736104) (xy 392.52017 -248.780554)
			(xy 392.720322 -248.780554)
		)
		(stroke
			(width 0)
			(type solid)
		)
		(fill yes)
		(layer "In6.Cu")
		(net "M_K_CPU0_SA_CB<5>")
	)
	(gr_poly
		(pts
			(xy 392.720322 -247.115838) (xy 392.620246 -247.015762) (xy 392.52017 -247.115838) (xy 392.52017 -247.163336)
			(xy 392.720322 -247.163336)
		)
		(stroke
			(width 0)
			(type solid)
		)
		(fill yes)
		(layer "In6.Cu")
		(net "M_K_CPU0_SA_DQS_DN<9>")
	)
	(gr_poly
		(pts
			(xy 392.720322 -243.876068) (xy 392.620246 -243.775992) (xy 392.52017 -243.876068) (xy 392.52017 -243.920518)
			(xy 392.720322 -243.920518)
		)
		(stroke
			(width 0)
			(type solid)
		)
		(fill yes)
		(layer "In6.Cu")
		(net "M_K_CPU0_SA_DQ<29>")
	)
	(gr_poly
		(pts
			(xy 392.720322 -242.255802) (xy 392.620246 -242.155726) (xy 392.52017 -242.255802) (xy 392.52017 -242.3033)
			(xy 392.720322 -242.3033)
		)
		(stroke
			(width 0)
			(type solid)
		)
		(fill yes)
		(layer "In6.Cu")
		(net "M_K_CPU0_SA_DQS_DN<8>")
	)
	(gr_poly
		(pts
			(xy 392.720322 -240.636044) (xy 392.620246 -240.535968) (xy 392.52017 -240.636044) (xy 392.52017 -240.680494)
			(xy 392.720322 -240.680494)
		)
		(stroke
			(width 0)
			(type solid)
		)
		(fill yes)
		(layer "In6.Cu")
		(net "M_K_CPU0_SA_DQ<25>")
	)
	(gr_poly
		(pts
			(xy 392.720322 -239.016032) (xy 392.620246 -238.915956) (xy 392.52017 -239.016032) (xy 392.52017 -239.060482)
			(xy 392.720322 -239.060482)
		)
		(stroke
			(width 0)
			(type solid)
		)
		(fill yes)
		(layer "In6.Cu")
		(net "M_K_CPU0_SA_DQ<21>")
	)
	(gr_poly
		(pts
			(xy 392.720322 -235.776008) (xy 392.620246 -235.675932) (xy 392.52017 -235.776008) (xy 392.52017 -235.820458)
			(xy 392.720322 -235.820458)
		)
		(stroke
			(width 0)
			(type solid)
		)
		(fill yes)
		(layer "In6.Cu")
		(net "M_K_CPU0_SA_DQ<17>")
	)
	(gr_poly
		(pts
			(xy 392.720322 -234.155996) (xy 392.620246 -234.05592) (xy 392.52017 -234.155996) (xy 392.52017 -234.200446)
			(xy 392.720322 -234.200446)
		)
		(stroke
			(width 0)
			(type solid)
		)
		(fill yes)
		(layer "In6.Cu")
		(net "M_K_CPU0_SA_DQ<13>")
	)
	(gr_poly
		(pts
			(xy 392.720576 -254.812292) (xy 392.720576 -254.767842) (xy 392.520678 -254.767842) (xy 392.520678 -254.812292)
			(xy 392.6205 -254.912368)
		)
		(stroke
			(width 0)
			(type solid)
		)
		(fill yes)
		(layer "In6.Cu")
		(net "M_K_CPU0_SA_CA<5>")
	)
	(gr_poly
		(pts
			(xy 392.720576 -253.19228) (xy 392.720576 -253.14783) (xy 392.520678 -253.14783) (xy 392.520678 -253.19228)
			(xy 392.6205 -253.292356)
		)
		(stroke
			(width 0)
			(type solid)
		)
		(fill yes)
		(layer "In6.Cu")
		(net "M_K_CPU0_SA_CA<1>")
	)
	(gr_poly
		(pts
			(xy 392.720576 -248.332244) (xy 392.720576 -248.287794) (xy 392.520678 -248.287794) (xy 392.520678 -248.332244)
			(xy 392.6205 -248.43232)
		)
		(stroke
			(width 0)
			(type solid)
		)
		(fill yes)
		(layer "In6.Cu")
		(net "M_K_CPU0_SA_CB<6>")
	)
	(gr_poly
		(pts
			(xy 392.720576 -246.712486) (xy 392.720576 -246.664988) (xy 392.520678 -246.664988) (xy 392.520678 -246.712486)
			(xy 392.6205 -246.812562)
		)
		(stroke
			(width 0)
			(type solid)
		)
		(fill yes)
		(layer "In6.Cu")
		(net "M_K_CPU0_SA_DQS_DN<4>")
	)
	(gr_poly
		(pts
			(xy 392.720576 -245.49608) (xy 392.6205 -245.396004) (xy 392.520678 -245.49608) (xy 392.520678 -245.54053)
			(xy 392.720576 -245.54053)
		)
		(stroke
			(width 0)
			(type solid)
		)
		(fill yes)
		(layer "In6.Cu")
		(net "M_K_CPU0_SA_CB<1>")
	)
	(gr_poly
		(pts
			(xy 392.720576 -245.09222) (xy 392.720576 -245.04777) (xy 392.520678 -245.04777) (xy 392.520678 -245.09222)
			(xy 392.6205 -245.192296)
		)
		(stroke
			(width 0)
			(type solid)
		)
		(fill yes)
		(layer "In6.Cu")
		(net "M_K_CPU0_SA_CB<2>")
	)
	(gr_poly
		(pts
			(xy 392.720576 -243.472208) (xy 392.720576 -243.427758) (xy 392.520678 -243.427758) (xy 392.520678 -243.472208)
			(xy 392.6205 -243.572284)
		)
		(stroke
			(width 0)
			(type solid)
		)
		(fill yes)
		(layer "In6.Cu")
		(net "M_K_CPU0_SA_DQ<30>")
	)
	(gr_poly
		(pts
			(xy 392.720576 -241.85245) (xy 392.720576 -241.804952) (xy 392.520678 -241.804952) (xy 392.520678 -241.85245)
			(xy 392.6205 -241.952526)
		)
		(stroke
			(width 0)
			(type solid)
		)
		(fill yes)
		(layer "In6.Cu")
		(net "M_K_CPU0_SA_DQS_DN<3>")
	)
	(gr_poly
		(pts
			(xy 392.720576 -240.232184) (xy 392.720576 -240.187734) (xy 392.520678 -240.187734) (xy 392.520678 -240.232184)
			(xy 392.6205 -240.33226)
		)
		(stroke
			(width 0)
			(type solid)
		)
		(fill yes)
		(layer "In6.Cu")
		(net "M_K_CPU0_SA_DQ<26>")
	)
	(gr_poly
		(pts
			(xy 392.720576 -238.612172) (xy 392.720576 -238.567722) (xy 392.520678 -238.567722) (xy 392.520678 -238.612172)
			(xy 392.6205 -238.712248)
		)
		(stroke
			(width 0)
			(type solid)
		)
		(fill yes)
		(layer "In6.Cu")
		(net "M_K_CPU0_SA_DQ<22>")
	)
	(gr_poly
		(pts
			(xy 392.720576 -236.992414) (xy 392.720576 -236.944916) (xy 392.520678 -236.944916) (xy 392.520678 -236.992414)
			(xy 392.6205 -237.09249)
		)
		(stroke
			(width 0)
			(type solid)
		)
		(fill yes)
		(layer "In6.Cu")
		(net "M_K_CPU0_SA_DQS_DN<2>")
	)
	(gr_poly
		(pts
			(xy 392.720576 -235.372148) (xy 392.720576 -235.327698) (xy 392.520678 -235.327698) (xy 392.520678 -235.372148)
			(xy 392.6205 -235.472224)
		)
		(stroke
			(width 0)
			(type solid)
		)
		(fill yes)
		(layer "In6.Cu")
		(net "M_K_CPU0_SA_DQ<18>")
	)
	(gr_poly
		(pts
			(xy 392.720576 -233.752136) (xy 392.720576 -233.707686) (xy 392.520678 -233.707686) (xy 392.520678 -233.752136)
			(xy 392.6205 -233.852212)
		)
		(stroke
			(width 0)
			(type solid)
		)
		(fill yes)
		(layer "In6.Cu")
		(net "M_K_CPU0_SA_DQ<14>")
	)
	(gr_poly
		(pts
			(xy 392.720576 -232.53573) (xy 392.6205 -232.435654) (xy 392.520678 -232.53573) (xy 392.520678 -232.583228)
			(xy 392.720576 -232.583228)
		)
		(stroke
			(width 0)
			(type solid)
		)
		(fill yes)
		(layer "In6.Cu")
		(net "M_K_CPU0_SA_DQS_DN<6>")
	)
	(gr_poly
		(pts
			(xy 392.720576 -232.132378) (xy 392.720576 -232.08488) (xy 392.520678 -232.08488) (xy 392.520678 -232.132378)
			(xy 392.6205 -232.232454)
		)
		(stroke
			(width 0)
			(type solid)
		)
		(fill yes)
		(layer "In6.Cu")
		(net "M_K_CPU0_SA_DQS_DN<1>")
	)
	(gr_poly
		(pts
			(xy 392.722862 -237.396274) (xy 392.62304 -237.296198) (xy 392.522964 -237.396274) (xy 392.522964 -237.443772)
			(xy 392.722862 -237.443772)
		)
		(stroke
			(width 0)
			(type solid)
		)
		(fill yes)
		(layer "In6.Cu")
		(net "M_K_CPU0_SA_DQS_DN<7>")
	)
	(gr_poly
		(pts
			(xy 392.723116 -256.432558) (xy 392.723116 -256.38506) (xy 392.523218 -256.38506) (xy 392.523218 -256.432558)
			(xy 392.62304 -256.532634)
		)
		(stroke
			(width 0)
			(type solid)
		)
		(fill yes)
		(layer "In6.Cu")
		(net "M_K_CPU0_CLK_DN<0>")
	)
	(gr_poly
		(pts
			(xy 392.770614 -226.189286) (xy 392.734038 -226.052888) (xy 392.692636 -226.029012) (xy 392.592814 -226.20224)
			(xy 392.633962 -226.226116)
		)
		(stroke
			(width 0)
			(type solid)
		)
		(fill yes)
		(layer "In6.Cu")
		(net "M_K_CPU0_SA_DQS_DN<0>")
	)
	(gr_poly
		(pts
			(xy 392.770614 -222.948754) (xy 392.734038 -222.812102) (xy 392.695684 -222.78975) (xy 392.595608 -222.962978)
			(xy 392.634216 -222.98533)
		)
		(stroke
			(width 0)
			(type solid)
		)
		(fill yes)
		(layer "In6.Cu")
		(net "M_K_CPU0_SA_DQ<3>")
	)
	(gr_poly
		(pts
			(xy 392.930888 -295.505378) (xy 392.830812 -295.33215) (xy 392.792458 -295.354502) (xy 392.755882 -295.491154)
			(xy 392.89228 -295.52773)
		)
		(stroke
			(width 0)
			(type solid)
		)
		(fill yes)
		(layer "In6.Cu")
		(net "M_K_CPU0_SB_DQ<31>")
	)
	(gr_poly
		(pts
			(xy 392.933936 -293.874698) (xy 392.83386 -293.70147) (xy 392.795506 -293.723822) (xy 392.75893 -293.860474)
			(xy 392.895328 -293.89705)
		)
		(stroke
			(width 0)
			(type solid)
		)
		(fill yes)
		(layer "In6.Cu")
		(net "M_K_CPU0_SB_DQ<30>")
	)
	(gr_poly
		(pts
			(xy 393.014962 -269.42796) (xy 392.914886 -269.327884) (xy 392.81481 -269.42796) (xy 392.81481 -269.47241)
			(xy 393.014962 -269.47241)
		)
		(stroke
			(width 0)
			(type solid)
		)
		(fill yes)
		(layer "In6.Cu")
		(net "M_K_CPU0_SB_CB<5>")
	)
	(gr_poly
		(pts
			(xy 393.014962 -269.0241) (xy 393.014962 -268.97965) (xy 392.81481 -268.97965) (xy 392.81481 -269.0241)
			(xy 392.914886 -269.124176)
		)
		(stroke
			(width 0)
			(type solid)
		)
		(fill yes)
		(layer "In6.Cu")
		(net "M_K_CPU0_SB_CB<6>")
	)
	(gr_poly
		(pts
			(xy 393.015216 -277.527766) (xy 392.91514 -277.427944) (xy 392.815318 -277.527766) (xy 392.815318 -277.572216)
			(xy 393.015216 -277.572216)
		)
		(stroke
			(width 0)
			(type solid)
		)
		(fill yes)
		(layer "In6.Cu")
		(net "M_K_CPU0_SB_DQ<4>")
	)
	(gr_poly
		(pts
			(xy 393.016232 -281.983942) (xy 393.016232 -281.936444) (xy 392.816334 -281.936444) (xy 392.816334 -281.983942)
			(xy 392.916156 -282.084018)
		)
		(stroke
			(width 0)
			(type solid)
		)
		(fill yes)
		(layer "In6.Cu")
		(net "M_K_CPU0_SB_DQS_DP<6>")
	)
	(gr_poly
		(pts
			(xy 393.020296 -285.22422) (xy 393.020296 -285.17977) (xy 392.820398 -285.17977) (xy 392.820398 -285.22422)
			(xy 392.92022 -285.324296)
		)
		(stroke
			(width 0)
			(type solid)
		)
		(fill yes)
		(layer "In6.Cu")
		(net "M_K_CPU0_SB_DQ<19>")
	)
	(gr_poly
		(pts
			(xy 393.020296 -283.604208) (xy 393.020296 -283.559758) (xy 392.820398 -283.559758) (xy 392.820398 -283.604208)
			(xy 392.92022 -283.704284)
		)
		(stroke
			(width 0)
			(type solid)
		)
		(fill yes)
		(layer "In6.Cu")
		(net "M_K_CPU0_SB_DQ<15>")
	)
	(gr_poly
		(pts
			(xy 393.020296 -280.364184) (xy 393.020296 -280.319734) (xy 392.820398 -280.319734) (xy 392.820398 -280.364184)
			(xy 392.92022 -280.46426)
		)
		(stroke
			(width 0)
			(type solid)
		)
		(fill yes)
		(layer "In6.Cu")
		(net "M_K_CPU0_SB_DQ<11>")
	)
	(gr_poly
		(pts
			(xy 393.020296 -278.744172) (xy 393.020296 -278.699722) (xy 392.820398 -278.699722) (xy 392.820398 -278.744172)
			(xy 392.92022 -278.844248)
		)
		(stroke
			(width 0)
			(type solid)
		)
		(fill yes)
		(layer "In6.Cu")
		(net "M_K_CPU0_SB_DQ<7>")
	)
	(gr_poly
		(pts
			(xy 393.020296 -277.124668) (xy 393.020296 -277.076916) (xy 392.820398 -277.076916) (xy 392.820398 -277.124668)
			(xy 392.920474 -277.22449)
		)
		(stroke
			(width 0)
			(type solid)
		)
		(fill yes)
		(layer "In6.Cu")
		(net "M_K_CPU0_SB_DQS_DP<5>")
	)
	(gr_poly
		(pts
			(xy 393.020296 -275.504148) (xy 393.020296 -275.459698) (xy 392.820398 -275.459698) (xy 392.820398 -275.504148)
			(xy 392.92022 -275.604224)
		)
		(stroke
			(width 0)
			(type solid)
		)
		(fill yes)
		(layer "In6.Cu")
		(net "M_K_CPU0_SB_DQ<3>")
	)
	(gr_poly
		(pts
			(xy 393.020296 -273.884136) (xy 393.020296 -273.839686) (xy 392.820398 -273.839686) (xy 392.820398 -273.884136)
			(xy 392.92022 -273.984212)
		)
		(stroke
			(width 0)
			(type solid)
		)
		(fill yes)
		(layer "In6.Cu")
		(net "M_K_CPU0_SB_CB<3>")
	)
	(gr_poly
		(pts
			(xy 393.020296 -265.784076) (xy 393.020296 -265.739626) (xy 392.820398 -265.739626) (xy 392.820398 -265.784076)
			(xy 392.92022 -265.884152)
		)
		(stroke
			(width 0)
			(type solid)
		)
		(fill yes)
		(layer "In6.Cu")
		(net "M_K_CPU0_SB_CS_N<0>")
	)
	(gr_poly
		(pts
			(xy 393.020296 -264.164064) (xy 393.020296 -264.119614) (xy 392.820398 -264.119614) (xy 392.820398 -264.164064)
			(xy 392.92022 -264.26414)
		)
		(stroke
			(width 0)
			(type solid)
		)
		(fill yes)
		(layer "In6.Cu")
		(net "M_K_CPU0_SB_CA<5>")
	)
	(gr_poly
		(pts
			(xy 393.020296 -262.544052) (xy 393.020296 -262.499602) (xy 392.820398 -262.499602) (xy 392.820398 -262.544052)
			(xy 392.92022 -262.644128)
		)
		(stroke
			(width 0)
			(type solid)
		)
		(fill yes)
		(layer "In6.Cu")
		(net "M_K_CPU0_SB_CA<1>")
	)
	(gr_poly
		(pts
			(xy 393.02055 -284.008068) (xy 392.920474 -283.907992) (xy 392.820398 -284.008068) (xy 392.820398 -284.052518)
			(xy 393.02055 -284.052518)
		)
		(stroke
			(width 0)
			(type solid)
		)
		(fill yes)
		(layer "In6.Cu")
		(net "M_K_CPU0_SB_DQ<16>")
	)
	(gr_poly
		(pts
			(xy 393.02055 -282.388056) (xy 392.920474 -282.28798) (xy 392.820398 -282.388056) (xy 392.820398 -282.432506)
			(xy 393.02055 -282.432506)
		)
		(stroke
			(width 0)
			(type solid)
		)
		(fill yes)
		(layer "In6.Cu")
		(net "M_K_CPU0_SB_DQ<12>")
	)
	(gr_poly
		(pts
			(xy 393.02055 -279.148032) (xy 392.920474 -279.047956) (xy 392.820398 -279.148032) (xy 392.820398 -279.192482)
			(xy 393.02055 -279.192482)
		)
		(stroke
			(width 0)
			(type solid)
		)
		(fill yes)
		(layer "In6.Cu")
		(net "M_K_CPU0_SB_DQ<8>")
	)
	(gr_poly
		(pts
			(xy 393.02055 -274.287996) (xy 392.920474 -274.18792) (xy 392.820398 -274.287996) (xy 392.820398 -274.332446)
			(xy 393.02055 -274.332446)
		)
		(stroke
			(width 0)
			(type solid)
		)
		(fill yes)
		(layer "In6.Cu")
		(net "M_K_CPU0_SB_DQ<0>")
	)
	(gr_poly
		(pts
			(xy 393.02055 -272.667984) (xy 392.920474 -272.567908) (xy 392.820398 -272.667984) (xy 392.820398 -272.712434)
			(xy 393.02055 -272.712434)
		)
		(stroke
			(width 0)
			(type solid)
		)
		(fill yes)
		(layer "In6.Cu")
		(net "M_K_CPU0_SB_CB<0>")
	)
	(gr_poly
		(pts
			(xy 393.02055 -267.807948) (xy 392.920474 -267.707872) (xy 392.820398 -267.807948) (xy 392.820398 -267.852398)
			(xy 393.02055 -267.852398)
		)
		(stroke
			(width 0)
			(type solid)
		)
		(fill yes)
		(layer "In6.Cu")
		(net "M_K_CPU0_SB_RSP<0>")
	)
	(gr_poly
		(pts
			(xy 393.02055 -264.567924) (xy 392.920474 -264.467848) (xy 392.820398 -264.567924) (xy 392.820398 -264.612374)
			(xy 393.02055 -264.612374)
		)
		(stroke
			(width 0)
			(type solid)
		)
		(fill yes)
		(layer "In6.Cu")
		(net "M_K_CPU0_SB_CA<6>")
	)
	(gr_poly
		(pts
			(xy 393.02055 -262.947912) (xy 392.920474 -262.847836) (xy 392.820398 -262.947912) (xy 392.820398 -262.992362)
			(xy 393.02055 -262.992362)
		)
		(stroke
			(width 0)
			(type solid)
		)
		(fill yes)
		(layer "In6.Cu")
		(net "M_K_CPU0_SB_CA<2>")
	)
	(gr_poly
		(pts
			(xy 393.02309 -290.487608) (xy 392.923014 -290.387532) (xy 392.822938 -290.487608) (xy 392.822938 -290.53536)
			(xy 393.02309 -290.53536)
		)
		(stroke
			(width 0)
			(type solid)
		)
		(fill yes)
		(layer "In6.Cu")
		(net "M_K_CPU0_SB_DQS_DP<3>")
	)
	(gr_poly
		(pts
			(xy 393.02309 -285.627826) (xy 392.923014 -285.52775) (xy 392.823192 -285.627826) (xy 392.823192 -285.675324)
			(xy 393.02309 -285.675324)
		)
		(stroke
			(width 0)
			(type solid)
		)
		(fill yes)
		(layer "In6.Cu")
		(net "M_K_CPU0_SB_DQS_DP<2>")
	)
	(gr_poly
		(pts
			(xy 393.02309 -280.76779) (xy 392.923014 -280.667714) (xy 392.823192 -280.76779) (xy 392.823192 -280.815288)
			(xy 393.02309 -280.815288)
		)
		(stroke
			(width 0)
			(type solid)
		)
		(fill yes)
		(layer "In6.Cu")
		(net "M_K_CPU0_SB_DQS_DP<1>")
	)
	(gr_poly
		(pts
			(xy 393.02309 -275.907754) (xy 392.923014 -275.807678) (xy 392.823192 -275.907754) (xy 392.823192 -275.955252)
			(xy 393.02309 -275.955252)
		)
		(stroke
			(width 0)
			(type solid)
		)
		(fill yes)
		(layer "In6.Cu")
		(net "M_K_CPU0_SB_DQS_DP<0>")
	)
	(gr_poly
		(pts
			(xy 393.02309 -272.26387) (xy 393.02309 -272.216118) (xy 392.823192 -272.216118) (xy 392.823192 -272.26387)
			(xy 392.923014 -272.363946)
		)
		(stroke
			(width 0)
			(type solid)
		)
		(fill yes)
		(layer "In6.Cu")
		(net "M_K_CPU0_SB_DQS_DP<4>")
	)
	(gr_poly
		(pts
			(xy 393.034012 -293.32809) (xy 393.070842 -293.191438) (xy 392.93419 -293.154862) (xy 392.895582 -293.177214)
			(xy 392.995658 -293.350442)
		)
		(stroke
			(width 0)
			(type solid)
		)
		(fill yes)
		(layer "In6.Cu")
		(net "M_K_CPU0_SB_DQ<28>")
	)
	(gr_poly
		(pts
			(xy 393.045442 -294.943022) (xy 393.082018 -294.80637) (xy 392.945366 -294.769794) (xy 392.906758 -294.791892)
			(xy 393.006834 -294.96512)
		)
		(stroke
			(width 0)
			(type solid)
		)
		(fill yes)
		(layer "In6.Cu")
		(net "M_K_CPU0_SB_DQ<29>")
	)
	(gr_poly
		(pts
			(xy 393.077954 -271.16659) (xy 393.029694 -271.033748) (xy 392.986514 -271.013682) (xy 392.901932 -271.194784)
			(xy 392.945112 -271.215104)
		)
		(stroke
			(width 0)
			(type solid)
		)
		(fill yes)
		(layer "In6.Cu")
		(net "M_K_CPU0_SB_DQS_DN<9>")
	)
	(gr_poly
		(pts
			(xy 393.144756 -236.18952) (xy 393.148566 -236.145324) (xy 392.94943 -236.128052) (xy 392.945366 -236.172248)
			(xy 393.036298 -236.280452)
		)
		(stroke
			(width 0)
			(type solid)
		)
		(fill yes)
		(layer "In6.Cu")
		(net "M_K_CPU0_SA_DQ<19>")
	)
	(gr_poly
		(pts
			(xy 393.173966 -247.522492) (xy 393.173966 -247.47474) (xy 392.974068 -247.47474) (xy 392.974068 -247.522492)
			(xy 393.074144 -247.622568)
		)
		(stroke
			(width 0)
			(type solid)
		)
		(fill yes)
		(layer "In6.Cu")
		(net "M_K_CPU0_SA_DQS_DP<9>")
	)
	(gr_poly
		(pts
			(xy 393.175998 -256.025904) (xy 393.076176 -255.925828) (xy 392.9761 -256.025904) (xy 392.9761 -256.073402)
			(xy 393.175998 -256.073402)
		)
		(stroke
			(width 0)
			(type solid)
		)
		(fill yes)
		(layer "In6.Cu")
		(net "M_K_CPU0_CLK_DP<0>")
	)
	(gr_poly
		(pts
			(xy 393.175998 -254.406146) (xy 393.076176 -254.30607) (xy 392.9761 -254.406146) (xy 392.9761 -254.450596)
			(xy 393.175998 -254.450596)
		)
		(stroke
			(width 0)
			(type solid)
		)
		(fill yes)
		(layer "In6.Cu")
		(net "M_K_CPU0_SA_CA<4>")
	)
	(gr_poly
		(pts
			(xy 393.175998 -252.786134) (xy 393.076176 -252.686058) (xy 392.9761 -252.786134) (xy 392.9761 -252.830584)
			(xy 393.175998 -252.830584)
		)
		(stroke
			(width 0)
			(type solid)
		)
		(fill yes)
		(layer "In6.Cu")
		(net "M_K_CPU0_SA_CA<0>")
	)
	(gr_poly
		(pts
			(xy 393.175998 -251.166122) (xy 393.076176 -251.066046) (xy 392.9761 -251.166122) (xy 392.9761 -251.210572)
			(xy 393.175998 -251.210572)
		)
		(stroke
			(width 0)
			(type solid)
		)
		(fill yes)
		(layer "In6.Cu")
		(net "M_K_CPU0_SA_CS_N<0>")
	)
	(gr_poly
		(pts
			(xy 393.175998 -247.926098) (xy 393.076176 -247.826022) (xy 392.9761 -247.926098) (xy 392.9761 -247.970548)
			(xy 393.175998 -247.970548)
		)
		(stroke
			(width 0)
			(type solid)
		)
		(fill yes)
		(layer "In6.Cu")
		(net "M_K_CPU0_SA_CB<4>")
	)
	(gr_poly
		(pts
			(xy 393.175998 -246.305832) (xy 393.076176 -246.205756) (xy 392.9761 -246.305832) (xy 392.9761 -246.35333)
			(xy 393.175998 -246.35333)
		)
		(stroke
			(width 0)
			(type solid)
		)
		(fill yes)
		(layer "In6.Cu")
		(net "M_K_CPU0_SA_DQS_DP<4>")
	)
	(gr_poly
		(pts
			(xy 393.175998 -244.686074) (xy 393.076176 -244.585998) (xy 392.9761 -244.686074) (xy 392.9761 -244.730524)
			(xy 393.175998 -244.730524)
		)
		(stroke
			(width 0)
			(type solid)
		)
		(fill yes)
		(layer "In6.Cu")
		(net "M_K_CPU0_SA_CB<0>")
	)
	(gr_poly
		(pts
			(xy 393.175998 -232.942384) (xy 393.175998 -232.894886) (xy 392.9761 -232.894886) (xy 392.9761 -232.942384)
			(xy 393.076176 -233.04246)
		)
		(stroke
			(width 0)
			(type solid)
		)
		(fill yes)
		(layer "In6.Cu")
		(net "M_K_CPU0_SA_DQS_DP<6>")
	)
	(gr_poly
		(pts
			(xy 393.177522 -254.002286) (xy 393.177522 -253.957836) (xy 392.977624 -253.957836) (xy 392.977624 -254.002286)
			(xy 393.077446 -254.102362)
		)
		(stroke
			(width 0)
			(type solid)
		)
		(fill yes)
		(layer "In6.Cu")
		(net "M_K_CPU0_SA_CA<3>")
	)
	(gr_poly
		(pts
			(xy 393.177522 -239.422178) (xy 393.177522 -239.377728) (xy 392.977624 -239.377728) (xy 392.977624 -239.422178)
			(xy 393.077446 -239.522254)
		)
		(stroke
			(width 0)
			(type solid)
		)
		(fill yes)
		(layer "In6.Cu")
		(net "M_K_CPU0_SA_DQ<23>")
	)
	(gr_poly
		(pts
			(xy 393.177522 -234.562142) (xy 393.177522 -234.517692) (xy 392.977624 -234.517692) (xy 392.977624 -234.562142)
			(xy 393.077446 -234.662218)
		)
		(stroke
			(width 0)
			(type solid)
		)
		(fill yes)
		(layer "In6.Cu")
		(net "M_K_CPU0_SA_DQ<15>")
	)
	(gr_poly
		(pts
			(xy 393.206732 -227.055426) (xy 393.182094 -226.916234) (xy 393.143232 -226.888802) (xy 393.028424 -227.052632)
			(xy 393.06754 -227.080064)
		)
		(stroke
			(width 0)
			(type solid)
		)
		(fill yes)
		(layer "In6.Cu")
		(net "M_K_CPU0_SA_DQS_DP<5>")
	)
	(gr_poly
		(pts
			(xy 393.267438 -237.790228) (xy 393.263374 -237.74273) (xy 393.064238 -237.760256) (xy 393.068302 -237.8075)
			(xy 393.176506 -237.898432)
		)
		(stroke
			(width 0)
			(type solid)
		)
		(fill yes)
		(layer "In6.Cu")
		(net "M_K_CPU0_SA_DQS_DP<7>")
	)
	(gr_poly
		(pts
			(xy 393.403836 -294.684704) (xy 393.30376 -294.511476) (xy 393.265406 -294.533828) (xy 393.22883 -294.67048)
			(xy 393.365228 -294.707056)
		)
		(stroke
			(width 0)
			(type solid)
		)
		(fill yes)
		(layer "In6.Cu")
		(net "M_K_CPU0_SB_DQ<30>")
	)
	(gr_poly
		(pts
			(xy 393.47394 -276.314408) (xy 393.47394 -276.266656) (xy 393.274042 -276.266656) (xy 393.274042 -276.314408)
			(xy 393.374118 -276.414484)
		)
		(stroke
			(width 0)
			(type solid)
		)
		(fill yes)
		(layer "In6.Cu")
		(net "M_K_CPU0_SB_DQS_DN<0>")
	)
	(gr_poly
		(pts
			(xy 393.503912 -294.138096) (xy 393.540742 -294.001444) (xy 393.40409 -293.964868) (xy 393.365482 -293.98722)
			(xy 393.465558 -294.160448)
		)
		(stroke
			(width 0)
			(type solid)
		)
		(fill yes)
		(layer "In6.Cu")
		(net "M_K_CPU0_SB_DQ<28>")
	)
	(gr_poly
		(pts
			(xy 393.57681 -223.886268) (xy 393.535662 -223.862392) (xy 393.39901 -223.899222) (xy 393.435586 -224.03562)
			(xy 393.476988 -224.059496)
		)
		(stroke
			(width 0)
			(type solid)
		)
		(fill yes)
		(layer "In6.Cu")
		(net "M_K_CPU0_SA_DQS_DN<5>")
	)
	(gr_poly
		(pts
			(xy 393.657582 -253.59614) (xy 393.557506 -253.496064) (xy 393.45743 -253.59614) (xy 393.45743 -253.64059)
			(xy 393.657582 -253.64059)
		)
		(stroke
			(width 0)
			(type solid)
		)
		(fill yes)
		(layer "In6.Cu")
		(net "M_K_CPU0_SA_CA<2>")
	)
	(gr_poly
		(pts
			(xy 393.662662 -247.115838) (xy 393.562586 -247.016016) (xy 393.462764 -247.115838) (xy 393.462764 -247.16359)
			(xy 393.662662 -247.16359)
		)
		(stroke
			(width 0)
			(type solid)
		)
		(fill yes)
		(layer "In6.Cu")
		(net "M_K_CPU0_SA_DQS_DN<9>")
	)
	(gr_poly
		(pts
			(xy 393.710668 -222.9485) (xy 393.674092 -222.812102) (xy 393.63269 -222.788226) (xy 393.532868 -222.961454)
			(xy 393.574016 -222.985076)
		)
		(stroke
			(width 0)
			(type solid)
		)
		(fill yes)
		(layer "In6.Cu")
		(net "M_K_CPU0_SA_DQS_DN<0>")
	)
	(gr_poly
		(pts
			(xy 394.180568 -223.759268) (xy 394.143992 -223.62287) (xy 394.10259 -223.598994) (xy 394.002768 -223.772222)
			(xy 394.043916 -223.795844)
		)
		(stroke
			(width 0)
			(type solid)
		)
		(fill yes)
		(layer "In6.Cu")
		(net "M_K_CPU0_SA_DQS_DP<5>")
	)
	(gr_poly
		(pts
			(xy 77.95514 -222.953326) (xy 77.855064 -222.780098) (xy 77.813916 -222.80372) (xy 77.777086 -222.940372)
			(xy 77.77734 -222.940372) (xy 77.913738 -222.976948)
		)
		(stroke
			(width 0)
			(type solid)
		)
		(fill yes)
		(layer "In6.Cu")
		(net "M_E_CPU1_SA_DQS_DN<0>")
	)
	(gr_poly
		(pts
			(xy 79.272638 -269.428214) (xy 79.172816 -269.328138) (xy 79.172562 -269.328138) (xy 79.07274 -269.428214)
			(xy 79.07274 -269.472664) (xy 79.272638 -269.472664)
		)
		(stroke
			(width 0)
			(type solid)
		)
		(fill yes)
		(layer "In6.Cu")
		(net "M_E_CPU1_SB_CB<4>")
	)
	(gr_poly
		(pts
			(xy 79.760572 -289.677856) (xy 79.66075 -289.57778) (xy 79.660496 -289.57778) (xy 79.560674 -289.677856)
			(xy 79.560674 -289.722306) (xy 79.760572 -289.722306)
		)
		(stroke
			(width 0)
			(type solid)
		)
		(fill yes)
		(layer "In6.Cu")
		(net "M_E_CPU1_SB_DQ<25>")
	)
	(gr_poly
		(pts
			(xy 80.210152 -290.08451) (xy 80.210152 -290.04006) (xy 80.010254 -290.04006) (xy 80.010254 -290.08451)
			(xy 80.110076 -290.184586) (xy 80.11033 -290.184586)
		)
		(stroke
			(width 0)
			(type solid)
		)
		(fill yes)
		(layer "In6.Cu")
		(net "M_E_CPU1_SB_DQ<27>")
	)
	(gr_poly
		(pts
			(xy 142.81785 -224.583752) (xy 142.717774 -224.410524) (xy 142.676626 -224.4344) (xy 142.639796 -224.571052)
			(xy 142.64005 -224.571052) (xy 142.776448 -224.607628)
		)
		(stroke
			(width 0)
			(type solid)
		)
		(fill yes)
		(layer "In6.Cu")
		(net "M_K_CPU1_SA_DQ<0>")
	)
	(gr_poly
		(pts
			(xy 142.81785 -223.885252) (xy 142.776448 -223.861376) (xy 142.64005 -223.897952) (xy 142.639796 -223.897952)
			(xy 142.676626 -224.034604) (xy 142.717774 -224.05848)
		)
		(stroke
			(width 0)
			(type solid)
		)
		(fill yes)
		(layer "In6.Cu")
		(net "M_K_CPU1_SA_DQ<0>")
	)
	(gr_poly
		(pts
			(xy 143.382746 -224.84461) (xy 143.419576 -224.708212) (xy 143.419322 -224.708212) (xy 143.282924 -224.671382)
			(xy 143.241522 -224.695258) (xy 143.341598 -224.868486)
		)
		(stroke
			(width 0)
			(type solid)
		)
		(fill yes)
		(layer "In6.Cu")
		(net "M_K_CPU1_SA_DQ<2>")
	)
	(gr_poly
		(pts
			(xy 143.419322 -225.380804) (xy 143.419576 -225.380804) (xy 143.382746 -225.244406) (xy 143.341598 -225.22053)
			(xy 143.241522 -225.393758) (xy 143.282924 -225.417634)
		)
		(stroke
			(width 0)
			(type solid)
		)
		(fill yes)
		(layer "In6.Cu")
		(net "M_K_CPU1_SA_DQ<2>")
	)
	(gr_poly
		(pts
			(xy 144.697958 -224.583752) (xy 144.597882 -224.410524) (xy 144.556734 -224.4344) (xy 144.519904 -224.571052)
			(xy 144.520158 -224.571052) (xy 144.656556 -224.607628)
		)
		(stroke
			(width 0)
			(type solid)
		)
		(fill yes)
		(layer "In6.Cu")
		(net "M_K_CPU1_SA_DQS_DP<0>")
	)
	(gr_poly
		(pts
			(xy 144.697958 -223.885252) (xy 144.656556 -223.861376) (xy 144.520158 -223.897952) (xy 144.519904 -223.897952)
			(xy 144.556734 -224.034604) (xy 144.597882 -224.05848)
		)
		(stroke
			(width 0)
			(type solid)
		)
		(fill yes)
		(layer "In6.Cu")
		(net "M_K_CPU1_SA_DQS_DP<0>")
	)
	(gr_poly
		(pts
			(xy 145.167858 -223.075246) (xy 145.126456 -223.05137) (xy 144.990058 -223.0882) (xy 144.989804 -223.0882)
			(xy 145.026634 -223.224598) (xy 145.067782 -223.248474)
		)
		(stroke
			(width 0)
			(type solid)
		)
		(fill yes)
		(layer "In6.Cu")
		(net "M_K_CPU1_SA_DQS_DP<0>")
	)
	(gr_poly
		(pts
			(xy 145.190972 -226.300284) (xy 145.14957 -226.276408) (xy 145.013172 -226.312984) (xy 145.012918 -226.312984)
			(xy 145.049748 -226.449636) (xy 145.090896 -226.473512)
		)
		(stroke
			(width 0)
			(type solid)
		)
		(fill yes)
		(layer "In6.Cu")
		(net "M_K_CPU1_SA_DQS_DN<5>")
	)
	(gr_poly
		(pts
			(xy 145.262854 -224.84461) (xy 145.299684 -224.708212) (xy 145.29943 -224.708212) (xy 145.163032 -224.671382)
			(xy 145.12163 -224.695258) (xy 145.221706 -224.868486)
		)
		(stroke
			(width 0)
			(type solid)
		)
		(fill yes)
		(layer "In6.Cu")
		(net "M_K_CPU1_SA_DQS_DN<0>")
	)
	(gr_poly
		(pts
			(xy 145.29943 -225.380804) (xy 145.299684 -225.380804) (xy 145.262854 -225.244406) (xy 145.221706 -225.22053)
			(xy 145.12163 -225.393758) (xy 145.163032 -225.417634)
		)
		(stroke
			(width 0)
			(type solid)
		)
		(fill yes)
		(layer "In6.Cu")
		(net "M_K_CPU1_SA_DQS_DN<0>")
	)
	(gr_poly
		(pts
			(xy 145.29943 -223.760792) (xy 145.299684 -223.760792) (xy 145.262854 -223.624394) (xy 145.221706 -223.600518)
			(xy 145.12163 -223.773746) (xy 145.163032 -223.797622)
		)
		(stroke
			(width 0)
			(type solid)
		)
		(fill yes)
		(layer "In6.Cu")
		(net "M_K_CPU1_SA_DQS_DN<0>")
	)
	(gr_poly
		(pts
			(xy 145.620994 -269.820644) (xy 145.617184 -269.776448) (xy 145.418048 -269.793974) (xy 145.421858 -269.83817)
			(xy 145.530062 -269.929102) (xy 145.530316 -269.929102)
		)
		(stroke
			(width 0)
			(type solid)
		)
		(fill yes)
		(layer "In6.Cu")
		(net "M_K_CPU1_SB_CB<7>")
	)
	(gr_poly
		(pts
			(xy 325.895208 -222.953072) (xy 325.795132 -222.779844) (xy 325.753984 -222.803466) (xy 325.717154 -222.940118)
			(xy 325.717408 -222.940118) (xy 325.853806 -222.976694)
		)
		(stroke
			(width 0)
			(type solid)
		)
		(fill yes)
		(layer "In6.Cu")
		(net "M_E_CPU0_SA_DQS_DN<0>")
	)
	(gr_poly
		(pts
			(xy 327.70064 -289.677602) (xy 327.600818 -289.577526) (xy 327.600564 -289.577526) (xy 327.500742 -289.677602)
			(xy 327.500742 -289.722052) (xy 327.70064 -289.722052)
		)
		(stroke
			(width 0)
			(type solid)
		)
		(fill yes)
		(layer "In6.Cu")
		(net "M_E_CPU0_SB_DQ<25>")
	)
	(gr_poly
		(pts
			(xy 328.15022 -290.084256) (xy 328.15022 -290.039806) (xy 327.950322 -290.039806) (xy 327.950322 -290.084256)
			(xy 328.050144 -290.184332) (xy 328.050398 -290.184332)
		)
		(stroke
			(width 0)
			(type solid)
		)
		(fill yes)
		(layer "In6.Cu")
		(net "M_E_CPU0_SB_DQ<27>")
	)
	(gr_poly
		(pts
			(xy 390.757918 -224.583498) (xy 390.657842 -224.41027) (xy 390.616694 -224.434146) (xy 390.579864 -224.570544)
			(xy 390.580118 -224.570544) (xy 390.716516 -224.607374)
		)
		(stroke
			(width 0)
			(type solid)
		)
		(fill yes)
		(layer "In6.Cu")
		(net "M_K_CPU0_SA_DQ<0>")
	)
	(gr_poly
		(pts
			(xy 390.757918 -223.884998) (xy 390.716516 -223.861122) (xy 390.580118 -223.897952) (xy 390.579864 -223.897952)
			(xy 390.616694 -224.03435) (xy 390.657842 -224.058226)
		)
		(stroke
			(width 0)
			(type solid)
		)
		(fill yes)
		(layer "In6.Cu")
		(net "M_K_CPU0_SA_DQ<0>")
	)
	(gr_poly
		(pts
			(xy 391.322814 -224.844356) (xy 391.359644 -224.707704) (xy 391.35939 -224.707704) (xy 391.222992 -224.671128)
			(xy 391.18159 -224.695004) (xy 391.281666 -224.868232)
		)
		(stroke
			(width 0)
			(type solid)
		)
		(fill yes)
		(layer "In6.Cu")
		(net "M_K_CPU0_SA_DQ<2>")
	)
	(gr_poly
		(pts
			(xy 391.35939 -225.380804) (xy 391.359644 -225.380804) (xy 391.322814 -225.244152) (xy 391.281666 -225.220276)
			(xy 391.18159 -225.393504) (xy 391.222992 -225.41738)
		)
		(stroke
			(width 0)
			(type solid)
		)
		(fill yes)
		(layer "In6.Cu")
		(net "M_K_CPU0_SA_DQ<2>")
	)
	(gr_poly
		(pts
			(xy 392.065764 -286.844232) (xy 392.065764 -286.796734) (xy 391.865866 -286.796734) (xy 391.865866 -286.844232)
			(xy 391.965688 -286.944308) (xy 391.965942 -286.944308)
		)
		(stroke
			(width 0)
			(type solid)
		)
		(fill yes)
		(layer "In6.Cu")
		(net "M_K_CPU0_SB_DQS_DP<7>")
	)
	(gr_poly
		(pts
			(xy 392.638026 -224.583498) (xy 392.53795 -224.41027) (xy 392.496802 -224.434146) (xy 392.459972 -224.570544)
			(xy 392.460226 -224.570544) (xy 392.596624 -224.607374)
		)
		(stroke
			(width 0)
			(type solid)
		)
		(fill yes)
		(layer "In6.Cu")
		(net "M_K_CPU0_SA_DQS_DP<0>")
	)
	(gr_poly
		(pts
			(xy 392.638026 -223.884998) (xy 392.596624 -223.861122) (xy 392.460226 -223.897952) (xy 392.459972 -223.897952)
			(xy 392.496802 -224.03435) (xy 392.53795 -224.058226)
		)
		(stroke
			(width 0)
			(type solid)
		)
		(fill yes)
		(layer "In6.Cu")
		(net "M_K_CPU0_SA_DQS_DP<0>")
	)
	(gr_poly
		(pts
			(xy 393.107926 -223.074992) (xy 393.066524 -223.051116) (xy 392.930126 -223.087692) (xy 392.929872 -223.087692)
			(xy 392.966702 -223.224344) (xy 393.00785 -223.24822)
		)
		(stroke
			(width 0)
			(type solid)
		)
		(fill yes)
		(layer "In6.Cu")
		(net "M_K_CPU0_SA_DQS_DP<0>")
	)
	(gr_poly
		(pts
			(xy 393.13104 -226.30003) (xy 393.089638 -226.276154) (xy 392.95324 -226.31273) (xy 392.952986 -226.31273)
			(xy 392.989816 -226.449382) (xy 393.030964 -226.473258)
		)
		(stroke
			(width 0)
			(type solid)
		)
		(fill yes)
		(layer "In6.Cu")
		(net "M_K_CPU0_SA_DQS_DN<5>")
	)
	(gr_poly
		(pts
			(xy 393.202922 -224.844356) (xy 393.239752 -224.707704) (xy 393.239498 -224.707704) (xy 393.1031 -224.671128)
			(xy 393.061698 -224.695004) (xy 393.161774 -224.868232)
		)
		(stroke
			(width 0)
			(type solid)
		)
		(fill yes)
		(layer "In6.Cu")
		(net "M_K_CPU0_SA_DQS_DN<0>")
	)
	(gr_poly
		(pts
			(xy 393.239498 -225.380804) (xy 393.239752 -225.380804) (xy 393.202922 -225.244152) (xy 393.161774 -225.220276)
			(xy 393.061698 -225.393504) (xy 393.1031 -225.41738)
		)
		(stroke
			(width 0)
			(type solid)
		)
		(fill yes)
		(layer "In6.Cu")
		(net "M_K_CPU0_SA_DQS_DN<0>")
	)
	(gr_poly
		(pts
			(xy 393.239498 -223.760538) (xy 393.239752 -223.760538) (xy 393.202922 -223.62414) (xy 393.161774 -223.600264)
			(xy 393.061698 -223.773492) (xy 393.1031 -223.797368)
		)
		(stroke
			(width 0)
			(type solid)
		)
		(fill yes)
		(layer "In6.Cu")
		(net "M_K_CPU0_SA_DQS_DN<0>")
	)
	(gr_poly
		(pts
			(xy 393.561062 -269.82039) (xy 393.557252 -269.776194) (xy 393.358116 -269.79372) (xy 393.361926 -269.837916)
			(xy 393.47013 -269.928848) (xy 393.470384 -269.928848)
		)
		(stroke
			(width 0)
			(type solid)
		)
		(fill yes)
		(layer "In6.Cu")
		(net "M_K_CPU0_SB_CB<7>")
	)
	(gr_poly
		(pts
			(xy 17.178782 -411.961584) (xy 17.178782 -408.532584) (xy 17.051782 -408.405584) (xy 13.241782 -408.405584)
			(xy 13.114782 -408.532584) (xy 13.114782 -411.961584) (xy 13.241782 -412.088584) (xy 17.051782 -412.088584)
		)
		(stroke
			(width 0)
			(type solid)
		)
		(fill yes)
		(layer "In6.Cu")
		(net "GND")
	)
	(gr_poly
		(pts
			(xy 404.143972 -318.199008) (xy 404.143972 -316.039246) (xy 403.091142 -314.986416) (xy 394.941552 -314.986416)
			(xy 394.802106 -315.125862) (xy 394.802106 -317.75654) (xy 395.678406 -318.63284) (xy 403.71014 -318.63284)
		)
		(stroke
			(width 0)
			(type solid)
		)
		(fill yes)
		(layer "In6.Cu")
		(net "GND")
	)
	(gr_poly
		(pts
			(xy 446.395602 -425.69511) (xy 446.395602 -422.26611) (xy 446.268602 -422.13911) (xy 442.458602 -422.13911)
			(xy 442.331602 -422.26611) (xy 442.331602 -425.69511) (xy 442.458602 -425.82211) (xy 446.268602 -425.82211)
		)
		(stroke
			(width 0)
			(type solid)
		)
		(fill yes)
		(layer "In6.Cu")
		(net "GND")
	)
	(gr_poly
		(pts
			(xy 32.7152 -366.088422) (xy 32.7152 -362.1024) (xy 32.7152 -361.8992) (xy 32.6898 -361.8738) (xy 28.2956 -361.8738)
			(xy 28.245308 -361.924092) (xy 28.245308 -362.086144) (xy 28.245308 -366.117886) (xy 28.360116 -366.232694)
			(xy 32.570928 -366.232694)
		)
		(stroke
			(width 0)
			(type solid)
		)
		(fill yes)
		(layer "In6.Cu")
		(net "GND")
	)
	(gr_poly
		(pts
			(xy 312.3692 -362.88853) (xy 312.3692 -358.6734) (xy 312.3692 -358.4702) (xy 312.3438 -358.4448)
			(xy 307.9496 -358.4448) (xy 307.899308 -358.495092) (xy 307.899308 -358.657144) (xy 307.899308 -362.889292)
			(xy 307.9242 -362.91393) (xy 312.3438 -362.91393)
		)
		(stroke
			(width 0)
			(type solid)
		)
		(fill yes)
		(layer "In6.Cu")
		(net "GND")
	)
	(gr_poly
		(pts
			(xy 8.62076 -102.117144) (xy 8.86079 -101.877114) (xy 8.86079 -97.4217) (xy 8.678672 -97.239582)
			(xy 5.976366 -97.239582) (xy 5.494782 -97.721166) (xy 5.36956 -97.846388) (xy 5.075428 -98.14052)
			(xy 5.075428 -101.823012) (xy 5.36956 -102.117144) (xy 5.494782 -102.242366) (xy 8.495538 -102.242366)
		)
		(stroke
			(width 0)
			(type solid)
		)
		(fill yes)
		(layer "In6.Cu")
		(net "GND")
	)
	(gr_poly
		(pts
			(xy 441.045092 -43.578018) (xy 441.045092 -43.451018) (xy 441.045092 -38.853618) (xy 440.918092 -38.726618)
			(xy 434.288692 -38.726618) (xy 433.780692 -38.726618) (xy 433.628292 -38.879018) (xy 433.628292 -43.001946)
			(xy 433.628292 -43.618658) (xy 433.780692 -43.771058) (xy 438.893458 -43.771058) (xy 440.852052 -43.771058)
		)
		(stroke
			(width 0)
			(type solid)
		)
		(fill yes)
		(layer "In6.Cu")
		(net "P12V_AUX")
	)
	(gr_poly
		(pts
			(xy 155.952952 -319.820798) (xy 155.952952 -316.907418) (xy 155.693364 -316.64783) (xy 151.944832 -316.64783)
			(xy 151.40559 -316.108588) (xy 151.40559 -315.483494) (xy 151.140414 -315.218318) (xy 147.148804 -315.218318)
			(xy 147.023582 -315.34354) (xy 146.703796 -315.663326) (xy 146.703796 -318.473074) (xy 147.209256 -318.978534)
			(xy 150.965154 -318.978534) (xy 151.2951 -319.30848) (xy 151.2951 -319.870074) (xy 151.382476 -319.95745)
			(xy 151.549608 -319.95745) (xy 155.8163 -319.95745)
		)
		(stroke
			(width 0)
			(type solid)
		)
		(fill yes)
		(layer "In6.Cu")
		(net "GND")
	)
	(gr_poly
		(pts
			(arc
				(start 174.749714 -361.963716)
				(mid 174.539402 -361.963716)
				(end 174.749714 -361.963716)
			)
		)
		(stroke
			(width 0)
			(type solid)
		)
		(fill yes)
		(layer "In6.Cu")
		(net "GND")
	)
	(gr_poly
		(pts
			(arc
				(start 381.56261 -206.215488)
				(mid 381.31623 -206.215488)
				(end 381.56261 -206.215488)
			)
		)
		(stroke
			(width 0)
			(type solid)
		)
		(fill yes)
		(layer "In6.Cu")
		(net "GND")
	)
	(gr_poly
		(pts
			(arc
				(start 384.981958 -206.830676)
				(mid 384.735578 -206.830676)
				(end 384.981958 -206.830676)
			)
		)
		(stroke
			(width 0)
			(type solid)
		)
		(fill yes)
		(layer "In6.Cu")
		(net "GND")
	)
	(gr_poly
		(pts
			(xy 229.6795 -435.74208) (xy 229.6795 -422.049194) (xy 234.763056 -416.965638) (xy 272.06448 -416.965638)
			(xy 280.05024 -408.979878) (xy 280.05024 -398.563338) (xy 279.270206 -397.783304) (xy 240.06175 -397.783304)
			(xy 239.91189 -397.933164) (xy 239.91189 -404.086822) (xy 239.91189 -405.227536) (xy 239.91189 -405.609298)
			(xy 234.87634 -410.644848) (xy 229.69855 -410.644848) (xy 229.676198 -410.6672) (xy 227.067872 -413.275526)
			(xy 196.769482 -413.275526) (xy 196.26072 -413.784288) (xy 196.26072 -414.072832) (xy 196.26072 -421.757602)
			(arc
				(start 206.039974 -431.536856)
				(mid 206.051085 -431.55339)
				(end 206.05496 -431.572924)
			)
			(xy 206.05496 -435.09946) (xy 207.43418 -436.47868) (xy 228.9429 -436.47868)
		)
		(stroke
			(width 0)
			(type solid)
		)
		(fill yes)
		(layer "In6.Cu")
		(net "P12V_PSU")
	)
	(gr_poly
		(pts
			(arc
				(start 161.275776 -194.728084)
				(mid 160.942528 -194.728084)
				(end 161.275776 -194.728084)
			)
		)
		(stroke
			(width 0)
			(type solid)
		)
		(fill yes)
		(layer "In6.Cu")
		(net "GND")
	)
	(gr_poly
		(pts
			(arc
				(start 81.154778 -2.750312)
				(mid 81.182917 -2.732466)
				(end 81.193894 -2.701036)
			)
			(arc
				(start 81.193894 -0.5588)
				(mid 81.179015 -0.522879)
				(end 81.143094 -0.508)
			)
			(arc
				(start 13.660882 -0.508)
				(mid 13.624961 -0.522879)
				(end 13.610082 -0.5588)
			)
			(arc
				(start 13.610082 -2.701036)
				(mid 13.621129 -2.732411)
				(end 13.649198 -2.750312)
			)
			(xy 13.762482 -2.77749) (xy 13.794486 -2.762504)
			(arc
				(start 13.80236 -2.746756)
				(mid 13.928356 -2.557713)
				(end 14.095984 -2.404364)
			)
			(xy 14.11732 -2.363216) (xy 14.11732 -1.014984) (xy 80.686656 -1.014984) (xy 80.686656 -2.363216)
			(arc
				(start 80.707992 -2.404364)
				(mid 80.875659 -2.55768)
				(end 81.001616 -2.746756)
			)
			(xy 81.00949 -2.762504) (xy 81.041494 -2.77749)
		)
		(stroke
			(width 0)
			(type solid)
		)
		(fill yes)
		(layer "In6.Cu")
		(net "GND")
	)
	(gr_poly
		(pts
			(arc
				(start 194.154806 -8.03021)
				(mid 194.182945 -8.012364)
				(end 194.193922 -7.980934)
			)
			(arc
				(start 194.193922 -5.838698)
				(mid 194.179043 -5.802777)
				(end 194.143122 -5.787898)
			)
			(arc
				(start 126.66091 -5.787898)
				(mid 126.624989 -5.802777)
				(end 126.61011 -5.838698)
			)
			(arc
				(start 126.61011 -7.980934)
				(mid 126.621157 -8.012309)
				(end 126.649226 -8.03021)
			)
			(xy 126.76251 -8.057388) (xy 126.794514 -8.042402)
			(arc
				(start 126.802388 -8.026654)
				(mid 126.928384 -7.837611)
				(end 127.096012 -7.684262)
			)
			(xy 127.117348 -7.643114) (xy 127.117348 -6.295136) (xy 193.686684 -6.295136) (xy 193.686684 -7.643114)
			(arc
				(start 193.70802 -7.684262)
				(mid 193.875687 -7.837578)
				(end 194.001644 -8.026654)
			)
			(xy 194.009518 -8.042402) (xy 194.041522 -8.057388)
		)
		(stroke
			(width 0)
			(type solid)
		)
		(fill yes)
		(layer "In6.Cu")
		(net "GND")
	)
	(gr_poly
		(pts
			(arc
				(start 455.654918 -2.75082)
				(mid 455.683057 -2.732974)
				(end 455.694034 -2.701544)
			)
			(arc
				(start 455.694034 -0.5588)
				(mid 455.679155 -0.522879)
				(end 455.643234 -0.508)
			)
			(arc
				(start 388.160768 -0.508)
				(mid 388.124847 -0.522879)
				(end 388.109968 -0.5588)
			)
			(arc
				(start 388.109968 -2.701036)
				(mid 388.121015 -2.732411)
				(end 388.149084 -2.750312)
			)
			(xy 388.262368 -2.77749) (xy 388.294372 -2.762504)
			(arc
				(start 388.302246 -2.746756)
				(mid 388.428345 -2.557672)
				(end 388.596124 -2.404364)
			)
			(arc
				(start 388.596124 -2.404364)
				(mid 388.610195 -2.388884)
				(end 388.616952 -2.369058)
			)
			(xy 388.616952 -1.014984) (xy 455.186796 -1.014984) (xy 455.186796 -2.36347)
			(arc
				(start 455.208132 -2.404618)
				(mid 455.3758 -2.558068)
				(end 455.501756 -2.747264)
			)
			(xy 455.50963 -2.763012) (xy 455.54138 -2.777744)
		)
		(stroke
			(width 0)
			(type solid)
		)
		(fill yes)
		(layer "In6.Cu")
		(net "GND")
	)
	(gr_poly
		(pts
			(arc
				(start 6.198616 -404.900384)
				(mid 6.234537 -404.885505)
				(end 6.249416 -404.849584)
			)
			(arc
				(start 6.249416 -399.824702)
				(mid 6.288207 -399.630158)
				(end 6.398514 -399.465292)
			)
			(arc
				(start 11.096752 -394.767054)
				(mid 11.111512 -394.73115)
				(end 11.096752 -394.695172)
			)
			(arc
				(start 10.635234 -394.233654)
				(mid 10.524969 -394.06877)
				(end 10.486136 -393.874244)
			)
			(arc
				(start 10.486136 -389.119872)
				(mid 10.482352 -389.100378)
				(end 10.471404 -389.083804)
			)
			(arc
				(start 4.074922 -382.687576)
				(mid 4.048931 -382.67357)
				(end 4.01955 -382.6764)
			)
			(xy 4.005326 -382.682496) (xy 3.988308 -382.707896)
			(arc
				(start 3.988308 -403.319996)
				(mid 3.992209 -403.339519)
				(end 4.003294 -403.356064)
			)
			(arc
				(start 5.532628 -404.885398)
				(mid 5.549162 -404.896509)
				(end 5.568696 -404.900384)
			)
		)
		(stroke
			(width 0)
			(type solid)
		)
		(fill yes)
		(layer "In6.Cu")
		(net "GND")
	)
	(gr_poly
		(pts
			(arc
				(start 7.548626 -137.9601)
				(mid 7.568149 -137.956199)
				(end 7.584694 -137.945114)
			)
			(arc
				(start 7.679944 -137.849864)
				(mid 7.691055 -137.83333)
				(end 7.69493 -137.813796)
			)
			(xy 7.69493 -135.794496) (xy 7.67461 -135.767572)
			(arc
				(start 7.6581 -135.762746)
				(mid 7.381151 -135.39597)
				(end 7.6581 -135.029194)
			)
			(xy 7.67461 -135.024368) (xy 7.69493 -134.997444)
			(arc
				(start 7.69493 -132.962396)
				(mid 7.691029 -132.942873)
				(end 7.679944 -132.926328)
			)
			(arc
				(start 7.584694 -132.831078)
				(mid 7.56816 -132.819967)
				(end 7.548626 -132.816092)
			)
			(arc
				(start 4.00177 -132.816092)
				(mid 3.982247 -132.819993)
				(end 3.965702 -132.831078)
			)
			(arc
				(start 3.870452 -132.926328)
				(mid 3.859341 -132.942862)
				(end 3.855466 -132.962396)
			)
			(arc
				(start 3.855466 -137.813796)
				(mid 3.859367 -137.833319)
				(end 3.870452 -137.849864)
			)
			(arc
				(start 3.965702 -137.945114)
				(mid 3.982236 -137.956225)
				(end 4.00177 -137.9601)
			)
		)
		(stroke
			(width 0)
			(type solid)
		)
		(fill yes)
		(layer "In6.Cu")
		(net "GND")
	)
	(gr_poly
		(pts
			(arc
				(start 379.600968 -137.280142)
				(mid 379.660504 -137.26549)
				(end 379.721618 -137.260584)
			)
			(arc
				(start 379.721618 -137.260584)
				(mid 379.751425 -137.26171)
				(end 379.781054 -137.265156)
			)
			(xy 379.793246 -137.267188) (xy 379.816106 -137.259822)
			(arc
				(start 380.097284 -136.97839)
				(mid 380.16336 -136.934239)
				(end 380.241302 -136.9187)
			)
			(arc
				(start 384.87604 -136.9187)
				(mid 384.903039 -136.911091)
				(end 384.92176 -136.890252)
			)
			(xy 384.968242 -136.794748) (xy 384.965194 -136.766046)
			(arc
				(start 384.95605 -136.754616)
				(mid 384.895674 -136.643701)
				(end 384.87477 -136.519158)
			)
			(arc
				(start 384.87477 -136.519158)
				(mid 384.907764 -136.364015)
				(end 385.001008 -136.235694)
			)
			(xy 385.012692 -136.225026) (xy 385.020058 -136.194546)
			(arc
				(start 384.980434 -136.091168)
				(mid 384.961721 -136.067594)
				(end 384.932936 -136.058656)
			)
			(arc
				(start 380.421896 -136.058656)
				(mid 380.402402 -136.06244)
				(end 380.385828 -136.073388)
			)
			(xy 379.480826 -136.97839) (xy 379.47346 -137.00125)
			(arc
				(start 379.475492 -137.013442)
				(mid 379.478944 -137.04307)
				(end 379.480064 -137.072878)
			)
			(arc
				(start 379.480064 -137.072878)
				(mid 379.477535 -137.116989)
				(end 379.469904 -137.160508)
			)
			(xy 379.466602 -137.17397) (xy 379.47473 -137.200386) (xy 379.560836 -137.278872) (xy 379.58776 -137.28446)
		)
		(stroke
			(width 0)
			(type solid)
		)
		(fill yes)
		(layer "In6.Cu")
		(net "GND")
	)
	(gr_poly
		(pts
			(xy 107.850686 -25.448514) (xy 108.3818 -24.9174) (xy 108.3818 -21.719286) (xy 108.3818 -20.6756)
			(xy 107.3658 -19.6596) (xy 104.1654 -19.6596) (xy 103.7844 -20.0406) (xy 103.7844 -24.54148) (xy 104.799891 -24.54148)
			(xy 104.803956 -24.485932) (xy 104.816066 -24.431567) (xy 104.835963 -24.379546) (xy 104.863222 -24.330975)
			(xy 104.897262 -24.286892) (xy 104.937359 -24.248234) (xy 104.982656 -24.215826) (xy 105.03219 -24.190359)
			(xy 105.084904 -24.172376) (xy 105.139674 -24.162259) (xy 105.195333 -24.160225) (xy 105.250696 -24.166317)
			(xy 105.304582 -24.180404) (xy 105.355842 -24.202188) (xy 105.403385 -24.231202) (xy 105.446196 -24.26683)
			(xy 105.483363 -24.308311) (xy 105.514095 -24.354762) (xy 105.537736 -24.405193) (xy 105.553782 -24.458528)
			(xy 105.561892 -24.513632) (xy 105.5624 -24.54148) (xy 106.273091 -24.54148) (xy 106.277156 -24.485932)
			(xy 106.289266 -24.431567) (xy 106.309163 -24.379546) (xy 106.336422 -24.330975) (xy 106.370462 -24.286892)
			(xy 106.410559 -24.248234) (xy 106.455856 -24.215826) (xy 106.50539 -24.190359) (xy 106.558104 -24.172376)
			(xy 106.612874 -24.162259) (xy 106.668533 -24.160225) (xy 106.723896 -24.166317) (xy 106.777782 -24.180404)
			(xy 106.829042 -24.202188) (xy 106.876585 -24.231202) (xy 106.919396 -24.26683) (xy 106.956563 -24.308311)
			(xy 106.987295 -24.354762) (xy 107.010936 -24.405193) (xy 107.026982 -24.458528) (xy 107.035092 -24.513632)
			(xy 107.0356 -24.54148) (xy 107.035092 -24.569328) (xy 107.026982 -24.624432) (xy 107.010936 -24.677767)
			(xy 106.987295 -24.728198) (xy 106.956563 -24.774649) (xy 106.919396 -24.81613) (xy 106.876585 -24.851758)
			(xy 106.829042 -24.880772) (xy 106.777782 -24.902556) (xy 106.723896 -24.916643) (xy 106.668533 -24.922735)
			(xy 106.612874 -24.920701) (xy 106.558104 -24.910584) (xy 106.50539 -24.892601) (xy 106.455856 -24.867134)
			(xy 106.410559 -24.834726) (xy 106.370462 -24.796068) (xy 106.336422 -24.751985) (xy 106.309163 -24.703414)
			(xy 106.289266 -24.651393) (xy 106.277156 -24.597028) (xy 106.273091 -24.54148) (xy 105.5624 -24.54148)
			(xy 105.561892 -24.569328) (xy 105.553782 -24.624432) (xy 105.537736 -24.677767) (xy 105.514095 -24.728198)
			(xy 105.483363 -24.774649) (xy 105.446196 -24.81613) (xy 105.403385 -24.851758) (xy 105.355842 -24.880772)
			(xy 105.304582 -24.902556) (xy 105.250696 -24.916643) (xy 105.195333 -24.922735) (xy 105.139674 -24.920701)
			(xy 105.084904 -24.910584) (xy 105.03219 -24.892601) (xy 104.982656 -24.867134) (xy 104.937359 -24.834726)
			(xy 104.897262 -24.796068) (xy 104.863222 -24.751985) (xy 104.835963 -24.703414) (xy 104.816066 -24.651393)
			(xy 104.803956 -24.597028) (xy 104.799891 -24.54148) (xy 103.7844 -24.54148) (xy 103.7844 -25.3238)
			(xy 104.2416 -25.781) (xy 107.5182 -25.781)
		)
		(stroke
			(width 0)
			(type solid)
		)
		(fill yes)
		(layer "In6.Cu")
		(net "GND")
	)
	(gr_poly
		(pts
			(xy 125.734318 -31.1658) (xy 125.744387 -31.165373) (xy 125.762986 -31.157654) (xy 125.770386 -31.150814)
			(xy 126.477014 -30.444186) (xy 126.484409 -30.437332) (xy 126.503008 -30.42959) (xy 126.513082 -30.4292)
			(xy 127.410718 -30.4292) (xy 127.420787 -30.428773) (xy 127.439386 -30.421054) (xy 127.446786 -30.414214)
			(xy 128.432814 -29.428186) (xy 128.439668 -29.420791) (xy 128.44741 -29.402192) (xy 128.4478 -29.392118)
			(xy 128.4478 -27.351482) (xy 128.447373 -27.341413) (xy 128.439654 -27.322814) (xy 128.432814 -27.315414)
			(xy 127.776986 -26.659586) (xy 127.769591 -26.652732) (xy 127.750992 -26.64499) (xy 127.740918 -26.6446)
			(xy 123.744482 -26.6446) (xy 123.734413 -26.645027) (xy 123.715814 -26.652746) (xy 123.708414 -26.659586)
			(xy 122.519186 -27.848814) (xy 122.512332 -27.856209) (xy 122.50459 -27.874808) (xy 122.5042 -27.884882)
			(xy 122.5042 -28.264104) (xy 127.316482 -28.264104) (xy 127.320553 -28.208482) (xy 127.332679 -28.154045)
			(xy 127.352602 -28.101954) (xy 127.379898 -28.053319) (xy 127.413984 -28.009176) (xy 127.454133 -27.970467)
			(xy 127.499491 -27.938016) (xy 127.549091 -27.912515) (xy 127.601875 -27.894508) (xy 127.656718 -27.884378)
			(xy 127.712452 -27.882341) (xy 127.767889 -27.888441) (xy 127.821846 -27.902547) (xy 127.873175 -27.924359)
			(xy 127.920781 -27.953413) (xy 127.963649 -27.989088) (xy 128.000866 -28.030625) (xy 128.031639 -28.077138)
			(xy 128.055311 -28.127635) (xy 128.071379 -28.181042) (xy 128.079499 -28.236218) (xy 128.080008 -28.264104)
			(xy 128.079499 -28.29199) (xy 128.071379 -28.347166) (xy 128.055311 -28.400573) (xy 128.031639 -28.45107)
			(xy 128.000866 -28.497583) (xy 127.963649 -28.53912) (xy 127.920781 -28.574795) (xy 127.873175 -28.603849)
			(xy 127.821846 -28.625661) (xy 127.767889 -28.639767) (xy 127.712452 -28.645867) (xy 127.656718 -28.64383)
			(xy 127.601875 -28.6337) (xy 127.549091 -28.615693) (xy 127.499491 -28.590192) (xy 127.454133 -28.557741)
			(xy 127.413984 -28.519032) (xy 127.379898 -28.474889) (xy 127.352602 -28.426254) (xy 127.332679 -28.374163)
			(xy 127.320553 -28.319726) (xy 127.316482 -28.264104) (xy 122.5042 -28.264104) (xy 122.5042 -29.530294)
			(xy 126.789178 -29.530294) (xy 126.793249 -29.474672) (xy 126.805375 -29.420235) (xy 126.825298 -29.368144)
			(xy 126.852594 -29.319509) (xy 126.88668 -29.275366) (xy 126.926829 -29.236657) (xy 126.972187 -29.204206)
			(xy 127.021787 -29.178705) (xy 127.074571 -29.160698) (xy 127.129414 -29.150568) (xy 127.185148 -29.148531)
			(xy 127.240585 -29.154631) (xy 127.294542 -29.168737) (xy 127.345871 -29.190549) (xy 127.393477 -29.219603)
			(xy 127.436345 -29.255278) (xy 127.473562 -29.296815) (xy 127.504335 -29.343328) (xy 127.528007 -29.393825)
			(xy 127.544075 -29.447232) (xy 127.552195 -29.502408) (xy 127.552704 -29.530294) (xy 127.552195 -29.55818)
			(xy 127.544075 -29.613356) (xy 127.528007 -29.666763) (xy 127.504335 -29.71726) (xy 127.473562 -29.763773)
			(xy 127.436345 -29.80531) (xy 127.393477 -29.840985) (xy 127.345871 -29.870039) (xy 127.294542 -29.891851)
			(xy 127.240585 -29.905957) (xy 127.185148 -29.912057) (xy 127.129414 -29.91002) (xy 127.074571 -29.89989)
			(xy 127.021787 -29.881883) (xy 126.972187 -29.856382) (xy 126.926829 -29.823931) (xy 126.88668 -29.785222)
			(xy 126.852594 -29.741079) (xy 126.825298 -29.692444) (xy 126.805375 -29.640353) (xy 126.793249 -29.585916)
			(xy 126.789178 -29.530294) (xy 122.5042 -29.530294) (xy 122.5042 -30.331918) (xy 122.504627 -30.341987)
			(xy 122.512346 -30.360586) (xy 122.519186 -30.367986) (xy 123.302014 -31.150814) (xy 123.309409 -31.157668)
			(xy 123.328008 -31.16541) (xy 123.338082 -31.1658)
		)
		(stroke
			(width 0)
			(type solid)
		)
		(fill yes)
		(layer "In6.Cu")
		(net "GND")
	)
	(gr_poly
		(pts
			(arc
				(start 124.102114 -12.795504)
				(mid 126.234222 -11.912198)
				(end 127.117348 -9.780016)
			)
			(arc
				(start 127.117348 -9.256776)
				(mid 127.111697 -9.233491)
				(end 127.096012 -9.215374)
			)
			(arc
				(start 127.096012 -9.215374)
				(mid 126.928345 -9.062058)
				(end 126.802388 -8.872982)
			)
			(xy 126.794514 -8.857234) (xy 126.76251 -8.842248)
			(arc
				(start 126.649226 -8.869426)
				(mid 126.621087 -8.887272)
				(end 126.61011 -8.918702)
			)
			(arc
				(start 126.61011 -9.780016)
				(mid 125.875535 -11.553437)
				(end 124.102114 -12.288012)
			)
			(arc
				(start 83.70189 -12.288012)
				(mid 81.928469 -11.553437)
				(end 81.193894 -9.780016)
			)
			(arc
				(start 81.193894 -3.638804)
				(mid 81.182847 -3.607429)
				(end 81.154778 -3.589528)
			)
			(xy 81.041494 -3.56235) (xy 81.00949 -3.577336)
			(arc
				(start 81.001616 -3.593084)
				(mid 80.87562 -3.782127)
				(end 80.707992 -3.935476)
			)
			(arc
				(start 80.707992 -3.935476)
				(mid 80.692292 -3.953586)
				(end 80.686656 -3.976878)
			)
			(arc
				(start 80.686656 -9.780016)
				(mid 80.687352 -9.850646)
				(end 80.689704 -9.92124)
			)
			(arc
				(start 80.689704 -9.92124)
				(mid 80.694009 -9.939548)
				(end 80.70469 -9.955022)
			)
			(arc
				(start 80.753712 -10.00379)
				(mid 80.821354 -10.105073)
				(end 80.845152 -10.224516)
			)
			(arc
				(start 80.845152 -10.737088)
				(mid 80.845847 -10.745463)
				(end 80.847946 -10.753598)
			)
			(arc
				(start 80.847946 -10.753598)
				(mid 81.947313 -12.232426)
				(end 83.70189 -12.795504)
			)
		)
		(stroke
			(width 0)
			(type solid)
		)
		(fill yes)
		(layer "In6.Cu")
		(net "GND")
	)
	(gr_poly
		(pts
			(arc
				(start 200.806558 -32.013398)
				(mid 200.826081 -32.009497)
				(end 200.842626 -31.998412)
			)
			(arc
				(start 202.018646 -30.822392)
				(mid 202.029757 -30.805858)
				(end 202.033632 -30.786324)
			)
			(arc
				(start 202.033632 -29.275278)
				(mid 202.029731 -29.255755)
				(end 202.018646 -29.23921)
			)
			(arc
				(start 197.91807 -25.138634)
				(mid 197.906959 -25.1221)
				(end 197.903084 -25.102566)
			)
			(arc
				(start 197.903084 -22.408896)
				(mid 197.899183 -22.389373)
				(end 197.888098 -22.372828)
			)
			(xy 196.20865 -20.69338) (xy 196.192648 -20.686014)
			(arc
				(start 196.183504 -20.685252)
				(mid 195.949282 -20.623172)
				(end 195.750688 -20.484338)
			)
			(arc
				(start 195.633848 -20.367498)
				(mid 195.495009 -20.168907)
				(end 195.432934 -19.934682)
			)
			(xy 195.432172 -19.925538) (xy 195.424806 -19.909536)
			(arc
				(start 193.994278 -18.479008)
				(mid 193.983167 -18.462474)
				(end 193.979292 -18.44294)
			)
			(arc
				(start 193.979292 -13.323824)
				(mid 193.975391 -13.304301)
				(end 193.964306 -13.287756)
			)
			(arc
				(start 193.447924 -12.771374)
				(mid 193.43139 -12.760263)
				(end 193.411856 -12.756388)
			)
			(arc
				(start 191.686688 -12.756388)
				(mid 191.667165 -12.760289)
				(end 191.65062 -12.771374)
			)
			(xy 191.209676 -13.212318) (xy 191.20231 -13.21943) (xy 191.19469 -13.238226) (xy 191.19469 -14.80312)
			(xy 191.2112 -14.828266)
			(arc
				(start 191.225424 -14.834362)
				(mid 191.455773 -15.184628)
				(end 191.225424 -15.534894)
			)
			(xy 191.2112 -15.54099) (xy 191.19469 -15.566136)
			(arc
				(start 191.19469 -17.894554)
				(mid 191.197713 -17.911817)
				(end 191.206374 -17.927066)
			)
			(arc
				(start 191.206374 -17.927066)
				(mid 191.357299 -18.187994)
				(end 191.412368 -18.484342)
			)
			(xy 191.412622 -18.496788) (xy 191.424052 -18.518124) (xy 191.511682 -18.579592) (xy 191.535812 -18.582894)
			(arc
				(start 191.547496 -18.57883)
				(mid 191.609703 -18.562705)
				(end 191.673734 -18.55724)
			)
			(arc
				(start 191.673734 -18.55724)
				(mid 192.055242 -18.938748)
				(end 191.673734 -19.320256)
			)
			(arc
				(start 191.673734 -19.320256)
				(mid 191.46187 -19.25597)
				(end 191.321436 -19.084798)
			)
			(xy 191.316102 -19.072606) (xy 191.296036 -19.056604)
			(arc
				(start 191.253872 -19.049238)
				(mid 191.231919 -19.05039)
				(end 191.21247 -19.060668)
			)
			(xy 191.204088 -19.06778) (xy 191.19469 -19.087846)
			(arc
				(start 191.19469 -19.492976)
				(mid 191.198591 -19.512499)
				(end 191.209676 -19.529044)
			)
			(arc
				(start 193.856356 -22.175724)
				(mid 193.867467 -22.192258)
				(end 193.871342 -22.211792)
			)
			(arc
				(start 193.871342 -26.614882)
				(mid 193.872821 -26.627051)
				(end 193.877184 -26.638504)
			)
			(arc
				(start 193.877184 -26.638504)
				(mid 193.952818 -26.838616)
				(end 193.97853 -27.051)
			)
			(arc
				(start 193.97853 -27.051)
				(mid 193.952863 -27.263395)
				(end 193.877184 -27.463496)
			)
			(arc
				(start 193.877184 -27.463496)
				(mid 193.872835 -27.474953)
				(end 193.871342 -27.487118)
			)
			(arc
				(start 193.871342 -30.52191)
				(mid 193.875243 -30.541433)
				(end 193.886328 -30.557978)
			)
			(arc
				(start 195.326762 -31.998412)
				(mid 195.343296 -32.009523)
				(end 195.36283 -32.013398)
			)
		)
		(stroke
			(width 0)
			(type solid)
		)
		(fill yes)
		(layer "In6.Cu")
		(net "P12V_SCM")
	)
	(gr_poly
		(pts
			(xy 320.836798 -23.9903) (xy 320.846786 -23.989763) (xy 320.865218 -23.98205) (xy 320.872612 -23.975314)
			(xy 321.404234 -23.443692) (xy 321.41105 -23.436349) (xy 321.41879 -23.417886) (xy 321.41922 -23.407878)
			(xy 321.41922 -21.987002) (xy 321.419643 -21.976932) (xy 321.427359 -21.958329) (xy 321.434206 -21.950934)
			(xy 326.964294 -16.420846) (xy 326.97169 -16.413994) (xy 326.990288 -16.40625) (xy 327.000362 -16.40586)
			(xy 342.909398 -16.40586) (xy 342.919467 -16.406284) (xy 342.938066 -16.414005) (xy 342.945466 -16.420846)
			(xy 343.609676 -17.085056) (xy 345.451682 -17.085056) (xy 345.455753 -17.029434) (xy 345.467879 -16.974997)
			(xy 345.487802 -16.922906) (xy 345.515098 -16.874271) (xy 345.549184 -16.830128) (xy 345.589333 -16.791419)
			(xy 345.634691 -16.758968) (xy 345.684291 -16.733467) (xy 345.737075 -16.71546) (xy 345.791918 -16.70533)
			(xy 345.847652 -16.703293) (xy 345.903089 -16.709393) (xy 345.957046 -16.723499) (xy 346.008375 -16.745311)
			(xy 346.055981 -16.774365) (xy 346.098849 -16.81004) (xy 346.136066 -16.851577) (xy 346.166839 -16.89809)
			(xy 346.190511 -16.948587) (xy 346.206579 -17.001994) (xy 346.214699 -17.05717) (xy 346.215208 -17.085056)
			(xy 346.214699 -17.112942) (xy 346.206579 -17.168118) (xy 346.190511 -17.221525) (xy 346.166839 -17.272022)
			(xy 346.136066 -17.318535) (xy 346.098849 -17.360072) (xy 346.055981 -17.395747) (xy 346.008375 -17.424801)
			(xy 345.957046 -17.446613) (xy 345.903089 -17.460719) (xy 345.847652 -17.466819) (xy 345.791918 -17.464782)
			(xy 345.737075 -17.454652) (xy 345.684291 -17.436645) (xy 345.634691 -17.411144) (xy 345.589333 -17.378693)
			(xy 345.549184 -17.339984) (xy 345.515098 -17.295841) (xy 345.487802 -17.247206) (xy 345.467879 -17.195115)
			(xy 345.455753 -17.140678) (xy 345.451682 -17.085056) (xy 343.609676 -17.085056) (xy 344.800174 -18.275554)
			(xy 344.807574 -18.282394) (xy 344.826173 -18.290109) (xy 344.836242 -18.29054) (xy 346.815918 -18.29054)
			(xy 346.825985 -18.290112) (xy 346.844579 -18.282386) (xy 346.851986 -18.275554) (xy 347.281754 -17.845786)
			(xy 347.289151 -17.838939) (xy 347.307751 -17.831211) (xy 347.317822 -17.8308) (xy 347.872558 -17.8308)
			(xy 347.882623 -17.830366) (xy 347.901213 -17.822637) (xy 347.908626 -17.815814) (xy 348.109794 -17.614646)
			(xy 348.116633 -17.607245) (xy 348.124348 -17.588647) (xy 348.12478 -17.578578) (xy 348.12478 -14.013942)
			(xy 348.124346 -14.003877) (xy 348.116614 -13.98529) (xy 348.109794 -13.977874) (xy 347.588586 -13.456666)
			(xy 347.58119 -13.449815) (xy 347.562591 -13.442075) (xy 347.552518 -13.44168) (xy 324.404482 -13.44168)
			(xy 324.394413 -13.442106) (xy 324.375811 -13.449823) (xy 324.368414 -13.456666) (xy 319.181226 -18.643854)
			(xy 319.174385 -18.651254) (xy 319.166667 -18.669853) (xy 319.16624 -18.679922) (xy 319.16624 -22.494748)
			(xy 319.166572 -22.503642) (xy 319.172651 -22.520357) (xy 319.184092 -22.533976) (xy 319.19164 -22.53869)
			(xy 319.220263 -22.555778) (xy 319.273188 -22.596309) (xy 319.320363 -22.64341) (xy 319.360978 -22.696271)
			(xy 319.394337 -22.753987) (xy 319.419867 -22.815568) (xy 319.43713 -22.879956) (xy 319.445832 -22.946049)
			(xy 319.446402 -22.97938) (xy 319.445965 -23.009584) (xy 319.438798 -23.069564) (xy 319.424576 -23.128274)
			(xy 319.403499 -23.184884) (xy 319.375862 -23.238599) (xy 319.342057 -23.288661) (xy 319.302558 -23.334366)
			(xy 319.28054 -23.355046) (xy 319.27292 -23.362158) (xy 319.264284 -23.380954) (xy 319.262506 -23.464774)
			(xy 319.262729 -23.475076) (xy 319.270337 -23.494205) (xy 319.277238 -23.501858) (xy 319.316608 -23.541228)
			(xy 319.323974 -23.548068) (xy 319.342507 -23.55581) (xy 319.362591 -23.55581) (xy 319.381124 -23.548068)
			(xy 319.38849 -23.541228) (xy 319.394586 -23.535386) (xy 319.401698 -23.521162) (xy 319.402968 -23.51278)
			(xy 319.408317 -23.480304) (xy 319.426306 -23.416992) (xy 319.452312 -23.35653) (xy 319.485902 -23.299929)
			(xy 319.526514 -23.248134) (xy 319.573468 -23.202011) (xy 319.62598 -23.162332) (xy 319.683173 -23.129758)
			(xy 319.74409 -23.104836) (xy 319.807713 -23.087981) (xy 319.872979 -23.079475) (xy 319.905888 -23.078948)
			(xy 319.93662 -23.079411) (xy 319.997637 -23.086818) (xy 320.057317 -23.101525) (xy 320.114788 -23.123319)
			(xy 320.169214 -23.151881) (xy 320.2198 -23.186794) (xy 320.26581 -23.227551) (xy 320.306571 -23.273556)
			(xy 320.34149 -23.324138) (xy 320.370058 -23.378561) (xy 320.391858 -23.43603) (xy 320.406572 -23.495707)
			(xy 320.413986 -23.556724) (xy 320.414396 -23.587456) (xy 320.413901 -23.62031) (xy 320.405469 -23.685473)
			(xy 320.388704 -23.749004) (xy 320.363883 -23.809843) (xy 320.348102 -23.838662) (xy 320.341244 -23.850346)
			(xy 320.341498 -23.87727) (xy 320.392552 -23.965154) (xy 320.397304 -23.97265) (xy 320.410933 -23.984004)
			(xy 320.427624 -23.99001) (xy 320.436494 -23.9903)
		)
		(stroke
			(width 0)
			(type solid)
		)
		(fill yes)
		(layer "In6.Cu")
		(net "P5V_AUX")
	)
	(gr_poly
		(pts
			(arc
				(start 467.792054 -82.82813)
				(mid 467.983012 -81.868498)
				(end 468.526622 -81.054956)
			)
			(arc
				(start 470.85504 -78.726538)
				(mid 471.178373 -78.242681)
				(end 471.29192 -77.67193)
			)
			(arc
				(start 471.29192 -13.780008)
				(mid 470.854924 -12.725008)
				(end 469.799924 -12.288012)
			)
			(arc
				(start 458.20203 -12.288012)
				(mid 456.428609 -11.553437)
				(end 455.694034 -9.780016)
			)
			(xy 455.694034 -3.638296)
			(arc
				(start 455.693526 -3.63093)
				(mid 455.680691 -3.603937)
				(end 455.654918 -3.588766)
			)
			(xy 455.541634 -3.561842) (xy 455.509884 -3.576574) (xy 455.509884 -3.576828) (xy 455.50963 -3.576828)
			(arc
				(start 455.501756 -3.592576)
				(mid 455.377933 -3.779283)
				(end 455.213466 -3.931412)
			)
			(xy 455.212704 -3.93192)
			(arc
				(start 455.208132 -3.935222)
				(mid 455.192432 -3.953332)
				(end 455.186796 -3.976624)
			)
			(arc
				(start 455.186796 -9.780524)
				(mid 456.070027 -11.912452)
				(end 458.20203 -12.795504)
			)
			(arc
				(start 469.799924 -12.795504)
				(mid 470.496073 -13.083859)
				(end 470.784428 -13.780008)
			)
			(arc
				(start 470.784428 -77.672184)
				(mid 470.70959 -78.048688)
				(end 470.496392 -78.36789)
			)
			(arc
				(start 468.167974 -80.696308)
				(mid 467.514407 -81.674395)
				(end 467.284816 -82.82813)
			)
			(arc
				(start 467.284816 -357.040688)
				(mid 467.554494 -357.44994)
				(end 467.792054 -357.878634)
			)
		)
		(stroke
			(width 0)
			(type solid)
		)
		(fill yes)
		(layer "In6.Cu")
		(net "GND")
	)
	(gr_poly
		(pts
			(arc
				(start 2.507996 -339.99297)
				(mid 2.607946 -340.094557)
				(end 2.711196 -339.996272)
			)
			(xy 3.015488 -330.71562) (xy 3.015488 -330.714096)
			(arc
				(start 3.015488 -81.32826)
				(mid 2.785816 -80.174473)
				(end 2.132076 -79.196438)
			)
			(arc
				(start 1.303528 -78.36789)
				(mid 1.090411 -78.048655)
				(end 1.015492 -77.672184)
			)
			(arc
				(start 1.015492 -13.780008)
				(mid 1.303847 -13.083859)
				(end 1.999996 -12.795504)
			)
			(arc
				(start 11.102086 -12.795504)
				(mid 13.234194 -11.912198)
				(end 14.11732 -9.780016)
			)
			(arc
				(start 14.11732 -3.98907)
				(mid 14.115908 -3.977177)
				(end 14.111732 -3.965956)
			)
			(xy 14.098778 -3.94081) (xy 14.091412 -3.932174)
			(arc
				(start 14.086332 -3.928618)
				(mid 13.924474 -3.77767)
				(end 13.80236 -3.593084)
			)
			(xy 13.794232 -3.577082) (xy 13.762482 -3.56235)
			(arc
				(start 13.649198 -3.589274)
				(mid 13.62338 -3.604404)
				(end 13.61059 -3.631438)
			)
			(xy 13.610082 -3.638804)
			(arc
				(start 13.610082 -9.780016)
				(mid 12.875507 -11.553437)
				(end 11.102086 -12.288012)
			)
			(arc
				(start 1.999996 -12.288012)
				(mid 0.944996 -12.725008)
				(end 0.508 -13.780008)
			)
			(arc
				(start 0.508 -77.67193)
				(mid 0.621601 -78.242658)
				(end 0.94488 -78.726538)
			)
			(arc
				(start 1.773428 -79.555086)
				(mid 2.317047 -80.368624)
				(end 2.507996 -81.32826)
			)
		)
		(stroke
			(width 0)
			(type solid)
		)
		(fill yes)
		(layer "In6.Cu")
		(net "GND")
	)
	(gr_poly
		(pts
			(xy 128.587246 -40.962072) (xy 128.59639 -40.961735) (xy 128.613542 -40.955397) (xy 128.627373 -40.943437)
			(xy 128.636122 -40.927381) (xy 128.637792 -40.918384) (xy 128.638046 -40.9067) (xy 128.636522 -40.87368)
			(xy 128.636522 -40.873426) (xy 128.636984 -40.846173) (xy 128.644738 -40.792221) (xy 128.660092 -40.739921)
			(xy 128.682733 -40.69034) (xy 128.712201 -40.644486) (xy 128.747895 -40.603292) (xy 128.789089 -40.567599)
			(xy 128.834943 -40.538131) (xy 128.884525 -40.51549) (xy 128.936824 -40.500137) (xy 128.990777 -40.492383)
			(xy 129.01803 -40.491918) (xy 129.018538 -40.491918) (xy 129.045512 -40.492386) (xy 129.098922 -40.499988)
			(xy 129.150729 -40.515035) (xy 129.17551 -40.5257) (xy 129.185036 -40.529473) (xy 129.205504 -40.52993)
			(xy 129.22454 -40.522398) (xy 129.232152 -40.51554) (xy 129.940304 -39.807388) (xy 129.949598 -39.798178)
			(xy 129.968909 -39.780517) (xy 129.978912 -39.772082) (xy 129.987123 -39.764527) (xy 129.996608 -39.744362)
			(xy 129.9972 -39.73322) (xy 129.9972 -35.250882) (xy 129.997627 -35.240813) (xy 130.005346 -35.222214)
			(xy 130.012186 -35.214814) (xy 130.820414 -34.406586) (xy 130.827809 -34.399732) (xy 130.846408 -34.39199)
			(xy 130.856482 -34.3916) (xy 134.979918 -34.3916) (xy 134.989987 -34.392027) (xy 135.008586 -34.399746)
			(xy 135.015986 -34.406586) (xy 135.722614 -35.113214) (xy 135.729468 -35.120609) (xy 135.73721 -35.139208)
			(xy 135.7376 -35.149282) (xy 135.7376 -39.590472) (xy 135.738015 -39.600497) (xy 135.74568 -39.619024)
			(xy 135.759853 -39.633205) (xy 135.778375 -39.64088) (xy 135.7884 -39.641272) (xy 137.161016 -39.641272)
			(xy 137.172798 -39.640725) (xy 137.193933 -39.630321) (xy 137.208195 -39.611571) (xy 137.211054 -39.600124)
			(xy 137.216541 -39.574417) (xy 137.233638 -39.52471) (xy 137.257399 -39.477822) (xy 137.287372 -39.43464)
			(xy 137.322991 -39.395982) (xy 137.36358 -39.362581) (xy 137.40837 -39.335069) (xy 137.456514 -39.313968)
			(xy 137.507099 -39.299677) (xy 137.559167 -39.292466) (xy 137.58545 -39.292022) (xy 137.611306 -39.292457)
			(xy 137.662542 -39.299455) (xy 137.712362 -39.313315) (xy 137.75985 -39.333783) (xy 137.804135 -39.360484)
			(xy 137.844404 -39.392926) (xy 137.879918 -39.430515) (xy 137.89533 -39.45128) (xy 137.896346 -39.452804)
			(xy 137.903254 -39.460828) (xy 137.921854 -39.470891) (xy 137.942931 -39.472617) (xy 137.962921 -39.465714)
			(xy 137.971022 -39.4589) (xy 137.972546 -39.45763) (xy 138.262614 -39.167562) (xy 138.269464 -39.160166)
			(xy 138.277198 -39.141566) (xy 138.2776 -39.131494) (xy 138.2776 -35.479482) (xy 138.277173 -35.469413)
			(xy 138.269454 -35.450814) (xy 138.262614 -35.443414) (xy 138.140186 -35.320986) (xy 138.132791 -35.314132)
			(xy 138.114192 -35.30639) (xy 138.104118 -35.306) (xy 137.231882 -35.306) (xy 137.221813 -35.305573)
			(xy 137.203214 -35.297854) (xy 137.195814 -35.291014) (xy 136.692386 -34.787586) (xy 136.685532 -34.780191)
			(xy 136.67779 -34.761592) (xy 136.6774 -34.751518) (xy 136.6774 -34.641282) (xy 136.676973 -34.631213)
			(xy 136.669254 -34.612614) (xy 136.662414 -34.605214) (xy 136.64946 -34.59226) (xy 136.642046 -34.585586)
			(xy 136.623611 -34.578025) (xy 136.613646 -34.577528) (xy 136.4742 -34.577528) (xy 136.442388 -34.577097)
			(xy 136.379166 -34.569969) (xy 136.31714 -34.555803) (xy 136.257091 -34.534777) (xy 136.199777 -34.507155)
			(xy 136.145918 -34.473287) (xy 136.096192 -34.433597) (xy 136.073388 -34.411412) (xy 135.08609 -33.424114)
			(xy 135.078691 -33.417268) (xy 135.060093 -33.409535) (xy 135.050022 -33.409128) (xy 132.7912 -33.409128)
			(xy 132.759388 -33.408697) (xy 132.696166 -33.401569) (xy 132.63414 -33.387403) (xy 132.574091 -33.366377)
			(xy 132.516777 -33.338755) (xy 132.462918 -33.304887) (xy 132.413192 -33.265197) (xy 132.390388 -33.243012)
			(xy 132.258562 -33.111186) (xy 132.251166 -33.104336) (xy 132.232566 -33.096602) (xy 132.222494 -33.0962)
			(xy 131.466082 -33.0962) (xy 131.456013 -33.095773) (xy 131.437414 -33.088054) (xy 131.430014 -33.081214)
			(xy 130.42265 -32.07385) (xy 130.416371 -32.068114) (xy 130.401076 -32.060706) (xy 130.392678 -32.059372)
			(xy 130.392424 -32.059372) (xy 130.360735 -32.05544) (xy 130.29845 -32.041358) (xy 130.23814 -32.02037)
			(xy 130.180568 -31.992742) (xy 130.126463 -31.958824) (xy 130.076509 -31.919045) (xy 130.053588 -31.896812)
			(xy 129.769362 -31.612586) (xy 129.761966 -31.605736) (xy 129.743366 -31.598002) (xy 129.733294 -31.5976)
			(xy 129.346706 -31.5976) (xy 129.336635 -31.598022) (xy 129.318029 -31.605735) (xy 129.310638 -31.612586)
			(xy 127.632714 -33.29051) (xy 127.625868 -33.297909) (xy 127.618135 -33.316507) (xy 127.617728 -33.326578)
			(xy 127.617728 -34.417) (xy 127.617297 -34.448812) (xy 127.610169 -34.512034) (xy 127.596003 -34.57406)
			(xy 127.574977 -34.634109) (xy 127.547355 -34.691423) (xy 127.513487 -34.745282) (xy 127.473797 -34.795008)
			(xy 127.451612 -34.817812) (xy 125.719586 -36.549838) (xy 125.712736 -36.557234) (xy 125.705002 -36.575834)
			(xy 125.7046 -36.585906) (xy 125.7046 -38.07333) (xy 127.420876 -38.07333) (xy 127.424947 -38.017708)
			(xy 127.437073 -37.963271) (xy 127.456996 -37.91118) (xy 127.484292 -37.862545) (xy 127.518378 -37.818402)
			(xy 127.558527 -37.779693) (xy 127.603885 -37.747242) (xy 127.653485 -37.721741) (xy 127.706269 -37.703734)
			(xy 127.761112 -37.693604) (xy 127.816846 -37.691567) (xy 127.872283 -37.697667) (xy 127.92624 -37.711773)
			(xy 127.977569 -37.733585) (xy 128.025175 -37.762639) (xy 128.068043 -37.798314) (xy 128.10526 -37.839851)
			(xy 128.136033 -37.886364) (xy 128.159705 -37.936861) (xy 128.175773 -37.990268) (xy 128.183893 -38.045444)
			(xy 128.184402 -38.07333) (xy 128.183893 -38.101216) (xy 128.175773 -38.156392) (xy 128.159705 -38.209799)
			(xy 128.136033 -38.260296) (xy 128.10526 -38.306809) (xy 128.068043 -38.348346) (xy 128.025175 -38.384021)
			(xy 127.977569 -38.413075) (xy 127.92624 -38.434887) (xy 127.872283 -38.448993) (xy 127.816846 -38.455093)
			(xy 127.761112 -38.453056) (xy 127.706269 -38.442926) (xy 127.653485 -38.424919) (xy 127.603885 -38.399418)
			(xy 127.558527 -38.366967) (xy 127.518378 -38.328258) (xy 127.484292 -38.284115) (xy 127.456996 -38.23548)
			(xy 127.437073 -38.183389) (xy 127.424947 -38.128952) (xy 127.420876 -38.07333) (xy 125.7046 -38.07333)
			(xy 125.7046 -39.679118) (xy 125.705027 -39.689187) (xy 125.712746 -39.707786) (xy 125.719586 -39.715186)
			(xy 126.95174 -40.947086) (xy 126.95914 -40.953928) (xy 126.977738 -40.96165) (xy 126.987808 -40.962072)
		)
		(stroke
			(width 0)
			(type solid)
		)
		(fill yes)
		(layer "In6.Cu")
		(net "P1V2_AUX")
	)
	(gr_poly
		(pts
			(xy 143.55699 -388.617714) (xy 143.557244 -388.576312)
			(arc
				(start 143.54302 -388.56158)
				(mid 143.464575 -388.439856)
				(end 143.437102 -388.297674)
			)
			(arc
				(start 143.437102 -388.297674)
				(mid 143.478753 -388.124338)
				(end 143.594582 -387.98881)
			)
			(arc
				(start 143.594582 -387.98881)
				(mid 143.610057 -387.970769)
				(end 143.615664 -387.947662)
			)
			(xy 143.615664 -385.978146) (xy 143.596106 -385.951476)
			(arc
				(start 143.580104 -385.946396)
				(mid 143.31212 -385.58216)
				(end 143.580104 -385.217924)
			)
			(xy 143.596106 -385.212844) (xy 143.615664 -385.186174) (xy 143.615664 -385.058666) (xy 143.596106 -385.031996)
			(arc
				(start 143.580104 -385.026916)
				(mid 143.386334 -384.888779)
				(end 143.312134 -384.66268)
			)
			(arc
				(start 143.312134 -384.66268)
				(mid 143.33993 -384.519978)
				(end 143.419068 -384.398012)
			)
			(xy 143.425926 -384.390646) (xy 143.433292 -384.372358)
			(arc
				(start 143.43253 -384.291078)
				(mid 143.428533 -384.271828)
				(end 143.417544 -384.255518)
			)
			(arc
				(start 142.750794 -383.588768)
				(mid 142.73426 -383.577657)
				(end 142.714726 -383.573782)
			)
			(arc
				(start 138.099038 -383.573782)
				(mid 138.079515 -383.577683)
				(end 138.06297 -383.588768)
			)
			(xy 137.817606 -383.834132) (xy 137.812272 -383.866136)
			(arc
				(start 137.819384 -383.880868)
				(mid 137.857854 -383.989438)
				(end 137.870946 -384.10388)
			)
			(arc
				(start 137.870946 -384.10388)
				(mid 137.814978 -384.335802)
				(end 137.659364 -384.51663)
			)
			(arc
				(start 137.659364 -384.51663)
				(mid 137.643832 -384.534784)
				(end 137.638282 -384.558032)
			)
			(arc
				(start 137.638282 -384.640328)
				(mid 137.643793 -384.663596)
				(end 137.659364 -384.68173)
			)
			(arc
				(start 137.659364 -384.68173)
				(mid 137.814932 -384.862582)
				(end 137.870946 -385.09448)
			)
			(arc
				(start 137.870946 -385.09448)
				(mid 137.722007 -385.454049)
				(end 137.362438 -385.602988)
			)
			(arc
				(start 137.362438 -385.602988)
				(mid 137.184432 -385.570909)
				(end 137.028936 -385.478528)
			)
			(xy 137.022078 -385.472178) (xy 137.00506 -385.466082) (xy 136.919716 -385.466082) (xy 136.902698 -385.472178)
			(xy 136.89584 -385.478528)
			(arc
				(start 136.868408 -385.500626)
				(mid 136.853116 -385.519231)
				(end 136.848088 -385.54279)
			)
			(arc
				(start 136.849104 -385.574286)
				(mid 136.855669 -385.597549)
				(end 136.872218 -385.61518)
			)
			(arc
				(start 136.872218 -385.61518)
				(mid 137.040911 -385.798853)
				(end 137.102088 -386.04063)
			)
			(arc
				(start 137.102088 -386.04063)
				(mid 137.05165 -386.261428)
				(end 136.910318 -386.438394)
			)
			(xy 136.901682 -386.445252) (xy 136.89203 -386.464302)
			(arc
				(start 136.88695 -386.550916)
				(mid 136.890261 -386.571965)
				(end 136.901936 -386.589778)
			)
			(arc
				(start 137.045192 -386.733034)
				(mid 137.061726 -386.744145)
				(end 137.08126 -386.74802)
			)
			(xy 137.178796 -386.74802) (xy 137.189972 -386.74548)
			(arc
				(start 137.195306 -386.742686)
				(mid 137.278187 -386.712686)
				(end 137.36574 -386.702554)
			)
			(arc
				(start 137.36574 -386.702554)
				(mid 137.453282 -386.712734)
				(end 137.536174 -386.742686)
			)
			(xy 137.541508 -386.74548) (xy 137.552684 -386.74802)
			(arc
				(start 137.968228 -386.74802)
				(mid 137.987615 -386.74407)
				(end 138.004042 -386.733034)
			)
			(arc
				(start 138.13536 -386.60197)
				(mid 138.257341 -386.508753)
				(end 138.39952 -386.45084)
			)
			(xy 138.406378 -386.449062) (xy 138.417808 -386.442458)
			(arc
				(start 139.09802 -385.762246)
				(mid 139.114554 -385.751135)
				(end 139.134088 -385.74726)
			)
			(arc
				(start 141.558772 -385.74726)
				(mid 141.578295 -385.751161)
				(end 141.59484 -385.762246)
			)
			(arc
				(start 141.720316 -385.887722)
				(mid 141.731427 -385.904256)
				(end 141.735302 -385.92379)
			)
			(arc
				(start 141.735302 -386.182616)
				(mid 141.7388 -386.201141)
				(end 141.748764 -386.21716)
			)
			(arc
				(start 141.748764 -386.21716)
				(mid 141.824239 -386.337192)
				(end 141.850618 -386.476494)
			)
			(arc
				(start 141.850618 -386.476494)
				(mid 141.824185 -386.615775)
				(end 141.748764 -386.735828)
			)
			(arc
				(start 141.748764 -386.735828)
				(mid 141.738738 -386.751823)
				(end 141.735302 -386.770372)
			)
			(xy 141.735302 -388.308596)
			(arc
				(start 141.739112 -388.317994)
				(mid 141.761127 -388.389939)
				(end 141.768576 -388.464806)
			)
			(arc
				(start 141.768576 -388.464806)
				(mid 141.761108 -388.539669)
				(end 141.739112 -388.611618)
			)
			(xy 141.735302 -388.621016)
			(arc
				(start 141.735302 -388.986776)
				(mid 141.739203 -389.006299)
				(end 141.750288 -389.022844)
			)
			(arc
				(start 141.850364 -389.12292)
				(mid 141.86681 -389.133846)
				(end 141.886178 -389.137652)
			)
			(xy 142.98295 -389.137652) (xy 142.988792 -389.143748) (xy 143.030956 -389.143748)
		)
		(stroke
			(width 0)
			(type solid)
		)
		(fill yes)
		(layer "In6.Cu")
		(net "P1V8_CPU1_RT_1D")
	)
	(gr_poly
		(pts
			(xy 176.319434 -27.785822) (xy 176.356141 -27.776351) (xy 176.430792 -27.763118) (xy 176.506317 -27.756491)
			(xy 176.544224 -27.756104) (xy 176.58213 -27.756515) (xy 176.657651 -27.763154) (xy 176.732303 -27.77637)
			(xy 176.769014 -27.785822) (xy 176.775618 -27.7876) (xy 177.212752 -27.7876) (xy 177.219356 -27.785822)
			(xy 177.256063 -27.776352) (xy 177.330714 -27.763121) (xy 177.406239 -27.756496) (xy 177.444146 -27.756104)
			(xy 177.482052 -27.756516) (xy 177.557573 -27.763157) (xy 177.632224 -27.776375) (xy 177.668936 -27.785822)
			(xy 177.67554 -27.7876) (xy 178.112674 -27.7876) (xy 178.119278 -27.785822) (xy 178.155986 -27.776353)
			(xy 178.230637 -27.763124) (xy 178.306161 -27.7565) (xy 178.344068 -27.756104) (xy 178.381974 -27.756513)
			(xy 178.457497 -27.763147) (xy 178.53215 -27.776358) (xy 178.568858 -27.785822) (xy 178.575462 -27.7876)
			(xy 179.01285 -27.7876) (xy 179.019454 -27.785822) (xy 179.056161 -27.776352) (xy 179.130812 -27.763121)
			(xy 179.206337 -27.756495) (xy 179.244244 -27.756104) (xy 179.28215 -27.756516) (xy 179.357671 -27.763157)
			(xy 179.432322 -27.776374) (xy 179.469034 -27.785822) (xy 179.475638 -27.7876) (xy 181.736238 -27.7876)
			(xy 181.746305 -27.78717) (xy 181.764899 -27.779446) (xy 181.772306 -27.772614) (xy 182.058056 -27.486864)
			(xy 182.064901 -27.479466) (xy 182.07263 -27.460867) (xy 182.073042 -27.450796) (xy 182.073042 -23.40991)
			(xy 182.072619 -23.39984) (xy 182.064901 -23.381239) (xy 182.058056 -23.373842) (xy 181.829964 -23.145496)
			(xy 181.804012 -23.118876) (xy 181.75734 -23.061005) (xy 181.71712 -22.998477) (xy 181.683813 -22.932008)
			(xy 181.657801 -22.862361) (xy 181.6481 -22.826472) (xy 181.645451 -22.817433) (xy 181.63458 -22.802068)
			(xy 181.618876 -22.791693) (xy 181.609746 -22.789388) (xy 181.569223 -22.780056) (xy 181.48998 -22.75483)
			(xy 181.413436 -22.722322) (xy 181.340258 -22.682814) (xy 181.271085 -22.636652) (xy 181.206521 -22.584237)
			(xy 181.147128 -22.526028) (xy 181.093425 -22.462531) (xy 181.069234 -22.428708) (xy 181.061667 -22.419087)
			(xy 181.040046 -22.407692) (xy 181.027832 -22.406864) (xy 180.986858 -22.406199) (xy 180.905289 -22.398268)
			(xy 180.824795 -22.382868) (xy 180.74606 -22.360128) (xy 180.66975 -22.330242) (xy 180.596513 -22.293463)
			(xy 180.52697 -22.250103) (xy 180.46171 -22.200529) (xy 180.401287 -22.145162) (xy 180.346214 -22.084472)
			(xy 180.296957 -22.018972) (xy 180.253935 -21.94922) (xy 180.217511 -21.875805) (xy 180.187995 -21.799351)
			(xy 180.165637 -21.720506) (xy 180.150627 -21.639939) (xy 180.143093 -21.558333) (xy 180.142642 -21.517356)
			(xy 180.143119 -21.476254) (xy 180.150707 -21.394401) (xy 180.165815 -21.313597) (xy 180.188314 -21.234532)
			(xy 180.218011 -21.157879) (xy 180.254654 -21.084294) (xy 180.29793 -21.014403) (xy 180.347469 -20.948803)
			(xy 180.40285 -20.888054) (xy 180.463599 -20.832673) (xy 180.529198 -20.783133) (xy 180.599089 -20.739857)
			(xy 180.672674 -20.703213) (xy 180.749326 -20.673515) (xy 180.828391 -20.651016) (xy 180.909195 -20.635908)
			(xy 180.991048 -20.628319) (xy 181.03215 -20.627848) (xy 181.074961 -20.62836) (xy 181.160188 -20.636589)
			(xy 181.244229 -20.652967) (xy 181.326309 -20.677341) (xy 181.405669 -20.709487) (xy 181.481573 -20.749106)
			(xy 181.553321 -20.795834) (xy 181.620249 -20.849237) (xy 181.681738 -20.908822) (xy 181.737219 -20.974037)
			(xy 181.762146 -21.008848) (xy 181.769708 -21.018479) (xy 181.79133 -21.029892) (xy 181.803548 -21.030692)
			(xy 181.83987 -21.031708) (xy 181.850538 -21.032216) (xy 181.870604 -21.024342) (xy 182.056278 -20.838922)
			(xy 182.058056 -20.83689) (xy 182.064906 -20.829493) (xy 182.072643 -20.810895) (xy 182.073042 -20.800822)
			(xy 182.073042 -19.574002) (xy 182.072618 -19.563933) (xy 182.064897 -19.545333) (xy 182.058056 -19.537934)
			(xy 181.951122 -19.431) (xy 181.914038 -19.427952) (xy 181.898798 -19.438874) (xy 181.866423 -19.461582)
			(xy 181.798334 -19.50181) (xy 181.726943 -19.535836) (xy 181.652814 -19.56339) (xy 181.576531 -19.584254)
			(xy 181.498697 -19.598265) (xy 181.419926 -19.60531) (xy 181.380384 -19.605752) (xy 181.336551 -19.605239)
			(xy 181.249307 -19.596638) (xy 181.163334 -19.579492) (xy 181.079466 -19.553968) (xy 180.998517 -19.520312)
			(xy 180.921274 -19.478853) (xy 180.884576 -19.454876) (xy 180.869336 -19.444462) (xy 180.833522 -19.448018)
			(xy 180.650896 -19.63039) (xy 180.622995 -19.657548) (xy 180.562144 -19.706127) (xy 180.496238 -19.747589)
			(xy 180.426104 -19.781412) (xy 180.352624 -19.80717) (xy 180.276723 -19.824541) (xy 180.199354 -19.833305)
			(xy 180.160422 -19.833844) (xy 178.56454 -19.833844) (xy 178.525606 -19.833309) (xy 178.448229 -19.824567)
			(xy 178.372318 -19.807213) (xy 178.298829 -19.781464) (xy 178.228688 -19.747645) (xy 178.162776 -19.706181)
			(xy 178.101924 -19.657594) (xy 178.074066 -19.63039) (xy 178.059842 -19.61642) (xy 178.052436 -19.609727)
			(xy 178.033999 -19.602127) (xy 178.024028 -19.601688) (xy 176.509172 -19.601688) (xy 176.499207 -19.602167)
			(xy 176.480771 -19.609744) (xy 176.473358 -19.61642) (xy 176.459134 -19.63039) (xy 176.431232 -19.657545)
			(xy 176.37038 -19.706119) (xy 176.304472 -19.747575) (xy 176.234338 -19.781391) (xy 176.160858 -19.807143)
			(xy 176.084958 -19.824507) (xy 176.00759 -19.833264) (xy 175.96866 -19.833844) (xy 175.298354 -19.833844)
			(xy 175.288356 -19.834341) (xy 175.269887 -19.84201) (xy 175.25576 -19.856163) (xy 175.248123 -19.874645)
			(xy 175.247554 -19.884644) (xy 175.247554 -19.968972) (xy 175.250602 -19.977354) (xy 175.259339 -20.002605)
			(xy 175.270476 -20.054864) (xy 175.274215 -20.108166) (xy 175.270485 -20.161468) (xy 175.259358 -20.21373)
			(xy 175.250602 -20.238974) (xy 175.247554 -20.247356) (xy 175.247554 -25.92324) (xy 180.826662 -25.92324)
			(xy 180.830733 -25.867618) (xy 180.842859 -25.813181) (xy 180.862782 -25.76109) (xy 180.890078 -25.712455)
			(xy 180.924164 -25.668312) (xy 180.964313 -25.629603) (xy 181.009671 -25.597152) (xy 181.059271 -25.571651)
			(xy 181.112055 -25.553644) (xy 181.166898 -25.543514) (xy 181.222632 -25.541477) (xy 181.278069 -25.547577)
			(xy 181.332026 -25.561683) (xy 181.383355 -25.583495) (xy 181.430961 -25.612549) (xy 181.473829 -25.648224)
			(xy 181.511046 -25.689761) (xy 181.541819 -25.736274) (xy 181.565491 -25.786771) (xy 181.581559 -25.840178)
			(xy 181.589679 -25.895354) (xy 181.590188 -25.92324) (xy 181.589679 -25.951126) (xy 181.581559 -26.006302)
			(xy 181.565491 -26.059709) (xy 181.541819 -26.110206) (xy 181.511046 -26.156719) (xy 181.473829 -26.198256)
			(xy 181.430961 -26.233931) (xy 181.383355 -26.262985) (xy 181.332026 -26.284797) (xy 181.278069 -26.298903)
			(xy 181.222632 -26.305003) (xy 181.166898 -26.302966) (xy 181.112055 -26.292836) (xy 181.059271 -26.274829)
			(xy 181.009671 -26.249328) (xy 180.964313 -26.216877) (xy 180.924164 -26.178168) (xy 180.890078 -26.134025)
			(xy 180.862782 -26.08539) (xy 180.842859 -26.033299) (xy 180.830733 -25.978862) (xy 180.826662 -25.92324)
			(xy 175.247554 -25.92324) (xy 175.247554 -27.402282) (xy 175.247994 -27.412344) (xy 175.255735 -27.430922)
			(xy 175.26254 -27.43835) (xy 175.596804 -27.772614) (xy 175.604199 -27.779469) (xy 175.622798 -27.787216)
			(xy 175.632872 -27.7876) (xy 176.31283 -27.7876)
		)
		(stroke
			(width 0)
			(type solid)
		)
		(fill yes)
		(layer "In6.Cu")
		(net "P12V_SCM_R")
	)
	(gr_poly
		(pts
			(xy 228.388418 -53.99278) (xy 228.398295 -53.99232) (xy 228.416591 -53.984874) (xy 228.423978 -53.978302)
			(xy 228.424232 -53.978048) (xy 229.054914 -53.347366) (xy 229.055422 -53.346858) (xy 229.062009 -53.339479)
			(xy 229.069469 -53.32118) (xy 229.0699 -53.311298) (xy 229.0699 -49.421542) (xy 229.069466 -49.411477)
			(xy 229.061737 -49.392887) (xy 229.054914 -49.385474) (xy 224.863406 -45.193966) (xy 224.856564 -45.186566)
			(xy 224.848841 -45.167968) (xy 224.84842 -45.157898) (xy 224.84842 -41.903142) (xy 224.847987 -41.893076)
			(xy 224.84026 -41.874485) (xy 224.833434 -41.867074) (xy 224.272602 -41.306242) (xy 224.265206 -41.299391)
			(xy 224.246607 -41.291649) (xy 224.236534 -41.291256) (xy 222.623126 -41.291256) (xy 222.591293 -41.29081)
			(xy 222.528032 -41.283649) (xy 222.46597 -41.269446) (xy 222.40589 -41.248382) (xy 222.348547 -41.220722)
			(xy 222.321374 -41.204134) (xy 222.315278 -41.20007) (xy 222.301562 -41.19626) (xy 222.287846 -41.19626)
			(xy 222.277816 -41.196671) (xy 222.259276 -41.204331) (xy 222.24508 -41.218504) (xy 222.237388 -41.23703)
			(xy 222.237046 -41.24706) (xy 222.237046 -41.260776) (xy 222.250508 -41.284144) (xy 222.262446 -41.291002)
			(xy 222.286818 -41.30576) (xy 222.331293 -41.34137) (xy 222.369978 -41.383198) (xy 222.402013 -41.430313)
			(xy 222.426686 -41.481668) (xy 222.443449 -41.536121) (xy 222.451928 -41.592461) (xy 222.452438 -41.620948)
			(xy 222.451949 -41.648198) (xy 222.444187 -41.702142) (xy 222.428828 -41.754433) (xy 222.406185 -41.804006)
			(xy 222.376718 -41.849852) (xy 222.341026 -41.891039) (xy 222.299838 -41.926728) (xy 222.25399 -41.956193)
			(xy 222.204416 -41.978834) (xy 222.152124 -41.994191) (xy 222.09818 -42.00195) (xy 222.07093 -42.002456)
			(xy 222.04407 -42.001993) (xy 221.990883 -41.994451) (xy 221.939278 -41.979524) (xy 221.890277 -41.957509)
			(xy 221.844847 -41.92884) (xy 221.803886 -41.894083) (xy 221.768204 -41.853927) (xy 221.738505 -41.809163)
			(xy 221.715377 -41.760677) (xy 221.699276 -41.709427) (xy 221.690521 -41.656426) (xy 221.689422 -41.629584)
			(xy 221.689422 -41.621964) (xy 221.689841 -41.593914) (xy 221.697906 -41.5384) (xy 221.714017 -41.484667)
			(xy 221.737829 -41.433874) (xy 221.768825 -41.387119) (xy 221.787212 -41.365932) (xy 221.787212 -41.365678)
			(xy 221.793453 -41.358126) (xy 221.800168 -41.339741) (xy 221.799447 -41.320181) (xy 221.795848 -41.311068)
			(xy 221.758256 -41.226486) (xy 221.75216 -41.212516) (xy 221.727014 -41.19626) (xy 220.780102 -41.19626)
			(xy 220.770033 -41.196684) (xy 220.751434 -41.204405) (xy 220.744034 -41.211246) (xy 220.088206 -41.867074)
			(xy 220.08084 -41.874186) (xy 220.07322 -41.892982) (xy 220.07322 -43.153838) (xy 220.073684 -43.163713)
			(xy 220.081135 -43.182005) (xy 220.087698 -43.189398) (xy 220.087952 -43.189652) (xy 221.904814 -45.006514)
			(xy 221.911668 -45.013909) (xy 221.91941 -45.032508) (xy 221.9198 -45.042582) (xy 221.9198 -46.524926)
			(xy 224.949002 -46.524926) (xy 224.953073 -46.469304) (xy 224.965199 -46.414867) (xy 224.985122 -46.362776)
			(xy 225.012418 -46.314141) (xy 225.046504 -46.269998) (xy 225.086653 -46.231289) (xy 225.132011 -46.198838)
			(xy 225.181611 -46.173337) (xy 225.234395 -46.15533) (xy 225.289238 -46.1452) (xy 225.344972 -46.143163)
			(xy 225.400409 -46.149263) (xy 225.454366 -46.163369) (xy 225.505695 -46.185181) (xy 225.553301 -46.214235)
			(xy 225.596169 -46.24991) (xy 225.633386 -46.291447) (xy 225.664159 -46.33796) (xy 225.687831 -46.388457)
			(xy 225.703899 -46.441864) (xy 225.712019 -46.49704) (xy 225.712528 -46.524926) (xy 225.712019 -46.552812)
			(xy 225.703899 -46.607988) (xy 225.687831 -46.661395) (xy 225.664159 -46.711892) (xy 225.633386 -46.758405)
			(xy 225.596169 -46.799942) (xy 225.553301 -46.835617) (xy 225.505695 -46.864671) (xy 225.454366 -46.886483)
			(xy 225.400409 -46.900589) (xy 225.344972 -46.906689) (xy 225.289238 -46.904652) (xy 225.234395 -46.894522)
			(xy 225.181611 -46.876515) (xy 225.132011 -46.851014) (xy 225.086653 -46.818563) (xy 225.046504 -46.779854)
			(xy 225.012418 -46.735711) (xy 224.985122 -46.687076) (xy 224.965199 -46.634985) (xy 224.953073 -46.580548)
			(xy 224.949002 -46.524926) (xy 221.9198 -46.524926) (xy 221.9198 -46.619414) (xy 221.920232 -46.628574)
			(xy 221.926736 -46.645705) (xy 221.938812 -46.659487) (xy 221.946724 -46.664118) (xy 222.038926 -46.712886)
			(xy 222.066612 -46.711362) (xy 222.07855 -46.703234) (xy 222.10242 -46.687643) (xy 222.153808 -46.662953)
			(xy 222.208297 -46.64618) (xy 222.264674 -46.637698) (xy 222.29318 -46.637194) (xy 222.320434 -46.637656)
			(xy 222.374386 -46.645411) (xy 222.426686 -46.660765) (xy 222.476269 -46.683406) (xy 222.522124 -46.712873)
			(xy 222.563319 -46.748567) (xy 222.599015 -46.78976) (xy 222.628484 -46.835614) (xy 222.651128 -46.885195)
			(xy 222.666485 -46.937494) (xy 222.674243 -46.991446) (xy 222.674243 -47.045954) (xy 222.666485 -47.099906)
			(xy 222.651128 -47.152205) (xy 222.628484 -47.201786) (xy 222.599015 -47.24764) (xy 222.563319 -47.288833)
			(xy 222.522124 -47.324527) (xy 222.476269 -47.353994) (xy 222.426686 -47.376635) (xy 222.374386 -47.391989)
			(xy 222.320434 -47.399744) (xy 222.29318 -47.40021) (xy 222.264676 -47.39968) (xy 222.208301 -47.391201)
			(xy 222.153814 -47.374433) (xy 222.102425 -47.34975) (xy 222.07855 -47.33417) (xy 222.066612 -47.326042)
			(xy 222.038926 -47.324518) (xy 221.946724 -47.373286) (xy 221.938793 -47.377913) (xy 221.926644 -47.39166)
			(xy 221.920147 -47.408817) (xy 221.9198 -47.41799) (xy 221.9198 -48.78197) (xy 222.686116 -48.78197)
			(xy 222.690187 -48.726348) (xy 222.702313 -48.671911) (xy 222.722236 -48.61982) (xy 222.749532 -48.571185)
			(xy 222.783618 -48.527042) (xy 222.823767 -48.488333) (xy 222.869125 -48.455882) (xy 222.918725 -48.430381)
			(xy 222.971509 -48.412374) (xy 223.026352 -48.402244) (xy 223.082086 -48.400207) (xy 223.137523 -48.406307)
			(xy 223.19148 -48.420413) (xy 223.242809 -48.442225) (xy 223.290415 -48.471279) (xy 223.333283 -48.506954)
			(xy 223.3705 -48.548491) (xy 223.401273 -48.595004) (xy 223.424945 -48.645501) (xy 223.441013 -48.698908)
			(xy 223.449133 -48.754084) (xy 223.449642 -48.78197) (xy 223.449133 -48.809856) (xy 223.441013 -48.865032)
			(xy 223.424945 -48.918439) (xy 223.401273 -48.968936) (xy 223.3705 -49.015449) (xy 223.333283 -49.056986)
			(xy 223.290415 -49.092661) (xy 223.242809 -49.121715) (xy 223.19148 -49.143527) (xy 223.137523 -49.157633)
			(xy 223.082086 -49.163733) (xy 223.026352 -49.161696) (xy 222.971509 -49.151566) (xy 222.918725 -49.133559)
			(xy 222.869125 -49.108058) (xy 222.823767 -49.075607) (xy 222.783618 -49.036898) (xy 222.749532 -48.992755)
			(xy 222.722236 -48.94412) (xy 222.702313 -48.892029) (xy 222.690187 -48.837592) (xy 222.686116 -48.78197)
			(xy 221.9198 -48.78197) (xy 221.9198 -49.654206) (xy 225.513136 -49.654206) (xy 225.517207 -49.598584)
			(xy 225.529333 -49.544147) (xy 225.549256 -49.492056) (xy 225.576552 -49.443421) (xy 225.610638 -49.399278)
			(xy 225.650787 -49.360569) (xy 225.696145 -49.328118) (xy 225.745745 -49.302617) (xy 225.798529 -49.28461)
			(xy 225.853372 -49.27448) (xy 225.909106 -49.272443) (xy 225.964543 -49.278543) (xy 226.0185 -49.292649)
			(xy 226.069829 -49.314461) (xy 226.117435 -49.343515) (xy 226.160303 -49.37919) (xy 226.19752 -49.420727)
			(xy 226.228293 -49.46724) (xy 226.251965 -49.517737) (xy 226.268033 -49.571144) (xy 226.276153 -49.62632)
			(xy 226.276662 -49.654206) (xy 226.276153 -49.682092) (xy 226.268033 -49.737268) (xy 226.251965 -49.790675)
			(xy 226.228293 -49.841172) (xy 226.19752 -49.887685) (xy 226.160303 -49.929222) (xy 226.117435 -49.964897)
			(xy 226.069829 -49.993951) (xy 226.0185 -50.015763) (xy 225.964543 -50.029869) (xy 225.909106 -50.035969)
			(xy 225.853372 -50.033932) (xy 225.798529 -50.023802) (xy 225.745745 -50.005795) (xy 225.696145 -49.980294)
			(xy 225.650787 -49.947843) (xy 225.610638 -49.909134) (xy 225.576552 -49.864991) (xy 225.549256 -49.816356)
			(xy 225.529333 -49.764265) (xy 225.517207 -49.709828) (xy 225.513136 -49.654206) (xy 221.9198 -49.654206)
			(xy 221.9198 -50.534527) (xy 224.278438 -50.534527) (xy 224.278438 -50.470605) (xy 224.286449 -50.407187)
			(xy 224.302346 -50.345273) (xy 224.325878 -50.28584) (xy 224.356672 -50.229825) (xy 224.394245 -50.17811)
			(xy 224.438002 -50.131513) (xy 224.487255 -50.090768) (xy 224.541226 -50.056517) (xy 224.599065 -50.0293)
			(xy 224.659858 -50.009547) (xy 224.722648 -49.997569) (xy 224.786444 -49.993556) (xy 224.85024 -49.997569)
			(xy 224.91303 -50.009547) (xy 224.973823 -50.0293) (xy 225.031662 -50.056517) (xy 225.085633 -50.090768)
			(xy 225.134886 -50.131513) (xy 225.178643 -50.17811) (xy 225.216216 -50.229825) (xy 225.24701 -50.28584)
			(xy 225.270542 -50.345273) (xy 225.286439 -50.407187) (xy 225.29445 -50.470605) (xy 225.294952 -50.502566)
			(xy 225.29445 -50.534527) (xy 225.286439 -50.597945) (xy 225.270542 -50.659859) (xy 225.24701 -50.719292)
			(xy 225.216216 -50.775307) (xy 225.178643 -50.827022) (xy 225.134886 -50.873619) (xy 225.085633 -50.914364)
			(xy 225.031662 -50.948615) (xy 224.973823 -50.975832) (xy 224.91303 -50.995585) (xy 224.85024 -51.007563)
			(xy 224.786444 -51.011577) (xy 224.722648 -51.007563) (xy 224.659858 -50.995585) (xy 224.599065 -50.975832)
			(xy 224.541226 -50.948615) (xy 224.487255 -50.914364) (xy 224.438002 -50.873619) (xy 224.394245 -50.827022)
			(xy 224.356672 -50.775307) (xy 224.325878 -50.719292) (xy 224.302346 -50.659859) (xy 224.286449 -50.597945)
			(xy 224.278438 -50.534527) (xy 221.9198 -50.534527) (xy 221.9198 -52.600098) (xy 221.920256 -52.609977)
			(xy 221.927695 -52.62828) (xy 221.934278 -52.635658) (xy 221.934532 -52.635912) (xy 223.276414 -53.977794)
			(xy 223.276922 -53.978302) (xy 223.284299 -53.984895) (xy 223.302599 -53.992364) (xy 223.312482 -53.99278)
		)
		(stroke
			(width 0)
			(type solid)
		)
		(fill yes)
		(layer "In6.Cu")
		(net "P3V3_E1S_0")
	)
	(gr_poly
		(pts
			(arc
				(start 256.800604 -37.135308)
				(mid 258.932532 -36.252077)
				(end 259.815584 -34.120074)
			)
			(arc
				(start 259.815584 -13.780008)
				(mid 260.103939 -13.083859)
				(end 260.800088 -12.795504)
			)
			(arc
				(start 385.601972 -12.795504)
				(mid 387.734244 -11.912288)
				(end 388.61746 -9.780016)
			)
			(arc
				(start 388.61746 -3.976878)
				(mid 388.611809 -3.953593)
				(end 388.596124 -3.935476)
			)
			(arc
				(start 388.596124 -3.935476)
				(mid 388.428347 -3.782165)
				(end 388.302246 -3.593084)
			)
			(xy 388.294372 -3.577336) (xy 388.262368 -3.56235)
			(arc
				(start 388.149084 -3.589528)
				(mid 388.120945 -3.607374)
				(end 388.109968 -3.638804)
			)
			(arc
				(start 388.109968 -9.780016)
				(mid 387.375393 -11.553437)
				(end 385.601972 -12.288012)
			)
			(arc
				(start 260.800088 -12.288012)
				(mid 259.745088 -12.725008)
				(end 259.308092 -13.780008)
			)
			(arc
				(start 259.308092 -34.120074)
				(mid 258.573517 -35.893495)
				(end 256.800096 -36.62807)
			)
			(arc
				(start 225.300032 -36.62807)
				(mid 223.526611 -35.893495)
				(end 222.792036 -34.120074)
			)
			(arc
				(start 222.792036 -13.780008)
				(mid 222.35504 -12.725008)
				(end 221.30004 -12.288012)
			)
			(arc
				(start 196.701918 -12.288012)
				(mid 194.928497 -11.553437)
				(end 194.193922 -9.780016)
			)
			(arc
				(start 194.193922 -8.918702)
				(mid 194.182875 -8.887327)
				(end 194.154806 -8.869426)
			)
			(xy 194.041522 -8.842248) (xy 194.009518 -8.857234)
			(arc
				(start 194.001644 -8.872982)
				(mid 193.875648 -9.062025)
				(end 193.70802 -9.215374)
			)
			(arc
				(start 193.70802 -9.215374)
				(mid 193.69232 -9.233484)
				(end 193.686684 -9.256776)
			)
			(arc
				(start 193.686684 -9.780524)
				(mid 194.569915 -11.912452)
				(end 196.701918 -12.795504)
			)
			(arc
				(start 221.30004 -12.795504)
				(mid 221.996189 -13.083859)
				(end 222.284544 -13.780008)
			)
			(arc
				(start 222.284544 -34.120074)
				(mid 223.16785 -36.252182)
				(end 225.300032 -37.135308)
			)
		)
		(stroke
			(width 0)
			(type solid)
		)
		(fill yes)
		(layer "In6.Cu")
		(net "GND")
	)
	(gr_poly
		(pts
			(arc
				(start 34.203894 -367.111788)
				(mid 34.223417 -367.107887)
				(end 34.239962 -367.096802)
			)
			(arc
				(start 34.821368 -366.515396)
				(mid 34.832479 -366.498862)
				(end 34.836354 -366.479328)
			)
			(arc
				(start 34.836354 -366.221518)
				(mid 34.831349 -366.19953)
				(end 34.817304 -366.181894)
			)
			(arc
				(start 34.817304 -366.181894)
				(mid 34.711524 -366.049168)
				(end 34.673794 -365.883698)
			)
			(arc
				(start 34.673794 -365.883698)
				(mid 34.676233 -365.840883)
				(end 34.683446 -365.798608)
			)
			(xy 34.686494 -365.7854) (xy 34.679382 -365.760762)
			(arc
				(start 33.916112 -364.997492)
				(mid 33.905186 -364.981046)
				(end 33.90138 -364.961678)
			)
			(arc
				(start 33.90138 -364.152688)
				(mid 33.899414 -364.138945)
				(end 33.89376 -364.126272)
			)
			(arc
				(start 33.89376 -364.126272)
				(mid 33.781483 -363.728)
				(end 33.89376 -363.329728)
			)
			(arc
				(start 33.89376 -363.329728)
				(mid 33.899368 -363.317042)
				(end 33.90138 -363.303312)
			)
			(arc
				(start 33.90138 -361.036108)
				(mid 33.886501 -361.000187)
				(end 33.85058 -360.985308)
			)
			(arc
				(start 30.7848 -360.985308)
				(mid 30.687458 -360.965852)
				(end 30.604968 -360.910632)
			)
			(xy 29.671264 -359.976928) (xy 29.652722 -359.969308)
			(arc
				(start 29.642308 -359.969308)
				(mid 29.372213 -359.857747)
				(end 29.260292 -359.5878)
			)
			(arc
				(start 29.260292 -359.5878)
				(mid 29.642054 -359.206292)
				(end 30.023308 -359.588308)
			)
			(xy 30.023308 -359.598722) (xy 30.030928 -359.617264)
			(arc
				(start 30.875224 -360.46156)
				(mid 30.891787 -360.472534)
				(end 30.911292 -360.476292)
			)
			(arc
				(start 31.565596 -360.476292)
				(mid 31.589939 -360.47008)
				(end 31.608268 -360.452924)
			)
			(xy 31.661608 -360.369866) (xy 31.663132 -360.343958)
			(arc
				(start 31.657798 -360.332274)
				(mid 31.631428 -360.254058)
				(end 31.622492 -360.172)
			)
			(arc
				(start 31.622492 -360.172)
				(mid 31.637191 -360.067123)
				(end 31.68015 -359.970324)
			)
			(xy 31.685738 -359.961434) (xy 31.688786 -359.940606) (xy 31.664402 -359.848658) (xy 31.651448 -359.832148)
			(arc
				(start 31.64205 -359.827068)
				(mid 31.349282 -359.546749)
				(end 31.241492 -359.156)
			)
			(arc
				(start 31.241492 -359.156)
				(mid 32.004 -358.393492)
				(end 32.766508 -359.156)
			)
			(arc
				(start 32.766508 -359.156)
				(mid 32.658762 -359.546775)
				(end 32.36595 -359.827068)
			)
			(xy 32.356552 -359.832148) (xy 32.343598 -359.848658) (xy 32.319214 -359.940606) (xy 32.322262 -359.961434)
			(arc
				(start 32.32785 -359.970324)
				(mid 32.370814 -360.067121)
				(end 32.385508 -360.172)
			)
			(arc
				(start 32.385508 -360.172)
				(mid 32.376578 -360.254059)
				(end 32.350202 -360.332274)
			)
			(xy 32.344868 -360.343958) (xy 32.346392 -360.369866)
			(arc
				(start 32.399732 -360.452924)
				(mid 32.418095 -360.470017)
				(end 32.442404 -360.476292)
			)
			(arc
				(start 34.008568 -360.476292)
				(mid 34.028062 -360.472508)
				(end 34.044636 -360.46156)
			)
			(arc
				(start 34.116264 -360.389932)
				(mid 34.13271 -360.379006)
				(end 34.152078 -360.3752)
			)
			(arc
				(start 34.785554 -360.3752)
				(mid 34.821475 -360.360321)
				(end 34.836354 -360.3244)
			)
			(arc
				(start 34.836354 -359.49636)
				(mid 34.821475 -359.460439)
				(end 34.785554 -359.44556)
			)
			(arc
				(start 34.465514 -359.44556)
				(mid 34.446127 -359.44161)
				(end 34.4297 -359.430574)
			)
			(arc
				(start 34.195766 -359.19664)
				(mid 34.179203 -359.185666)
				(end 34.159698 -359.181908)
			)
			(arc
				(start 33.6042 -359.181908)
				(mid 33.506858 -359.162452)
				(end 33.424368 -359.107232)
			)
			(arc
				(start 32.446976 -358.12984)
				(mid 32.430413 -358.118866)
				(end 32.410908 -358.115108)
			)
			(arc
				(start 31.571692 -358.115108)
				(mid 31.552198 -358.118892)
				(end 31.535624 -358.12984)
			)
			(arc
				(start 30.990032 -358.675432)
				(mid 30.907539 -358.730645)
				(end 30.8102 -358.750108)
			)
			(arc
				(start 29.8704 -358.750108)
				(mid 29.773058 -358.730652)
				(end 29.690568 -358.675432)
			)
			(xy 29.671264 -358.656128) (xy 29.652722 -358.648508)
			(arc
				(start 29.642308 -358.648508)
				(mid 29.372213 -358.536947)
				(end 29.260292 -358.267)
			)
			(arc
				(start 29.260292 -358.267)
				(mid 29.372033 -357.997233)
				(end 29.6418 -357.885492)
			)
			(arc
				(start 29.6418 -357.885492)
				(mid 29.886512 -357.974315)
				(end 30.017212 -358.199436)
			)
			(xy 30.020514 -358.217724) (xy 30.048708 -358.241092)
			(arc
				(start 30.683708 -358.241092)
				(mid 30.703202 -358.237308)
				(end 30.719776 -358.22636)
			)
			(arc
				(start 30.733746 -358.21239)
				(mid 30.747648 -358.186252)
				(end 30.744668 -358.156764)
			)
			(xy 30.70225 -358.055672) (xy 30.676596 -358.038654) (xy 30.661102 -358.038908)
			(arc
				(start 30.6578 -358.038908)
				(mid 30.388033 -357.387633)
				(end 31.039308 -357.6574)
			)
			(xy 31.039308 -357.660702) (xy 31.039054 -357.676196) (xy 31.056072 -357.70185)
			(arc
				(start 31.157164 -357.744268)
				(mid 31.186674 -357.747359)
				(end 31.21279 -357.733346)
			)
			(arc
				(start 31.265368 -357.680768)
				(mid 31.347861 -357.625555)
				(end 31.4452 -357.606092)
			)
			(arc
				(start 32.5374 -357.606092)
				(mid 32.634742 -357.625548)
				(end 32.717232 -357.680768)
			)
			(arc
				(start 33.512252 -358.475788)
				(mid 33.538281 -358.489598)
				(end 33.567624 -358.48671)
			)
			(xy 33.582102 -358.480868) (xy 33.59912 -358.455468)
			(arc
				(start 33.59912 -356.984808)
				(mid 33.595219 -356.965285)
				(end 33.584134 -356.94874)
			)
			(arc
				(start 33.158176 -356.522782)
				(mid 33.141642 -356.511671)
				(end 33.122108 -356.507796)
			)
			(xy 31.41218 -356.507796) (xy 31.382462 -356.537006)
			(arc
				(start 31.382208 -356.558088)
				(mid 31.0007 -356.934049)
				(end 30.619192 -356.558088)
			)
			(xy 30.618938 -356.537006) (xy 30.58922 -356.507796)
			(arc
				(start 29.002736 -356.507796)
				(mid 28.983349 -356.511746)
				(end 28.966922 -356.522782)
			)
			(arc
				(start 28.55722 -356.932484)
				(mid 28.546294 -356.94893)
				(end 28.542488 -356.968298)
			)
			(arc
				(start 28.542488 -359.951782)
				(mid 28.546272 -359.971276)
				(end 28.55722 -359.98785)
			)
			(arc
				(start 30.094682 -361.525312)
				(mid 30.111245 -361.536286)
				(end 30.13075 -361.540044)
			)
			(arc
				(start 32.639762 -361.540044)
				(mid 32.659149 -361.543994)
				(end 32.675576 -361.55503)
			)
			(xy 32.678878 -361.558332)
			(arc
				(start 32.86125 -361.558332)
				(mid 32.880773 -361.562233)
				(end 32.897318 -361.573318)
			)
			(arc
				(start 32.974534 -361.650534)
				(mid 32.985645 -361.667068)
				(end 32.98952 -361.686602)
			)
			(arc
				(start 32.98952 -361.847892)
				(mid 32.99347 -361.867279)
				(end 33.004506 -361.883706)
			)
			(arc
				(start 33.054036 -361.93349)
				(mid 33.064962 -361.949936)
				(end 33.068768 -361.969304)
			)
			(arc
				(start 33.068768 -366.126776)
				(mid 33.064935 -366.146133)
				(end 33.054036 -366.16259)
			)
			(arc
				(start 33.004506 -366.212374)
				(mid 32.993444 -366.228791)
				(end 32.98952 -366.248188)
			)
			(arc
				(start 32.98952 -366.800892)
				(mid 32.993421 -366.820415)
				(end 33.004506 -366.83696)
			)
			(arc
				(start 33.264348 -367.096802)
				(mid 33.280882 -367.107913)
				(end 33.300416 -367.111788)
			)
		)
		(stroke
			(width 0)
			(type solid)
		)
		(fill yes)
		(layer "In6.Cu")
		(net "PVDDCR_CPU1_P1_VCCS")
	)
	(gr_poly
		(pts
			(xy 337.754214 -145.68932) (xy 337.761326 -145.681954) (xy 339.308694 -144.134586) (xy 339.315539 -144.127187)
			(xy 339.323269 -144.108589) (xy 339.32368 -144.098518) (xy 339.32368 -131.682236) (xy 339.323245 -131.672171)
			(xy 339.315512 -131.653586) (xy 339.308694 -131.646168) (xy 338.877656 -131.21513) (xy 338.870256 -131.208287)
			(xy 338.851658 -131.200564) (xy 338.841588 -131.200144) (xy 329.273408 -131.200144) (xy 329.273408 -131.209288)
			(xy 328.425048 -131.209288) (xy 328.414982 -131.20972) (xy 328.39639 -131.217446) (xy 328.38898 -131.224274)
			(xy 327.565258 -132.047996) (xy 327.558405 -132.055391) (xy 327.550659 -132.07399) (xy 327.550272 -132.084064)
			(xy 327.550272 -133.355957) (xy 330.367519 -133.355957) (xy 330.367519 -133.301443) (xy 330.375278 -133.247483)
			(xy 330.390637 -133.195177) (xy 330.413285 -133.14559) (xy 330.442759 -133.09973) (xy 330.478461 -133.058533)
			(xy 330.519662 -133.022835) (xy 330.565525 -132.993366) (xy 330.615115 -132.970723) (xy 330.667422 -132.955369)
			(xy 330.721383 -132.947616) (xy 330.74864 -132.947156) (xy 330.763497 -132.947282) (xy 330.793122 -132.949572)
			(xy 330.807822 -132.951728) (xy 330.81849 -132.953506) (xy 330.838302 -132.948426) (xy 330.913486 -132.890514)
			(xy 330.923646 -132.872734) (xy 330.924662 -132.862066) (xy 330.92807 -132.834301) (xy 330.942037 -132.780133)
			(xy 330.96376 -132.728583) (xy 330.992775 -132.680757) (xy 331.028459 -132.637677) (xy 331.070049 -132.600266)
			(xy 331.116654 -132.569327) (xy 331.167275 -132.545521) (xy 331.220829 -132.529358) (xy 331.276168 -132.521184)
			(xy 331.304138 -132.52069) (xy 331.328938 -132.521109) (xy 331.378116 -132.527578) (xy 331.426042 -132.540362)
			(xy 331.471908 -132.559246) (xy 331.493622 -132.571236) (xy 331.50175 -132.575808) (xy 331.520038 -132.578602)
			(xy 331.604366 -132.56133) (xy 331.61986 -132.551424) (xy 331.625448 -132.543804) (xy 331.64358 -132.520479)
			(xy 331.68586 -132.479218) (xy 331.733991 -132.444961) (xy 331.786824 -132.418526) (xy 331.843099 -132.400546)
			(xy 331.901471 -132.391447) (xy 331.93101 -132.390896) (xy 331.958721 -132.391366) (xy 332.013559 -132.399387)
			(xy 332.06666 -132.415257) (xy 332.116906 -132.438643) (xy 332.163239 -132.469052) (xy 332.204686 -132.505846)
			(xy 332.240372 -132.548249) (xy 332.269548 -132.595369) (xy 332.2916 -132.646215) (xy 332.29931 -132.672836)
			(xy 332.301596 -132.681726) (xy 332.312518 -132.696712) (xy 332.384654 -132.743956) (xy 332.402688 -132.74802)
			(xy 332.412086 -132.74675) (xy 332.425788 -132.744864) (xy 332.453374 -132.742831) (xy 332.467204 -132.742686)
			(xy 332.494455 -132.743174) (xy 332.548402 -132.750931) (xy 332.600697 -132.766286) (xy 332.650274 -132.788927)
			(xy 332.696124 -132.818394) (xy 332.737314 -132.854085) (xy 332.773005 -132.895275) (xy 332.802472 -132.941125)
			(xy 332.825113 -132.990701) (xy 332.840469 -133.042996) (xy 332.848226 -133.096943) (xy 332.848712 -133.124194)
			(xy 332.848263 -133.150619) (xy 332.840943 -133.202961) (xy 332.826471 -133.253792) (xy 332.805124 -133.30214)
			(xy 332.777308 -133.347079) (xy 332.743558 -133.387751) (xy 332.704519 -133.423376) (xy 332.660937 -133.453273)
			(xy 332.613646 -133.476871) (xy 332.563552 -133.493717) (xy 332.511612 -133.50349) (xy 332.485238 -133.505194)
			(xy 332.475586 -133.505702) (xy 332.458568 -133.513068) (xy 332.396846 -133.574282) (xy 332.389226 -133.591046)
			(xy 332.388464 -133.600698) (xy 332.386225 -133.62945) (xy 332.374164 -133.685843) (xy 332.353749 -133.739777)
			(xy 332.325446 -133.790023) (xy 332.289901 -133.835434) (xy 332.247922 -133.874975) (xy 332.200469 -133.907745)
			(xy 332.148623 -133.932996) (xy 332.093565 -133.950152) (xy 332.036552 -133.958823) (xy 332.007718 -133.959346)
			(xy 331.98238 -133.958906) (xy 331.932151 -133.9522) (xy 331.883252 -133.938903) (xy 331.836543 -133.91925)
			(xy 331.792847 -133.893586) (xy 331.752933 -133.862364) (xy 331.734922 -133.844538) (xy 331.728064 -133.837426)
			(xy 331.7113 -133.829806) (xy 331.62367 -133.824472) (xy 331.606144 -133.83006) (xy 331.598524 -133.836156)
			(xy 331.578119 -133.851968) (xy 331.533876 -133.878562) (xy 331.486454 -133.898957) (xy 331.436718 -133.91278)
			(xy 331.385574 -133.91978) (xy 331.359764 -133.92023) (xy 331.330759 -133.919685) (xy 331.27342 -133.910885)
			(xy 331.218073 -133.893508) (xy 331.165993 -133.867956) (xy 331.118381 -133.834815) (xy 331.076333 -133.794851)
			(xy 331.040817 -133.748983) (xy 331.026262 -133.723888) (xy 331.02169 -133.715506) (xy 331.007466 -133.703822)
			(xy 330.92517 -133.675374) (xy 330.906628 -133.676136) (xy 330.897738 -133.679946) (xy 330.874067 -133.689537)
			(xy 330.8248 -133.703004) (xy 330.774177 -133.709781) (xy 330.74864 -133.710172) (xy 330.721383 -133.709784)
			(xy 330.667422 -133.702031) (xy 330.615115 -133.686677) (xy 330.565525 -133.664034) (xy 330.519662 -133.634565)
			(xy 330.478461 -133.598867) (xy 330.442759 -133.55767) (xy 330.413285 -133.51181) (xy 330.390637 -133.462223)
			(xy 330.375278 -133.409917) (xy 330.367519 -133.355957) (xy 327.550272 -133.355957) (xy 327.550272 -136.473946)
			(xy 330.23505 -136.473946) (xy 330.239121 -136.418324) (xy 330.251247 -136.363887) (xy 330.27117 -136.311796)
			(xy 330.298466 -136.263161) (xy 330.332552 -136.219018) (xy 330.372701 -136.180309) (xy 330.418059 -136.147858)
			(xy 330.467659 -136.122357) (xy 330.520443 -136.10435) (xy 330.575286 -136.09422) (xy 330.63102 -136.092183)
			(xy 330.686457 -136.098283) (xy 330.740414 -136.112389) (xy 330.791743 -136.134201) (xy 330.839349 -136.163255)
			(xy 330.882217 -136.19893) (xy 330.919434 -136.240467) (xy 330.950207 -136.28698) (xy 330.973879 -136.337477)
			(xy 330.989947 -136.390884) (xy 330.998067 -136.44606) (xy 330.998576 -136.473946) (xy 330.998067 -136.501832)
			(xy 330.989947 -136.557008) (xy 330.973879 -136.610415) (xy 330.950207 -136.660912) (xy 330.919434 -136.707425)
			(xy 330.882217 -136.748962) (xy 330.839349 -136.784637) (xy 330.791743 -136.813691) (xy 330.740414 -136.835503)
			(xy 330.686457 -136.849609) (xy 330.63102 -136.855709) (xy 330.575286 -136.853672) (xy 330.520443 -136.843542)
			(xy 330.467659 -136.825535) (xy 330.418059 -136.800034) (xy 330.372701 -136.767583) (xy 330.332552 -136.728874)
			(xy 330.298466 -136.684731) (xy 330.27117 -136.636096) (xy 330.251247 -136.584005) (xy 330.239121 -136.529568)
			(xy 330.23505 -136.473946) (xy 327.550272 -136.473946) (xy 327.550272 -137.849864) (xy 328.187556 -137.849864)
			(xy 328.191627 -137.794242) (xy 328.203753 -137.739805) (xy 328.223676 -137.687714) (xy 328.250972 -137.639079)
			(xy 328.285058 -137.594936) (xy 328.325207 -137.556227) (xy 328.370565 -137.523776) (xy 328.420165 -137.498275)
			(xy 328.472949 -137.480268) (xy 328.527792 -137.470138) (xy 328.583526 -137.468101) (xy 328.638963 -137.474201)
			(xy 328.69292 -137.488307) (xy 328.744249 -137.510119) (xy 328.791855 -137.539173) (xy 328.834723 -137.574848)
			(xy 328.87194 -137.616385) (xy 328.902713 -137.662898) (xy 328.926385 -137.713395) (xy 328.942453 -137.766802)
			(xy 328.950573 -137.821978) (xy 328.951082 -137.849864) (xy 328.950573 -137.87775) (xy 328.942453 -137.932926)
			(xy 328.926385 -137.986333) (xy 328.902713 -138.03683) (xy 328.87194 -138.083343) (xy 328.834723 -138.12488)
			(xy 328.791855 -138.160555) (xy 328.744249 -138.189609) (xy 328.69292 -138.211421) (xy 328.638963 -138.225527)
			(xy 328.583526 -138.231627) (xy 328.527792 -138.22959) (xy 328.472949 -138.21946) (xy 328.420165 -138.201453)
			(xy 328.370565 -138.175952) (xy 328.325207 -138.143501) (xy 328.285058 -138.104792) (xy 328.250972 -138.060649)
			(xy 328.223676 -138.012014) (xy 328.203753 -137.959923) (xy 328.191627 -137.905486) (xy 328.187556 -137.849864)
			(xy 327.550272 -137.849864) (xy 327.550272 -140.408152) (xy 332.324962 -140.408152) (xy 332.329033 -140.35253)
			(xy 332.341159 -140.298093) (xy 332.361082 -140.246002) (xy 332.388378 -140.197367) (xy 332.422464 -140.153224)
			(xy 332.462613 -140.114515) (xy 332.507971 -140.082064) (xy 332.557571 -140.056563) (xy 332.610355 -140.038556)
			(xy 332.665198 -140.028426) (xy 332.720932 -140.026389) (xy 332.776369 -140.032489) (xy 332.830326 -140.046595)
			(xy 332.881655 -140.068407) (xy 332.929261 -140.097461) (xy 332.972129 -140.133136) (xy 333.009346 -140.174673)
			(xy 333.040119 -140.221186) (xy 333.063791 -140.271683) (xy 333.079859 -140.32509) (xy 333.087979 -140.380266)
			(xy 333.088488 -140.408152) (xy 333.087979 -140.436038) (xy 333.079859 -140.491214) (xy 333.063791 -140.544621)
			(xy 333.040119 -140.595118) (xy 333.009346 -140.641631) (xy 332.972129 -140.683168) (xy 332.929261 -140.718843)
			(xy 332.881655 -140.747897) (xy 332.830326 -140.769709) (xy 332.776369 -140.783815) (xy 332.720932 -140.789915)
			(xy 332.665198 -140.787878) (xy 332.610355 -140.777748) (xy 332.557571 -140.759741) (xy 332.507971 -140.73424)
			(xy 332.462613 -140.701789) (xy 332.422464 -140.66308) (xy 332.388378 -140.618937) (xy 332.361082 -140.570302)
			(xy 332.341159 -140.518211) (xy 332.329033 -140.463774) (xy 332.324962 -140.408152) (xy 327.550272 -140.408152)
			(xy 327.550272 -142.578074) (xy 328.532234 -142.578074) (xy 328.536305 -142.522452) (xy 328.548431 -142.468015)
			(xy 328.568354 -142.415924) (xy 328.59565 -142.367289) (xy 328.629736 -142.323146) (xy 328.669885 -142.284437)
			(xy 328.715243 -142.251986) (xy 328.764843 -142.226485) (xy 328.817627 -142.208478) (xy 328.87247 -142.198348)
			(xy 328.928204 -142.196311) (xy 328.935138 -142.197074) (xy 332.301086 -142.197074) (xy 332.305157 -142.141452)
			(xy 332.317283 -142.087015) (xy 332.337206 -142.034924) (xy 332.364502 -141.986289) (xy 332.398588 -141.942146)
			(xy 332.438737 -141.903437) (xy 332.484095 -141.870986) (xy 332.533695 -141.845485) (xy 332.586479 -141.827478)
			(xy 332.641322 -141.817348) (xy 332.697056 -141.815311) (xy 332.752493 -141.821411) (xy 332.80645 -141.835517)
			(xy 332.857779 -141.857329) (xy 332.905385 -141.886383) (xy 332.948253 -141.922058) (xy 332.98547 -141.963595)
			(xy 333.016243 -142.010108) (xy 333.039915 -142.060605) (xy 333.055983 -142.114012) (xy 333.064103 -142.169188)
			(xy 333.064612 -142.197074) (xy 333.064103 -142.22496) (xy 333.055983 -142.280136) (xy 333.039915 -142.333543)
			(xy 333.016243 -142.38404) (xy 332.98547 -142.430553) (xy 332.948253 -142.47209) (xy 332.905385 -142.507765)
			(xy 332.857779 -142.536819) (xy 332.80645 -142.558631) (xy 332.752493 -142.572737) (xy 332.697056 -142.578837)
			(xy 332.641322 -142.5768) (xy 332.586479 -142.56667) (xy 332.533695 -142.548663) (xy 332.484095 -142.523162)
			(xy 332.438737 -142.490711) (xy 332.398588 -142.452002) (xy 332.364502 -142.407859) (xy 332.337206 -142.359224)
			(xy 332.317283 -142.307133) (xy 332.305157 -142.252696) (xy 332.301086 -142.197074) (xy 328.935138 -142.197074)
			(xy 328.983641 -142.202411) (xy 329.037598 -142.216517) (xy 329.088927 -142.238329) (xy 329.136533 -142.267383)
			(xy 329.179401 -142.303058) (xy 329.216618 -142.344595) (xy 329.247391 -142.391108) (xy 329.271063 -142.441605)
			(xy 329.287131 -142.495012) (xy 329.295251 -142.550188) (xy 329.29576 -142.578074) (xy 329.295251 -142.60596)
			(xy 329.287131 -142.661136) (xy 329.275822 -142.698724) (xy 337.332572 -142.698724) (xy 337.336643 -142.643102)
			(xy 337.348769 -142.588665) (xy 337.368692 -142.536574) (xy 337.395988 -142.487939) (xy 337.430074 -142.443796)
			(xy 337.470223 -142.405087) (xy 337.515581 -142.372636) (xy 337.565181 -142.347135) (xy 337.617965 -142.329128)
			(xy 337.672808 -142.318998) (xy 337.728542 -142.316961) (xy 337.783979 -142.323061) (xy 337.837936 -142.337167)
			(xy 337.889265 -142.358979) (xy 337.936871 -142.388033) (xy 337.979739 -142.423708) (xy 338.016956 -142.465245)
			(xy 338.047729 -142.511758) (xy 338.071401 -142.562255) (xy 338.087469 -142.615662) (xy 338.095589 -142.670838)
			(xy 338.096098 -142.698724) (xy 338.095589 -142.72661) (xy 338.087469 -142.781786) (xy 338.071401 -142.835193)
			(xy 338.047729 -142.88569) (xy 338.016956 -142.932203) (xy 337.979739 -142.97374) (xy 337.936871 -143.009415)
			(xy 337.889265 -143.038469) (xy 337.837936 -143.060281) (xy 337.783979 -143.074387) (xy 337.728542 -143.080487)
			(xy 337.672808 -143.07845) (xy 337.617965 -143.06832) (xy 337.565181 -143.050313) (xy 337.515581 -143.024812)
			(xy 337.470223 -142.992361) (xy 337.430074 -142.953652) (xy 337.395988 -142.909509) (xy 337.368692 -142.860874)
			(xy 337.348769 -142.808783) (xy 337.336643 -142.754346) (xy 337.332572 -142.698724) (xy 329.275822 -142.698724)
			(xy 329.271063 -142.714543) (xy 329.247391 -142.76504) (xy 329.216618 -142.811553) (xy 329.179401 -142.85309)
			(xy 329.136533 -142.888765) (xy 329.088927 -142.917819) (xy 329.037598 -142.939631) (xy 328.983641 -142.953737)
			(xy 328.928204 -142.959837) (xy 328.87247 -142.9578) (xy 328.817627 -142.94767) (xy 328.764843 -142.929663)
			(xy 328.715243 -142.904162) (xy 328.669885 -142.871711) (xy 328.629736 -142.833002) (xy 328.59565 -142.788859)
			(xy 328.568354 -142.740224) (xy 328.548431 -142.688133) (xy 328.536305 -142.633696) (xy 328.532234 -142.578074)
			(xy 327.550272 -142.578074) (xy 327.550272 -144.27327) (xy 327.550776 -144.283321) (xy 327.558494 -144.301885)
			(xy 327.565258 -144.309338) (xy 328.937874 -145.681954) (xy 328.945274 -145.688794) (xy 328.963873 -145.696509)
			(xy 328.973942 -145.69694) (xy 337.735418 -145.69694)
		)
		(stroke
			(width 0)
			(type solid)
		)
		(fill yes)
		(layer "In6.Cu")
		(net "GND")
	)
	(gr_poly
		(pts
			(xy 368.278664 -46.790864) (xy 368.288728 -46.790428) (xy 368.307313 -46.782694) (xy 368.314732 -46.775878)
			(xy 372.097554 -42.993056) (xy 372.104398 -42.985657) (xy 372.112124 -42.967059) (xy 372.11254 -42.956988)
			(xy 372.11254 -35.373056) (xy 372.112107 -35.362991) (xy 372.104375 -35.344404) (xy 372.097554 -35.336988)
			(xy 371.763544 -35.002978) (xy 371.736366 -34.996374) (xy 371.722396 -35.000946) (xy 371.694182 -35.009363)
			(xy 371.636009 -35.018424) (xy 371.606572 -35.01898) (xy 371.606318 -35.01898) (xy 371.578112 -35.018465)
			(xy 371.522317 -35.010144) (xy 371.468357 -34.993694) (xy 371.417409 -34.969475) (xy 371.370584 -34.938015)
			(xy 371.328903 -34.900001) (xy 371.293278 -34.856262) (xy 371.278404 -34.83229) (xy 371.273604 -34.824916)
			(xy 371.26005 -34.813717) (xy 371.243507 -34.807764) (xy 371.234716 -34.807398) (xy 369.200684 -34.807398)
			(xy 369.190615 -34.806972) (xy 369.172015 -34.799253) (xy 369.164616 -34.792412) (xy 364.59541 -30.223206)
			(xy 364.588561 -30.215808) (xy 364.580823 -30.19721) (xy 364.580424 -30.187138) (xy 364.580424 -27.6352)
			(xy 364.579882 -27.623664) (xy 364.569842 -27.60289) (xy 364.56112 -27.595322) (xy 364.489238 -27.53868)
			(xy 364.466632 -27.5336) (xy 364.455202 -27.536394) (xy 364.433493 -27.54126) (xy 364.389309 -27.54648)
			(xy 364.367064 -27.546808) (xy 364.366302 -27.546808) (xy 364.339049 -27.546345) (xy 364.285098 -27.538588)
			(xy 364.2328 -27.523232) (xy 364.183219 -27.50059) (xy 364.137366 -27.471122) (xy 364.096173 -27.435428)
			(xy 364.060479 -27.394236) (xy 364.031011 -27.348382) (xy 364.008368 -27.298802) (xy 363.993012 -27.246504)
			(xy 363.985255 -27.192553) (xy 363.985255 -27.138047) (xy 363.993012 -27.084096) (xy 364.008368 -27.031798)
			(xy 364.031011 -26.982218) (xy 364.060479 -26.936364) (xy 364.096173 -26.895172) (xy 364.137366 -26.859478)
			(xy 364.183219 -26.83001) (xy 364.2328 -26.807368) (xy 364.285098 -26.792012) (xy 364.339049 -26.784255)
			(xy 364.366302 -26.783792) (xy 364.367064 -26.783792) (xy 364.389307 -26.784151) (xy 364.433486 -26.789376)
			(xy 364.455202 -26.794206) (xy 364.466632 -26.797) (xy 364.489238 -26.79192) (xy 364.56112 -26.735278)
			(xy 364.569828 -26.727698) (xy 364.579862 -26.706933) (xy 364.580424 -26.6954) (xy 364.580424 -26.309066)
			(xy 364.579995 -26.298998) (xy 364.572275 -26.2804) (xy 364.565438 -26.272998) (xy 364.42777 -26.13533)
			(xy 364.420371 -26.128485) (xy 364.401773 -26.120757) (xy 364.391702 -26.120344) (xy 361.039918 -26.120344)
			(xy 361.029855 -26.120783) (xy 361.011277 -26.128524) (xy 361.00385 -26.13533) (xy 360.908092 -26.231088)
			(xy 360.901245 -26.238486) (xy 360.893507 -26.257084) (xy 360.893106 -26.267156) (xy 360.893106 -33.049972)
			(xy 365.599216 -33.049972) (xy 365.603287 -32.99435) (xy 365.615413 -32.939913) (xy 365.635336 -32.887822)
			(xy 365.662632 -32.839187) (xy 365.696718 -32.795044) (xy 365.736867 -32.756335) (xy 365.782225 -32.723884)
			(xy 365.831825 -32.698383) (xy 365.884609 -32.680376) (xy 365.939452 -32.670246) (xy 365.995186 -32.668209)
			(xy 366.050623 -32.674309) (xy 366.10458 -32.688415) (xy 366.155909 -32.710227) (xy 366.203515 -32.739281)
			(xy 366.246383 -32.774956) (xy 366.2836 -32.816493) (xy 366.314373 -32.863006) (xy 366.338045 -32.913503)
			(xy 366.354113 -32.96691) (xy 366.362233 -33.022086) (xy 366.362742 -33.049972) (xy 366.362233 -33.077858)
			(xy 366.354113 -33.133034) (xy 366.338045 -33.186441) (xy 366.314373 -33.236938) (xy 366.2836 -33.283451)
			(xy 366.246383 -33.324988) (xy 366.203515 -33.360663) (xy 366.155909 -33.389717) (xy 366.10458 -33.411529)
			(xy 366.050623 -33.425635) (xy 365.995186 -33.431735) (xy 365.939452 -33.429698) (xy 365.884609 -33.419568)
			(xy 365.831825 -33.401561) (xy 365.782225 -33.37606) (xy 365.736867 -33.343609) (xy 365.696718 -33.3049)
			(xy 365.662632 -33.260757) (xy 365.635336 -33.212122) (xy 365.615413 -33.160031) (xy 365.603287 -33.105594)
			(xy 365.599216 -33.049972) (xy 360.893106 -33.049972) (xy 360.893106 -38.650164) (xy 364.94923 -38.650164)
			(xy 364.953301 -38.594542) (xy 364.965427 -38.540105) (xy 364.98535 -38.488014) (xy 365.012646 -38.439379)
			(xy 365.046732 -38.395236) (xy 365.086881 -38.356527) (xy 365.132239 -38.324076) (xy 365.181839 -38.298575)
			(xy 365.234623 -38.280568) (xy 365.289466 -38.270438) (xy 365.3452 -38.268401) (xy 365.400637 -38.274501)
			(xy 365.454594 -38.288607) (xy 365.505923 -38.310419) (xy 365.553529 -38.339473) (xy 365.596397 -38.375148)
			(xy 365.633614 -38.416685) (xy 365.664387 -38.463198) (xy 365.688059 -38.513695) (xy 365.704127 -38.567102)
			(xy 365.712247 -38.622278) (xy 365.712756 -38.650164) (xy 368.8494 -38.650164) (xy 368.853471 -38.594542)
			(xy 368.865597 -38.540105) (xy 368.88552 -38.488014) (xy 368.912816 -38.439379) (xy 368.946902 -38.395236)
			(xy 368.987051 -38.356527) (xy 369.032409 -38.324076) (xy 369.082009 -38.298575) (xy 369.134793 -38.280568)
			(xy 369.189636 -38.270438) (xy 369.24537 -38.268401) (xy 369.300807 -38.274501) (xy 369.354764 -38.288607)
			(xy 369.406093 -38.310419) (xy 369.453699 -38.339473) (xy 369.496567 -38.375148) (xy 369.533784 -38.416685)
			(xy 369.564557 -38.463198) (xy 369.588229 -38.513695) (xy 369.604297 -38.567102) (xy 369.612417 -38.622278)
			(xy 369.612926 -38.650164) (xy 369.612417 -38.67805) (xy 369.604297 -38.733226) (xy 369.588229 -38.786633)
			(xy 369.564557 -38.83713) (xy 369.533784 -38.883643) (xy 369.496567 -38.92518) (xy 369.453699 -38.960855)
			(xy 369.406093 -38.989909) (xy 369.354764 -39.011721) (xy 369.300807 -39.025827) (xy 369.24537 -39.031927)
			(xy 369.189636 -39.02989) (xy 369.134793 -39.01976) (xy 369.082009 -39.001753) (xy 369.032409 -38.976252)
			(xy 368.987051 -38.943801) (xy 368.946902 -38.905092) (xy 368.912816 -38.860949) (xy 368.88552 -38.812314)
			(xy 368.865597 -38.760223) (xy 368.853471 -38.705786) (xy 368.8494 -38.650164) (xy 365.712756 -38.650164)
			(xy 365.712247 -38.67805) (xy 365.704127 -38.733226) (xy 365.688059 -38.786633) (xy 365.664387 -38.83713)
			(xy 365.633614 -38.883643) (xy 365.596397 -38.92518) (xy 365.553529 -38.960855) (xy 365.505923 -38.989909)
			(xy 365.454594 -39.011721) (xy 365.400637 -39.025827) (xy 365.3452 -39.031927) (xy 365.289466 -39.02989)
			(xy 365.234623 -39.01976) (xy 365.181839 -39.001753) (xy 365.132239 -38.976252) (xy 365.086881 -38.943801)
			(xy 365.046732 -38.905092) (xy 365.012646 -38.860949) (xy 364.98535 -38.812314) (xy 364.965427 -38.760223)
			(xy 364.953301 -38.705786) (xy 364.94923 -38.650164) (xy 360.893106 -38.650164) (xy 360.893106 -41.669069)
			(xy 365.7318 -41.669069) (xy 365.7318 -41.614531) (xy 365.739561 -41.560547) (xy 365.754926 -41.508218)
			(xy 365.77758 -41.458607) (xy 365.807064 -41.412725) (xy 365.842778 -41.371506) (xy 365.883993 -41.335788)
			(xy 365.929872 -41.3063) (xy 365.97948 -41.28364) (xy 366.031808 -41.26827) (xy 366.085791 -41.260503)
			(xy 366.11306 -41.260014) (xy 366.139179 -41.260415) (xy 366.190928 -41.267545) (xy 366.241222 -41.281662)
			(xy 366.289122 -41.302505) (xy 366.333733 -41.329683) (xy 366.374222 -41.362689) (xy 366.409834 -41.400907)
			(xy 366.439903 -41.443623) (xy 366.463868 -41.490039) (xy 366.472978 -41.514522) (xy 366.47978 -41.483576)
			(xy 366.500034 -41.42354) (xy 366.527589 -41.366484) (xy 366.562017 -41.313292) (xy 366.602785 -41.264789)
			(xy 366.649262 -41.221724) (xy 366.700727 -41.184766) (xy 366.756385 -41.154486) (xy 366.815372 -41.131354)
			(xy 366.876776 -41.115727) (xy 366.939646 -41.107848) (xy 366.971326 -41.10736) (xy 367.003284 -41.107927)
			(xy 367.066696 -41.115941) (xy 367.128603 -41.131839) (xy 367.188029 -41.15537) (xy 367.244038 -41.186164)
			(xy 367.295746 -41.223735) (xy 367.342338 -41.267489) (xy 367.383078 -41.316738) (xy 367.417325 -41.370705)
			(xy 367.444539 -41.428538) (xy 367.464289 -41.489326) (xy 367.476265 -41.55211) (xy 367.480279 -41.6159)
			(xy 367.47827 -41.647829) (xy 369.00332 -41.647829) (xy 369.00332 -41.583907) (xy 369.011331 -41.520489)
			(xy 369.027228 -41.458575) (xy 369.05076 -41.399142) (xy 369.081554 -41.343127) (xy 369.119127 -41.291412)
			(xy 369.162884 -41.244815) (xy 369.212137 -41.20407) (xy 369.266108 -41.169819) (xy 369.323947 -41.142602)
			(xy 369.38474 -41.122849) (xy 369.44753 -41.110871) (xy 369.511326 -41.106858) (xy 369.575122 -41.110871)
			(xy 369.637912 -41.122849) (xy 369.698705 -41.142602) (xy 369.756544 -41.169819) (xy 369.810515 -41.20407)
			(xy 369.859768 -41.244815) (xy 369.903525 -41.291412) (xy 369.941098 -41.343127) (xy 369.971892 -41.399142)
			(xy 369.995424 -41.458575) (xy 370.011321 -41.520489) (xy 370.019332 -41.583907) (xy 370.01965 -41.604184)
			(xy 370.248686 -41.604184) (xy 370.252759 -41.548525) (xy 370.264894 -41.494052) (xy 370.28483 -41.441926)
			(xy 370.312144 -41.393258) (xy 370.346252 -41.349086) (xy 370.386429 -41.310351) (xy 370.431817 -41.277879)
			(xy 370.481449 -41.252361) (xy 370.534269 -41.234342) (xy 370.589148 -41.224205) (xy 370.644919 -41.222167)
			(xy 370.700393 -41.22827) (xy 370.754386 -41.242386) (xy 370.805749 -41.264213) (xy 370.853387 -41.293286)
			(xy 370.896283 -41.328985) (xy 370.933525 -41.370549) (xy 370.964319 -41.417093) (xy 370.988007 -41.467624)
			(xy 371.004085 -41.521066) (xy 371.012211 -41.57628) (xy 371.01272 -41.604184) (xy 371.012211 -41.632088)
			(xy 371.004085 -41.687302) (xy 370.988007 -41.740744) (xy 370.964319 -41.791275) (xy 370.933525 -41.837819)
			(xy 370.896283 -41.879383) (xy 370.853387 -41.915082) (xy 370.805749 -41.944155) (xy 370.754386 -41.965982)
			(xy 370.700393 -41.980098) (xy 370.644919 -41.986201) (xy 370.589148 -41.984163) (xy 370.534269 -41.974026)
			(xy 370.481449 -41.956007) (xy 370.431817 -41.930489) (xy 370.386429 -41.898017) (xy 370.346252 -41.859282)
			(xy 370.312144 -41.81511) (xy 370.28483 -41.766442) (xy 370.264894 -41.714316) (xy 370.252759 -41.659843)
			(xy 370.248686 -41.604184) (xy 370.01965 -41.604184) (xy 370.019834 -41.615868) (xy 370.019332 -41.647829)
			(xy 370.011321 -41.711247) (xy 369.995424 -41.773161) (xy 369.971892 -41.832594) (xy 369.941098 -41.888609)
			(xy 369.903525 -41.940324) (xy 369.859768 -41.986921) (xy 369.810515 -42.027666) (xy 369.756544 -42.061917)
			(xy 369.698705 -42.089134) (xy 369.637912 -42.108887) (xy 369.575122 -42.120865) (xy 369.511326 -42.124879)
			(xy 369.44753 -42.120865) (xy 369.38474 -42.108887) (xy 369.323947 -42.089134) (xy 369.266108 -42.061917)
			(xy 369.212137 -42.027666) (xy 369.162884 -41.986921) (xy 369.119127 -41.940324) (xy 369.081554 -41.888609)
			(xy 369.05076 -41.832594) (xy 369.027228 -41.773161) (xy 369.011331 -41.711247) (xy 369.00332 -41.647829)
			(xy 367.47827 -41.647829) (xy 367.476265 -41.67969) (xy 367.464289 -41.742474) (xy 367.444539 -41.803262)
			(xy 367.417325 -41.861095) (xy 367.383078 -41.915062) (xy 367.342338 -41.964311) (xy 367.295746 -42.008065)
			(xy 367.244038 -42.045636) (xy 367.188029 -42.07643) (xy 367.128603 -42.099961) (xy 367.066696 -42.115859)
			(xy 367.003284 -42.123873) (xy 366.971326 -42.124376) (xy 366.93801 -42.123798) (xy 366.871952 -42.115075)
			(xy 366.807598 -42.097801) (xy 366.746051 -42.072272) (xy 366.688364 -42.038925) (xy 366.635526 -41.998331)
			(xy 366.58844 -41.951185) (xy 366.547914 -41.898294) (xy 366.514641 -41.840565) (xy 366.48919 -41.778985)
			(xy 366.48009 -41.746932) (xy 366.472046 -41.773139) (xy 366.44956 -41.823133) (xy 366.420155 -41.869398)
			(xy 366.384436 -41.910982) (xy 366.343138 -41.947031) (xy 366.29711 -41.976803) (xy 366.247296 -41.999687)
			(xy 366.194723 -42.015213) (xy 366.140469 -42.02306) (xy 366.11306 -42.023538) (xy 366.085791 -42.023097)
			(xy 366.031808 -42.01533) (xy 365.97948 -41.99996) (xy 365.929872 -41.9773) (xy 365.883993 -41.947812)
			(xy 365.842778 -41.912094) (xy 365.807064 -41.870875) (xy 365.77758 -41.824993) (xy 365.754926 -41.775382)
			(xy 365.739561 -41.723053) (xy 365.7318 -41.669069) (xy 360.893106 -41.669069) (xy 360.893106 -44.283079)
			(xy 365.19332 -44.283079) (xy 365.19332 -44.219157) (xy 365.201331 -44.155739) (xy 365.217228 -44.093825)
			(xy 365.24076 -44.034392) (xy 365.271554 -43.978377) (xy 365.309127 -43.926662) (xy 365.352884 -43.880065)
			(xy 365.402137 -43.83932) (xy 365.456108 -43.805069) (xy 365.513947 -43.777852) (xy 365.57474 -43.758099)
			(xy 365.63753 -43.746121) (xy 365.701326 -43.742108) (xy 365.765122 -43.746121) (xy 365.827912 -43.758099)
			(xy 365.888705 -43.777852) (xy 365.946544 -43.805069) (xy 366.000515 -43.83932) (xy 366.049768 -43.880065)
			(xy 366.093525 -43.926662) (xy 366.131098 -43.978377) (xy 366.161892 -44.034392) (xy 366.185424 -44.093825)
			(xy 366.201321 -44.155739) (xy 366.209332 -44.219157) (xy 366.209834 -44.251118) (xy 366.209332 -44.283079)
			(xy 367.73332 -44.283079) (xy 367.73332 -44.219157) (xy 367.741331 -44.155739) (xy 367.757228 -44.093825)
			(xy 367.78076 -44.034392) (xy 367.811554 -43.978377) (xy 367.849127 -43.926662) (xy 367.892884 -43.880065)
			(xy 367.942137 -43.83932) (xy 367.996108 -43.805069) (xy 368.053947 -43.777852) (xy 368.11474 -43.758099)
			(xy 368.17753 -43.746121) (xy 368.241326 -43.742108) (xy 368.305122 -43.746121) (xy 368.367912 -43.758099)
			(xy 368.428705 -43.777852) (xy 368.486544 -43.805069) (xy 368.540515 -43.83932) (xy 368.589768 -43.880065)
			(xy 368.633525 -43.926662) (xy 368.671098 -43.978377) (xy 368.701892 -44.034392) (xy 368.725424 -44.093825)
			(xy 368.741321 -44.155739) (xy 368.749332 -44.219157) (xy 368.749834 -44.251118) (xy 368.749332 -44.283079)
			(xy 368.741321 -44.346497) (xy 368.725424 -44.408411) (xy 368.701892 -44.467844) (xy 368.671098 -44.523859)
			(xy 368.633525 -44.575574) (xy 368.589768 -44.622171) (xy 368.540515 -44.662916) (xy 368.486544 -44.697167)
			(xy 368.428705 -44.724384) (xy 368.367912 -44.744137) (xy 368.305122 -44.756115) (xy 368.241326 -44.760129)
			(xy 368.17753 -44.756115) (xy 368.11474 -44.744137) (xy 368.053947 -44.724384) (xy 367.996108 -44.697167)
			(xy 367.942137 -44.662916) (xy 367.892884 -44.622171) (xy 367.849127 -44.575574) (xy 367.811554 -44.523859)
			(xy 367.78076 -44.467844) (xy 367.757228 -44.408411) (xy 367.741331 -44.346497) (xy 367.73332 -44.283079)
			(xy 366.209332 -44.283079) (xy 366.201321 -44.346497) (xy 366.185424 -44.408411) (xy 366.161892 -44.467844)
			(xy 366.131098 -44.523859) (xy 366.093525 -44.575574) (xy 366.049768 -44.622171) (xy 366.000515 -44.662916)
			(xy 365.946544 -44.697167) (xy 365.888705 -44.724384) (xy 365.827912 -44.744137) (xy 365.766689 -44.755816)
			(xy 366.13795 -44.755816) (xy 366.142023 -44.700157) (xy 366.154158 -44.645684) (xy 366.174094 -44.593558)
			(xy 366.201408 -44.54489) (xy 366.235516 -44.500718) (xy 366.275693 -44.461983) (xy 366.321081 -44.429511)
			(xy 366.370713 -44.403993) (xy 366.423533 -44.385974) (xy 366.478412 -44.375837) (xy 366.534183 -44.373799)
			(xy 366.589657 -44.379902) (xy 366.64365 -44.394018) (xy 366.695013 -44.415845) (xy 366.742651 -44.444918)
			(xy 366.785547 -44.480617) (xy 366.822789 -44.522181) (xy 366.853583 -44.568725) (xy 366.877271 -44.619256)
			(xy 366.893349 -44.672698) (xy 366.901475 -44.727912) (xy 366.901984 -44.755816) (xy 366.901475 -44.78372)
			(xy 366.893349 -44.838934) (xy 366.877271 -44.892376) (xy 366.853583 -44.942907) (xy 366.822789 -44.989451)
			(xy 366.785547 -45.031015) (xy 366.742651 -45.066714) (xy 366.695013 -45.095787) (xy 366.64365 -45.117614)
			(xy 366.589657 -45.13173) (xy 366.534183 -45.137833) (xy 366.478412 -45.135795) (xy 366.423533 -45.125658)
			(xy 366.370713 -45.107639) (xy 366.321081 -45.082121) (xy 366.275693 -45.049649) (xy 366.235516 -45.010914)
			(xy 366.201408 -44.966742) (xy 366.174094 -44.918074) (xy 366.154158 -44.865948) (xy 366.142023 -44.811475)
			(xy 366.13795 -44.755816) (xy 365.766689 -44.755816) (xy 365.765122 -44.756115) (xy 365.701326 -44.760129)
			(xy 365.63753 -44.756115) (xy 365.57474 -44.744137) (xy 365.513947 -44.724384) (xy 365.456108 -44.697167)
			(xy 365.402137 -44.662916) (xy 365.352884 -44.622171) (xy 365.309127 -44.575574) (xy 365.271554 -44.523859)
			(xy 365.24076 -44.467844) (xy 365.217228 -44.408411) (xy 365.201331 -44.346497) (xy 365.19332 -44.283079)
			(xy 360.893106 -44.283079) (xy 360.893106 -45.625004) (xy 360.89353 -45.635074) (xy 360.901246 -45.653677)
			(xy 360.908092 -45.661072) (xy 362.022898 -46.775878) (xy 362.030295 -46.782727) (xy 362.048894 -46.790466)
			(xy 362.058966 -46.790864)
		)
		(stroke
			(width 0)
			(type solid)
		)
		(fill yes)
		(layer "In6.Cu")
		(net "PVDD18_S5_P0")
	)
	(gr_poly
		(pts
			(xy 109.426756 -51.491642) (xy 109.456661 -51.482136) (xy 109.518572 -51.47193) (xy 109.549946 -51.471322)
			(xy 109.581319 -51.47194) (xy 109.643226 -51.482154) (xy 109.673136 -51.491642) (xy 109.68101 -51.494436)
			(xy 124.784358 -51.494436) (xy 124.794422 -51.494001) (xy 124.813005 -51.486264) (xy 124.820426 -51.47945)
			(xy 125.40869 -50.891186) (xy 125.416084 -50.884329) (xy 125.434683 -50.876577) (xy 125.444758 -50.8762)
			(xy 127.080518 -50.8762) (xy 127.090395 -50.87574) (xy 127.108694 -50.868297) (xy 127.116078 -50.861722)
			(xy 127.116332 -50.861468) (xy 127.7366 -50.2412) (xy 127.748284 -50.2412) (xy 127.76327 -50.21707)
			(xy 127.778228 -50.193703) (xy 127.81247 -50.150046) (xy 127.831596 -50.129948) (xy 127.83912 -50.121267)
			(xy 127.846361 -50.0995) (xy 127.845566 -50.088038) (xy 127.843653 -50.072042) (xy 127.84162 -50.039886)
			(xy 127.841502 -50.023776) (xy 127.842004 -49.991815) (xy 127.850015 -49.928397) (xy 127.865912 -49.866483)
			(xy 127.889444 -49.80705) (xy 127.920238 -49.751035) (xy 127.957811 -49.69932) (xy 128.001568 -49.652723)
			(xy 128.050821 -49.611978) (xy 128.104792 -49.577727) (xy 128.162631 -49.55051) (xy 128.223424 -49.530757)
			(xy 128.286214 -49.518779) (xy 128.35001 -49.514766) (xy 128.413806 -49.518779) (xy 128.476596 -49.530757)
			(xy 128.537389 -49.55051) (xy 128.595228 -49.577727) (xy 128.649199 -49.611978) (xy 128.698452 -49.652723)
			(xy 128.742209 -49.69932) (xy 128.779782 -49.751035) (xy 128.810576 -49.80705) (xy 128.834108 -49.866483)
			(xy 128.850005 -49.928397) (xy 128.858016 -49.991815) (xy 128.858518 -50.023776) (xy 128.858476 -50.035412)
			(xy 128.857461 -50.058663) (xy 128.856486 -50.070258) (xy 128.855216 -50.082704) (xy 128.864106 -50.104802)
			(xy 128.944624 -50.175414) (xy 128.967992 -50.181256) (xy 128.97993 -50.178462) (xy 129.006691 -50.172788)
			(xy 129.061041 -50.166534) (xy 129.115747 -50.166156) (xy 129.142998 -50.168556) (xy 129.177746 -50.172613)
			(xy 129.245745 -50.189052) (xy 129.310846 -50.214665) (xy 129.341626 -50.231294) (xy 129.347214 -50.234342)
			(xy 129.36601 -50.239422) (xy 129.379472 -50.2412) (xy 131.068318 -50.2412) (xy 131.078387 -50.241627)
			(xy 131.096986 -50.249346) (xy 131.104386 -50.256186) (xy 131.249928 -50.401728) (xy 131.259337 -50.410255)
			(xy 131.283605 -50.417611) (xy 131.296156 -50.415698) (xy 131.321034 -50.410972) (xy 131.371419 -50.405882)
			(xy 131.39674 -50.405538) (xy 131.397756 -50.405538) (xy 131.430402 -50.406044) (xy 131.495156 -50.414405)
			(xy 131.558308 -50.430984) (xy 131.618819 -50.455508) (xy 131.675695 -50.487573) (xy 131.728 -50.526651)
			(xy 131.774875 -50.572102) (xy 131.815549 -50.623177) (xy 131.849353 -50.679037) (xy 131.875732 -50.738763)
			(xy 131.894251 -50.801373) (xy 131.899914 -50.833528) (xy 131.902962 -50.85207) (xy 131.931156 -50.8762)
			(xy 138.400028 -50.8762) (xy 138.411787 -50.87561) (xy 138.432853 -50.865157) (xy 138.440414 -50.856134)
			(xy 138.496548 -50.78222) (xy 138.50112 -50.758852) (xy 138.497818 -50.747422) (xy 138.489166 -50.714182)
			(xy 138.47986 -50.646129) (xy 138.479276 -50.611786) (xy 138.479276 -50.611024) (xy 138.47972 -50.580291)
			(xy 138.487126 -50.519272) (xy 138.501834 -50.45959) (xy 138.523628 -50.402117) (xy 138.55219 -50.34769)
			(xy 138.587105 -50.297102) (xy 138.627864 -50.251092) (xy 138.673871 -50.21033) (xy 138.724455 -50.175411)
			(xy 138.77888 -50.146844) (xy 138.836352 -50.125046) (xy 138.896032 -50.110334) (xy 138.957051 -50.102923)
			(xy 138.987784 -50.102516) (xy 139.018689 -50.102977) (xy 139.080042 -50.110482) (xy 139.140033 -50.125369)
			(xy 139.197776 -50.14742) (xy 139.25242 -50.176309) (xy 139.303158 -50.211611) (xy 139.349241 -50.252803)
			(xy 139.389991 -50.299279) (xy 139.424805 -50.350352) (xy 139.45317 -50.40527) (xy 139.474667 -50.463222)
			(xy 139.482322 -50.493168) (xy 139.48537 -50.505106) (xy 139.501118 -50.523648) (xy 139.60094 -50.564288)
			(xy 139.62507 -50.562002) (xy 139.635738 -50.555398) (xy 139.658841 -50.54124) (xy 139.708201 -50.518887)
			(xy 139.760229 -50.503752) (xy 139.813877 -50.496142) (xy 139.84097 -50.495708) (xy 139.843256 -50.495708)
			(xy 139.875208 -50.496594) (xy 139.938151 -50.507705) (xy 139.968478 -50.517806) (xy 139.968732 -50.517806)
			(xy 139.977917 -50.520634) (xy 139.997111 -50.519985) (xy 140.01474 -50.512368) (xy 140.021818 -50.505868)
			(xy 141.234414 -49.293018) (xy 141.234922 -49.29251) (xy 141.241502 -49.285128) (xy 141.248944 -49.266829)
			(xy 141.2494 -49.25695) (xy 141.2494 -48.318928) (xy 141.248985 -48.308903) (xy 141.24132 -48.290376)
			(xy 141.227147 -48.276195) (xy 141.208625 -48.26852) (xy 141.1986 -48.268128) (xy 140.309092 -48.268128)
			(xy 140.299074 -48.26855) (xy 140.280565 -48.276222) (xy 140.266402 -48.290395) (xy 140.258742 -48.30891)
			(xy 140.258292 -48.318928) (xy 140.258292 -48.325024) (xy 140.257827 -48.355754) (xy 140.250416 -48.416765)
			(xy 140.235705 -48.476438) (xy 140.213908 -48.533902) (xy 140.185344 -48.588321) (xy 140.150429 -48.638899)
			(xy 140.109672 -48.684901) (xy 140.063668 -48.725654) (xy 140.013086 -48.760565) (xy 139.958666 -48.789125)
			(xy 139.901199 -48.810917) (xy 139.841525 -48.825623) (xy 139.780514 -48.833029) (xy 139.749784 -48.833532)
			(xy 139.719578 -48.833099) (xy 139.659591 -48.825941) (xy 139.600874 -48.811727) (xy 139.544255 -48.790658)
			(xy 139.49053 -48.763031) (xy 139.440456 -48.729234) (xy 139.417298 -48.709834) (xy 139.410186 -48.703738)
			(xy 139.393422 -48.697388) (xy 139.344146 -48.697388) (xy 139.327382 -48.703738) (xy 139.32027 -48.709834)
			(xy 139.297124 -48.729246) (xy 139.247042 -48.763033) (xy 139.193314 -48.790652) (xy 139.136693 -48.811717)
			(xy 139.077976 -48.82593) (xy 139.01799 -48.833092) (xy 138.987784 -48.833532) (xy 138.957712 -48.833075)
			(xy 138.897992 -48.825944) (xy 138.868658 -48.819308) (xy 138.856425 -48.816984) (xy 138.832318 -48.823105)
			(xy 138.822684 -48.830992) (xy 138.815456 -48.836952) (xy 138.798004 -48.843718) (xy 138.788648 -48.8442)
			(xy 132.264658 -48.8442) (xy 132.237988 -48.864012) (xy 132.232908 -48.880268) (xy 132.222923 -48.910655)
			(xy 132.196367 -48.968845) (xy 132.162725 -49.023246) (xy 132.122527 -49.073) (xy 132.076407 -49.11732)
			(xy 132.051044 -49.136808) (xy 132.039106 -49.145698) (xy 132.028692 -49.173384) (xy 132.051044 -49.278286)
			(xy 132.053441 -49.28767) (xy 132.064147 -49.303791) (xy 132.080069 -49.31479) (xy 132.089398 -49.317402)
			(xy 132.089652 -49.317402) (xy 132.12003 -49.324683) (xy 132.178864 -49.345681) (xy 132.234683 -49.373728)
			(xy 132.286645 -49.408403) (xy 132.333967 -49.449183) (xy 132.375937 -49.495453) (xy 132.411921 -49.546517)
			(xy 132.43786 -49.595024) (xy 138.605766 -49.595024) (xy 138.609837 -49.539402) (xy 138.621963 -49.484965)
			(xy 138.641886 -49.432874) (xy 138.669182 -49.384239) (xy 138.703268 -49.340096) (xy 138.743417 -49.301387)
			(xy 138.788775 -49.268936) (xy 138.838375 -49.243435) (xy 138.891159 -49.225428) (xy 138.946002 -49.215298)
			(xy 139.001736 -49.213261) (xy 139.057173 -49.219361) (xy 139.11113 -49.233467) (xy 139.162459 -49.255279)
			(xy 139.210065 -49.284333) (xy 139.252933 -49.320008) (xy 139.29015 -49.361545) (xy 139.320923 -49.408058)
			(xy 139.344595 -49.458555) (xy 139.360663 -49.511962) (xy 139.368783 -49.567138) (xy 139.369292 -49.595024)
			(xy 139.368783 -49.62291) (xy 139.360663 -49.678086) (xy 139.344595 -49.731493) (xy 139.320923 -49.78199)
			(xy 139.29015 -49.828503) (xy 139.252933 -49.87004) (xy 139.210065 -49.905715) (xy 139.162459 -49.934769)
			(xy 139.11113 -49.956581) (xy 139.057173 -49.970687) (xy 139.001736 -49.976787) (xy 138.946002 -49.97475)
			(xy 138.891159 -49.96462) (xy 138.838375 -49.946613) (xy 138.788775 -49.921112) (xy 138.743417 -49.888661)
			(xy 138.703268 -49.849952) (xy 138.669182 -49.805809) (xy 138.641886 -49.757174) (xy 138.621963 -49.705083)
			(xy 138.609837 -49.650646) (xy 138.605766 -49.595024) (xy 132.43786 -49.595024) (xy 132.441379 -49.601604)
			(xy 132.463866 -49.659886) (xy 132.479043 -49.720483) (xy 132.486682 -49.782483) (xy 132.487162 -49.813718)
			(xy 132.48666 -49.845679) (xy 132.478649 -49.909097) (xy 132.462752 -49.971011) (xy 132.43922 -50.030444)
			(xy 132.408426 -50.086459) (xy 132.370853 -50.138174) (xy 132.327096 -50.184771) (xy 132.277843 -50.225516)
			(xy 132.223872 -50.259767) (xy 132.166033 -50.286984) (xy 132.10524 -50.306737) (xy 132.04245 -50.318715)
			(xy 131.978654 -50.322729) (xy 131.914858 -50.318715) (xy 131.852068 -50.306737) (xy 131.791275 -50.286984)
			(xy 131.733436 -50.259767) (xy 131.679465 -50.225516) (xy 131.630212 -50.184771) (xy 131.586455 -50.138174)
			(xy 131.548882 -50.086459) (xy 131.518088 -50.030444) (xy 131.494556 -49.971011) (xy 131.478659 -49.909097)
			(xy 131.470648 -49.845679) (xy 131.470146 -49.813718) (xy 131.470702 -49.779888) (xy 131.479676 -49.712825)
			(xy 131.49747 -49.647547) (xy 131.523767 -49.585206) (xy 131.558103 -49.526905) (xy 131.599871 -49.473676)
			(xy 131.648332 -49.426459) (xy 131.675124 -49.405794) (xy 131.687062 -49.396904) (xy 131.697476 -49.369218)
			(xy 131.675124 -49.264316) (xy 131.67273 -49.254927) (xy 131.66203 -49.238792) (xy 131.646111 -49.227773)
			(xy 131.63677 -49.2252) (xy 131.636516 -49.2252) (xy 131.604075 -49.217405) (xy 131.541427 -49.194451)
			(xy 131.482316 -49.163506) (xy 131.427758 -49.1251) (xy 131.378688 -49.079891) (xy 131.335948 -49.028657)
			(xy 131.300272 -48.972275) (xy 131.272271 -48.911714) (xy 131.261866 -48.880014) (xy 131.256786 -48.863758)
			(xy 131.230116 -48.8442) (xy 126.83744 -48.8442) (xy 126.827375 -48.844634) (xy 126.808786 -48.852364)
			(xy 126.801372 -48.859186) (xy 126.163578 -49.49698) (xy 126.162816 -49.497742) (xy 126.142151 -49.51951)
			(xy 126.096552 -49.558543) (xy 126.046674 -49.591935) (xy 125.993211 -49.619222) (xy 125.936908 -49.640024)
			(xy 125.878547 -49.654052) (xy 125.81894 -49.661111) (xy 125.788928 -49.661572) (xy 125.777244 -49.661572)
			(xy 125.746812 -49.660422) (xy 125.686531 -49.651758) (xy 125.627715 -49.635959) (xy 125.571206 -49.613252)
			(xy 125.517811 -49.583963) (xy 125.468294 -49.548509) (xy 125.423363 -49.507398) (xy 125.383661 -49.461217)
			(xy 125.349756 -49.410627) (xy 125.335538 -49.383696) (xy 125.330917 -49.375593) (xy 125.317047 -49.363145)
			(xy 125.299644 -49.356476) (xy 125.290326 -49.35601) (xy 124.115576 -49.35601) (xy 124.106256 -49.356432)
			(xy 124.088858 -49.363122) (xy 124.075014 -49.375604) (xy 124.070364 -49.383696) (xy 124.055845 -49.411182)
			(xy 124.021098 -49.462728) (xy 123.980327 -49.509654) (xy 123.934142 -49.551261) (xy 123.883229 -49.58693)
			(xy 123.82835 -49.616128) (xy 123.770321 -49.638421) (xy 123.710008 -49.653475) (xy 123.64831 -49.661066)
			(xy 123.617228 -49.661572) (xy 123.585738 -49.661096) (xy 123.52324 -49.65331) (xy 123.462183 -49.637867)
			(xy 123.403499 -49.615003) (xy 123.348088 -49.585067) (xy 123.296797 -49.548519) (xy 123.250412 -49.505917)
			(xy 123.209642 -49.457913) (xy 123.175111 -49.405243) (xy 123.147349 -49.348712) (xy 123.126779 -49.289185)
			(xy 123.113717 -49.227574) (xy 123.110498 -49.196244) (xy 123.10872 -49.176178) (xy 123.10872 -49.15408)
			(xy 123.109148 -49.122717) (xy 123.116749 -49.060456) (xy 123.131942 -48.9996) (xy 123.154498 -48.941072)
			(xy 123.184076 -48.88576) (xy 123.220226 -48.834502) (xy 123.262402 -48.788074) (xy 123.309962 -48.747181)
			(xy 123.335796 -48.729392) (xy 123.345849 -48.721871) (xy 123.357689 -48.699764) (xy 123.358402 -48.687228)
			(xy 123.358402 -48.6029) (xy 123.356878 -48.5902) (xy 123.354183 -48.581186) (xy 123.343226 -48.56591)
			(xy 123.335542 -48.560482) (xy 123.3043 -48.537876) (xy 123.295173 -48.530678) (xy 123.277514 -48.515557)
			(xy 123.268994 -48.50765) (xy 123.250706 -48.506888) (xy 123.250198 -48.506888) (xy 123.221242 -48.505618)
			(xy 123.211336 -48.506126) (xy 123.205152 -48.507233) (xy 123.193586 -48.512123) (xy 123.188476 -48.515778)
			(xy 123.162077 -48.534751) (xy 123.105377 -48.566556) (xy 123.045086 -48.590875) (xy 122.982187 -48.607312)
			(xy 122.917706 -48.615598) (xy 122.8852 -48.616108) (xy 122.8852 -48.616362) (xy 122.850719 -48.615749)
			(xy 122.782398 -48.60636) (xy 122.71597 -48.587835) (xy 122.652649 -48.560514) (xy 122.622818 -48.54321)
			(xy 122.609864 -48.53559) (xy 122.579892 -48.536352) (xy 122.491754 -48.59782) (xy 122.483967 -48.603733)
			(xy 122.47321 -48.62004) (xy 122.469333 -48.639188) (xy 122.470672 -48.648874) (xy 122.474696 -48.671905)
			(xy 122.479021 -48.71846) (xy 122.479308 -48.741838) (xy 122.479308 -48.7426) (xy 122.478844 -48.773331)
			(xy 122.471435 -48.834345) (xy 122.456727 -48.894021) (xy 122.434932 -48.951489) (xy 122.406369 -49.005911)
			(xy 122.371455 -49.056493) (xy 122.330698 -49.102498) (xy 122.284693 -49.143255) (xy 122.234111 -49.178169)
			(xy 122.179689 -49.206732) (xy 122.122221 -49.228527) (xy 122.062545 -49.243235) (xy 122.001531 -49.250644)
			(xy 121.9708 -49.251108) (xy 121.939438 -49.250638) (xy 121.87719 -49.242912) (xy 121.816365 -49.227591)
			(xy 121.757885 -49.204905) (xy 121.70264 -49.175201) (xy 121.651466 -49.138929) (xy 121.605141 -49.096639)
			(xy 121.564368 -49.048973) (xy 121.529766 -48.996655) (xy 121.50186 -48.940479) (xy 121.481075 -48.881298)
			(xy 121.467724 -48.820011) (xy 121.464324 -48.788828) (xy 121.462546 -48.76927) (xy 121.43359 -48.7426)
			(xy 106.08564 -48.7426) (xy 106.075575 -48.742166) (xy 106.056986 -48.734436) (xy 106.049572 -48.727614)
			(xy 104.834944 -47.512986) (xy 104.827547 -47.506139) (xy 104.808947 -47.498412) (xy 104.798876 -47.498)
			(xy 104.491282 -47.498) (xy 104.481213 -47.498427) (xy 104.462614 -47.506146) (xy 104.455214 -47.512986)
			(xy 104.099868 -47.868332) (xy 104.093019 -47.875729) (xy 104.085286 -47.894328) (xy 104.084882 -47.9044)
			(xy 104.084882 -50.704242) (xy 104.085312 -50.714309) (xy 104.093035 -50.732904) (xy 104.099868 -50.74031)
			(xy 104.362758 -51.0032) (xy 123.214892 -51.0032) (xy 123.215469 -50.9741) (xy 123.224303 -50.916575)
			(xy 123.241765 -50.861057) (xy 123.267451 -50.808833) (xy 123.300766 -50.761112) (xy 123.340938 -50.719)
			(xy 123.387036 -50.683474) (xy 123.41225 -50.668936) (xy 123.425275 -50.661193) (xy 123.446361 -50.639448)
			(xy 123.460143 -50.612476) (xy 123.465409 -50.582648) (xy 123.461696 -50.552587) (xy 123.449331 -50.524937)
			(xy 123.429401 -50.502129) (xy 123.416822 -50.493676) (xy 123.393456 -50.478705) (xy 123.350959 -50.44302)
			(xy 123.31408 -50.401554) (xy 123.283599 -50.355182) (xy 123.260158 -50.304883) (xy 123.244252 -50.251719)
			(xy 123.236216 -50.196811) (xy 123.23572 -50.169064) (xy 123.236206 -50.141813) (xy 123.243962 -50.087865)
			(xy 123.259317 -50.03557) (xy 123.281959 -49.985993) (xy 123.311425 -49.940143) (xy 123.347116 -49.898952)
			(xy 123.388307 -49.863261) (xy 123.434157 -49.833795) (xy 123.483734 -49.811153) (xy 123.536029 -49.795798)
			(xy 123.589977 -49.788042) (xy 123.644479 -49.788042) (xy 123.698427 -49.795798) (xy 123.750722 -49.811153)
			(xy 123.800299 -49.833795) (xy 123.846149 -49.863261) (xy 123.88734 -49.898952) (xy 123.923031 -49.940143)
			(xy 123.952497 -49.985993) (xy 123.975139 -50.03557) (xy 123.990494 -50.087865) (xy 123.99825 -50.141813)
			(xy 123.998736 -50.169064) (xy 125.40691 -50.169064) (xy 125.410981 -50.113442) (xy 125.423107 -50.059005)
			(xy 125.44303 -50.006914) (xy 125.470326 -49.958279) (xy 125.504412 -49.914136) (xy 125.544561 -49.875427)
			(xy 125.589919 -49.842976) (xy 125.639519 -49.817475) (xy 125.692303 -49.799468) (xy 125.747146 -49.789338)
			(xy 125.80288 -49.787301) (xy 125.858317 -49.793401) (xy 125.912274 -49.807507) (xy 125.963603 -49.829319)
			(xy 126.011209 -49.858373) (xy 126.054077 -49.894048) (xy 126.091294 -49.935585) (xy 126.122067 -49.982098)
			(xy 126.145739 -50.032595) (xy 126.161807 -50.086002) (xy 126.169927 -50.141178) (xy 126.170436 -50.169064)
			(xy 126.169927 -50.19695) (xy 126.161807 -50.252126) (xy 126.145739 -50.305533) (xy 126.122067 -50.35603)
			(xy 126.091294 -50.402543) (xy 126.054077 -50.44408) (xy 126.011209 -50.479755) (xy 125.963603 -50.508809)
			(xy 125.912274 -50.530621) (xy 125.858317 -50.544727) (xy 125.80288 -50.550827) (xy 125.747146 -50.54879)
			(xy 125.692303 -50.53866) (xy 125.639519 -50.520653) (xy 125.589919 -50.495152) (xy 125.544561 -50.462701)
			(xy 125.504412 -50.423992) (xy 125.470326 -50.379849) (xy 125.44303 -50.331214) (xy 125.423107 -50.279123)
			(xy 125.410981 -50.224686) (xy 125.40691 -50.169064) (xy 123.998736 -50.169064) (xy 123.998247 -50.198167)
			(xy 123.989402 -50.255698) (xy 123.971927 -50.31122) (xy 123.946227 -50.363446) (xy 123.912898 -50.411166)
			(xy 123.872711 -50.453274) (xy 123.826599 -50.488794) (xy 123.801378 -50.503328) (xy 123.788383 -50.511119)
			(xy 123.767294 -50.532852) (xy 123.753508 -50.559814) (xy 123.748237 -50.589634) (xy 123.751944 -50.619689)
			(xy 123.764304 -50.647334) (xy 123.78423 -50.670138) (xy 123.796806 -50.678588) (xy 123.820139 -50.693608)
			(xy 123.86264 -50.729282) (xy 123.899523 -50.770739) (xy 123.93001 -50.817102) (xy 123.953457 -50.867394)
			(xy 123.969368 -50.920552) (xy 123.977409 -50.975456) (xy 123.977908 -51.0032) (xy 123.977422 -51.030451)
			(xy 123.969666 -51.084399) (xy 123.954311 -51.136694) (xy 123.931669 -51.186271) (xy 123.902203 -51.232121)
			(xy 123.866512 -51.273312) (xy 123.825321 -51.309003) (xy 123.779471 -51.338469) (xy 123.729894 -51.361111)
			(xy 123.677599 -51.376466) (xy 123.623651 -51.384222) (xy 123.569149 -51.384222) (xy 123.515201 -51.376466)
			(xy 123.462906 -51.361111) (xy 123.413329 -51.338469) (xy 123.367479 -51.309003) (xy 123.326288 -51.273312)
			(xy 123.290597 -51.232121) (xy 123.261131 -51.186271) (xy 123.238489 -51.136694) (xy 123.223134 -51.084399)
			(xy 123.215378 -51.030451) (xy 123.214892 -51.0032) (xy 104.362758 -51.0032) (xy 104.839008 -51.47945)
			(xy 104.846404 -51.486301) (xy 104.865003 -51.49404) (xy 104.875076 -51.494436) (xy 109.418882 -51.494436)
		)
		(stroke
			(width 0)
			(type solid)
		)
		(fill yes)
		(layer "In6.Cu")
		(net "P5V_AUX")
	)
	(gr_poly
		(pts
			(arc
				(start 194.446144 -441.481972)
				(mid 194.482065 -441.467093)
				(end 194.496944 -441.431172)
			)
			(arc
				(start 194.496944 -441.17006)
				(mid 194.792217 -440.457207)
				(end 195.50507 -440.161934)
			)
			(arc
				(start 276.314916 -440.161934)
				(mid 277.027769 -440.457207)
				(end 277.323042 -441.17006)
			)
			(arc
				(start 277.323042 -441.431172)
				(mid 277.337921 -441.467093)
				(end 277.373842 -441.481972)
			)
			(arc
				(start 463.300064 -441.481972)
				(mid 464.355064 -441.044976)
				(end 464.79206 -439.989976)
			)
			(arc
				(start 464.79206 -409.528264)
				(mid 464.983018 -408.568632)
				(end 465.526628 -407.75509)
			)
			(arc
				(start 467.355174 -405.926544)
				(mid 467.678507 -405.442687)
				(end 467.792054 -404.871936)
			)
			(arc
				(start 467.792054 -363.649514)
				(mid 467.554484 -364.078202)
				(end 467.284816 -364.48746)
			)
			(arc
				(start 467.284816 -404.871936)
				(mid 467.209909 -405.248606)
				(end 466.996526 -405.567896)
			)
			(arc
				(start 465.16798 -407.396442)
				(mid 464.51433 -408.374514)
				(end 464.284568 -409.528264)
			)
			(arc
				(start 464.284568 -439.989976)
				(mid 463.996213 -440.686125)
				(end 463.300064 -440.97448)
			)
			(xy 410.911294 -440.97448) (xy 410.90342 -440.976766)
			(arc
				(start 410.902912 -440.97702)
				(mid 410.827473 -440.994504)
				(end 410.750258 -441.000388)
			)
			(arc
				(start 410.74975 -441.000388)
				(mid 410.672533 -440.994515)
				(end 410.597096 -440.97702)
			)
			(xy 410.596588 -440.976766) (xy 410.588714 -440.97448) (xy 406.911302 -440.97448) (xy 406.903428 -440.976766)
			(arc
				(start 406.90292 -440.97702)
				(mid 406.827481 -440.994504)
				(end 406.750266 -441.000388)
			)
			(arc
				(start 406.749758 -441.000388)
				(mid 406.672541 -440.994515)
				(end 406.597104 -440.97702)
			)
			(xy 406.596596 -440.976766) (xy 406.588722 -440.97448) (xy 402.91131 -440.97448) (xy 402.903436 -440.976766)
			(arc
				(start 402.902928 -440.97702)
				(mid 402.827489 -440.994504)
				(end 402.750274 -441.000388)
			)
			(arc
				(start 402.749766 -441.000388)
				(mid 402.672549 -440.994515)
				(end 402.597112 -440.97702)
			)
			(xy 402.596604 -440.976766) (xy 402.58873 -440.97448) (xy 398.911064 -440.97448)
			(arc
				(start 398.903444 -440.976766)
				(mid 398.827889 -440.994391)
				(end 398.750536 -441.000388)
			)
			(arc
				(start 398.74952 -441.000388)
				(mid 398.672163 -440.994416)
				(end 398.596612 -440.976766)
			)
			(xy 398.588992 -440.97448) (xy 393.911074 -440.97448) (xy 393.9032 -440.976766)
			(arc
				(start 393.902692 -440.97702)
				(mid 393.827253 -440.994504)
				(end 393.750038 -441.000388)
			)
			(arc
				(start 393.74953 -441.000388)
				(mid 393.672313 -440.994515)
				(end 393.596876 -440.97702)
			)
			(xy 393.596368 -440.976766) (xy 393.588494 -440.97448) (xy 389.911082 -440.97448) (xy 389.903208 -440.976766)
			(arc
				(start 389.9027 -440.97702)
				(mid 389.827261 -440.994504)
				(end 389.750046 -441.000388)
			)
			(arc
				(start 389.749538 -441.000388)
				(mid 389.672321 -440.994515)
				(end 389.596884 -440.97702)
			)
			(xy 389.596376 -440.976766) (xy 389.588502 -440.97448) (xy 385.91109 -440.97448) (xy 385.903216 -440.976766)
			(arc
				(start 385.902708 -440.97702)
				(mid 385.827269 -440.994504)
				(end 385.750054 -441.000388)
			)
			(arc
				(start 385.749546 -441.000388)
				(mid 385.672329 -440.994515)
				(end 385.596892 -440.97702)
			)
			(xy 385.596384 -440.976766) (xy 385.58851 -440.97448) (xy 381.910844 -440.97448)
			(arc
				(start 381.903224 -440.976766)
				(mid 381.827669 -440.994391)
				(end 381.750316 -441.000388)
			)
			(arc
				(start 381.7493 -441.000388)
				(mid 381.671943 -440.994416)
				(end 381.596392 -440.976766)
			)
			(xy 381.588772 -440.97448) (xy 343.811098 -440.97448) (xy 343.803224 -440.976766)
			(arc
				(start 343.802716 -440.97702)
				(mid 343.727277 -440.994504)
				(end 343.650062 -441.000388)
			)
			(arc
				(start 343.649554 -441.000388)
				(mid 343.572337 -440.994515)
				(end 343.4969 -440.97702)
			)
			(xy 343.496392 -440.976766) (xy 343.488518 -440.97448) (xy 339.811106 -440.97448) (xy 339.803232 -440.976766)
			(arc
				(start 339.802724 -440.97702)
				(mid 339.727285 -440.994504)
				(end 339.65007 -441.000388)
			)
			(arc
				(start 339.649562 -441.000388)
				(mid 339.572345 -440.994515)
				(end 339.496908 -440.97702)
			)
			(xy 339.4964 -440.976766) (xy 339.488526 -440.97448) (xy 335.811114 -440.97448) (xy 335.80324 -440.976766)
			(arc
				(start 335.802732 -440.97702)
				(mid 335.727293 -440.994504)
				(end 335.650078 -441.000388)
			)
			(arc
				(start 335.64957 -441.000388)
				(mid 335.572353 -440.994515)
				(end 335.496916 -440.97702)
			)
			(xy 335.496408 -440.976766) (xy 335.488534 -440.97448) (xy 331.810868 -440.97448)
			(arc
				(start 331.803248 -440.976766)
				(mid 331.727693 -440.994391)
				(end 331.65034 -441.000388)
			)
			(arc
				(start 331.649324 -441.000388)
				(mid 331.571967 -440.994416)
				(end 331.496416 -440.976766)
			)
			(xy 331.488796 -440.97448) (xy 326.811132 -440.97448) (xy 326.803258 -440.976766)
			(arc
				(start 326.80275 -440.97702)
				(mid 326.727311 -440.994504)
				(end 326.650096 -441.000388)
			)
			(arc
				(start 326.649588 -441.000388)
				(mid 326.572371 -440.994515)
				(end 326.496934 -440.97702)
			)
			(xy 326.496426 -440.976766) (xy 326.488552 -440.97448) (xy 322.81114 -440.97448) (xy 322.803266 -440.976766)
			(arc
				(start 322.802758 -440.97702)
				(mid 322.727319 -440.994504)
				(end 322.650104 -441.000388)
			)
			(arc
				(start 322.649596 -441.000388)
				(mid 322.572379 -440.994515)
				(end 322.496942 -440.97702)
			)
			(xy 322.496434 -440.976766) (xy 322.48856 -440.97448) (xy 318.811148 -440.97448) (xy 318.803274 -440.976766)
			(arc
				(start 318.802766 -440.97702)
				(mid 318.727327 -440.994504)
				(end 318.650112 -441.000388)
			)
			(arc
				(start 318.649604 -441.000388)
				(mid 318.572387 -440.994515)
				(end 318.49695 -440.97702)
			)
			(xy 318.496442 -440.976766) (xy 318.488568 -440.97448) (xy 314.810902 -440.97448)
			(arc
				(start 314.803282 -440.976766)
				(mid 314.727727 -440.994391)
				(end 314.650374 -441.000388)
			)
			(arc
				(start 314.649358 -441.000388)
				(mid 314.572001 -440.994416)
				(end 314.49645 -440.976766)
			)
			(xy 314.48883 -440.97448)
			(arc
				(start 277.817834 -440.97448)
				(mid 277.314992 -440.031472)
				(end 276.314916 -439.654696)
			)
			(arc
				(start 195.50507 -439.654696)
				(mid 194.504998 -440.031475)
				(end 194.002152 -440.97448)
			)
			(xy 154.911298 -440.97448) (xy 154.903424 -440.976766)
			(arc
				(start 154.902916 -440.97702)
				(mid 154.827477 -440.994504)
				(end 154.750262 -441.000388)
			)
			(arc
				(start 154.749754 -441.000388)
				(mid 154.672537 -440.994515)
				(end 154.5971 -440.97702)
			)
			(xy 154.596592 -440.976766) (xy 154.588718 -440.97448) (xy 150.911306 -440.97448) (xy 150.903432 -440.976766)
			(arc
				(start 150.902924 -440.97702)
				(mid 150.827485 -440.994504)
				(end 150.75027 -441.000388)
			)
			(arc
				(start 150.749762 -441.000388)
				(mid 150.672545 -440.994515)
				(end 150.597108 -440.97702)
			)
			(xy 150.5966 -440.976766) (xy 150.588726 -440.97448) (xy 146.911314 -440.97448) (xy 146.90344 -440.976766)
			(arc
				(start 146.902932 -440.97702)
				(mid 146.827493 -440.994504)
				(end 146.750278 -441.000388)
			)
			(arc
				(start 146.74977 -441.000388)
				(mid 146.672553 -440.994515)
				(end 146.597116 -440.97702)
			)
			(xy 146.596608 -440.976766) (xy 146.588734 -440.97448) (xy 142.911068 -440.97448)
			(arc
				(start 142.903448 -440.976766)
				(mid 142.827893 -440.994391)
				(end 142.75054 -441.000388)
			)
			(arc
				(start 142.749524 -441.000388)
				(mid 142.672167 -440.994416)
				(end 142.596616 -440.976766)
			)
			(xy 142.588996 -440.97448) (xy 137.911078 -440.97448) (xy 137.903204 -440.976766)
			(arc
				(start 137.902696 -440.97702)
				(mid 137.827257 -440.994504)
				(end 137.750042 -441.000388)
			)
			(arc
				(start 137.749534 -441.000388)
				(mid 137.672317 -440.994515)
				(end 137.59688 -440.97702)
			)
			(xy 137.596372 -440.976766) (xy 137.588498 -440.97448) (xy 133.911086 -440.97448) (xy 133.903212 -440.976766)
			(arc
				(start 133.902704 -440.97702)
				(mid 133.827265 -440.994504)
				(end 133.75005 -441.000388)
			)
			(arc
				(start 133.749542 -441.000388)
				(mid 133.672325 -440.994515)
				(end 133.596888 -440.97702)
			)
			(xy 133.59638 -440.976766) (xy 133.588506 -440.97448) (xy 129.911094 -440.97448) (xy 129.90322 -440.976766)
			(arc
				(start 129.902712 -440.97702)
				(mid 129.827273 -440.994504)
				(end 129.750058 -441.000388)
			)
			(arc
				(start 129.74955 -441.000388)
				(mid 129.672333 -440.994515)
				(end 129.596896 -440.97702)
			)
			(xy 129.596388 -440.976766) (xy 129.588514 -440.97448) (xy 125.910848 -440.97448)
			(arc
				(start 125.903228 -440.976766)
				(mid 125.827673 -440.994391)
				(end 125.75032 -441.000388)
			)
			(arc
				(start 125.749304 -441.000388)
				(mid 125.671947 -440.994416)
				(end 125.596396 -440.976766)
			)
			(xy 125.588776 -440.97448) (xy 87.811356 -440.97448) (xy 87.803482 -440.976766)
			(arc
				(start 87.802974 -440.97702)
				(mid 87.727535 -440.994504)
				(end 87.65032 -441.000388)
			)
			(arc
				(start 87.649812 -441.000388)
				(mid 87.572595 -440.994515)
				(end 87.497158 -440.97702)
			)
			(xy 87.49665 -440.976766) (xy 87.488776 -440.97448) (xy 83.811364 -440.97448) (xy 83.80349 -440.976766)
			(arc
				(start 83.802982 -440.97702)
				(mid 83.727543 -440.994504)
				(end 83.650328 -441.000388)
			)
			(arc
				(start 83.64982 -441.000388)
				(mid 83.572603 -440.994515)
				(end 83.497166 -440.97702)
			)
			(xy 83.496658 -440.976766) (xy 83.488784 -440.97448) (xy 79.811372 -440.97448) (xy 79.803498 -440.976766)
			(arc
				(start 79.80299 -440.97702)
				(mid 79.727551 -440.994504)
				(end 79.650336 -441.000388)
			)
			(arc
				(start 79.649828 -441.000388)
				(mid 79.572611 -440.994515)
				(end 79.497174 -440.97702)
			)
			(xy 79.496666 -440.976766) (xy 79.488792 -440.97448) (xy 75.811126 -440.97448)
			(arc
				(start 75.803506 -440.976766)
				(mid 75.727951 -440.994391)
				(end 75.650598 -441.000388)
			)
			(arc
				(start 75.649582 -441.000388)
				(mid 75.572225 -440.994416)
				(end 75.496674 -440.976766)
			)
			(xy 75.489054 -440.97448) (xy 70.811136 -440.97448) (xy 70.803262 -440.976766)
			(arc
				(start 70.802754 -440.97702)
				(mid 70.727315 -440.994504)
				(end 70.6501 -441.000388)
			)
			(arc
				(start 70.649592 -441.000388)
				(mid 70.572375 -440.994515)
				(end 70.496938 -440.97702)
			)
			(xy 70.49643 -440.976766) (xy 70.488556 -440.97448) (xy 66.811144 -440.97448) (xy 66.80327 -440.976766)
			(arc
				(start 66.802762 -440.97702)
				(mid 66.727323 -440.994504)
				(end 66.650108 -441.000388)
			)
			(arc
				(start 66.6496 -441.000388)
				(mid 66.572383 -440.994515)
				(end 66.496946 -440.97702)
			)
			(xy 66.496438 -440.976766) (xy 66.488564 -440.97448) (xy 62.811152 -440.97448) (xy 62.803278 -440.976766)
			(arc
				(start 62.80277 -440.97702)
				(mid 62.727331 -440.994504)
				(end 62.650116 -441.000388)
			)
			(arc
				(start 62.649608 -441.000388)
				(mid 62.572391 -440.994515)
				(end 62.496954 -440.97702)
			)
			(xy 62.496446 -440.976766) (xy 62.488572 -440.97448) (xy 58.810906 -440.97448)
			(arc
				(start 58.803286 -440.976766)
				(mid 58.727731 -440.994391)
				(end 58.650378 -441.000388)
			)
			(arc
				(start 58.649362 -441.000388)
				(mid 58.572005 -440.994416)
				(end 58.496454 -440.976766)
			)
			(xy 58.488834 -440.97448)
			(arc
				(start 8.50011 -440.97448)
				(mid 7.803871 -440.686141)
				(end 7.515352 -439.989976)
			)
			(arc
				(start 7.515352 -409.528518)
				(mid 7.285694 -408.374511)
				(end 6.63194 -407.396188)
			)
			(arc
				(start 3.303778 -404.068026)
				(mid 3.090447 -403.748703)
				(end 3.015488 -403.372066)
			)
			(xy 3.015488 -356.949756) (xy 3.015488 -356.948486) (xy 3.015488 -356.947216)
			(arc
				(start 2.710942 -350.750886)
				(mid 2.607182 -350.654521)
				(end 2.507996 -350.755712)
			)
			(arc
				(start 2.507996 -403.371812)
				(mid 2.621533 -403.942691)
				(end 2.944876 -404.426674)
			)
			(arc
				(start 6.273292 -407.75509)
				(mid 6.817042 -408.568731)
				(end 7.008114 -409.528518)
			)
			(arc
				(start 7.008114 -439.989976)
				(mid 7.44511 -441.044976)
				(end 8.50011 -441.481972)
			)
		)
		(stroke
			(width 0)
			(type solid)
		)
		(fill yes)
		(layer "In6.Cu")
		(net "GND")
	)
	(gr_poly
		(pts
			(xy 243.95176 -53.983636) (xy 243.961635 -53.983169) (xy 243.979926 -53.975719) (xy 243.98732 -53.969158)
			(xy 243.987574 -53.968904) (xy 244.131592 -53.824886) (xy 244.138986 -53.818029) (xy 244.157585 -53.810278)
			(xy 244.16766 -53.8099) (xy 251.506228 -53.8099) (xy 251.516104 -53.809438) (xy 251.5344 -53.801992)
			(xy 251.541788 -53.795422) (xy 251.542042 -53.795168) (xy 252.178058 -53.159152) (xy 252.178566 -53.158644)
			(xy 252.185146 -53.151262) (xy 252.192594 -53.132963) (xy 252.193044 -53.123084) (xy 252.193044 -49.894744)
			(xy 252.192609 -49.88468) (xy 252.184874 -49.866095) (xy 252.178058 -49.858676) (xy 251.136912 -48.81753)
			(xy 251.1298 -48.810164) (xy 251.111004 -48.802544) (xy 246.049038 -48.802544) (xy 246.038974 -48.802108)
			(xy 246.020391 -48.794372) (xy 246.01297 -48.787558) (xy 241.956336 -44.730924) (xy 241.948854 -44.724121)
			(xy 241.930132 -44.716519) (xy 241.909927 -44.716708) (xy 241.900456 -44.720256) (xy 241.799364 -44.76369)
			(xy 241.7826 -44.790106) (xy 241.783108 -44.8056) (xy 241.783362 -44.830746) (xy 241.782885 -44.871846)
			(xy 241.775297 -44.953696) (xy 241.760188 -45.034496) (xy 241.737689 -45.113558) (xy 241.70799 -45.190206)
			(xy 241.671346 -45.263788) (xy 241.62807 -45.333674) (xy 241.578529 -45.399269) (xy 241.523148 -45.460013)
			(xy 241.462398 -45.515388) (xy 241.396798 -45.564922) (xy 241.326907 -45.608191) (xy 241.253322 -45.644827)
			(xy 241.176671 -45.674518) (xy 241.097607 -45.697009) (xy 241.016805 -45.712109) (xy 240.934954 -45.71969)
			(xy 240.893854 -45.720254) (xy 240.872484 -45.720141) (xy 240.829793 -45.718111) (xy 240.80851 -45.71619)
			(xy 240.79454 -45.71492) (xy 240.769902 -45.72635) (xy 240.703354 -45.822108) (xy 240.701322 -45.849286)
			(xy 240.707418 -45.861732) (xy 240.724723 -45.898235) (xy 240.753427 -45.973755) (xy 240.775169 -46.051565)
			(xy 240.789771 -46.131025) (xy 240.797112 -46.211481) (xy 240.797588 -46.251876) (xy 240.797084 -46.294224)
			(xy 240.789033 -46.378538) (xy 240.773004 -46.461704) (xy 240.749143 -46.542971) (xy 240.717664 -46.621601)
			(xy 240.678853 -46.696882) (xy 240.633063 -46.768134) (xy 240.580707 -46.83471) (xy 240.522259 -46.896008)
			(xy 240.458249 -46.951473) (xy 240.389257 -47.000602) (xy 240.315907 -47.042951) (xy 240.238864 -47.078135)
			(xy 240.158825 -47.105837) (xy 240.076516 -47.125805) (xy 239.992681 -47.137858) (xy 239.90808 -47.141889)
			(xy 239.823479 -47.137858) (xy 239.739644 -47.125805) (xy 239.657335 -47.105837) (xy 239.577296 -47.078135)
			(xy 239.500253 -47.042951) (xy 239.426903 -47.000602) (xy 239.357911 -46.951473) (xy 239.293901 -46.896008)
			(xy 239.235453 -46.83471) (xy 239.183097 -46.768134) (xy 239.137307 -46.696882) (xy 239.098496 -46.621601)
			(xy 239.067017 -46.542971) (xy 239.043156 -46.461704) (xy 239.027127 -46.378538) (xy 239.019076 -46.294224)
			(xy 239.018572 -46.251876) (xy 239.019097 -46.208743) (xy 239.027478 -46.122883) (xy 239.044129 -46.038238)
			(xy 239.068895 -45.955603) (xy 239.101543 -45.875752) (xy 239.121188 -45.837348) (xy 239.127792 -45.824902)
			(xy 239.126268 -45.797216) (xy 239.06099 -45.699426) (xy 239.036352 -45.687488) (xy 239.022128 -45.688758)
			(xy 239.002421 -45.690415) (xy 238.96291 -45.692192) (xy 238.943134 -45.692314) (xy 238.903868 -45.691885)
			(xy 238.825641 -45.684965) (xy 238.748328 -45.671177) (xy 238.672531 -45.650628) (xy 238.63554 -45.63745)
			(xy 238.626991 -45.634686) (xy 238.609037 -45.634686) (xy 238.600488 -45.63745) (xy 238.563494 -45.650618)
			(xy 238.487697 -45.671163) (xy 238.410386 -45.684949) (xy 238.33216 -45.691868) (xy 238.292894 -45.692314)
			(xy 238.24936 -45.691785) (xy 238.16271 -45.683275) (xy 238.077305 -45.666338) (xy 237.993965 -45.641136)
			(xy 237.913487 -45.60791) (xy 237.87481 -45.58792) (xy 237.866575 -45.583964) (xy 237.848473 -45.581616)
			(xy 237.839504 -45.583348) (xy 237.79034 -45.593945) (xy 237.690403 -45.605275) (xy 237.640114 -45.605954)
			(xy 237.59901 -45.60548) (xy 237.517154 -45.597896) (xy 237.436346 -45.582792) (xy 237.357276 -45.560297)
			(xy 237.280619 -45.530602) (xy 237.207029 -45.493961) (xy 237.137134 -45.450687) (xy 237.071529 -45.401148)
			(xy 237.010776 -45.345767) (xy 236.955391 -45.285017) (xy 236.905847 -45.219416) (xy 236.862568 -45.149523)
			(xy 236.825922 -45.075936) (xy 236.796222 -44.999281) (xy 236.773721 -44.920213) (xy 236.758612 -44.839406)
			(xy 236.751023 -44.75755) (xy 236.750606 -44.716446) (xy 236.751045 -44.676233) (xy 236.758286 -44.596135)
			(xy 236.77272 -44.517016) (xy 236.794231 -44.439521) (xy 236.80801 -44.40174) (xy 236.81104 -44.392624)
			(xy 236.810783 -44.37343) (xy 236.807502 -44.364402) (xy 236.793323 -44.328877) (xy 236.770384 -44.255903)
			(xy 236.753787 -44.18123) (xy 236.743656 -44.105409) (xy 236.741462 -44.067222) (xy 236.740446 -44.046648)
			(xy 236.711236 -44.018708) (xy 235.782104 -44.018708) (xy 235.772136 -44.019182) (xy 235.753695 -44.026752)
			(xy 235.74629 -44.03344) (xy 234.986322 -44.793408) (xy 234.978956 -44.80052) (xy 234.971336 -44.819316)
			(xy 234.971336 -45.615606) (xy 234.971761 -45.625675) (xy 234.979481 -45.644275) (xy 234.986322 -45.651674)
			(xy 235.15193 -45.817282) (xy 235.158771 -45.824682) (xy 235.166487 -45.843281) (xy 235.166916 -45.85335)
			(xy 235.166916 -46.998128) (xy 235.166488 -47.008196) (xy 235.158769 -47.026795) (xy 235.15193 -47.034196)
			(xy 234.986322 -47.199804) (xy 234.979474 -47.207202) (xy 234.971737 -47.2258) (xy 234.971336 -47.235872)
			(xy 234.971336 -48.104044) (xy 235.110018 -48.104044) (xy 235.114089 -48.048422) (xy 235.126215 -47.993985)
			(xy 235.146138 -47.941894) (xy 235.173434 -47.893259) (xy 235.20752 -47.849116) (xy 235.247669 -47.810407)
			(xy 235.293027 -47.777956) (xy 235.342627 -47.752455) (xy 235.395411 -47.734448) (xy 235.450254 -47.724318)
			(xy 235.505988 -47.722281) (xy 235.561425 -47.728381) (xy 235.615382 -47.742487) (xy 235.666711 -47.764299)
			(xy 235.714317 -47.793353) (xy 235.757185 -47.829028) (xy 235.794402 -47.870565) (xy 235.825175 -47.917078)
			(xy 235.848847 -47.967575) (xy 235.864915 -48.020982) (xy 235.873035 -48.076158) (xy 235.873544 -48.104044)
			(xy 235.873035 -48.13193) (xy 235.864915 -48.187106) (xy 235.848847 -48.240513) (xy 235.825175 -48.29101)
			(xy 235.794402 -48.337523) (xy 235.757185 -48.37906) (xy 235.714317 -48.414735) (xy 235.666711 -48.443789)
			(xy 235.615382 -48.465601) (xy 235.561425 -48.479707) (xy 235.505988 -48.485807) (xy 235.450254 -48.48377)
			(xy 235.395411 -48.47364) (xy 235.342627 -48.455633) (xy 235.293027 -48.430132) (xy 235.247669 -48.397681)
			(xy 235.20752 -48.358972) (xy 235.173434 -48.314829) (xy 235.146138 -48.266194) (xy 235.126215 -48.214103)
			(xy 235.114089 -48.159666) (xy 235.110018 -48.104044) (xy 234.971336 -48.104044) (xy 234.971336 -48.344328)
			(xy 234.97155 -48.350908) (xy 234.974899 -48.363635) (xy 234.97794 -48.369474) (xy 234.992672 -48.395382)
			(xy 235.001562 -48.404526) (xy 235.006896 -48.407828) (xy 235.0409 -48.429298) (xy 235.105289 -48.477488)
			(xy 235.165064 -48.531295) (xy 235.219734 -48.590281) (xy 235.242986 -48.620426) (xy 236.796326 -48.620426)
			(xy 236.796813 -48.578224) (xy 236.804797 -48.494199) (xy 236.820707 -48.411308) (xy 236.844398 -48.330298)
			(xy 236.875657 -48.251896) (xy 236.914204 -48.176809) (xy 236.959691 -48.105711) (xy 237.01171 -48.039243)
			(xy 237.069791 -47.978001) (xy 237.133414 -47.922539) (xy 237.16742 -47.897542) (xy 237.175256 -47.891296)
			(xy 237.185846 -47.874309) (xy 237.187994 -47.864522) (xy 237.195895 -47.819937) (xy 237.219564 -47.732532)
			(xy 237.251985 -47.647983) (xy 237.292826 -47.567164) (xy 237.316772 -47.528734) (xy 237.321444 -47.520669)
			(xy 237.325219 -47.502432) (xy 237.324138 -47.493174) (xy 237.319312 -47.46371) (xy 237.317423 -47.454553)
			(xy 237.308034 -47.438402) (xy 237.301024 -47.432214) (xy 237.267023 -47.404126) (xy 237.204173 -47.342247)
			(xy 237.147757 -47.274452) (xy 237.098329 -47.201404) (xy 237.056374 -47.123824) (xy 237.022305 -47.042471)
			(xy 236.996455 -46.958145) (xy 236.97908 -46.871675) (xy 236.970348 -46.783909) (xy 236.969808 -46.73981)
			(xy 236.970312 -46.697462) (xy 236.978363 -46.613148) (xy 236.994392 -46.529982) (xy 237.018253 -46.448715)
			(xy 237.049732 -46.370085) (xy 237.088543 -46.294804) (xy 237.134333 -46.223552) (xy 237.186689 -46.156976)
			(xy 237.245137 -46.095678) (xy 237.309147 -46.040213) (xy 237.378139 -45.991084) (xy 237.451489 -45.948735)
			(xy 237.528532 -45.913551) (xy 237.608571 -45.885849) (xy 237.69088 -45.865881) (xy 237.774715 -45.853828)
			(xy 237.859316 -45.849798) (xy 237.943917 -45.853828) (xy 238.027752 -45.865881) (xy 238.110061 -45.885849)
			(xy 238.1901 -45.913551) (xy 238.267143 -45.948735) (xy 238.340493 -45.991084) (xy 238.409485 -46.040213)
			(xy 238.473495 -46.095678) (xy 238.531943 -46.156976) (xy 238.584299 -46.223552) (xy 238.630089 -46.294804)
			(xy 238.6689 -46.370085) (xy 238.700379 -46.448715) (xy 238.72424 -46.529982) (xy 238.740269 -46.613148)
			(xy 238.74832 -46.697462) (xy 238.748824 -46.73981) (xy 238.748314 -46.782048) (xy 238.740307 -46.866144)
			(xy 238.724365 -46.949103) (xy 238.700633 -47.030177) (xy 238.669324 -47.108637) (xy 238.630719 -47.183776)
			(xy 238.608362 -47.219616) (xy 238.603715 -47.227694) (xy 238.599924 -47.24592) (xy 238.600996 -47.255176)
			(xy 238.605822 -47.28464) (xy 238.607752 -47.293785) (xy 238.617114 -47.309941) (xy 238.62411 -47.316136)
			(xy 238.655269 -47.341806) (xy 238.71328 -47.39796) (xy 238.76596 -47.459143) (xy 238.812876 -47.524851)
			(xy 238.853639 -47.594542) (xy 238.887915 -47.667643) (xy 238.915421 -47.743551) (xy 238.926116 -47.78248)
			(xy 238.929446 -47.793128) (xy 238.943696 -47.810262) (xy 238.953548 -47.8155) (xy 238.992058 -47.834214)
			(xy 239.065657 -47.877976) (xy 239.134714 -47.928602) (xy 239.198591 -47.985624) (xy 239.256699 -48.048516)
			(xy 239.3085 -48.116696) (xy 239.353515 -48.189534) (xy 239.39133 -48.266358) (xy 239.406938 -48.306228)
			(xy 239.411002 -48.31715) (xy 239.42802 -48.333152) (xy 239.526572 -48.36414) (xy 239.549686 -48.360838)
			(xy 239.559338 -48.354234) (xy 239.596304 -48.329676) (xy 239.674229 -48.287196) (xy 239.756 -48.252695)
			(xy 239.840803 -48.226515) (xy 239.927793 -48.208919) (xy 240.016104 -48.200081) (xy 240.06048 -48.199548)
			(xy 240.102828 -48.200123) (xy 240.18714 -48.208172) (xy 240.270305 -48.224199) (xy 240.35157 -48.248059)
			(xy 240.430199 -48.279536) (xy 240.50548 -48.318345) (xy 240.576731 -48.364133) (xy 240.643307 -48.416488)
			(xy 240.704605 -48.474934) (xy 240.760069 -48.538942) (xy 240.809198 -48.607932) (xy 240.851547 -48.68128)
			(xy 240.886731 -48.758322) (xy 240.914432 -48.838359) (xy 240.9344 -48.920667) (xy 240.946454 -49.0045)
			(xy 240.950484 -49.0891) (xy 240.946454 -49.1737) (xy 240.9344 -49.257533) (xy 240.914432 -49.339841)
			(xy 240.886731 -49.419878) (xy 240.851547 -49.49692) (xy 240.809198 -49.570268) (xy 240.760069 -49.639258)
			(xy 240.704605 -49.703266) (xy 240.643307 -49.761712) (xy 240.576731 -49.814067) (xy 240.50548 -49.859855)
			(xy 240.430199 -49.898664) (xy 240.35157 -49.930141) (xy 240.270305 -49.954001) (xy 240.18714 -49.970028)
			(xy 240.102828 -49.978077) (xy 240.06048 -49.978564) (xy 240.019088 -49.978036) (xy 239.936663 -49.970334)
			(xy 239.85531 -49.955008) (xy 239.775732 -49.932189) (xy 239.698619 -49.902077) (xy 239.624637 -49.86493)
			(xy 239.554426 -49.821071) (xy 239.488593 -49.770878) (xy 239.427708 -49.714787) (xy 239.372298 -49.653282)
			(xy 239.322841 -49.586894) (xy 239.279766 -49.516199) (xy 239.243445 -49.441809) (xy 239.228376 -49.403254)
			(xy 239.224312 -49.392332) (xy 239.207294 -49.37633) (xy 239.108742 -49.345342) (xy 239.085628 -49.348644)
			(xy 239.075976 -49.355248) (xy 239.039005 -49.379797) (xy 238.961081 -49.422279) (xy 238.879311 -49.456782)
			(xy 238.794509 -49.482963) (xy 238.70752 -49.500561) (xy 238.61921 -49.5094) (xy 238.574834 -49.509934)
			(xy 238.53104 -49.509399) (xy 238.443879 -49.500763) (xy 238.357986 -49.483611) (xy 238.274193 -49.458109)
			(xy 238.193308 -49.424502) (xy 238.154464 -49.40427) (xy 238.142998 -49.398852) (xy 238.11767 -49.398852)
			(xy 238.106204 -49.40427) (xy 238.082491 -49.416782) (xy 238.033819 -49.439279) (xy 238.008922 -49.449228)
			(xy 237.998762 -49.453038) (xy 237.983776 -49.468278) (xy 237.949232 -49.55921) (xy 237.950502 -49.580546)
			(xy 237.955328 -49.590452) (xy 237.968686 -49.617579) (xy 237.987576 -49.675017) (xy 237.997154 -49.734718)
			(xy 237.997746 -49.76495) (xy 237.99726 -49.792201) (xy 237.989504 -49.846149) (xy 237.974149 -49.898444)
			(xy 237.951507 -49.948021) (xy 237.922041 -49.993871) (xy 237.88635 -50.035062) (xy 237.845159 -50.070753)
			(xy 237.799309 -50.100219) (xy 237.749732 -50.122861) (xy 237.697437 -50.138216) (xy 237.643489 -50.145972)
			(xy 237.588987 -50.145972) (xy 237.535039 -50.138216) (xy 237.482744 -50.122861) (xy 237.433167 -50.100219)
			(xy 237.387317 -50.070753) (xy 237.346126 -50.035062) (xy 237.310435 -49.993871) (xy 237.280969 -49.948021)
			(xy 237.258327 -49.898444) (xy 237.242972 -49.846149) (xy 237.235216 -49.792201) (xy 237.23473 -49.76495)
			(xy 237.235236 -49.736474) (xy 237.243721 -49.680158) (xy 237.260494 -49.625733) (xy 237.285182 -49.57441)
			(xy 237.30077 -49.550574) (xy 237.306866 -49.54143) (xy 237.310676 -49.520602) (xy 237.287562 -49.426114)
			(xy 237.274354 -49.409096) (xy 237.264702 -49.404016) (xy 237.226556 -49.38293) (xy 237.154186 -49.334346)
			(xy 237.086914 -49.278917) (xy 237.025387 -49.217173) (xy 236.970194 -49.149708) (xy 236.921864 -49.077168)
			(xy 236.880861 -49.000248) (xy 236.847578 -48.919687) (xy 236.822334 -48.836257) (xy 236.805372 -48.750757)
			(xy 236.796853 -48.664009) (xy 236.796326 -48.620426) (xy 235.242986 -48.620426) (xy 235.268854 -48.653963)
			(xy 235.312022 -48.721822) (xy 235.348885 -48.793301) (xy 235.379142 -48.867818) (xy 235.402545 -48.944762)
			(xy 235.418904 -49.023506) (xy 235.423964 -49.063402) (xy 235.42498 -49.07407) (xy 235.445808 -49.10963)
			(xy 235.454444 -49.11598) (xy 235.487944 -49.141034) (xy 235.55058 -49.196494) (xy 235.607733 -49.257588)
			(xy 235.658898 -49.323779) (xy 235.703623 -49.39448) (xy 235.741514 -49.469068) (xy 235.772235 -49.546883)
			(xy 235.795515 -49.627239) (xy 235.811149 -49.709425) (xy 235.818999 -49.792716) (xy 235.819442 -49.834546)
			(xy 235.818977 -49.875491) (xy 235.811455 -49.957033) (xy 235.796469 -50.037539) (xy 235.774146 -50.116327)
			(xy 235.744675 -50.192729) (xy 235.708306 -50.266099) (xy 235.665347 -50.335815) (xy 235.616162 -50.401287)
			(xy 235.561166 -50.461961) (xy 235.500826 -50.517322) (xy 235.435653 -50.566903) (xy 235.366198 -50.610283)
			(xy 235.293049 -50.647095) (xy 235.216827 -50.677027) (xy 235.138176 -50.699826) (xy 235.057762 -50.715298)
			(xy 235.017056 -50.719736) (xy 235.007773 -50.721088) (xy 234.991038 -50.72953) (xy 234.978457 -50.743423)
			(xy 234.971712 -50.760911) (xy 234.971336 -50.770282) (xy 234.971336 -51.181762) (xy 234.971729 -51.191285)
			(xy 234.978639 -51.209034) (xy 234.984798 -51.216306) (xy 235.03128 -51.266852) (xy 235.034532 -51.270306)
			(xy 235.042079 -51.276052) (xy 235.046266 -51.278282) (xy 235.055156 -51.2826) (xy 235.083862 -51.284909)
			(xy 235.140151 -51.297078) (xy 235.193971 -51.317568) (xy 235.244101 -51.345913) (xy 235.289401 -51.381471)
			(xy 235.328843 -51.423433) (xy 235.36153 -51.470846) (xy 235.386721 -51.522633) (xy 235.399928 -51.565048)
			(xy 237.23422 -51.565048) (xy 237.238291 -51.509426) (xy 237.250417 -51.454989) (xy 237.27034 -51.402898)
			(xy 237.297636 -51.354263) (xy 237.331722 -51.31012) (xy 237.371871 -51.271411) (xy 237.417229 -51.23896)
			(xy 237.466829 -51.213459) (xy 237.519613 -51.195452) (xy 237.574456 -51.185322) (xy 237.63019 -51.183285)
			(xy 237.685627 -51.189385) (xy 237.739584 -51.203491) (xy 237.790913 -51.225303) (xy 237.838519 -51.254357)
			(xy 237.881387 -51.290032) (xy 237.918604 -51.331569) (xy 237.949377 -51.378082) (xy 237.973049 -51.428579)
			(xy 237.989117 -51.481986) (xy 237.997237 -51.537162) (xy 237.997746 -51.565048) (xy 237.997237 -51.592934)
			(xy 237.989117 -51.64811) (xy 237.973049 -51.701517) (xy 237.949377 -51.752014) (xy 237.918604 -51.798527)
			(xy 237.881387 -51.840064) (xy 237.838519 -51.875739) (xy 237.790913 -51.904793) (xy 237.739584 -51.926605)
			(xy 237.685627 -51.940711) (xy 237.63019 -51.946811) (xy 237.574456 -51.944774) (xy 237.519613 -51.934644)
			(xy 237.466829 -51.916637) (xy 237.417229 -51.891136) (xy 237.371871 -51.858685) (xy 237.331722 -51.819976)
			(xy 237.297636 -51.775833) (xy 237.27034 -51.727198) (xy 237.250417 -51.675107) (xy 237.238291 -51.62067)
			(xy 237.23422 -51.565048) (xy 235.399928 -51.565048) (xy 235.403842 -51.577618) (xy 235.412505 -51.634552)
			(xy 235.413042 -51.663346) (xy 235.412528 -51.691678) (xy 235.404149 -51.74772) (xy 235.387567 -51.801904)
			(xy 235.363147 -51.853037) (xy 235.331428 -51.899993) (xy 235.293109 -51.941736) (xy 235.249033 -51.977348)
			(xy 235.200171 -52.006043) (xy 235.1476 -52.027191) (xy 235.092479 -52.040324) (xy 235.0643 -52.04333)
			(xy 235.059615 -52.043865) (xy 235.05054 -52.04642) (xy 235.046266 -52.04841) (xy 235.03763 -52.052728)
			(xy 234.984798 -52.110386) (xy 234.978606 -52.117642) (xy 234.974192 -52.128947) (xy 243.816428 -52.128947)
			(xy 243.816428 -52.074453) (xy 243.824183 -52.020515) (xy 243.839535 -51.968229) (xy 243.862172 -51.918659)
			(xy 243.891632 -51.872816) (xy 243.927316 -51.831632) (xy 243.968498 -51.795945) (xy 244.01434 -51.766482)
			(xy 244.063908 -51.743843) (xy 244.116193 -51.728488) (xy 244.170131 -51.72073) (xy 244.197378 -51.720242)
			(xy 244.223757 -51.720681) (xy 244.276014 -51.727943) (xy 244.326772 -51.742331) (xy 244.375066 -51.763572)
			(xy 244.419975 -51.79126) (xy 244.460644 -51.824869) (xy 244.496297 -51.863757) (xy 244.526255 -51.907184)
			(xy 244.5385 -51.930554) (xy 244.545202 -51.942913) (xy 244.564177 -51.963641) (xy 244.588091 -51.978403)
			(xy 244.615127 -51.986075) (xy 244.643229 -51.986075) (xy 244.670265 -51.978403) (xy 244.694179 -51.963641)
			(xy 244.713154 -51.942913) (xy 244.719856 -51.930554) (xy 244.732095 -51.907182) (xy 244.762059 -51.86376)
			(xy 244.797716 -51.824876) (xy 244.838386 -51.791271) (xy 244.883295 -51.763585) (xy 244.931588 -51.742344)
			(xy 244.982345 -51.727954) (xy 245.034599 -51.720689) (xy 245.060978 -51.720242) (xy 245.088235 -51.720603)
			(xy 245.142196 -51.728359) (xy 245.194503 -51.743715) (xy 245.244093 -51.766359) (xy 245.289955 -51.795831)
			(xy 245.331155 -51.831529) (xy 245.366856 -51.872728) (xy 245.39633 -51.918588) (xy 245.418977 -51.968176)
			(xy 245.434336 -52.020483) (xy 245.442095 -52.074443) (xy 245.442095 -52.128957) (xy 245.434336 -52.182917)
			(xy 245.418977 -52.235224) (xy 245.39633 -52.284812) (xy 245.366856 -52.330672) (xy 245.331155 -52.371871)
			(xy 245.289955 -52.407569) (xy 245.244093 -52.437041) (xy 245.194503 -52.459685) (xy 245.142196 -52.475041)
			(xy 245.088235 -52.482797) (xy 245.060978 -52.483258) (xy 245.0346 -52.482773) (xy 244.982346 -52.475519)
			(xy 244.931588 -52.461138) (xy 244.883295 -52.439904) (xy 244.838386 -52.412222) (xy 244.797716 -52.378619)
			(xy 244.762062 -52.339736) (xy 244.732101 -52.296313) (xy 244.719856 -52.272946) (xy 244.713154 -52.260587)
			(xy 244.694179 -52.239859) (xy 244.670265 -52.225097) (xy 244.643229 -52.217425) (xy 244.615127 -52.217425)
			(xy 244.588091 -52.225097) (xy 244.564177 -52.239859) (xy 244.545202 -52.260587) (xy 244.5385 -52.272946)
			(xy 244.526294 -52.296336) (xy 244.496326 -52.339759) (xy 244.460664 -52.378643) (xy 244.41999 -52.412247)
			(xy 244.375076 -52.439931) (xy 244.326778 -52.461168) (xy 244.276017 -52.475554) (xy 244.223758 -52.482814)
			(xy 244.197378 -52.483258) (xy 244.170131 -52.48267) (xy 244.116193 -52.474912) (xy 244.063908 -52.459557)
			(xy 244.01434 -52.436918) (xy 243.968498 -52.407455) (xy 243.927316 -52.371768) (xy 243.891632 -52.330584)
			(xy 243.862172 -52.284741) (xy 243.839535 -52.235171) (xy 243.824183 -52.182885) (xy 243.816428 -52.128947)
			(xy 234.974192 -52.128947) (xy 234.971673 -52.135398) (xy 234.971336 -52.14493) (xy 234.971336 -52.16779)
			(xy 234.971808 -52.177663) (xy 234.979262 -52.195948) (xy 234.985814 -52.20335) (xy 234.986068 -52.203604)
			(xy 236.147356 -53.364892) (xy 237.23422 -53.364892) (xy 237.238291 -53.30927) (xy 237.250417 -53.254833)
			(xy 237.27034 -53.202742) (xy 237.297636 -53.154107) (xy 237.331722 -53.109964) (xy 237.371871 -53.071255)
			(xy 237.417229 -53.038804) (xy 237.466829 -53.013303) (xy 237.519613 -52.995296) (xy 237.574456 -52.985166)
			(xy 237.63019 -52.983129) (xy 237.685627 -52.989229) (xy 237.739584 -53.003335) (xy 237.790913 -53.025147)
			(xy 237.838519 -53.054201) (xy 237.881387 -53.089876) (xy 237.918604 -53.131413) (xy 237.949377 -53.177926)
			(xy 237.973049 -53.228423) (xy 237.989117 -53.28183) (xy 237.997237 -53.337006) (xy 237.997746 -53.364892)
			(xy 237.997237 -53.392778) (xy 237.989117 -53.447954) (xy 237.973049 -53.501361) (xy 237.949377 -53.551858)
			(xy 237.918604 -53.598371) (xy 237.881387 -53.639908) (xy 237.838519 -53.675583) (xy 237.790913 -53.704637)
			(xy 237.739584 -53.726449) (xy 237.685627 -53.740555) (xy 237.63019 -53.746655) (xy 237.574456 -53.744618)
			(xy 237.519613 -53.734488) (xy 237.466829 -53.716481) (xy 237.417229 -53.69098) (xy 237.371871 -53.658529)
			(xy 237.331722 -53.61982) (xy 237.297636 -53.575677) (xy 237.27034 -53.527042) (xy 237.250417 -53.474951)
			(xy 237.238291 -53.420514) (xy 237.23422 -53.364892) (xy 236.147356 -53.364892) (xy 236.751114 -53.96865)
			(xy 236.751622 -53.969158) (xy 236.759002 -53.975744) (xy 236.777301 -53.983205) (xy 236.787182 -53.983636)
		)
		(stroke
			(width 0)
			(type solid)
		)
		(fill yes)
		(layer "In6.Cu")
		(net "P12V_E1S_0")
	)
	(gr_poly
		(pts
			(xy 155.310078 -83.35518) (xy 155.320141 -83.354742) (xy 155.338723 -83.347006) (xy 155.346146 -83.340194)
			(xy 156.101034 -82.585306) (xy 156.107889 -82.577911) (xy 156.115636 -82.559312) (xy 156.11602 -82.549238)
			(xy 156.11602 -72.901302) (xy 156.115598 -72.891231) (xy 156.107886 -72.872624) (xy 156.101034 -72.865234)
			(xy 155.544266 -72.308466) (xy 155.537154 -72.3011) (xy 155.518358 -72.29348) (xy 140.671042 -72.29348)
			(xy 140.660976 -72.293913) (xy 140.642385 -72.30164) (xy 140.634974 -72.308466) (xy 140.177266 -72.766174)
			(xy 140.1699 -72.773286) (xy 140.16228 -72.792082) (xy 140.16228 -73.616352) (xy 152.964589 -73.616352)
			(xy 152.964589 -73.561848) (xy 152.972347 -73.507898) (xy 152.987704 -73.455601) (xy 153.010347 -73.406023)
			(xy 153.039816 -73.360172) (xy 153.075511 -73.318982) (xy 153.116705 -73.283291) (xy 153.16256 -73.253827)
			(xy 153.212141 -73.231189) (xy 153.264439 -73.215838) (xy 153.31839 -73.208086) (xy 153.345642 -73.207626)
			(xy 153.373352 -73.208112) (xy 153.428187 -73.216142) (xy 153.481282 -73.232025) (xy 153.531518 -73.255427)
			(xy 153.577837 -73.285856) (xy 153.59888 -73.303892) (xy 153.605992 -73.309988) (xy 153.623264 -73.316592)
			(xy 153.70937 -73.316592) (xy 153.726642 -73.309988) (xy 153.733754 -73.303892) (xy 153.754797 -73.285858)
			(xy 153.801117 -73.255432) (xy 153.851353 -73.232034) (xy 153.904448 -73.216156) (xy 153.959283 -73.208132)
			(xy 154.014701 -73.208132) (xy 154.069536 -73.216156) (xy 154.122631 -73.232034) (xy 154.172867 -73.255432)
			(xy 154.219187 -73.285858) (xy 154.24023 -73.303892) (xy 154.247342 -73.309988) (xy 154.264614 -73.316592)
			(xy 154.35072 -73.316592) (xy 154.367992 -73.309988) (xy 154.375104 -73.303892) (xy 154.396136 -73.285844)
			(xy 154.442457 -73.255416) (xy 154.492696 -73.232017) (xy 154.545794 -73.21614) (xy 154.600632 -73.20812)
			(xy 154.628342 -73.207626) (xy 154.655594 -73.208047) (xy 154.709542 -73.215809) (xy 154.761836 -73.231169)
			(xy 154.811412 -73.253814) (xy 154.857262 -73.283285) (xy 154.898451 -73.318979) (xy 154.934141 -73.360172)
			(xy 154.963606 -73.406024) (xy 154.986246 -73.455603) (xy 155.0016 -73.507899) (xy 155.009356 -73.561848)
			(xy 155.009356 -73.616352) (xy 155.0016 -73.670301) (xy 154.986246 -73.722597) (xy 154.963606 -73.772176)
			(xy 154.934141 -73.818028) (xy 154.898451 -73.859221) (xy 154.857262 -73.894915) (xy 154.811412 -73.924386)
			(xy 154.761836 -73.947031) (xy 154.709542 -73.962391) (xy 154.655594 -73.970153) (xy 154.628342 -73.970642)
			(xy 154.600633 -73.970148) (xy 154.545799 -73.962118) (xy 154.492704 -73.946236) (xy 154.442468 -73.922835)
			(xy 154.396148 -73.89241) (xy 154.375104 -73.874376) (xy 154.367992 -73.86828) (xy 154.35072 -73.861676)
			(xy 154.264614 -73.861676) (xy 154.247342 -73.86828) (xy 154.24023 -73.874376) (xy 154.219187 -73.89241)
			(xy 154.172867 -73.922836) (xy 154.122631 -73.946234) (xy 154.069536 -73.962112) (xy 154.014701 -73.970136)
			(xy 153.959283 -73.970136) (xy 153.904448 -73.962112) (xy 153.851353 -73.946234) (xy 153.801117 -73.922836)
			(xy 153.754797 -73.89241) (xy 153.733754 -73.874376) (xy 153.726642 -73.86828) (xy 153.70937 -73.861676)
			(xy 153.623264 -73.861676) (xy 153.605992 -73.86828) (xy 153.59888 -73.874376) (xy 153.577849 -73.892427)
			(xy 153.531529 -73.922855) (xy 153.481289 -73.946254) (xy 153.428191 -73.96213) (xy 153.373353 -73.970148)
			(xy 153.345642 -73.970642) (xy 153.31839 -73.970114) (xy 153.264439 -73.962362) (xy 153.212141 -73.947011)
			(xy 153.16256 -73.924373) (xy 153.116705 -73.894909) (xy 153.075511 -73.859218) (xy 153.039816 -73.818028)
			(xy 153.010347 -73.772177) (xy 152.987704 -73.722599) (xy 152.972347 -73.670302) (xy 152.964589 -73.616352)
			(xy 140.16228 -73.616352) (xy 140.16228 -74.852022) (xy 141.157704 -74.852022) (xy 141.161775 -74.7964)
			(xy 141.173901 -74.741963) (xy 141.193824 -74.689872) (xy 141.22112 -74.641237) (xy 141.255206 -74.597094)
			(xy 141.295355 -74.558385) (xy 141.340713 -74.525934) (xy 141.390313 -74.500433) (xy 141.443097 -74.482426)
			(xy 141.49794 -74.472296) (xy 141.553674 -74.470259) (xy 141.609111 -74.476359) (xy 141.663068 -74.490465)
			(xy 141.714397 -74.512277) (xy 141.762003 -74.541331) (xy 141.804871 -74.577006) (xy 141.842088 -74.618543)
			(xy 141.872861 -74.665056) (xy 141.896533 -74.715553) (xy 141.912601 -74.76896) (xy 141.920721 -74.824136)
			(xy 141.92123 -74.852022) (xy 141.920721 -74.879908) (xy 141.917349 -74.902822) (xy 144.607024 -74.902822)
			(xy 144.611095 -74.8472) (xy 144.623221 -74.792763) (xy 144.643144 -74.740672) (xy 144.67044 -74.692037)
			(xy 144.704526 -74.647894) (xy 144.744675 -74.609185) (xy 144.790033 -74.576734) (xy 144.839633 -74.551233)
			(xy 144.892417 -74.533226) (xy 144.94726 -74.523096) (xy 145.002994 -74.521059) (xy 145.058431 -74.527159)
			(xy 145.112388 -74.541265) (xy 145.163717 -74.563077) (xy 145.211323 -74.592131) (xy 145.254191 -74.627806)
			(xy 145.291408 -74.669343) (xy 145.322181 -74.715856) (xy 145.345853 -74.766353) (xy 145.361921 -74.81976)
			(xy 145.370041 -74.874936) (xy 145.37055 -74.902822) (xy 145.370041 -74.930708) (xy 145.361921 -74.985884)
			(xy 145.345853 -75.039291) (xy 145.322181 -75.089788) (xy 145.291408 -75.136301) (xy 145.254191 -75.177838)
			(xy 145.211323 -75.213513) (xy 145.163717 -75.242567) (xy 145.112388 -75.264379) (xy 145.058431 -75.278485)
			(xy 145.002994 -75.284585) (xy 144.94726 -75.282548) (xy 144.892417 -75.272418) (xy 144.839633 -75.254411)
			(xy 144.790033 -75.22891) (xy 144.744675 -75.196459) (xy 144.704526 -75.15775) (xy 144.67044 -75.113607)
			(xy 144.643144 -75.064972) (xy 144.623221 -75.012881) (xy 144.611095 -74.958444) (xy 144.607024 -74.902822)
			(xy 141.917349 -74.902822) (xy 141.912601 -74.935084) (xy 141.896533 -74.988491) (xy 141.872861 -75.038988)
			(xy 141.842088 -75.085501) (xy 141.804871 -75.127038) (xy 141.762003 -75.162713) (xy 141.714397 -75.191767)
			(xy 141.663068 -75.213579) (xy 141.609111 -75.227685) (xy 141.553674 -75.233785) (xy 141.49794 -75.231748)
			(xy 141.443097 -75.221618) (xy 141.390313 -75.203611) (xy 141.340713 -75.17811) (xy 141.295355 -75.145659)
			(xy 141.255206 -75.10695) (xy 141.22112 -75.062807) (xy 141.193824 -75.014172) (xy 141.173901 -74.962081)
			(xy 141.161775 -74.907644) (xy 141.157704 -74.852022) (xy 140.16228 -74.852022) (xy 140.16228 -76.324968)
			(xy 142.317214 -76.324968) (xy 142.321285 -76.269346) (xy 142.333411 -76.214909) (xy 142.353334 -76.162818)
			(xy 142.38063 -76.114183) (xy 142.414716 -76.07004) (xy 142.454865 -76.031331) (xy 142.500223 -75.99888)
			(xy 142.549823 -75.973379) (xy 142.602607 -75.955372) (xy 142.65745 -75.945242) (xy 142.713184 -75.943205)
			(xy 142.768621 -75.949305) (xy 142.822578 -75.963411) (xy 142.873907 -75.985223) (xy 142.921513 -76.014277)
			(xy 142.964381 -76.049952) (xy 143.001598 -76.091489) (xy 143.032371 -76.138002) (xy 143.056043 -76.188499)
			(xy 143.072111 -76.241906) (xy 143.080231 -76.297082) (xy 143.080314 -76.301652) (xy 144.371777 -76.301652)
			(xy 144.371777 -76.247148) (xy 144.379534 -76.193198) (xy 144.394891 -76.140901) (xy 144.417533 -76.091323)
			(xy 144.447002 -76.045471) (xy 144.482696 -76.00428) (xy 144.523889 -75.968589) (xy 144.569742 -75.939123)
			(xy 144.619322 -75.916483) (xy 144.67162 -75.90113) (xy 144.72557 -75.893376) (xy 144.752822 -75.892914)
			(xy 144.782807 -75.893527) (xy 144.842034 -75.902939) (xy 144.899066 -75.921482) (xy 144.92605 -75.93457)
			(xy 144.935194 -75.939142) (xy 144.954752 -75.940666) (xy 145.042636 -75.912472) (xy 145.057622 -75.899772)
			(xy 145.062448 -75.890628) (xy 145.074767 -75.867592) (xy 145.104805 -75.824853) (xy 145.140395 -75.786612)
			(xy 145.18087 -75.753587) (xy 145.225474 -75.726394) (xy 145.273372 -75.705542) (xy 145.323667 -75.691422)
			(xy 145.375418 -75.684298) (xy 145.401538 -75.683872) (xy 145.428786 -75.684401) (xy 145.482727 -75.692161)
			(xy 145.535014 -75.707519) (xy 145.580194 -75.728156) (xy 152.583545 -75.728156) (xy 152.583545 -75.673644)
			(xy 152.591303 -75.619688) (xy 152.606662 -75.567386) (xy 152.629308 -75.517801) (xy 152.658781 -75.471945)
			(xy 152.69448 -75.43075) (xy 152.735679 -75.395056) (xy 152.781538 -75.365588) (xy 152.831125 -75.342947)
			(xy 152.883429 -75.327594) (xy 152.937386 -75.319842) (xy 152.964642 -75.319382) (xy 152.992351 -75.319879)
			(xy 153.047186 -75.327908) (xy 153.10028 -75.343789) (xy 153.150516 -75.367189) (xy 153.196836 -75.397614)
			(xy 153.21788 -75.415648) (xy 153.224992 -75.421744) (xy 153.242264 -75.428348) (xy 153.32837 -75.428348)
			(xy 153.345642 -75.421744) (xy 153.352754 -75.415648) (xy 153.373797 -75.397614) (xy 153.420117 -75.367188)
			(xy 153.470353 -75.34379) (xy 153.523448 -75.327912) (xy 153.578283 -75.319888) (xy 153.633701 -75.319888)
			(xy 153.688536 -75.327912) (xy 153.741631 -75.34379) (xy 153.791867 -75.367188) (xy 153.838187 -75.397614)
			(xy 153.85923 -75.415648) (xy 153.866342 -75.421744) (xy 153.883614 -75.428348) (xy 153.96972 -75.428348)
			(xy 153.986992 -75.421744) (xy 153.994104 -75.415648) (xy 154.015147 -75.397614) (xy 154.061467 -75.367188)
			(xy 154.111703 -75.34379) (xy 154.164798 -75.327912) (xy 154.219633 -75.319888) (xy 154.275051 -75.319888)
			(xy 154.329886 -75.327912) (xy 154.382981 -75.34379) (xy 154.433217 -75.367188) (xy 154.479537 -75.397614)
			(xy 154.50058 -75.415648) (xy 154.507692 -75.421744) (xy 154.524964 -75.428348) (xy 154.61107 -75.428348)
			(xy 154.628342 -75.421744) (xy 154.635454 -75.415648) (xy 154.6565 -75.397616) (xy 154.702817 -75.367187)
			(xy 154.753053 -75.343786) (xy 154.806148 -75.327905) (xy 154.860983 -75.31988) (xy 154.888692 -75.319382)
			(xy 154.915945 -75.319865) (xy 154.969895 -75.327621) (xy 155.022192 -75.342976) (xy 155.071772 -75.365617)
			(xy 155.117625 -75.395084) (xy 155.158818 -75.430777) (xy 155.194511 -75.471969) (xy 155.223979 -75.517821)
			(xy 155.246622 -75.5674) (xy 155.261978 -75.619697) (xy 155.269735 -75.673647) (xy 155.269735 -75.728153)
			(xy 155.261978 -75.782103) (xy 155.246622 -75.8344) (xy 155.223979 -75.883979) (xy 155.194511 -75.929831)
			(xy 155.158818 -75.971023) (xy 155.117625 -76.006716) (xy 155.071772 -76.036183) (xy 155.022192 -76.058824)
			(xy 154.969895 -76.074179) (xy 154.915945 -76.081935) (xy 154.888692 -76.082398) (xy 154.860983 -76.081886)
			(xy 154.806149 -76.073862) (xy 154.753055 -76.057984) (xy 154.702818 -76.034588) (xy 154.656498 -76.004165)
			(xy 154.635454 -75.986132) (xy 154.628342 -75.980036) (xy 154.61107 -75.973432) (xy 154.524964 -75.973432)
			(xy 154.507692 -75.980036) (xy 154.50058 -75.986132) (xy 154.479537 -76.004166) (xy 154.433217 -76.034592)
			(xy 154.382981 -76.05799) (xy 154.329886 -76.073868) (xy 154.275051 -76.081892) (xy 154.219633 -76.081892)
			(xy 154.164798 -76.073868) (xy 154.111703 -76.05799) (xy 154.061467 -76.034592) (xy 154.015147 -76.004166)
			(xy 153.994104 -75.986132) (xy 153.986992 -75.980036) (xy 153.96972 -75.973432) (xy 153.883614 -75.973432)
			(xy 153.866342 -75.980036) (xy 153.85923 -75.986132) (xy 153.838187 -76.004166) (xy 153.791867 -76.034592)
			(xy 153.741631 -76.05799) (xy 153.688536 -76.073868) (xy 153.633701 -76.081892) (xy 153.578283 -76.081892)
			(xy 153.523448 -76.073868) (xy 153.470353 -76.05799) (xy 153.420117 -76.034592) (xy 153.373797 -76.004166)
			(xy 153.352754 -75.986132) (xy 153.345642 -75.980036) (xy 153.32837 -75.973432) (xy 153.242264 -75.973432)
			(xy 153.224992 -75.980036) (xy 153.21788 -75.986132) (xy 153.196857 -76.004192) (xy 153.150533 -76.034617)
			(xy 153.100292 -76.058013) (xy 153.047192 -76.073888) (xy 152.992353 -76.081905) (xy 152.964642 -76.082398)
			(xy 152.937386 -76.081958) (xy 152.883429 -76.074206) (xy 152.831125 -76.058853) (xy 152.781538 -76.036212)
			(xy 152.735679 -76.006744) (xy 152.69448 -75.97105) (xy 152.658781 -75.929855) (xy 152.629308 -75.883999)
			(xy 152.606662 -75.834414) (xy 152.591303 -75.782112) (xy 152.583545 -75.728156) (xy 145.580194 -75.728156)
			(xy 145.584584 -75.730161) (xy 145.630427 -75.759627) (xy 145.671611 -75.795316) (xy 145.707296 -75.836503)
			(xy 145.736757 -75.882349) (xy 145.759394 -75.931922) (xy 145.774747 -75.98421) (xy 145.782502 -76.038152)
			(xy 145.782502 -76.092648) (xy 145.774747 -76.14659) (xy 145.759394 -76.198878) (xy 145.736757 -76.248451)
			(xy 145.707296 -76.294297) (xy 145.671611 -76.335484) (xy 145.630427 -76.371173) (xy 145.584584 -76.400639)
			(xy 145.535014 -76.423281) (xy 145.482727 -76.438639) (xy 145.428786 -76.446399) (xy 145.401538 -76.446888)
			(xy 145.371553 -76.446289) (xy 145.312325 -76.436871) (xy 145.255294 -76.418323) (xy 145.22831 -76.405232)
			(xy 145.219166 -76.40066) (xy 145.199608 -76.399136) (xy 145.111724 -76.42733) (xy 145.096738 -76.44003)
			(xy 145.091912 -76.449174) (xy 145.079623 -76.472227) (xy 145.049581 -76.514967) (xy 145.013987 -76.553207)
			(xy 144.973507 -76.586232) (xy 144.928899 -76.613423) (xy 144.880997 -76.634271) (xy 144.830698 -76.648387)
			(xy 144.778943 -76.655506) (xy 144.752822 -76.65593) (xy 144.72557 -76.655424) (xy 144.671619 -76.64767)
			(xy 144.619322 -76.632317) (xy 144.569742 -76.609677) (xy 144.523889 -76.580211) (xy 144.482696 -76.54452)
			(xy 144.447002 -76.503329) (xy 144.417533 -76.457477) (xy 144.394891 -76.407899) (xy 144.379534 -76.355602)
			(xy 144.371777 -76.301652) (xy 143.080314 -76.301652) (xy 143.08074 -76.324968) (xy 143.080231 -76.352854)
			(xy 143.072111 -76.40803) (xy 143.056043 -76.461437) (xy 143.032371 -76.511934) (xy 143.001598 -76.558447)
			(xy 142.964381 -76.599984) (xy 142.921513 -76.635659) (xy 142.873907 -76.664713) (xy 142.822578 -76.686525)
			(xy 142.768621 -76.700631) (xy 142.713184 -76.706731) (xy 142.65745 -76.704694) (xy 142.602607 -76.694564)
			(xy 142.549823 -76.676557) (xy 142.500223 -76.651056) (xy 142.454865 -76.618605) (xy 142.414716 -76.579896)
			(xy 142.38063 -76.535753) (xy 142.353334 -76.487118) (xy 142.333411 -76.435027) (xy 142.321285 -76.38059)
			(xy 142.317214 -76.324968) (xy 140.16228 -76.324968) (xy 140.16228 -76.702158) (xy 140.161846 -76.712223)
			(xy 140.154114 -76.73081) (xy 140.147294 -76.738226) (xy 137.289286 -79.596234) (xy 137.28192 -79.603346)
			(xy 137.2743 -79.622142) (xy 137.2743 -80.302862) (xy 143.832324 -80.302862) (xy 143.836395 -80.24724)
			(xy 143.848521 -80.192803) (xy 143.868444 -80.140712) (xy 143.89574 -80.092077) (xy 143.929826 -80.047934)
			(xy 143.969975 -80.009225) (xy 144.015333 -79.976774) (xy 144.064933 -79.951273) (xy 144.117717 -79.933266)
			(xy 144.17256 -79.923136) (xy 144.228294 -79.921099) (xy 144.272162 -79.925926) (xy 144.667984 -79.925926)
			(xy 144.672055 -79.870304) (xy 144.684181 -79.815867) (xy 144.704104 -79.763776) (xy 144.7314 -79.715141)
			(xy 144.765486 -79.670998) (xy 144.805635 -79.632289) (xy 144.850993 -79.599838) (xy 144.900593 -79.574337)
			(xy 144.953377 -79.55633) (xy 145.00822 -79.5462) (xy 145.063954 -79.544163) (xy 145.119391 -79.550263)
			(xy 145.173348 -79.564369) (xy 145.224677 -79.586181) (xy 145.272283 -79.615235) (xy 145.315151 -79.65091)
			(xy 145.352368 -79.692447) (xy 145.383141 -79.73896) (xy 145.406813 -79.789457) (xy 145.416018 -79.820053)
			(xy 152.583585 -79.820053) (xy 152.583585 -79.765547) (xy 152.591343 -79.711597) (xy 152.6067 -79.6593)
			(xy 152.629344 -79.609721) (xy 152.658813 -79.563869) (xy 152.694509 -79.522679) (xy 152.735703 -79.486988)
			(xy 152.781558 -79.457523) (xy 152.831139 -79.434885) (xy 152.883438 -79.419534) (xy 152.937389 -79.411782)
			(xy 152.964642 -79.411322) (xy 152.992352 -79.411809) (xy 153.047187 -79.419838) (xy 153.100282 -79.435722)
			(xy 153.150518 -79.459124) (xy 153.196837 -79.489553) (xy 153.21788 -79.507588) (xy 153.224992 -79.513684)
			(xy 153.242264 -79.520288) (xy 153.32837 -79.520288) (xy 153.345642 -79.513684) (xy 153.352754 -79.507588)
			(xy 153.373797 -79.489554) (xy 153.420117 -79.459128) (xy 153.470353 -79.43573) (xy 153.523448 -79.419852)
			(xy 153.578283 -79.411828) (xy 153.633701 -79.411828) (xy 153.688536 -79.419852) (xy 153.741631 -79.43573)
			(xy 153.791867 -79.459128) (xy 153.838187 -79.489554) (xy 153.85923 -79.507588) (xy 153.866342 -79.513684)
			(xy 153.883614 -79.520288) (xy 153.96972 -79.520288) (xy 153.986992 -79.513684) (xy 153.994104 -79.507588)
			(xy 154.015147 -79.489554) (xy 154.061467 -79.459128) (xy 154.111703 -79.43573) (xy 154.164798 -79.419852)
			(xy 154.219633 -79.411828) (xy 154.275051 -79.411828) (xy 154.329886 -79.419852) (xy 154.382981 -79.43573)
			(xy 154.433217 -79.459128) (xy 154.479537 -79.489554) (xy 154.50058 -79.507588) (xy 154.507692 -79.513684)
			(xy 154.524964 -79.520288) (xy 154.61107 -79.520288) (xy 154.628342 -79.513684) (xy 154.635454 -79.507588)
			(xy 154.656505 -79.489562) (xy 154.702821 -79.459131) (xy 154.753055 -79.435728) (xy 154.806149 -79.419846)
			(xy 154.860983 -79.41182) (xy 154.888692 -79.411322) (xy 154.915947 -79.411724) (xy 154.969903 -79.419481)
			(xy 155.022206 -79.434838) (xy 155.071792 -79.457481) (xy 155.117649 -79.486952) (xy 155.158846 -79.522648)
			(xy 155.194544 -79.563844) (xy 155.224015 -79.609701) (xy 155.24666 -79.659286) (xy 155.262017 -79.711589)
			(xy 155.269775 -79.765545) (xy 155.269775 -79.820055) (xy 155.262017 -79.874011) (xy 155.24666 -79.926314)
			(xy 155.224015 -79.975899) (xy 155.194544 -80.021756) (xy 155.158846 -80.062952) (xy 155.117649 -80.098648)
			(xy 155.071792 -80.128119) (xy 155.022206 -80.150762) (xy 154.969903 -80.166119) (xy 154.915947 -80.173876)
			(xy 154.888692 -80.174338) (xy 154.860984 -80.173816) (xy 154.806151 -80.165793) (xy 154.753057 -80.149917)
			(xy 154.70282 -80.126523) (xy 154.656499 -80.096103) (xy 154.635454 -80.078072) (xy 154.628342 -80.071976)
			(xy 154.61107 -80.065372) (xy 154.524964 -80.065372) (xy 154.507692 -80.071976) (xy 154.50058 -80.078072)
			(xy 154.479537 -80.096106) (xy 154.433217 -80.126532) (xy 154.382981 -80.14993) (xy 154.329886 -80.165808)
			(xy 154.275051 -80.173832) (xy 154.219633 -80.173832) (xy 154.164798 -80.165808) (xy 154.111703 -80.14993)
			(xy 154.061467 -80.126532) (xy 154.015147 -80.096106) (xy 153.994104 -80.078072) (xy 153.986992 -80.071976)
			(xy 153.96972 -80.065372) (xy 153.883614 -80.065372) (xy 153.866342 -80.071976) (xy 153.85923 -80.078072)
			(xy 153.838187 -80.096106) (xy 153.791867 -80.126532) (xy 153.741631 -80.14993) (xy 153.688536 -80.165808)
			(xy 153.633701 -80.173832) (xy 153.578283 -80.173832) (xy 153.523448 -80.165808) (xy 153.470353 -80.14993)
			(xy 153.420117 -80.126532) (xy 153.373797 -80.096106) (xy 153.352754 -80.078072) (xy 153.345642 -80.071976)
			(xy 153.32837 -80.065372) (xy 153.242264 -80.065372) (xy 153.224992 -80.071976) (xy 153.21788 -80.078072)
			(xy 153.196849 -80.096122) (xy 153.150528 -80.126551) (xy 153.100289 -80.14995) (xy 153.047191 -80.165826)
			(xy 152.992353 -80.173844) (xy 152.964642 -80.174338) (xy 152.937389 -80.173818) (xy 152.883438 -80.166066)
			(xy 152.831139 -80.150715) (xy 152.781558 -80.128077) (xy 152.735703 -80.098612) (xy 152.694509 -80.062921)
			(xy 152.658813 -80.021731) (xy 152.629344 -79.975879) (xy 152.6067 -79.9263) (xy 152.591343 -79.874003)
			(xy 152.583585 -79.820053) (xy 145.416018 -79.820053) (xy 145.422881 -79.842864) (xy 145.431001 -79.89804)
			(xy 145.43151 -79.925926) (xy 145.431001 -79.953812) (xy 145.422881 -80.008988) (xy 145.406813 -80.062395)
			(xy 145.383141 -80.112892) (xy 145.352368 -80.159405) (xy 145.315151 -80.200942) (xy 145.272283 -80.236617)
			(xy 145.224677 -80.265671) (xy 145.173348 -80.287483) (xy 145.119391 -80.301589) (xy 145.063954 -80.307689)
			(xy 145.00822 -80.305652) (xy 144.953377 -80.295522) (xy 144.900593 -80.277515) (xy 144.850993 -80.252014)
			(xy 144.805635 -80.219563) (xy 144.765486 -80.180854) (xy 144.7314 -80.136711) (xy 144.704104 -80.088076)
			(xy 144.684181 -80.035985) (xy 144.672055 -79.981548) (xy 144.667984 -79.925926) (xy 144.272162 -79.925926)
			(xy 144.283731 -79.927199) (xy 144.337688 -79.941305) (xy 144.389017 -79.963117) (xy 144.436623 -79.992171)
			(xy 144.479491 -80.027846) (xy 144.516708 -80.069383) (xy 144.547481 -80.115896) (xy 144.571153 -80.166393)
			(xy 144.587221 -80.2198) (xy 144.595341 -80.274976) (xy 144.59585 -80.302862) (xy 144.595341 -80.330748)
			(xy 144.587221 -80.385924) (xy 144.571153 -80.439331) (xy 144.547481 -80.489828) (xy 144.516708 -80.536341)
			(xy 144.479491 -80.577878) (xy 144.436623 -80.613553) (xy 144.389017 -80.642607) (xy 144.337688 -80.664419)
			(xy 144.283731 -80.678525) (xy 144.228294 -80.684625) (xy 144.17256 -80.682588) (xy 144.117717 -80.672458)
			(xy 144.064933 -80.654451) (xy 144.015333 -80.62895) (xy 143.969975 -80.596499) (xy 143.929826 -80.55779)
			(xy 143.89574 -80.513647) (xy 143.868444 -80.465012) (xy 143.848521 -80.412921) (xy 143.836395 -80.358484)
			(xy 143.832324 -80.302862) (xy 137.2743 -80.302862) (xy 137.2743 -81.866055) (xy 152.583555 -81.866055)
			(xy 152.583555 -81.811545) (xy 152.591314 -81.757591) (xy 152.606672 -81.705289) (xy 152.629317 -81.655707)
			(xy 152.658789 -81.609851) (xy 152.694487 -81.568658) (xy 152.735685 -81.532964) (xy 152.781543 -81.503497)
			(xy 152.831129 -81.480857) (xy 152.883432 -81.465505) (xy 152.937387 -81.457752) (xy 152.964642 -81.457292)
			(xy 152.992351 -81.457787) (xy 153.047186 -81.465815) (xy 153.10028 -81.481697) (xy 153.150517 -81.505098)
			(xy 153.196836 -81.535524) (xy 153.21788 -81.553558) (xy 153.224992 -81.559654) (xy 153.242264 -81.566258)
			(xy 153.32837 -81.566258) (xy 153.345642 -81.559654) (xy 153.352754 -81.553558) (xy 153.373797 -81.535524)
			(xy 153.420117 -81.505098) (xy 153.470353 -81.4817) (xy 153.523448 -81.465822) (xy 153.578283 -81.457798)
			(xy 153.633701 -81.457798) (xy 153.688536 -81.465822) (xy 153.741631 -81.4817) (xy 153.791867 -81.505098)
			(xy 153.838187 -81.535524) (xy 153.85923 -81.553558) (xy 153.866342 -81.559654) (xy 153.883614 -81.566258)
			(xy 153.96972 -81.566258) (xy 153.986992 -81.559654) (xy 153.994104 -81.553558) (xy 154.015147 -81.535524)
			(xy 154.061467 -81.505098) (xy 154.111703 -81.4817) (xy 154.164798 -81.465822) (xy 154.219633 -81.457798)
			(xy 154.275051 -81.457798) (xy 154.329886 -81.465822) (xy 154.382981 -81.4817) (xy 154.433217 -81.505098)
			(xy 154.479537 -81.535524) (xy 154.50058 -81.553558) (xy 154.507692 -81.559654) (xy 154.524964 -81.566258)
			(xy 154.61107 -81.566258) (xy 154.628342 -81.559654) (xy 154.635454 -81.553558) (xy 154.656501 -81.535528)
			(xy 154.702818 -81.505098) (xy 154.753054 -81.481697) (xy 154.806148 -81.465815) (xy 154.860983 -81.45779)
			(xy 154.888692 -81.457292) (xy 154.915945 -81.457755) (xy 154.969897 -81.465511) (xy 155.022196 -81.480866)
			(xy 155.071777 -81.503508) (xy 155.117631 -81.532976) (xy 155.158825 -81.56867) (xy 155.194519 -81.609863)
			(xy 155.223988 -81.655716) (xy 155.246631 -81.705297) (xy 155.261987 -81.757595) (xy 155.269745 -81.811547)
			(xy 155.269745 -81.866053) (xy 155.261987 -81.920005) (xy 155.246631 -81.972303) (xy 155.223988 -82.021884)
			(xy 155.194519 -82.067737) (xy 155.158825 -82.10893) (xy 155.117631 -82.144624) (xy 155.071777 -82.174092)
			(xy 155.022196 -82.196734) (xy 154.969897 -82.212089) (xy 154.915945 -82.219845) (xy 154.888692 -82.220308)
			(xy 154.860983 -82.219793) (xy 154.80615 -82.21177) (xy 154.753055 -82.195892) (xy 154.702819 -82.172496)
			(xy 154.656498 -82.142074) (xy 154.635454 -82.124042) (xy 154.628342 -82.117946) (xy 154.61107 -82.111342)
			(xy 154.524964 -82.111342) (xy 154.507692 -82.117946) (xy 154.50058 -82.124042) (xy 154.479537 -82.142076)
			(xy 154.433217 -82.172502) (xy 154.382981 -82.1959) (xy 154.329886 -82.211778) (xy 154.275051 -82.219802)
			(xy 154.219633 -82.219802) (xy 154.164798 -82.211778) (xy 154.111703 -82.1959) (xy 154.061467 -82.172502)
			(xy 154.015147 -82.142076) (xy 153.994104 -82.124042) (xy 153.986992 -82.117946) (xy 153.96972 -82.111342)
			(xy 153.883614 -82.111342) (xy 153.866342 -82.117946) (xy 153.85923 -82.124042) (xy 153.838187 -82.142076)
			(xy 153.791867 -82.172502) (xy 153.741631 -82.1959) (xy 153.688536 -82.211778) (xy 153.633701 -82.219802)
			(xy 153.578283 -82.219802) (xy 153.523448 -82.211778) (xy 153.470353 -82.1959) (xy 153.420117 -82.172502)
			(xy 153.373797 -82.142076) (xy 153.352754 -82.124042) (xy 153.345642 -82.117946) (xy 153.32837 -82.111342)
			(xy 153.242264 -82.111342) (xy 153.224992 -82.117946) (xy 153.21788 -82.124042) (xy 153.196859 -82.142103)
			(xy 153.150534 -82.172528) (xy 153.100292 -82.195924) (xy 153.047192 -82.211798) (xy 152.992353 -82.219815)
			(xy 152.964642 -82.220308) (xy 152.937387 -82.219848) (xy 152.883432 -82.212095) (xy 152.831129 -82.196743)
			(xy 152.781543 -82.174103) (xy 152.735685 -82.144636) (xy 152.694487 -82.108942) (xy 152.658789 -82.067749)
			(xy 152.629317 -82.021893) (xy 152.606672 -81.972311) (xy 152.591314 -81.920009) (xy 152.583555 -81.866055)
			(xy 137.2743 -81.866055) (xy 137.2743 -82.423508) (xy 143.419574 -82.423508) (xy 143.423645 -82.367886)
			(xy 143.435771 -82.313449) (xy 143.455694 -82.261358) (xy 143.48299 -82.212723) (xy 143.517076 -82.16858)
			(xy 143.557225 -82.129871) (xy 143.602583 -82.09742) (xy 143.652183 -82.071919) (xy 143.704967 -82.053912)
			(xy 143.75981 -82.043782) (xy 143.815544 -82.041745) (xy 143.870981 -82.047845) (xy 143.924938 -82.061951)
			(xy 143.976267 -82.083763) (xy 144.023873 -82.112817) (xy 144.066741 -82.148492) (xy 144.103958 -82.190029)
			(xy 144.134731 -82.236542) (xy 144.158403 -82.287039) (xy 144.174471 -82.340446) (xy 144.182591 -82.395622)
			(xy 144.1831 -82.423508) (xy 144.182591 -82.451394) (xy 144.174471 -82.50657) (xy 144.158403 -82.559977)
			(xy 144.134731 -82.610474) (xy 144.103958 -82.656987) (xy 144.066741 -82.698524) (xy 144.023873 -82.734199)
			(xy 143.976267 -82.763253) (xy 143.924938 -82.785065) (xy 143.870981 -82.799171) (xy 143.815544 -82.805271)
			(xy 143.75981 -82.803234) (xy 143.704967 -82.793104) (xy 143.652183 -82.775097) (xy 143.602583 -82.749596)
			(xy 143.557225 -82.717145) (xy 143.517076 -82.678436) (xy 143.48299 -82.634293) (xy 143.455694 -82.585658)
			(xy 143.435771 -82.533567) (xy 143.423645 -82.47913) (xy 143.419574 -82.423508) (xy 137.2743 -82.423508)
			(xy 137.2743 -82.747358) (xy 137.274734 -82.757423) (xy 137.282463 -82.776013) (xy 137.289286 -82.783426)
			(xy 137.846054 -83.340194) (xy 137.853455 -83.347033) (xy 137.872053 -83.354748) (xy 137.882122 -83.35518)
		)
		(stroke
			(width 0)
			(type solid)
		)
		(fill yes)
		(layer "In6.Cu")
		(net "GND")
	)
	(gr_poly
		(pts
			(xy 335.639918 -159.512) (xy 335.649795 -159.51154) (xy 335.668094 -159.504097) (xy 335.675478 -159.497522)
			(xy 335.675732 -159.497268) (xy 339.823298 -155.349702) (xy 339.823806 -155.349194) (xy 339.830401 -155.341817)
			(xy 339.837875 -155.323518) (xy 339.838284 -155.313634) (xy 339.838284 -147.073366) (xy 339.837854 -147.063299)
			(xy 339.830129 -147.044705) (xy 339.823298 -147.037298) (xy 339.437726 -146.651726) (xy 339.430325 -146.644888)
			(xy 339.411726 -146.637177) (xy 339.401658 -146.63674) (xy 310.457088 -146.63674) (xy 310.451077 -146.636902)
			(xy 310.439389 -146.639715) (xy 310.433974 -146.642328) (xy 310.430501 -146.644169) (xy 310.424124 -146.648765)
			(xy 310.421274 -146.651472) (xy 307.222906 -149.84984) (xy 307.204364 -149.85746) (xy 307.194712 -149.85746)
			(xy 307.182012 -149.858476) (xy 307.157628 -149.878288) (xy 307.146706 -149.916134) (xy 307.144271 -149.926093)
			(xy 307.146665 -149.946435) (xy 307.15684 -149.964213) (xy 307.16474 -149.970744) (xy 307.187697 -149.988899)
			(xy 307.228292 -150.031058) (xy 307.235606 -150.041453) (xy 329.180656 -150.041453) (xy 329.180656 -149.986947)
			(xy 329.188413 -149.932997) (xy 329.203769 -149.880699) (xy 329.226411 -149.831119) (xy 329.255879 -149.785266)
			(xy 329.291572 -149.744074) (xy 329.332764 -149.70838) (xy 329.378617 -149.678912) (xy 329.428197 -149.656269)
			(xy 329.480495 -149.640913) (xy 329.534445 -149.633156) (xy 329.561698 -149.63267) (xy 329.591918 -149.63325)
			(xy 329.651607 -149.642745) (xy 329.709054 -149.661531) (xy 329.762821 -149.689137) (xy 329.811564 -149.724873)
			(xy 329.833224 -149.745954) (xy 329.840336 -149.75332) (xy 329.858878 -149.761194) (xy 329.952096 -149.76094)
			(xy 329.970638 -149.753066) (xy 329.978004 -149.7457) (xy 329.996012 -149.72787) (xy 330.035925 -149.696642)
			(xy 330.07962 -149.670974) (xy 330.12633 -149.651316) (xy 330.17523 -149.638016) (xy 330.225461 -149.631306)
			(xy 330.2508 -149.630892) (xy 330.278051 -149.631378) (xy 330.331999 -149.639134) (xy 330.384294 -149.654489)
			(xy 330.433871 -149.677131) (xy 330.479721 -149.706597) (xy 330.520912 -149.742288) (xy 330.556603 -149.783479)
			(xy 330.586069 -149.829329) (xy 330.608711 -149.878906) (xy 330.624066 -149.931201) (xy 330.624785 -149.9362)
			(xy 332.028292 -149.9362) (xy 332.02876 -149.90883) (xy 332.036578 -149.854651) (xy 332.052066 -149.802148)
			(xy 332.074908 -149.752401) (xy 332.104631 -149.706434) (xy 332.122272 -149.685502) (xy 332.128368 -149.67839)
			(xy 332.134718 -149.661372) (xy 332.134718 -149.576028) (xy 332.128368 -149.55901) (xy 332.122272 -149.551898)
			(xy 332.104614 -149.530981) (xy 332.074906 -149.485004) (xy 332.052074 -149.435252) (xy 332.036587 -149.382748)
			(xy 332.028764 -149.32857) (xy 332.028292 -149.3012) (xy 332.028778 -149.273949) (xy 332.036534 -149.220001)
			(xy 332.051889 -149.167706) (xy 332.074531 -149.118129) (xy 332.103997 -149.072279) (xy 332.139688 -149.031088)
			(xy 332.180879 -148.995397) (xy 332.226729 -148.965931) (xy 332.276306 -148.943289) (xy 332.328601 -148.927934)
			(xy 332.382549 -148.920178) (xy 332.437051 -148.920178) (xy 332.490999 -148.927934) (xy 332.543294 -148.943289)
			(xy 332.592871 -148.965931) (xy 332.638721 -148.995397) (xy 332.679912 -149.031088) (xy 332.715603 -149.072279)
			(xy 332.745069 -149.118129) (xy 332.767711 -149.167706) (xy 332.783066 -149.220001) (xy 332.790822 -149.273949)
			(xy 332.791308 -149.3012) (xy 332.79084 -149.32857) (xy 332.783022 -149.382749) (xy 332.767534 -149.435252)
			(xy 332.744692 -149.484999) (xy 332.714969 -149.530966) (xy 332.697328 -149.551898) (xy 332.691232 -149.55901)
			(xy 332.684882 -149.576028) (xy 332.684882 -149.661372) (xy 332.691232 -149.67839) (xy 332.697328 -149.685502)
			(xy 332.714986 -149.706419) (xy 332.744694 -149.752396) (xy 332.767526 -149.802148) (xy 332.783013 -149.854652)
			(xy 332.790836 -149.90883) (xy 332.791308 -149.9362) (xy 332.790822 -149.963451) (xy 332.783066 -150.017399)
			(xy 332.767711 -150.069694) (xy 332.745069 -150.119271) (xy 332.715603 -150.165121) (xy 332.679912 -150.206312)
			(xy 332.638721 -150.242003) (xy 332.592871 -150.271469) (xy 332.543294 -150.294111) (xy 332.490999 -150.309466)
			(xy 332.437051 -150.317222) (xy 332.382549 -150.317222) (xy 332.328601 -150.309466) (xy 332.276306 -150.294111)
			(xy 332.226729 -150.271469) (xy 332.180879 -150.242003) (xy 332.139688 -150.206312) (xy 332.103997 -150.165121)
			(xy 332.074531 -150.119271) (xy 332.051889 -150.069694) (xy 332.036534 -150.017399) (xy 332.028778 -149.963451)
			(xy 332.028292 -149.9362) (xy 330.624785 -149.9362) (xy 330.631822 -149.985149) (xy 330.631822 -150.039651)
			(xy 330.624066 -150.093599) (xy 330.608711 -150.145894) (xy 330.586069 -150.195471) (xy 330.556603 -150.241321)
			(xy 330.520912 -150.282512) (xy 330.479721 -150.318203) (xy 330.433871 -150.347669) (xy 330.384294 -150.370311)
			(xy 330.331999 -150.385666) (xy 330.278051 -150.393422) (xy 330.2508 -150.393908) (xy 330.220579 -150.393336)
			(xy 330.16089 -150.383839) (xy 330.103443 -150.365052) (xy 330.049676 -150.337445) (xy 330.000933 -150.301706)
			(xy 329.979274 -150.280624) (xy 329.972162 -150.273258) (xy 329.95362 -150.265384) (xy 329.860402 -150.265638)
			(xy 329.84186 -150.273512) (xy 329.834494 -150.280878) (xy 329.816483 -150.298705) (xy 329.776571 -150.329934)
			(xy 329.732876 -150.355603) (xy 329.686168 -150.375261) (xy 329.637267 -150.388562) (xy 329.587036 -150.395272)
			(xy 329.561698 -150.395686) (xy 329.534445 -150.395244) (xy 329.480495 -150.387487) (xy 329.428197 -150.372131)
			(xy 329.378617 -150.349488) (xy 329.332764 -150.32002) (xy 329.291572 -150.284326) (xy 329.255879 -150.243134)
			(xy 329.226411 -150.197281) (xy 329.203769 -150.147701) (xy 329.188413 -150.095403) (xy 329.180656 -150.041453)
			(xy 307.235606 -150.041453) (xy 307.261972 -150.078923) (xy 307.287946 -150.13137) (xy 307.305604 -150.187169)
			(xy 307.314533 -150.245011) (xy 307.315108 -150.274274) (xy 307.314646 -150.301528) (xy 307.306892 -150.355482)
			(xy 307.291539 -150.407783) (xy 307.268898 -150.457366) (xy 307.241123 -150.500588) (xy 334.204056 -150.500588)
			(xy 334.204616 -150.471672) (xy 334.213334 -150.414502) (xy 334.230582 -150.359303) (xy 334.255966 -150.307341)
			(xy 334.288903 -150.259806) (xy 334.328639 -150.217789) (xy 334.351122 -150.199598) (xy 334.359884 -150.192037)
			(xy 334.370067 -150.171277) (xy 334.37068 -150.15972) (xy 334.37068 -150.079456) (xy 334.370084 -150.067891)
			(xy 334.359908 -150.047119) (xy 334.351122 -150.039578) (xy 334.328633 -150.021394) (xy 334.288897 -149.979373)
			(xy 334.255958 -149.931837) (xy 334.23057 -149.879874) (xy 334.213316 -149.824675) (xy 334.204589 -149.767505)
			(xy 334.204056 -149.738588) (xy 334.204542 -149.711337) (xy 334.212298 -149.657389) (xy 334.227653 -149.605094)
			(xy 334.250295 -149.555517) (xy 334.279761 -149.509667) (xy 334.315452 -149.468476) (xy 334.356643 -149.432785)
			(xy 334.402493 -149.403319) (xy 334.45207 -149.380677) (xy 334.504365 -149.365322) (xy 334.558313 -149.357566)
			(xy 334.612815 -149.357566) (xy 334.666763 -149.365322) (xy 334.719058 -149.380677) (xy 334.768635 -149.403319)
			(xy 334.814485 -149.432785) (xy 334.855676 -149.468476) (xy 334.891367 -149.509667) (xy 334.920833 -149.555517)
			(xy 334.943475 -149.605094) (xy 334.95883 -149.657389) (xy 334.966586 -149.711337) (xy 334.967072 -149.738588)
			(xy 334.966556 -149.767505) (xy 334.957828 -149.824677) (xy 334.94057 -149.879876) (xy 334.915178 -149.931838)
			(xy 334.882234 -149.979372) (xy 334.842492 -150.021388) (xy 334.820006 -150.039578) (xy 334.811259 -150.047155)
			(xy 334.801067 -150.067902) (xy 334.800448 -150.079456) (xy 334.800448 -150.15972) (xy 334.801048 -150.171285)
			(xy 334.81122 -150.192057) (xy 334.820006 -150.199598) (xy 334.84249 -150.217789) (xy 334.882225 -150.259809)
			(xy 334.915163 -150.307344) (xy 334.940552 -150.359305) (xy 334.957808 -150.414503) (xy 334.966537 -150.471672)
			(xy 334.967072 -150.500588) (xy 336.261456 -150.500588) (xy 336.262016 -150.471672) (xy 336.270734 -150.414502)
			(xy 336.287982 -150.359303) (xy 336.313366 -150.307341) (xy 336.346303 -150.259806) (xy 336.386039 -150.217789)
			(xy 336.408522 -150.199598) (xy 336.417284 -150.192037) (xy 336.427467 -150.171277) (xy 336.42808 -150.15972)
			(xy 336.42808 -150.079456) (xy 336.427484 -150.067891) (xy 336.417308 -150.047119) (xy 336.408522 -150.039578)
			(xy 336.386033 -150.021394) (xy 336.346297 -149.979373) (xy 336.313358 -149.931837) (xy 336.28797 -149.879874)
			(xy 336.270716 -149.824675) (xy 336.261989 -149.767505) (xy 336.261456 -149.738588) (xy 336.261942 -149.711337)
			(xy 336.269698 -149.657389) (xy 336.285053 -149.605094) (xy 336.307695 -149.555517) (xy 336.337161 -149.509667)
			(xy 336.372852 -149.468476) (xy 336.414043 -149.432785) (xy 336.459893 -149.403319) (xy 336.50947 -149.380677)
			(xy 336.561765 -149.365322) (xy 336.615713 -149.357566) (xy 336.670215 -149.357566) (xy 336.724163 -149.365322)
			(xy 336.776458 -149.380677) (xy 336.826035 -149.403319) (xy 336.871885 -149.432785) (xy 336.913076 -149.468476)
			(xy 336.948767 -149.509667) (xy 336.978233 -149.555517) (xy 337.000875 -149.605094) (xy 337.01623 -149.657389)
			(xy 337.023986 -149.711337) (xy 337.024472 -149.738588) (xy 337.023956 -149.767505) (xy 337.015228 -149.824677)
			(xy 336.99797 -149.879876) (xy 336.972578 -149.931838) (xy 336.939634 -149.979372) (xy 336.899892 -150.021388)
			(xy 336.877406 -150.039578) (xy 336.868659 -150.047155) (xy 336.858467 -150.067902) (xy 336.857848 -150.079456)
			(xy 336.857848 -150.15972) (xy 336.858448 -150.171285) (xy 336.86862 -150.192057) (xy 336.877406 -150.199598)
			(xy 336.89989 -150.217789) (xy 336.939625 -150.259809) (xy 336.972563 -150.307344) (xy 336.997952 -150.359305)
			(xy 337.015208 -150.414503) (xy 337.023937 -150.471672) (xy 337.024472 -150.500588) (xy 337.023986 -150.527839)
			(xy 337.01623 -150.581787) (xy 337.000875 -150.634082) (xy 336.978233 -150.683659) (xy 336.948767 -150.729509)
			(xy 336.913076 -150.7707) (xy 336.871885 -150.806391) (xy 336.826035 -150.835857) (xy 336.776458 -150.858499)
			(xy 336.724163 -150.873854) (xy 336.670215 -150.88161) (xy 336.615713 -150.88161) (xy 336.561765 -150.873854)
			(xy 336.50947 -150.858499) (xy 336.459893 -150.835857) (xy 336.414043 -150.806391) (xy 336.372852 -150.7707)
			(xy 336.337161 -150.729509) (xy 336.307695 -150.683659) (xy 336.285053 -150.634082) (xy 336.269698 -150.581787)
			(xy 336.261942 -150.527839) (xy 336.261456 -150.500588) (xy 334.967072 -150.500588) (xy 334.966586 -150.527839)
			(xy 334.95883 -150.581787) (xy 334.943475 -150.634082) (xy 334.920833 -150.683659) (xy 334.891367 -150.729509)
			(xy 334.855676 -150.7707) (xy 334.814485 -150.806391) (xy 334.768635 -150.835857) (xy 334.719058 -150.858499)
			(xy 334.666763 -150.873854) (xy 334.612815 -150.88161) (xy 334.558313 -150.88161) (xy 334.504365 -150.873854)
			(xy 334.45207 -150.858499) (xy 334.402493 -150.835857) (xy 334.356643 -150.806391) (xy 334.315452 -150.7707)
			(xy 334.279761 -150.729509) (xy 334.250295 -150.683659) (xy 334.227653 -150.634082) (xy 334.212298 -150.581787)
			(xy 334.204542 -150.527839) (xy 334.204056 -150.500588) (xy 307.241123 -150.500588) (xy 307.23943 -150.503223)
			(xy 307.203737 -150.544418) (xy 307.162543 -150.580115) (xy 307.116689 -150.609585) (xy 307.067107 -150.63223)
			(xy 307.014807 -150.647587) (xy 306.960854 -150.655345) (xy 306.9336 -150.655782) (xy 306.912854 -150.655466)
			(xy 306.871614 -150.650883) (xy 306.851304 -150.646638) (xy 306.839204 -150.644706) (xy 306.815583 -150.651079)
			(xy 306.806092 -150.65883) (xy 306.803298 -150.66137) (xy 306.733956 -150.73503) (xy 306.727606 -150.760938)
			(xy 306.731416 -150.773892) (xy 306.740547 -150.808093) (xy 306.75036 -150.878198) (xy 306.750974 -150.913592)
			(xy 306.750499 -150.945131) (xy 306.742698 -151.007724) (xy 306.727214 -151.068871) (xy 306.704287 -151.127633)
			(xy 306.674266 -151.183109) (xy 306.637615 -151.234445) (xy 306.594895 -151.280853) (xy 306.546763 -151.321621)
			(xy 306.493957 -151.356123) (xy 306.43729 -151.383827) (xy 306.377631 -151.40431) (xy 306.315897 -151.417257)
			(xy 306.253036 -151.422467) (xy 306.190012 -151.419863) (xy 306.127795 -151.409483) (xy 306.067339 -151.391487)
			(xy 306.009574 -151.366151) (xy 305.955386 -151.333865) (xy 305.905608 -151.295124) (xy 305.861004 -151.250524)
			(xy 305.822259 -151.200749) (xy 305.789968 -151.146563) (xy 305.764628 -151.0888) (xy 305.746627 -151.028346)
			(xy 305.736241 -150.96613) (xy 305.733632 -150.903106) (xy 305.738837 -150.840244) (xy 305.751779 -150.778509)
			(xy 305.772256 -150.718849) (xy 305.799957 -150.662179) (xy 305.834454 -150.609371) (xy 305.875218 -150.561236)
			(xy 305.921622 -150.518512) (xy 305.972956 -150.481856) (xy 306.028428 -150.451831) (xy 306.087189 -150.428898)
			(xy 306.148335 -150.41341) (xy 306.210927 -150.405604) (xy 306.242466 -150.405084) (xy 306.272661 -150.405532)
			(xy 306.332622 -150.412717) (xy 306.39131 -150.426955) (xy 306.419758 -150.437088) (xy 306.432458 -150.44166)
			(xy 306.45862 -150.437342) (xy 306.536852 -150.374604) (xy 306.545365 -150.366973) (xy 306.555258 -150.346395)
			(xy 306.555902 -150.33498) (xy 306.555902 -150.32736) (xy 306.555394 -150.324058) (xy 306.553859 -150.311669)
			(xy 306.552207 -150.286757) (xy 306.552092 -150.274274) (xy 306.552626 -150.24501) (xy 306.561569 -150.18717)
			(xy 306.57924 -150.131374) (xy 306.605225 -150.078931) (xy 306.638915 -150.031073) (xy 306.679519 -149.98892)
			(xy 306.70246 -149.970744) (xy 306.710313 -149.964175) (xy 306.720454 -149.946409) (xy 306.722869 -149.926095)
			(xy 306.720494 -149.916134) (xy 306.719478 -149.912578) (xy 306.716208 -149.903106) (xy 306.703677 -149.887495)
			(xy 306.686127 -149.877868) (xy 306.666228 -149.875689) (xy 306.656486 -149.878034) (xy 306.649628 -149.880066)
			(xy 306.643532 -149.883876) (xy 306.612963 -149.902412) (xy 306.547731 -149.93166) (xy 306.479044 -149.951481)
			(xy 306.408259 -149.961484) (xy 306.372514 -149.962108) (xy 306.340936 -149.961598) (xy 306.278275 -149.953708)
			(xy 306.217076 -149.93811) (xy 306.158282 -149.915044) (xy 306.102802 -149.884867) (xy 306.076858 -149.866858)
			(xy 306.070215 -149.862505) (xy 306.055078 -149.857727) (xy 306.04714 -149.85746) (xy 305.254914 -149.85746)
			(xy 305.244644 -149.85798) (xy 305.225771 -149.866102) (xy 305.218338 -149.873208) (xy 305.170586 -149.922992)
			(xy 305.163698 -149.93085) (xy 305.15635 -149.950389) (xy 305.156362 -149.960838) (xy 305.157124 -149.987)
			(xy 305.156676 -150.017916) (xy 305.149223 -150.079296) (xy 305.134425 -150.13933) (xy 305.112498 -150.197143)
			(xy 305.083763 -150.251892) (xy 305.048637 -150.302777) (xy 305.007634 -150.349057) (xy 304.961352 -150.390057)
			(xy 304.910464 -150.425179) (xy 304.855714 -150.453911) (xy 304.7979 -150.475834) (xy 304.737865 -150.490628)
			(xy 304.676484 -150.498078) (xy 304.645568 -150.498556) (xy 304.614806 -150.498097) (xy 304.553728 -150.490714)
			(xy 304.493976 -150.476058) (xy 304.436413 -150.454342) (xy 304.38187 -150.425879) (xy 304.331135 -150.391079)
			(xy 304.28494 -150.350445) (xy 304.243952 -150.304564) (xy 304.22596 -150.279608) (xy 304.220634 -150.272658)
			(xy 304.206349 -150.26255) (xy 304.189504 -150.257814) (xy 304.180748 -150.258018) (xy 304.083974 -150.264876)
			(xy 304.061622 -150.279862) (xy 304.055526 -150.2918) (xy 304.043258 -150.315059) (xy 304.01329 -150.358269)
			(xy 303.977675 -150.396957) (xy 303.937085 -150.430388) (xy 303.892291 -150.457932) (xy 303.844139 -150.479065)
			(xy 303.793542 -150.493388) (xy 303.741458 -150.500629) (xy 303.715166 -150.501096) (xy 303.687917 -150.500607)
			(xy 303.633973 -150.492847) (xy 303.581683 -150.477489) (xy 303.532111 -150.454845) (xy 303.486266 -150.425378)
			(xy 303.445081 -150.389686) (xy 303.409394 -150.348497) (xy 303.379932 -150.302648) (xy 303.357295 -150.253073)
			(xy 303.341943 -150.200782) (xy 303.334189 -150.146837) (xy 303.333658 -150.119588) (xy 303.333658 -150.11908)
			(xy 303.334315 -150.086762) (xy 303.345167 -150.023046) (xy 303.355248 -149.992334) (xy 303.358606 -149.980589)
			(xy 303.35515 -149.956446) (xy 303.348644 -149.946106) (xy 303.300892 -149.878796) (xy 303.293278 -149.869282)
			(xy 303.271656 -149.858122) (xy 303.25949 -149.85746) (xy 303.066196 -149.85746) (xy 303.042066 -149.872192)
			(xy 303.040542 -149.874986) (xy 303.031509 -149.899788) (xy 303.007595 -149.946846) (xy 302.977456 -149.990182)
			(xy 302.941662 -150.028976) (xy 302.900887 -150.062498) (xy 302.855901 -150.090113) (xy 302.807555 -150.111301)
			(xy 302.75676 -150.125661) (xy 302.704477 -150.132922) (xy 302.678084 -150.133304) (xy 302.649377 -150.132798)
			(xy 302.592606 -150.124244) (xy 302.537746 -150.107313) (xy 302.486027 -150.082385) (xy 302.438607 -150.050019)
			(xy 302.396547 -150.01094) (xy 302.36079 -149.966021) (xy 302.332137 -149.91627) (xy 302.321214 -149.889718)
			(xy 302.317078 -149.880415) (xy 302.302879 -149.865848) (xy 302.284141 -149.85793) (xy 302.27397 -149.85746)
			(xy 302.175926 -149.85746) (xy 302.169553 -149.857688) (xy 302.157214 -149.860896) (xy 302.151542 -149.86381)
			(xy 302.13173 -149.874732) (xy 302.121824 -149.88159) (xy 302.11776 -149.8854) (xy 302.114204 -149.890226)
			(xy 302.11395 -149.890734) (xy 302.097371 -149.913636) (xy 302.058565 -149.954749) (xy 302.014118 -149.989689)
			(xy 301.965004 -150.017691) (xy 301.912296 -150.038141) (xy 301.857149 -150.050593) (xy 301.800768 -150.054774)
			(xy 301.744387 -150.050593) (xy 301.68924 -150.038141) (xy 301.636532 -150.017691) (xy 301.587418 -149.989689)
			(xy 301.542971 -149.954749) (xy 301.504165 -149.913636) (xy 301.487586 -149.890734) (xy 301.487332 -149.890226)
			(xy 301.483776 -149.8854) (xy 301.479712 -149.88159) (xy 301.469806 -149.874732) (xy 301.449994 -149.86381)
			(xy 301.444329 -149.860875) (xy 301.431987 -149.857663) (xy 301.42561 -149.85746) (xy 300.379384 -149.85746)
			(xy 300.378876 -149.85746) (xy 296.256964 -149.85746) (xy 296.225197 -149.857003) (xy 296.162064 -149.849868)
			(xy 296.100125 -149.835715) (xy 296.040159 -149.814722) (xy 295.982917 -149.787151) (xy 295.92912 -149.75335)
			(xy 295.879442 -149.713742) (xy 295.85666 -149.691598) (xy 295.1099 -148.944838) (xy 295.102492 -148.93815)
			(xy 295.084056 -148.930562) (xy 295.074086 -148.930106) (xy 295.064434 -148.930106) (xy 293.914068 -147.77974)
			(xy 293.911216 -147.777035) (xy 293.904836 -147.772446) (xy 293.901368 -147.770596) (xy 293.895941 -147.768012)
			(xy 293.884262 -147.765186) (xy 293.878254 -147.765008) (xy 291.29609 -147.765008) (xy 291.290079 -147.765171)
			(xy 291.278393 -147.767987) (xy 291.272976 -147.770596) (xy 291.269502 -147.772436) (xy 291.263123 -147.77703)
			(xy 291.260276 -147.77974) (xy 290.271454 -148.768562) (xy 290.268746 -148.771411) (xy 290.264147 -148.777787)
			(xy 290.26231 -148.781262) (xy 290.259728 -148.786689) (xy 290.256908 -148.798369) (xy 290.256722 -148.804376)
			(xy 290.256722 -150.5389) (xy 298.703032 -150.5389) (xy 298.707045 -150.475109) (xy 298.719022 -150.412325)
			(xy 298.738773 -150.351536) (xy 298.765988 -150.293703) (xy 298.800236 -150.239736) (xy 298.840978 -150.190487)
			(xy 298.887571 -150.146733) (xy 298.939281 -150.109164) (xy 298.995292 -150.078372) (xy 299.05472 -150.054842)
			(xy 299.116629 -150.038947) (xy 299.180042 -150.030936) (xy 299.212 -150.030434) (xy 299.242207 -150.030853)
			(xy 299.302193 -150.038022) (xy 299.360908 -150.052247) (xy 299.417524 -150.073328) (xy 299.471244 -150.100967)
			(xy 299.521311 -150.134777) (xy 299.56702 -150.174279) (xy 299.607728 -150.218918) (xy 299.64286 -150.268066)
			(xy 299.65777 -150.29434) (xy 299.663972 -150.30434) (xy 299.68331 -150.317705) (xy 299.694854 -150.319994)
			(xy 299.78731 -150.333456) (xy 299.809916 -150.325836) (xy 299.818298 -150.317454) (xy 299.839852 -150.296867)
			(xy 299.888198 -150.262012) (xy 299.941379 -150.235102) (xy 299.998098 -150.216794) (xy 300.056975 -150.207533)
			(xy 300.086776 -150.206964) (xy 300.08703 -150.206964) (xy 300.114278 -150.207508) (xy 300.168218 -150.215268)
			(xy 300.220506 -150.230624) (xy 300.270075 -150.253265) (xy 300.315918 -150.28273) (xy 300.357102 -150.318419)
			(xy 300.392788 -150.359606) (xy 300.422249 -150.405451) (xy 300.444886 -150.455023) (xy 300.460239 -150.507311)
			(xy 300.467994 -150.561252) (xy 300.467994 -150.615748) (xy 300.460239 -150.669689) (xy 300.444886 -150.721977)
			(xy 300.422249 -150.771549) (xy 300.392788 -150.817394) (xy 300.357102 -150.858581) (xy 300.315919 -150.89427)
			(xy 300.270075 -150.923735) (xy 300.220506 -150.946376) (xy 300.168218 -150.961732) (xy 300.114278 -150.969492)
			(xy 300.08703 -150.96998) (xy 300.058586 -150.969419) (xy 300.002328 -150.96097) (xy 299.94795 -150.944255)
			(xy 299.89666 -150.919646) (xy 299.849596 -150.887688) (xy 299.807803 -150.849092) (xy 299.789596 -150.827232)
			(xy 299.789342 -150.826978) (xy 299.781452 -150.818329) (xy 299.760153 -150.808671) (xy 299.748448 -150.808436)
			(xy 299.667168 -150.810976) (xy 299.65544 -150.811917) (xy 299.634661 -150.822889) (xy 299.62729 -150.832058)
			(xy 299.62729 -150.832312) (xy 299.609419 -150.856891) (xy 299.5687 -150.902004) (xy 299.522891 -150.94194)
			(xy 299.472647 -150.976128) (xy 299.418684 -151.00408) (xy 299.361773 -151.025398) (xy 299.302727 -151.039777)
			(xy 299.242386 -151.047012) (xy 299.212 -151.04745) (xy 299.180042 -151.046864) (xy 299.116629 -151.038853)
			(xy 299.05472 -151.022958) (xy 298.995292 -150.999428) (xy 298.939281 -150.968636) (xy 298.887571 -150.931067)
			(xy 298.840978 -150.887313) (xy 298.800236 -150.838064) (xy 298.765988 -150.784097) (xy 298.738773 -150.726264)
			(xy 298.719022 -150.665475) (xy 298.707045 -150.602691) (xy 298.703032 -150.5389) (xy 290.256722 -150.5389)
			(xy 290.256722 -153.958036) (xy 304.271934 -153.958036) (xy 304.272469 -153.918141) (xy 304.28081 -153.838788)
			(xy 304.297393 -153.76074) (xy 304.322038 -153.684851) (xy 304.354474 -153.611951) (xy 304.394347 -153.542838)
			(xy 304.44122 -153.478267) (xy 304.467514 -153.448258) (xy 304.473514 -153.441071) (xy 304.480161 -153.42358)
			(xy 304.480468 -153.414222) (xy 304.480468 -153.38425) (xy 304.480067 -153.374912) (xy 304.473418 -153.35746)
			(xy 304.467514 -153.350214) (xy 304.441201 -153.32022) (xy 304.394319 -153.255652) (xy 304.354441 -153.186538)
			(xy 304.322003 -153.113635) (xy 304.297361 -153.037742) (xy 304.280783 -152.95969) (xy 304.272452 -152.880333)
			(xy 304.271934 -152.840436) (xy 304.272423 -152.801791) (xy 304.280243 -152.724897) (xy 304.295801 -152.649189)
			(xy 304.318939 -152.575443) (xy 304.349419 -152.504416) (xy 304.386928 -152.436838) (xy 304.431082 -152.3734)
			(xy 304.481427 -152.314756) (xy 304.537446 -152.261505) (xy 304.598565 -152.214195) (xy 304.664158 -152.173311)
			(xy 304.733549 -152.139273) (xy 304.806029 -152.11243) (xy 304.880852 -152.093057) (xy 304.957251 -152.081353)
			(xy 305.034442 -152.077438) (xy 305.111633 -152.081353) (xy 305.188032 -152.093057) (xy 305.262855 -152.11243)
			(xy 305.335335 -152.139273) (xy 305.404726 -152.173311) (xy 305.470319 -152.214195) (xy 305.531438 -152.261505)
			(xy 305.587457 -152.314756) (xy 305.637802 -152.3734) (xy 305.681956 -152.436838) (xy 305.719465 -152.504416)
			(xy 305.749945 -152.575443) (xy 305.773083 -152.649189) (xy 305.788641 -152.724897) (xy 305.796461 -152.801791)
			(xy 305.79695 -152.840436) (xy 305.796438 -152.880332) (xy 305.788091 -152.959685) (xy 305.771502 -153.037733)
			(xy 305.746853 -153.113621) (xy 305.714414 -153.186521) (xy 305.674539 -153.255634) (xy 305.627664 -153.320205)
			(xy 305.60137 -153.350214) (xy 305.59538 -153.357409) (xy 305.588727 -153.374894) (xy 305.588416 -153.38425)
			(xy 305.588416 -153.414222) (xy 305.588834 -153.423558) (xy 305.595472 -153.44101) (xy 305.60137 -153.448258)
			(xy 305.627667 -153.478266) (xy 305.67455 -153.542831) (xy 305.714431 -153.611943) (xy 305.746871 -153.684843)
			(xy 305.771516 -153.760733) (xy 305.788097 -153.838784) (xy 305.796431 -153.91814) (xy 305.79695 -153.958036)
			(xy 305.796461 -153.996681) (xy 305.788641 -154.073575) (xy 305.773083 -154.149283) (xy 305.749945 -154.223029)
			(xy 305.719465 -154.294056) (xy 305.681956 -154.361634) (xy 305.637802 -154.425072) (xy 305.587457 -154.483716)
			(xy 305.531438 -154.536967) (xy 305.470319 -154.584277) (xy 305.404726 -154.625161) (xy 305.335335 -154.659199)
			(xy 305.262855 -154.686042) (xy 305.188032 -154.705415) (xy 305.111633 -154.717119) (xy 305.034442 -154.721034)
			(xy 304.957251 -154.717119) (xy 304.880852 -154.705415) (xy 304.806029 -154.686042) (xy 304.733549 -154.659199)
			(xy 304.664158 -154.625161) (xy 304.598565 -154.584277) (xy 304.537446 -154.536967) (xy 304.481427 -154.483716)
			(xy 304.431082 -154.425072) (xy 304.386928 -154.361634) (xy 304.349419 -154.294056) (xy 304.318939 -154.223029)
			(xy 304.295801 -154.149283) (xy 304.280243 -154.073575) (xy 304.272423 -153.996681) (xy 304.271934 -153.958036)
			(xy 290.256722 -153.958036) (xy 290.256722 -157.62732) (xy 290.257738 -157.636972) (xy 290.259368 -157.644214)
			(xy 290.266214 -157.657379) (xy 290.2712 -157.66288) (xy 291.615622 -159.007302) (xy 291.621121 -159.01229)
			(xy 291.634287 -159.019134) (xy 291.64153 -159.020764) (xy 291.651182 -159.02178) (xy 317.802768 -159.02178)
			(xy 317.805054 -159.02178) (xy 317.815544 -159.020776) (xy 317.834426 -159.011472) (xy 317.848009 -158.995389)
			(xy 317.851536 -158.985458) (xy 317.88157 -158.887068) (xy 317.948333 -158.69246) (xy 318.022639 -158.500606)
			(xy 318.104374 -158.311797) (xy 318.193413 -158.12632) (xy 318.289621 -157.944459) (xy 318.392853 -157.766491)
			(xy 318.502949 -157.592685) (xy 318.619743 -157.423308) (xy 318.743057 -157.258617) (xy 318.872703 -157.098863)
			(xy 319.008483 -156.944289) (xy 319.150192 -156.79513) (xy 319.297612 -156.651614) (xy 319.45052 -156.51396)
			(xy 319.608682 -156.382376) (xy 319.771858 -156.257064) (xy 319.939799 -156.138214) (xy 320.025776 -156.08173)
			(xy 320.111477 -156.02656) (xy 320.286514 -155.922088) (xy 320.465459 -155.824461) (xy 320.648044 -155.733825)
			(xy 320.833997 -155.650315) (xy 321.023039 -155.574057) (xy 321.214889 -155.505165) (xy 321.409258 -155.44374)
			(xy 321.605857 -155.389877) (xy 321.804391 -155.343653) (xy 322.004563 -155.30514) (xy 322.206075 -155.274395)
			(xy 322.408625 -155.251463) (xy 322.61191 -155.236378) (xy 322.815626 -155.229164) (xy 323.019469 -155.229831)
			(xy 323.223134 -155.238378) (xy 323.426316 -155.254793) (xy 323.628711 -155.27905) (xy 323.830018 -155.311114)
			(xy 324.029934 -155.350936) (xy 324.228161 -155.398458) (xy 324.424403 -155.453607) (xy 324.618366 -155.516302)
			(xy 324.80976 -155.586449) (xy 324.9983 -155.663943) (xy 325.183702 -155.748667) (xy 325.365691 -155.840496)
			(xy 325.543993 -155.939292) (xy 325.718342 -156.044908) (xy 325.888478 -156.157185) (xy 326.054146 -156.275955)
			(xy 326.215099 -156.401042) (xy 326.371095 -156.532257) (xy 326.521902 -156.669405) (xy 326.667294 -156.812281)
			(xy 326.807054 -156.960671) (xy 326.940972 -157.114353) (xy 327.068849 -157.273098) (xy 327.190493 -157.436667)
			(xy 327.305723 -157.604818) (xy 327.414366 -157.777297) (xy 327.516259 -157.953847) (xy 327.611251 -158.134205)
			(xy 327.699199 -158.3181) (xy 327.779972 -158.505258) (xy 327.853449 -158.695399) (xy 327.91952 -158.888238)
			(xy 327.949306 -158.985712) (xy 327.950322 -158.989268) (xy 327.954423 -158.998676) (xy 327.968673 -159.013419)
			(xy 327.987566 -159.021385) (xy 327.99782 -159.02178) (xy 328.473054 -159.497014) (xy 328.473562 -159.497522)
			(xy 328.480942 -159.504106) (xy 328.499242 -159.511558) (xy 328.509122 -159.512)
		)
		(stroke
			(width 0)
			(type solid)
		)
		(fill yes)
		(layer "In6.Cu")
		(net "PVDD18_S5_P0")
	)
	(gr_poly
		(pts
			(xy 314.94857 -365.428784) (xy 314.955813 -365.427155) (xy 314.96898 -365.420311) (xy 314.974478 -365.415322)
			(xy 315.216032 -365.173768) (xy 315.22073 -365.168757) (xy 315.227433 -365.156773) (xy 315.22924 -365.150146)
			(xy 315.231018 -365.143542) (xy 315.230764 -365.130842) (xy 315.228732 -365.12373) (xy 315.221621 -365.097634)
			(xy 315.213967 -365.044093) (xy 315.213492 -365.01705) (xy 315.213952 -364.989795) (xy 315.221703 -364.935838)
			(xy 315.237055 -364.883535) (xy 315.259694 -364.833948) (xy 315.289161 -364.788089) (xy 315.324855 -364.74689)
			(xy 315.366049 -364.711191) (xy 315.411904 -364.681718) (xy 315.461488 -364.659072) (xy 315.51379 -364.643714)
			(xy 315.567745 -364.635955) (xy 315.595 -364.635542) (xy 315.62198 -364.636027) (xy 315.675394 -364.643679)
			(xy 315.701426 -364.650782) (xy 315.701934 -364.650782) (xy 315.702188 -364.651036) (xy 315.708568 -364.652574)
			(xy 315.721686 -364.652697) (xy 315.728096 -364.65129) (xy 315.734954 -364.649766) (xy 315.746892 -364.642908)
			(xy 316.228222 -364.161578) (xy 316.233209 -364.156079) (xy 316.240051 -364.142912) (xy 316.241684 -364.13567)
			(xy 316.2427 -364.126018) (xy 316.2427 -363.824266) (xy 316.24143 -363.812582) (xy 316.237556 -363.794992)
			(xy 316.233354 -363.759217) (xy 316.233048 -363.741208) (xy 316.233048 -360.28757) (xy 316.232624 -360.279053)
			(xy 316.225801 -360.263443) (xy 316.21984 -360.257344) (xy 316.200195 -360.238739) (xy 316.165704 -360.197053)
			(xy 316.137285 -360.151011) (xy 316.115483 -360.101493) (xy 316.100713 -360.049442) (xy 316.093257 -359.995853)
			(xy 316.093257 -359.941747) (xy 316.100713 -359.888158) (xy 316.115483 -359.836107) (xy 316.137285 -359.786589)
			(xy 316.165704 -359.740547) (xy 316.200195 -359.698861) (xy 316.21984 -359.680256) (xy 316.225811 -359.674165)
			(xy 316.232631 -359.65855) (xy 316.233048 -359.65003) (xy 316.233048 -356.96398) (xy 316.232655 -356.955922)
			(xy 316.226501 -356.941027) (xy 316.22111 -356.935024) (xy 316.21349 -356.927404) (xy 316.206886 -356.919784)
			(xy 316.189106 -356.897432) (xy 316.180724 -356.888542) (xy 316.172596 -356.881684) (xy 316.16396 -356.874572)
			(xy 316.159596 -356.871169) (xy 316.14973 -356.86616) (xy 316.144402 -356.864666) (xy 316.133734 -356.861872)
			(xy 316.122304 -356.863904) (xy 316.104939 -356.866966) (xy 316.069831 -356.870273) (xy 316.0522 -356.870508)
			(xy 316.024949 -356.870022) (xy 315.971001 -356.862266) (xy 315.918706 -356.846911) (xy 315.869129 -356.824269)
			(xy 315.823279 -356.794803) (xy 315.782088 -356.759112) (xy 315.746397 -356.717921) (xy 315.716931 -356.672071)
			(xy 315.694289 -356.622494) (xy 315.678934 -356.570199) (xy 315.671178 -356.516251) (xy 315.671178 -356.461749)
			(xy 315.678934 -356.407801) (xy 315.694289 -356.355506) (xy 315.716931 -356.305929) (xy 315.746397 -356.260079)
			(xy 315.782088 -356.218888) (xy 315.823279 -356.183197) (xy 315.869129 -356.153731) (xy 315.918706 -356.131089)
			(xy 315.971001 -356.115734) (xy 316.024949 -356.107978) (xy 316.0522 -356.107492) (xy 316.069832 -356.107711)
			(xy 316.104942 -356.111015) (xy 316.122304 -356.114096) (xy 316.133734 -356.116128) (xy 316.144402 -356.113334)
			(xy 316.149718 -356.111807) (xy 316.159584 -356.10681) (xy 316.16396 -356.103428) (xy 316.172342 -356.09657)
			(xy 316.17285 -356.096062) (xy 316.180724 -356.089458) (xy 316.189106 -356.080568) (xy 316.206886 -356.058216)
			(xy 316.21349 -356.050596) (xy 316.22111 -356.042976) (xy 316.226501 -356.036977) (xy 316.232628 -356.022076)
			(xy 316.233048 -356.01402) (xy 316.233048 -353.771708) (xy 316.233338 -353.753698) (xy 316.237538 -353.717921)
			(xy 316.24143 -353.700334) (xy 316.2427 -353.68865) (xy 316.2427 -353.411282) (xy 316.242536 -353.405271)
			(xy 316.239719 -353.393586) (xy 316.237112 -353.388168) (xy 316.235272 -353.384694) (xy 316.230678 -353.378316)
			(xy 316.227968 -353.375468) (xy 316.219332 -353.366832) (xy 316.216482 -353.364125) (xy 316.210105 -353.359528)
			(xy 316.206632 -353.357688) (xy 316.201204 -353.355108) (xy 316.189525 -353.352291) (xy 316.183518 -353.3521)
			(xy 315.095128 -353.3521) (xy 315.090238 -353.351961) (xy 315.080647 -353.35004) (xy 315.076078 -353.34829)
			(xy 315.055504 -353.339908) (xy 315.052456 -353.339654) (xy 315.046868 -353.3394) (xy 315.023158 -353.337486)
			(xy 314.97701 -353.325975) (xy 314.955174 -353.31654) (xy 314.950622 -353.315069) (xy 314.941161 -353.313668)
			(xy 314.936378 -353.313746) (xy 314.909454 -353.314508) (xy 314.908946 -353.314508) (xy 314.881707 -353.314005)
			(xy 314.827786 -353.306219) (xy 314.775522 -353.290842) (xy 314.725977 -353.268186) (xy 314.680158 -353.238713)
			(xy 314.638998 -353.203022) (xy 314.603334 -353.161838) (xy 314.573892 -353.116) (xy 314.551269 -353.06644)
			(xy 314.535927 -353.014165) (xy 314.528177 -352.96024) (xy 314.527692 -352.933) (xy 314.527692 -352.932238)
			(xy 314.527989 -352.911102) (xy 314.532698 -352.869094) (xy 314.53709 -352.848418) (xy 314.53709 -352.848164)
			(xy 314.538359 -352.841789) (xy 314.537969 -352.8288) (xy 314.536328 -352.82251) (xy 314.534296 -352.815398)
			(xy 314.520247 -352.806117) (xy 314.494026 -352.784991) (xy 314.481972 -352.773234) (xy 314.203842 -352.495104)
			(xy 314.191341 -352.482227) (xy 314.169064 -352.454088) (xy 314.159392 -352.43897) (xy 314.152026 -352.429826)
			(xy 314.060332 -352.338132) (xy 314.057482 -352.335425) (xy 314.051105 -352.330828) (xy 314.047632 -352.328988)
			(xy 314.042204 -352.326408) (xy 314.030525 -352.323591) (xy 314.024518 -352.3234) (xy 313.838082 -352.3234)
			(xy 313.832071 -352.323564) (xy 313.820386 -352.326381) (xy 313.814968 -352.328988) (xy 313.811494 -352.330828)
			(xy 313.805116 -352.335422) (xy 313.802268 -352.338132) (xy 313.349386 -352.791014) (xy 313.341991 -352.797868)
			(xy 313.323392 -352.80561) (xy 313.313318 -352.806) (xy 313.303158 -352.806) (xy 313.293174 -352.806545)
			(xy 313.274753 -352.814269) (xy 313.267344 -352.820986) (xy 312.723346 -353.3648) (xy 313.409582 -353.3648)
			(xy 313.413653 -353.309178) (xy 313.425779 -353.254741) (xy 313.445702 -353.20265) (xy 313.472998 -353.154015)
			(xy 313.507084 -353.109872) (xy 313.547233 -353.071163) (xy 313.592591 -353.038712) (xy 313.642191 -353.013211)
			(xy 313.694975 -352.995204) (xy 313.749818 -352.985074) (xy 313.805552 -352.983037) (xy 313.860989 -352.989137)
			(xy 313.914946 -353.003243) (xy 313.966275 -353.025055) (xy 314.013881 -353.054109) (xy 314.056749 -353.089784)
			(xy 314.093966 -353.131321) (xy 314.124739 -353.177834) (xy 314.148411 -353.228331) (xy 314.164479 -353.281738)
			(xy 314.172599 -353.336914) (xy 314.173108 -353.3648) (xy 314.172599 -353.392686) (xy 314.164479 -353.447862)
			(xy 314.148411 -353.501269) (xy 314.124739 -353.551766) (xy 314.093966 -353.598279) (xy 314.056749 -353.639816)
			(xy 314.013881 -353.675491) (xy 313.966275 -353.704545) (xy 313.914946 -353.726357) (xy 313.860989 -353.740463)
			(xy 313.805552 -353.746563) (xy 313.749818 -353.744526) (xy 313.694975 -353.734396) (xy 313.642191 -353.716389)
			(xy 313.592591 -353.690888) (xy 313.547233 -353.658437) (xy 313.507084 -353.619728) (xy 313.472998 -353.575585)
			(xy 313.445702 -353.52695) (xy 313.425779 -353.474859) (xy 313.413653 -353.420422) (xy 313.409582 -353.3648)
			(xy 312.723346 -353.3648) (xy 312.518298 -353.569778) (xy 312.517028 -353.571048) (xy 312.497171 -353.58976)
			(xy 312.45118 -353.619094) (xy 312.425842 -353.629214) (xy 312.415428 -353.634294) (xy 312.399426 -353.644962)
			(xy 312.395108 -353.649534) (xy 312.376977 -353.668444) (xy 312.336434 -353.701621) (xy 312.291734 -353.728943)
			(xy 312.243719 -353.749896) (xy 312.19329 -353.764088) (xy 312.141394 -353.771251) (xy 312.1152 -353.771708)
			(xy 312.087949 -353.771222) (xy 312.034001 -353.763466) (xy 311.981706 -353.748111) (xy 311.932129 -353.725469)
			(xy 311.886279 -353.696003) (xy 311.845088 -353.660312) (xy 311.809397 -353.619121) (xy 311.779931 -353.573271)
			(xy 311.757289 -353.523694) (xy 311.741934 -353.471399) (xy 311.734178 -353.417451) (xy 311.734178 -353.362949)
			(xy 311.741934 -353.309001) (xy 311.757289 -353.256706) (xy 311.779931 -353.207129) (xy 311.809397 -353.161279)
			(xy 311.845088 -353.120088) (xy 311.886279 -353.084397) (xy 311.932129 -353.054931) (xy 311.981706 -353.032289)
			(xy 312.034001 -353.016934) (xy 312.087949 -353.009178) (xy 312.1152 -353.008692) (xy 312.115454 -353.008692)
			(xy 312.143223 -353.009192) (xy 312.198173 -353.017255) (xy 312.251368 -353.033217) (xy 312.276744 -353.044506)
			(xy 312.283856 -353.047808) (xy 312.29935 -353.04984) (xy 312.30697 -353.04857) (xy 312.31461 -353.04693)
			(xy 312.32845 -353.039693) (xy 312.334148 -353.034346) (xy 312.476134 -352.89236) (xy 312.482338 -352.885567)
			(xy 312.489859 -352.868794) (xy 312.490963 -352.850444) (xy 312.48858 -352.84156) (xy 312.487564 -352.83902)
			(xy 312.46572 -352.824288) (xy 312.459313 -352.820259) (xy 312.444837 -352.81587) (xy 312.437272 -352.815652)
			(xy 311.861708 -352.815652) (xy 311.843762 -352.81534) (xy 311.808115 -352.811139) (xy 311.790588 -352.80727)
			(xy 311.778904 -352.806) (xy 310.967882 -352.806) (xy 310.961871 -352.806164) (xy 310.950186 -352.808981)
			(xy 310.944768 -352.811588) (xy 310.941294 -352.813428) (xy 310.934916 -352.818022) (xy 310.932068 -352.820732)
			(xy 310.186832 -353.565968) (xy 310.183637 -353.569339) (xy 310.178406 -353.57701) (xy 310.176418 -353.581208)
			(xy 310.172608 -353.58959) (xy 310.1721 -353.599242) (xy 310.170462 -353.624466) (xy 310.161361 -353.674189)
			(xy 310.145773 -353.722274) (xy 310.123973 -353.76788) (xy 310.096341 -353.810207) (xy 310.080152 -353.82962)
			(xy 310.076034 -353.835685) (xy 310.071138 -353.849495) (xy 310.0705 -353.856798) (xy 310.0705 -353.949)
			(xy 310.564782 -353.949) (xy 310.568853 -353.893378) (xy 310.580979 -353.838941) (xy 310.600902 -353.78685)
			(xy 310.628198 -353.738215) (xy 310.662284 -353.694072) (xy 310.702433 -353.655363) (xy 310.747791 -353.622912)
			(xy 310.797391 -353.597411) (xy 310.850175 -353.579404) (xy 310.905018 -353.569274) (xy 310.960752 -353.567237)
			(xy 311.016189 -353.573337) (xy 311.070146 -353.587443) (xy 311.121475 -353.609255) (xy 311.169081 -353.638309)
			(xy 311.211949 -353.673984) (xy 311.249166 -353.715521) (xy 311.279939 -353.762034) (xy 311.303611 -353.812531)
			(xy 311.319679 -353.865938) (xy 311.327799 -353.921114) (xy 311.328308 -353.949) (xy 311.327799 -353.976886)
			(xy 311.319679 -354.032062) (xy 311.303611 -354.085469) (xy 311.279939 -354.135966) (xy 311.249166 -354.182479)
			(xy 311.211949 -354.224016) (xy 311.169081 -354.259691) (xy 311.121475 -354.288745) (xy 311.070146 -354.310557)
			(xy 311.016189 -354.324663) (xy 310.960752 -354.330763) (xy 310.905018 -354.328726) (xy 310.850175 -354.318596)
			(xy 310.797391 -354.300589) (xy 310.747791 -354.275088) (xy 310.702433 -354.242637) (xy 310.662284 -354.203928)
			(xy 310.628198 -354.159785) (xy 310.600902 -354.11115) (xy 310.580979 -354.059059) (xy 310.568853 -354.004622)
			(xy 310.564782 -353.949) (xy 310.0705 -353.949) (xy 310.0705 -353.949254) (xy 310.07177 -353.960938)
			(xy 310.075634 -353.978466) (xy 310.079831 -354.014112) (xy 310.080152 -354.032058) (xy 310.080152 -354.839016)
			(xy 310.07986 -354.857026) (xy 310.075658 -354.892802) (xy 310.07177 -354.91039) (xy 310.0705 -354.922074)
			(xy 310.0705 -355.08692) (xy 310.070564 -355.090526) (xy 310.071587 -355.097664) (xy 310.072532 -355.101144)
			(xy 310.07812 -355.120448) (xy 310.081422 -355.126036) (xy 310.09404 -355.148191) (xy 310.113934 -355.195136)
			(xy 310.127399 -355.244311) (xy 310.134197 -355.294841) (xy 310.134206 -355.345827) (xy 310.131206 -355.371146)
			(xy 310.129505 -355.383077) (xy 310.1248 -355.406716) (xy 310.121808 -355.41839) (xy 310.114677 -355.443719)
			(xy 310.094418 -355.492283) (xy 310.081422 -355.515164) (xy 310.076342 -355.526848) (xy 310.072532 -355.540056)
			(xy 310.0705 -355.554026) (xy 310.0705 -355.796342) (xy 310.070754 -355.802184) (xy 310.072105 -355.810789)
			(xy 310.079772 -355.826417) (xy 310.092217 -355.838588) (xy 310.099964 -355.84257) (xy 310.10733 -355.845618)
			(xy 310.11622 -355.849174) (xy 310.130952 -355.84638) (xy 310.138292 -355.844643) (xy 310.151596 -355.837551)
			(xy 310.157114 -355.83241) (xy 310.778652 -355.210872) (xy 311.127902 -354.861368) (xy 311.145997 -354.844112)
			(xy 311.187543 -354.816303) (xy 311.233714 -354.79713) (xy 311.282738 -354.787329) (xy 311.307734 -354.786692)
			(xy 312.675016 -354.786692) (xy 312.684913 -354.786169) (xy 312.703203 -354.778584) (xy 312.710576 -354.77196)
			(xy 312.96356 -354.518976) (xy 312.966998 -354.515361) (xy 312.972508 -354.507047) (xy 312.974482 -354.502466)
			(xy 312.978292 -354.493322) (xy 312.978292 -354.482908) (xy 312.978721 -354.455631) (xy 312.986419 -354.401625)
			(xy 313.001731 -354.349267) (xy 313.024344 -354.299623) (xy 313.053799 -354.253706) (xy 313.089492 -354.212452)
			(xy 313.130698 -354.176703) (xy 313.176576 -354.147188) (xy 313.22619 -354.124508) (xy 313.278528 -354.109127)
			(xy 313.332524 -354.101357) (xy 313.3598 -354.100892) (xy 313.387064 -354.101356) (xy 313.441038 -354.10912)
			(xy 313.493356 -354.124489) (xy 313.542953 -354.14715) (xy 313.588818 -354.176641) (xy 313.630017 -354.212362)
			(xy 313.665711 -354.253585) (xy 313.695172 -354.29947) (xy 313.7178 -354.349083) (xy 313.733134 -354.401411)
			(xy 313.740862 -354.455389) (xy 313.740826 -354.509918) (xy 313.733026 -354.563886) (xy 313.717622 -354.616194)
			(xy 313.694928 -354.665776) (xy 313.665406 -354.711622) (xy 313.629658 -354.752797) (xy 313.588411 -354.788463)
			(xy 313.542506 -354.817894) (xy 313.492879 -354.840489) (xy 313.440541 -354.855788) (xy 313.386557 -354.86348)
			(xy 313.359292 -354.863908) (xy 313.348878 -354.863908) (xy 313.339734 -354.867718) (xy 313.33517 -354.869725)
			(xy 313.326856 -354.875224) (xy 313.323224 -354.87864) (xy 313.105292 -355.096572) (xy 312.981086 -355.221032)
			(xy 312.96299 -355.238287) (xy 312.921444 -355.266094) (xy 312.875273 -355.285265) (xy 312.82625 -355.295063)
			(xy 312.801254 -355.295708) (xy 312.337958 -355.295708) (xy 312.328489 -355.296073) (xy 312.310843 -355.302941)
			(xy 312.29693 -355.315785) (xy 312.292492 -355.324156) (xy 312.257694 -355.39553) (xy 312.25236 -355.406452)
			(xy 312.249444 -355.412965) (xy 312.247007 -355.42702) (xy 312.247534 -355.434138) (xy 312.248296 -355.440742)
			(xy 312.25363 -355.45395) (xy 312.258202 -355.459792) (xy 312.283812 -355.493404) (xy 312.328255 -355.56528)
			(xy 312.364479 -355.641629) (xy 312.39204 -355.721514) (xy 312.4106 -355.803957) (xy 312.419932 -355.887947)
			(xy 312.420508 -355.9302) (xy 312.420031 -355.968942) (xy 312.412175 -356.046027) (xy 312.396546 -356.121918)
			(xy 312.373303 -356.195834) (xy 312.342687 -356.267012) (xy 312.305012 -356.33472) (xy 312.260667 -356.39826)
			(xy 312.210109 -356.456976) (xy 312.153859 -356.510265) (xy 312.092496 -356.557576) (xy 312.059828 -356.578408)
			(xy 312.059574 -356.578408) (xy 312.054423 -356.581901) (xy 312.045818 -356.590888) (xy 312.042556 -356.596188)
			(xy 312.024014 -356.6287) (xy 312.024776 -356.637336) (xy 312.028078 -356.650036) (xy 312.033414 -356.672777)
			(xy 312.039148 -356.719136) (xy 312.039508 -356.742492) (xy 312.039508 -356.743) (xy 312.039022 -356.770251)
			(xy 312.031266 -356.824199) (xy 312.015911 -356.876494) (xy 311.993269 -356.926071) (xy 311.963803 -356.971921)
			(xy 311.928112 -357.013112) (xy 311.886921 -357.048803) (xy 311.841071 -357.078269) (xy 311.791494 -357.100911)
			(xy 311.739199 -357.116266) (xy 311.685251 -357.124022) (xy 311.630749 -357.124022) (xy 311.576801 -357.116266)
			(xy 311.524506 -357.100911) (xy 311.474929 -357.078269) (xy 311.429079 -357.048803) (xy 311.387888 -357.013112)
			(xy 311.352197 -356.971921) (xy 311.322731 -356.926071) (xy 311.300089 -356.876494) (xy 311.284734 -356.824199)
			(xy 311.276978 -356.770251) (xy 311.276492 -356.743) (xy 311.276492 -356.742492) (xy 311.276862 -356.719137)
			(xy 311.282596 -356.672779) (xy 311.287922 -356.650036) (xy 311.291224 -356.637336) (xy 311.291986 -356.6287)
			(xy 311.273444 -356.596188) (xy 311.270214 -356.590862) (xy 311.261608 -356.581864) (xy 311.256426 -356.578408)
			(xy 311.256172 -356.578408) (xy 311.224845 -356.55847) (xy 311.165826 -356.513398) (xy 311.11147 -356.4628)
			(xy 311.062292 -356.407155) (xy 311.018759 -356.346991) (xy 310.981284 -356.282879) (xy 310.950221 -356.215426)
			(xy 310.925865 -356.145272) (xy 310.908447 -356.073082) (xy 310.902858 -356.036372) (xy 310.902858 -356.036118)
			(xy 310.901617 -356.029099) (xy 310.895809 -356.016087) (xy 310.891428 -356.010464) (xy 310.88711 -356.00513)
			(xy 310.87568 -355.99751) (xy 310.847486 -355.988112) (xy 310.780684 -355.96576) (xy 310.768346 -355.962799)
			(xy 310.743542 -355.96799) (xy 310.73344 -355.975666) (xy 310.26862 -356.440232) (xy 310.253047 -356.455184)
			(xy 310.217826 -356.480143) (xy 310.178896 -356.498796) (xy 310.137376 -356.510607) (xy 310.115966 -356.513384)
			(xy 310.106717 -356.514791) (xy 310.090053 -356.523262) (xy 310.083454 -356.529894) (xy 310.078628 -356.535228)
			(xy 310.080152 -356.565708) (xy 310.080152 -356.945692) (xy 310.079862 -356.963702) (xy 310.075662 -356.999479)
			(xy 310.07177 -357.017066) (xy 310.0705 -357.02875) (xy 310.0705 -357.326692) (xy 310.070918 -357.336714)
			(xy 310.078587 -357.355234) (xy 310.092759 -357.369409) (xy 310.111278 -357.37708) (xy 310.1213 -357.377492)
			(xy 312.274204 -357.377492) (xy 312.284102 -357.376972) (xy 312.302395 -357.369389) (xy 312.309764 -357.36276)
			(xy 312.78576 -356.886764) (xy 312.792397 -356.879403) (xy 312.799955 -356.861103) (xy 312.800492 -356.851204)
			(xy 312.800492 -356.056946) (xy 312.801129 -356.03195) (xy 312.810931 -355.982928) (xy 312.830108 -355.93676)
			(xy 312.857924 -355.89522) (xy 312.875168 -355.877114) (xy 313.324494 -355.428042) (xy 314.127642 -354.624894)
			(xy 314.132309 -354.619788) (xy 314.138996 -354.607683) (xy 314.14085 -354.601018) (xy 314.142374 -354.594922)
			(xy 314.141866 -354.580698) (xy 314.13958 -354.57384) (xy 314.131074 -354.545511) (xy 314.121888 -354.487081)
			(xy 314.121292 -354.457508) (xy 314.121292 -354.453444) (xy 314.122019 -354.426359) (xy 314.130184 -354.372795)
			(xy 314.145845 -354.320926) (xy 314.168686 -354.271794) (xy 314.198249 -354.226388) (xy 314.233938 -354.185621)
			(xy 314.275036 -354.150313) (xy 314.320716 -354.121175) (xy 314.370059 -354.098792) (xy 314.422072 -354.083615)
			(xy 314.475709 -354.07595) (xy 314.5028 -354.075492) (xy 314.530051 -354.075978) (xy 314.583999 -354.083734)
			(xy 314.636294 -354.099089) (xy 314.685871 -354.121731) (xy 314.731721 -354.151197) (xy 314.772912 -354.186888)
			(xy 314.808603 -354.228079) (xy 314.838069 -354.273929) (xy 314.860711 -354.323506) (xy 314.876066 -354.375801)
			(xy 314.883822 -354.429749) (xy 314.884308 -354.457) (xy 314.883749 -354.486612) (xy 314.8746 -354.545124)
			(xy 314.85652 -354.601521) (xy 314.829946 -354.654448) (xy 314.795513 -354.702633) (xy 314.75405 -354.744921)
			(xy 314.706552 -354.780295) (xy 314.6806 -354.794566) (xy 314.673742 -354.798122) (xy 313.643458 -355.8286)
			(xy 314.196982 -355.8286) (xy 314.201053 -355.772978) (xy 314.213179 -355.718541) (xy 314.233102 -355.66645)
			(xy 314.260398 -355.617815) (xy 314.294484 -355.573672) (xy 314.334633 -355.534963) (xy 314.379991 -355.502512)
			(xy 314.429591 -355.477011) (xy 314.482375 -355.459004) (xy 314.537218 -355.448874) (xy 314.592952 -355.446837)
			(xy 314.648389 -355.452937) (xy 314.702346 -355.467043) (xy 314.753675 -355.488855) (xy 314.801281 -355.517909)
			(xy 314.844149 -355.553584) (xy 314.881366 -355.595121) (xy 314.912139 -355.641634) (xy 314.935811 -355.692131)
			(xy 314.951879 -355.745538) (xy 314.959999 -355.800714) (xy 314.960508 -355.8286) (xy 314.959999 -355.856486)
			(xy 314.951879 -355.911662) (xy 314.935811 -355.965069) (xy 314.912139 -356.015566) (xy 314.881366 -356.062079)
			(xy 314.844149 -356.103616) (xy 314.801281 -356.139291) (xy 314.753675 -356.168345) (xy 314.702346 -356.190157)
			(xy 314.648389 -356.204263) (xy 314.592952 -356.210363) (xy 314.537218 -356.208326) (xy 314.482375 -356.198196)
			(xy 314.429591 -356.180189) (xy 314.379991 -356.154688) (xy 314.334633 -356.122237) (xy 314.294484 -356.083528)
			(xy 314.260398 -356.039385) (xy 314.233102 -355.99075) (xy 314.213179 -355.938659) (xy 314.201053 -355.884222)
			(xy 314.196982 -355.8286) (xy 313.643458 -355.8286) (xy 313.322716 -356.149402) (xy 313.316754 -356.156629)
			(xy 313.309981 -356.174081) (xy 313.309508 -356.183438) (xy 313.309508 -356.306628) (xy 313.309909 -356.315378)
			(xy 313.31588 -356.33183) (xy 313.327044 -356.345309) (xy 313.3344 -356.350062) (xy 313.412886 -356.394004)
			(xy 313.418961 -356.397114) (xy 313.432222 -356.400323) (xy 313.439048 -356.400354) (xy 313.45251 -356.4001)
			(xy 313.46394 -356.392988) (xy 313.464448 -356.392988) (xy 313.487104 -356.379515) (xy 313.535337 -356.358256)
			(xy 313.58604 -356.343849) (xy 313.638245 -356.336569) (xy 313.6646 -356.336092) (xy 313.691851 -356.336578)
			(xy 313.745799 -356.344334) (xy 313.798094 -356.359689) (xy 313.847671 -356.382331) (xy 313.893521 -356.411797)
			(xy 313.934712 -356.447488) (xy 313.970403 -356.488679) (xy 313.999869 -356.534529) (xy 314.022511 -356.584106)
			(xy 314.037866 -356.636401) (xy 314.045622 -356.690349) (xy 314.045622 -356.744851) (xy 314.037866 -356.798799)
			(xy 314.022511 -356.851094) (xy 313.999869 -356.900671) (xy 313.970403 -356.946521) (xy 313.934712 -356.987712)
			(xy 313.893521 -357.023403) (xy 313.847671 -357.052869) (xy 313.798094 -357.075511) (xy 313.745799 -357.090866)
			(xy 313.691851 -357.098622) (xy 313.6646 -357.099108) (xy 313.635117 -357.098563) (xy 313.576855 -357.089487)
			(xy 313.520688 -357.071536) (xy 313.467961 -357.045141) (xy 313.44362 -357.028496) (xy 313.443366 -357.028496)
			(xy 313.438638 -357.025285) (xy 313.428128 -357.020799) (xy 313.422538 -357.019606) (xy 313.411362 -357.017828)
			(xy 313.361832 -357.032306) (xy 313.323224 -357.043482) (xy 313.317774 -357.045196) (xy 313.307768 -357.050708)
			(xy 313.303412 -357.054404) (xy 313.299602 -357.05796) (xy 313.292998 -357.067104) (xy 313.290712 -357.0732)
			(xy 313.28052 -357.096445) (xy 313.252366 -357.138668) (xy 313.234832 -357.15702) (xy 312.739786 -357.65232)
			(xy 312.732969 -357.659662) (xy 312.725231 -357.678126) (xy 312.7248 -357.688134) (xy 312.7248 -357.875586)
			(xy 312.72607 -357.88727) (xy 312.729935 -357.904798) (xy 312.73414 -357.940444) (xy 312.734452 -357.95839)
			(xy 312.734452 -360.402632) (xy 313.480448 -360.402632) (xy 313.484519 -360.34701) (xy 313.496645 -360.292573)
			(xy 313.516568 -360.240482) (xy 313.543864 -360.191847) (xy 313.57795 -360.147704) (xy 313.618099 -360.108995)
			(xy 313.663457 -360.076544) (xy 313.713057 -360.051043) (xy 313.765841 -360.033036) (xy 313.820684 -360.022906)
			(xy 313.876418 -360.020869) (xy 313.931855 -360.026969) (xy 313.985812 -360.041075) (xy 314.037141 -360.062887)
			(xy 314.084747 -360.091941) (xy 314.127615 -360.127616) (xy 314.164832 -360.169153) (xy 314.195605 -360.215666)
			(xy 314.219277 -360.266163) (xy 314.226252 -360.289348) (xy 314.38545 -360.289348) (xy 314.389521 -360.233726)
			(xy 314.401647 -360.179289) (xy 314.42157 -360.127198) (xy 314.448866 -360.078563) (xy 314.482952 -360.03442)
			(xy 314.523101 -359.995711) (xy 314.568459 -359.96326) (xy 314.618059 -359.937759) (xy 314.670843 -359.919752)
			(xy 314.725686 -359.909622) (xy 314.78142 -359.907585) (xy 314.836857 -359.913685) (xy 314.890814 -359.927791)
			(xy 314.942143 -359.949603) (xy 314.989749 -359.978657) (xy 315.032617 -360.014332) (xy 315.069834 -360.055869)
			(xy 315.100607 -360.102382) (xy 315.124279 -360.152879) (xy 315.140347 -360.206286) (xy 315.148467 -360.261462)
			(xy 315.148976 -360.289348) (xy 315.148467 -360.317234) (xy 315.140347 -360.37241) (xy 315.124279 -360.425817)
			(xy 315.100607 -360.476314) (xy 315.069834 -360.522827) (xy 315.032617 -360.564364) (xy 314.989749 -360.600039)
			(xy 314.942143 -360.629093) (xy 314.890814 -360.650905) (xy 314.836857 -360.665011) (xy 314.78142 -360.671111)
			(xy 314.725686 -360.669074) (xy 314.670843 -360.658944) (xy 314.618059 -360.640937) (xy 314.568459 -360.615436)
			(xy 314.523101 -360.582985) (xy 314.482952 -360.544276) (xy 314.448866 -360.500133) (xy 314.42157 -360.451498)
			(xy 314.401647 -360.399407) (xy 314.389521 -360.34497) (xy 314.38545 -360.289348) (xy 314.226252 -360.289348)
			(xy 314.235345 -360.31957) (xy 314.243465 -360.374746) (xy 314.243974 -360.402632) (xy 314.243465 -360.430518)
			(xy 314.235345 -360.485694) (xy 314.219277 -360.539101) (xy 314.195605 -360.589598) (xy 314.164832 -360.636111)
			(xy 314.127615 -360.677648) (xy 314.084747 -360.713323) (xy 314.037141 -360.742377) (xy 313.985812 -360.764189)
			(xy 313.931855 -360.778295) (xy 313.876418 -360.784395) (xy 313.820684 -360.782358) (xy 313.765841 -360.772228)
			(xy 313.713057 -360.754221) (xy 313.663457 -360.72872) (xy 313.618099 -360.696269) (xy 313.57795 -360.65756)
			(xy 313.543864 -360.613417) (xy 313.516568 -360.564782) (xy 313.496645 -360.512691) (xy 313.484519 -360.458254)
			(xy 313.480448 -360.402632) (xy 312.734452 -360.402632) (xy 312.734452 -361.279948) (xy 314.255656 -361.279948)
			(xy 314.259727 -361.224326) (xy 314.271853 -361.169889) (xy 314.291776 -361.117798) (xy 314.319072 -361.069163)
			(xy 314.353158 -361.02502) (xy 314.393307 -360.986311) (xy 314.438665 -360.95386) (xy 314.488265 -360.928359)
			(xy 314.541049 -360.910352) (xy 314.595892 -360.900222) (xy 314.651626 -360.898185) (xy 314.707063 -360.904285)
			(xy 314.76102 -360.918391) (xy 314.812349 -360.940203) (xy 314.859955 -360.969257) (xy 314.902823 -361.004932)
			(xy 314.94004 -361.046469) (xy 314.970813 -361.092982) (xy 314.994485 -361.143479) (xy 315.010553 -361.196886)
			(xy 315.018673 -361.252062) (xy 315.019182 -361.279948) (xy 315.018673 -361.307834) (xy 315.010553 -361.36301)
			(xy 314.994485 -361.416417) (xy 314.970813 -361.466914) (xy 314.94004 -361.513427) (xy 314.902823 -361.554964)
			(xy 314.859955 -361.590639) (xy 314.812349 -361.619693) (xy 314.76102 -361.641505) (xy 314.707063 -361.655611)
			(xy 314.651626 -361.661711) (xy 314.595892 -361.659674) (xy 314.541049 -361.649544) (xy 314.488265 -361.631537)
			(xy 314.438665 -361.606036) (xy 314.393307 -361.573585) (xy 314.353158 -361.534876) (xy 314.319072 -361.490733)
			(xy 314.291776 -361.442098) (xy 314.271853 -361.390007) (xy 314.259727 -361.33557) (xy 314.255656 -361.279948)
			(xy 312.734452 -361.279948) (xy 312.734452 -363.23905) (xy 315.212982 -363.23905) (xy 315.217053 -363.183428)
			(xy 315.229179 -363.128991) (xy 315.249102 -363.0769) (xy 315.276398 -363.028265) (xy 315.310484 -362.984122)
			(xy 315.350633 -362.945413) (xy 315.395991 -362.912962) (xy 315.445591 -362.887461) (xy 315.498375 -362.869454)
			(xy 315.553218 -362.859324) (xy 315.608952 -362.857287) (xy 315.664389 -362.863387) (xy 315.718346 -362.877493)
			(xy 315.769675 -362.899305) (xy 315.817281 -362.928359) (xy 315.860149 -362.964034) (xy 315.897366 -363.005571)
			(xy 315.928139 -363.052084) (xy 315.951811 -363.102581) (xy 315.967879 -363.155988) (xy 315.975999 -363.211164)
			(xy 315.976508 -363.23905) (xy 315.975999 -363.266936) (xy 315.967879 -363.322112) (xy 315.951811 -363.375519)
			(xy 315.928139 -363.426016) (xy 315.897366 -363.472529) (xy 315.860149 -363.514066) (xy 315.817281 -363.549741)
			(xy 315.769675 -363.578795) (xy 315.718346 -363.600607) (xy 315.664389 -363.614713) (xy 315.608952 -363.620813)
			(xy 315.553218 -363.618776) (xy 315.498375 -363.608646) (xy 315.445591 -363.590639) (xy 315.395991 -363.565138)
			(xy 315.350633 -363.532687) (xy 315.310484 -363.493978) (xy 315.276398 -363.449835) (xy 315.249102 -363.4012)
			(xy 315.229179 -363.349109) (xy 315.217053 -363.294672) (xy 315.212982 -363.23905) (xy 312.734452 -363.23905)
			(xy 312.734452 -364.706916) (xy 312.734153 -364.724863) (xy 312.729956 -364.760512) (xy 312.72607 -364.778036)
			(xy 312.7248 -364.78972) (xy 312.7248 -364.976918) (xy 312.725816 -364.98657) (xy 312.727445 -364.993813)
			(xy 312.734289 -365.00698) (xy 312.739278 -365.012478) (xy 313.142122 -365.415322) (xy 313.147621 -365.420309)
			(xy 313.160788 -365.427151) (xy 313.16803 -365.428784) (xy 313.177682 -365.4298) (xy 314.938918 -365.4298)
		)
		(stroke
			(width 0)
			(type solid)
		)
		(fill yes)
		(layer "In6.Cu")
		(net "PVDDCR_CPU1_P0_VCCS")
	)
	(gr_poly
		(pts
			(xy 26.282904 -368.780822) (xy 26.292974 -368.780399) (xy 26.31158 -368.772686) (xy 26.318972 -368.765836)
			(xy 26.381964 -368.702844) (xy 26.388805 -368.695444) (xy 26.396525 -368.676846) (xy 26.39695 -368.666776)
			(xy 26.39695 -367.38814) (xy 26.396418 -367.37815) (xy 26.38871 -367.359713) (xy 26.381964 -367.352326)
			(xy 26.267664 -367.237772) (xy 26.247851 -367.217179) (xy 26.214245 -367.170963) (xy 26.188277 -367.120062)
			(xy 26.170584 -367.065727) (xy 26.161602 -367.009295) (xy 26.160984 -366.980724) (xy 26.160984 -366.368076)
			(xy 26.160452 -366.357567) (xy 26.152046 -366.338301) (xy 26.144728 -366.330738) (xy 26.081736 -366.272572)
			(xy 26.061924 -366.265968) (xy 26.051002 -366.26673) (xy 26.009092 -366.268508) (xy 25.978361 -366.268043)
			(xy 25.917348 -366.260634) (xy 25.857673 -366.245925) (xy 25.800206 -366.22413) (xy 25.745785 -366.195566)
			(xy 25.695203 -366.160652) (xy 25.649199 -366.119895) (xy 25.608443 -366.07389) (xy 25.573529 -366.023308)
			(xy 25.544967 -365.968887) (xy 25.523173 -365.911419) (xy 25.508464 -365.851744) (xy 25.501056 -365.790731)
			(xy 25.500584 -365.76) (xy 25.501149 -365.726031) (xy 25.510194 -365.658698) (xy 25.528121 -365.593169)
			(xy 25.554613 -365.530609) (xy 25.589197 -365.472133) (xy 25.631259 -365.418782) (xy 25.65527 -365.394748)
			(xy 25.665176 -365.38535) (xy 25.672542 -365.360204) (xy 25.64765 -365.249206) (xy 25.630124 -365.229902)
			(xy 25.617424 -365.225584) (xy 25.587641 -365.214941) (xy 25.530753 -365.1873) (xy 25.477728 -365.152823)
			(xy 25.429384 -365.11204) (xy 25.386466 -365.065582) (xy 25.349636 -365.014163) (xy 25.319462 -364.958577)
			(xy 25.296408 -364.899681) (xy 25.28083 -364.838381) (xy 25.272968 -364.775624) (xy 25.272492 -364.744)
			(xy 25.272994 -364.711059) (xy 25.281468 -364.645724) (xy 25.298311 -364.582032) (xy 25.323242 -364.52105)
			(xy 25.355844 -364.4638) (xy 25.395568 -364.411242) (xy 25.418288 -364.387384) (xy 25.424568 -364.38047)
			(xy 25.432129 -364.363407) (xy 25.43302 -364.35411) (xy 25.43429 -364.323376) (xy 25.434256 -364.314102)
			(xy 25.428403 -364.29652) (xy 25.42286 -364.289086) (xy 25.414478 -364.278672) (xy 25.407112 -364.26902)
			(xy 25.385776 -364.25886) (xy 25.280366 -364.260638) (xy 25.259538 -364.27156) (xy 25.252172 -364.281212)
			(xy 25.234217 -364.305159) (xy 25.193567 -364.349093) (xy 25.148038 -364.387949) (xy 25.098261 -364.421189)
			(xy 25.044925 -364.448353) (xy 24.988768 -364.469065) (xy 24.930567 -364.483038) (xy 24.871127 -364.490079)
			(xy 24.8412 -364.490508) (xy 24.809239 -364.490006) (xy 24.745821 -364.481995) (xy 24.683907 -364.466098)
			(xy 24.624474 -364.442566) (xy 24.568459 -364.411772) (xy 24.516744 -364.374199) (xy 24.470147 -364.330442)
			(xy 24.429402 -364.281189) (xy 24.395151 -364.227218) (xy 24.367934 -364.169379) (xy 24.348181 -364.108586)
			(xy 24.336203 -364.045796) (xy 24.33219 -363.982) (xy 24.336203 -363.918204) (xy 24.348181 -363.855414)
			(xy 24.367934 -363.794621) (xy 24.395151 -363.736782) (xy 24.429402 -363.682811) (xy 24.470147 -363.633558)
			(xy 24.516744 -363.589801) (xy 24.568459 -363.552228) (xy 24.624474 -363.521434) (xy 24.683907 -363.497902)
			(xy 24.745821 -363.482005) (xy 24.809239 -363.473994) (xy 24.8412 -363.473492) (xy 24.874242 -363.474019)
			(xy 24.93977 -363.482577) (xy 25.003638 -363.499547) (xy 25.06477 -363.524646) (xy 25.122138 -363.557449)
			(xy 25.174775 -363.597405) (xy 25.221795 -363.64384) (xy 25.24252 -363.66958) (xy 25.249886 -363.679232)
			(xy 25.271222 -363.689392) (xy 25.376632 -363.687614) (xy 25.39746 -363.676692) (xy 25.404826 -363.66704)
			(xy 25.413515 -363.65521) (xy 25.432066 -363.632461) (xy 25.44191 -363.621574) (xy 25.45588 -363.606334)
			(xy 25.455118 -363.565694) (xy 23.67153 -361.782106) (xy 23.66468 -361.774709) (xy 23.656938 -361.756111)
			(xy 23.656544 -361.746038) (xy 23.656544 -361.630722) (xy 23.656009 -361.620734) (xy 23.648295 -361.602301)
			(xy 23.641558 -361.594908) (xy 23.623778 -361.576874) (xy 23.60676 -361.569254) (xy 23.597108 -361.569)
			(xy 23.564909 -361.566927) (xy 23.501379 -361.555652) (xy 23.439786 -361.536429) (xy 23.38112 -361.509567)
			(xy 23.326325 -361.475499) (xy 23.27628 -361.434771) (xy 23.231791 -361.388038) (xy 23.193573 -361.336052)
			(xy 23.162239 -361.279648) (xy 23.138293 -361.219733) (xy 23.122121 -361.157269) (xy 23.113983 -361.093262)
			(xy 23.113492 -361.061) (xy 23.113994 -361.029116) (xy 23.121977 -360.965848) (xy 23.137805 -360.904075)
			(xy 23.161229 -360.844764) (xy 23.191882 -360.788846) (xy 23.229284 -360.737198) (xy 23.272848 -360.690629)
			(xy 23.321891 -360.64987) (xy 23.375643 -360.61556) (xy 23.433262 -360.588238) (xy 23.493844 -360.568332)
			(xy 23.556439 -360.556153) (xy 23.588218 -360.553508) (xy 23.597496 -360.552477) (xy 23.614426 -360.544652)
			(xy 23.621238 -360.538268) (xy 23.642066 -360.516678) (xy 23.648617 -360.509351) (xy 23.656074 -360.491188)
			(xy 23.656544 -360.481372) (xy 23.656544 -360.46664) (xy 23.623778 -360.433874) (xy 23.60676 -360.426254)
			(xy 23.597108 -360.426) (xy 23.564909 -360.423927) (xy 23.501379 -360.412652) (xy 23.439786 -360.393429)
			(xy 23.38112 -360.366567) (xy 23.326325 -360.332499) (xy 23.27628 -360.291771) (xy 23.231791 -360.245038)
			(xy 23.193573 -360.193052) (xy 23.162239 -360.136648) (xy 23.138293 -360.076733) (xy 23.122121 -360.014269)
			(xy 23.113983 -359.950262) (xy 23.113492 -359.918) (xy 23.113994 -359.886116) (xy 23.121977 -359.822848)
			(xy 23.137805 -359.761075) (xy 23.161229 -359.701764) (xy 23.191882 -359.645846) (xy 23.229284 -359.594198)
			(xy 23.272848 -359.547629) (xy 23.321891 -359.50687) (xy 23.375643 -359.47256) (xy 23.433262 -359.445238)
			(xy 23.493844 -359.425332) (xy 23.556439 -359.413153) (xy 23.588218 -359.410508) (xy 23.597496 -359.409477)
			(xy 23.614426 -359.401652) (xy 23.621238 -359.395268) (xy 23.642066 -359.373678) (xy 23.648617 -359.366351)
			(xy 23.656074 -359.348188) (xy 23.656544 -359.338372) (xy 23.656544 -359.32364) (xy 23.622762 -359.289858)
			(xy 23.60676 -359.282492) (xy 23.597616 -359.28173) (xy 23.566222 -359.278653) (xy 23.504482 -359.26571)
			(xy 23.444817 -359.24523) (xy 23.388142 -359.217529) (xy 23.335329 -359.18303) (xy 23.287188 -359.142265)
			(xy 23.244459 -359.095859) (xy 23.207797 -359.044524) (xy 23.177765 -358.98905) (xy 23.154826 -358.930286)
			(xy 23.13933 -358.869137) (xy 23.131515 -358.806541) (xy 23.131018 -358.775) (xy 23.1315 -358.743765)
			(xy 23.139162 -358.681765) (xy 23.15436 -358.621171) (xy 23.176863 -358.562893) (xy 23.206334 -358.507811)
			(xy 23.242329 -358.456752) (xy 23.284305 -358.410485) (xy 23.331632 -358.369707) (xy 23.383596 -358.335032)
			(xy 23.439415 -358.306981) (xy 23.49825 -358.285977) (xy 23.559213 -358.272336) (xy 23.59025 -358.268778)
			(xy 23.599308 -358.26749) (xy 23.615721 -358.259433) (xy 23.622254 -358.25303) (xy 23.642828 -358.23144)
			(xy 23.649122 -358.224153) (xy 23.656195 -358.206262) (xy 23.656544 -358.196642) (xy 23.656544 -358.191054)
			(xy 23.621238 -358.154732) (xy 23.614438 -358.14833) (xy 23.597501 -358.140502) (xy 23.588218 -358.139492)
			(xy 23.556431 -358.136878) (xy 23.493819 -358.124718) (xy 23.433219 -358.104825) (xy 23.375582 -358.07751)
			(xy 23.321812 -358.043204) (xy 23.272754 -358.002444) (xy 23.229177 -357.95587) (xy 23.191766 -357.904213)
			(xy 23.161106 -357.848283) (xy 23.137681 -357.788959) (xy 23.121856 -357.727172) (xy 23.113882 -357.663891)
			(xy 23.113882 -357.600109) (xy 23.121856 -357.536828) (xy 23.137681 -357.475041) (xy 23.161106 -357.415717)
			(xy 23.191766 -357.359787) (xy 23.229177 -357.30813) (xy 23.272754 -357.261556) (xy 23.321812 -357.220796)
			(xy 23.375582 -357.18649) (xy 23.433219 -357.159175) (xy 23.493819 -357.139282) (xy 23.556431 -357.127122)
			(xy 23.588218 -357.124508) (xy 23.597496 -357.123477) (xy 23.614426 -357.115652) (xy 23.621238 -357.109268)
			(xy 23.642066 -357.087678) (xy 23.648617 -357.080351) (xy 23.656074 -357.062188) (xy 23.656544 -357.052372)
			(xy 23.656544 -354.449126) (xy 23.656106 -354.439063) (xy 23.648366 -354.420483) (xy 23.641558 -354.413058)
			(xy 22.37105 -353.14255) (xy 22.363651 -353.135706) (xy 22.345052 -353.127982) (xy 22.334982 -353.127564)
			(xy 21.564092 -353.127564) (xy 21.554024 -353.12799) (xy 21.535428 -353.135714) (xy 21.528024 -353.14255)
			(xy 19.444716 -355.225858) (xy 19.437877 -355.233259) (xy 19.430161 -355.251857) (xy 19.42973 -355.261926)
			(xy 19.42973 -356.668281) (xy 21.546052 -356.668281) (xy 21.546052 -356.604359) (xy 21.554063 -356.540941)
			(xy 21.56996 -356.479027) (xy 21.593492 -356.419594) (xy 21.624286 -356.363579) (xy 21.661859 -356.311864)
			(xy 21.705616 -356.265267) (xy 21.754869 -356.224522) (xy 21.80884 -356.190271) (xy 21.866679 -356.163054)
			(xy 21.927472 -356.143301) (xy 21.990262 -356.131323) (xy 22.054058 -356.12731) (xy 22.117854 -356.131323)
			(xy 22.180644 -356.143301) (xy 22.241437 -356.163054) (xy 22.299276 -356.190271) (xy 22.353247 -356.224522)
			(xy 22.4025 -356.265267) (xy 22.446257 -356.311864) (xy 22.48383 -356.363579) (xy 22.514624 -356.419594)
			(xy 22.538156 -356.479027) (xy 22.554053 -356.540941) (xy 22.562064 -356.604359) (xy 22.562566 -356.63632)
			(xy 22.562064 -356.668281) (xy 22.554053 -356.731699) (xy 22.538156 -356.793613) (xy 22.514624 -356.853046)
			(xy 22.48383 -356.909061) (xy 22.446257 -356.960776) (xy 22.4025 -357.007373) (xy 22.353247 -357.048118)
			(xy 22.299276 -357.082369) (xy 22.241437 -357.109586) (xy 22.180644 -357.129339) (xy 22.117854 -357.141317)
			(xy 22.054058 -357.145331) (xy 21.990262 -357.141317) (xy 21.927472 -357.129339) (xy 21.866679 -357.109586)
			(xy 21.80884 -357.082369) (xy 21.754869 -357.048118) (xy 21.705616 -357.007373) (xy 21.661859 -356.960776)
			(xy 21.624286 -356.909061) (xy 21.593492 -356.853046) (xy 21.56996 -356.793613) (xy 21.554063 -356.731699)
			(xy 21.546052 -356.668281) (xy 19.42973 -356.668281) (xy 19.42973 -356.875588) (xy 19.452844 -356.903782)
			(xy 19.471132 -356.907084) (xy 19.498347 -356.912758) (xy 19.550881 -356.930935) (xy 19.600222 -356.956542)
			(xy 19.645326 -356.989038) (xy 19.685237 -357.027734) (xy 19.719112 -357.071811) (xy 19.746232 -357.120337)
			(xy 19.766025 -357.172285) (xy 19.778071 -357.226555) (xy 19.782115 -357.281998) (xy 19.781116 -357.2957)
			(xy 19.906972 -357.2957) (xy 19.910986 -357.231901) (xy 19.922965 -357.169108) (xy 19.942719 -357.108312)
			(xy 19.969938 -357.050471) (xy 20.004191 -356.996497) (xy 20.044939 -356.947242) (xy 20.091539 -356.903483)
			(xy 20.143256 -356.86591) (xy 20.199274 -356.835114) (xy 20.258711 -356.811583) (xy 20.320628 -356.795687)
			(xy 20.384049 -356.787676) (xy 20.416012 -356.787196) (xy 20.448142 -356.787666) (xy 20.511888 -356.795763)
			(xy 20.574107 -356.811827) (xy 20.633807 -356.835601) (xy 20.690036 -356.866706) (xy 20.741898 -356.904648)
			(xy 20.788567 -356.948821) (xy 20.829299 -356.998521) (xy 20.863445 -357.052957) (xy 20.890461 -357.111261)
			(xy 20.909917 -357.172504) (xy 20.921502 -357.23571) (xy 20.923758 -357.267764) (xy 20.924893 -357.281832)
			(xy 20.934067 -357.308517) (xy 20.950196 -357.331671) (xy 20.972046 -357.349526) (xy 20.99795 -357.360717)
			(xy 21.025928 -357.36439) (xy 21.053843 -357.360264) (xy 21.079562 -357.348654) (xy 21.090636 -357.3399)
			(xy 21.111346 -357.323096) (xy 21.156554 -357.294804) (xy 21.205263 -357.273087) (xy 21.256523 -357.258369)
			(xy 21.309334 -357.250937) (xy 21.336 -357.250492) (xy 21.363251 -357.250978) (xy 21.417199 -357.258734)
			(xy 21.469494 -357.274089) (xy 21.519071 -357.296731) (xy 21.564921 -357.326197) (xy 21.606112 -357.361888)
			(xy 21.641803 -357.403079) (xy 21.671269 -357.448929) (xy 21.693911 -357.498506) (xy 21.709266 -357.550801)
			(xy 21.717022 -357.604749) (xy 21.717022 -357.659251) (xy 21.709266 -357.713199) (xy 21.693911 -357.765494)
			(xy 21.671269 -357.815071) (xy 21.641803 -357.860921) (xy 21.606112 -357.902112) (xy 21.564921 -357.937803)
			(xy 21.519071 -357.967269) (xy 21.469494 -357.989911) (xy 21.417199 -358.005266) (xy 21.363251 -358.013022)
			(xy 21.336 -358.013508) (xy 21.309292 -358.013055) (xy 21.256397 -358.005604) (xy 21.20506 -357.990847)
			(xy 21.156283 -357.969072) (xy 21.11102 -357.940707) (xy 21.070156 -357.906305) (xy 21.034491 -357.866539)
			(xy 21.004722 -357.822187) (xy 20.981431 -357.774116) (xy 20.965073 -357.723265) (xy 20.96008 -357.697024)
			(xy 20.957292 -357.683198) (xy 20.945126 -357.65776) (xy 20.926466 -357.636621) (xy 20.902734 -357.621394)
			(xy 20.875742 -357.613239) (xy 20.847549 -357.61278) (xy 20.820306 -357.620052) (xy 20.796091 -357.634499)
			(xy 20.78609 -357.644446) (xy 20.761967 -357.669191) (xy 20.7082 -357.712603) (xy 20.649048 -357.748334)
			(xy 20.585603 -357.775725) (xy 20.519033 -357.794271) (xy 20.450565 -357.803631) (xy 20.416012 -357.804212)
			(xy 20.384049 -357.803724) (xy 20.320628 -357.795713) (xy 20.258711 -357.779817) (xy 20.199274 -357.756286)
			(xy 20.143256 -357.72549) (xy 20.091539 -357.687917) (xy 20.044939 -357.644158) (xy 20.004191 -357.594903)
			(xy 19.969938 -357.540929) (xy 19.942719 -357.483088) (xy 19.922965 -357.422292) (xy 19.910986 -357.359499)
			(xy 19.906972 -357.2957) (xy 19.781116 -357.2957) (xy 19.778071 -357.337441) (xy 19.766026 -357.391711)
			(xy 19.746234 -357.443659) (xy 19.719114 -357.492185) (xy 19.68524 -357.536263) (xy 19.64533 -357.574959)
			(xy 19.600226 -357.607455) (xy 19.550885 -357.633063) (xy 19.498351 -357.651241) (xy 19.471132 -357.656892)
			(xy 19.452844 -357.660194) (xy 19.42973 -357.688388) (xy 19.42973 -358.775) (xy 20.953982 -358.775)
			(xy 20.958053 -358.719378) (xy 20.970179 -358.664941) (xy 20.990102 -358.61285) (xy 21.017398 -358.564215)
			(xy 21.051484 -358.520072) (xy 21.091633 -358.481363) (xy 21.136991 -358.448912) (xy 21.186591 -358.423411)
			(xy 21.239375 -358.405404) (xy 21.294218 -358.395274) (xy 21.349952 -358.393237) (xy 21.405389 -358.399337)
			(xy 21.459346 -358.413443) (xy 21.510675 -358.435255) (xy 21.558281 -358.464309) (xy 21.601149 -358.499984)
			(xy 21.638366 -358.541521) (xy 21.669139 -358.588034) (xy 21.692811 -358.638531) (xy 21.708879 -358.691938)
			(xy 21.716999 -358.747114) (xy 21.717508 -358.775) (xy 21.716999 -358.802886) (xy 21.708879 -358.858062)
			(xy 21.692811 -358.911469) (xy 21.669139 -358.961966) (xy 21.638366 -359.008479) (xy 21.601149 -359.050016)
			(xy 21.558281 -359.085691) (xy 21.510675 -359.114745) (xy 21.459346 -359.136557) (xy 21.405389 -359.150663)
			(xy 21.349952 -359.156763) (xy 21.294218 -359.154726) (xy 21.239375 -359.144596) (xy 21.186591 -359.126589)
			(xy 21.136991 -359.101088) (xy 21.091633 -359.068637) (xy 21.051484 -359.029928) (xy 21.017398 -358.985785)
			(xy 20.990102 -358.93715) (xy 20.970179 -358.885059) (xy 20.958053 -358.830622) (xy 20.953982 -358.775)
			(xy 19.42973 -358.775) (xy 19.42973 -359.918) (xy 20.953982 -359.918) (xy 20.958053 -359.862378)
			(xy 20.970179 -359.807941) (xy 20.990102 -359.75585) (xy 21.017398 -359.707215) (xy 21.051484 -359.663072)
			(xy 21.091633 -359.624363) (xy 21.136991 -359.591912) (xy 21.186591 -359.566411) (xy 21.239375 -359.548404)
			(xy 21.294218 -359.538274) (xy 21.349952 -359.536237) (xy 21.405389 -359.542337) (xy 21.459346 -359.556443)
			(xy 21.510675 -359.578255) (xy 21.558281 -359.607309) (xy 21.601149 -359.642984) (xy 21.638366 -359.684521)
			(xy 21.669139 -359.731034) (xy 21.692811 -359.781531) (xy 21.708879 -359.834938) (xy 21.716999 -359.890114)
			(xy 21.717508 -359.918) (xy 21.716999 -359.945886) (xy 21.708879 -360.001062) (xy 21.692811 -360.054469)
			(xy 21.669139 -360.104966) (xy 21.638366 -360.151479) (xy 21.601149 -360.193016) (xy 21.558281 -360.228691)
			(xy 21.510675 -360.257745) (xy 21.459346 -360.279557) (xy 21.405389 -360.293663) (xy 21.349952 -360.299763)
			(xy 21.294218 -360.297726) (xy 21.239375 -360.287596) (xy 21.186591 -360.269589) (xy 21.136991 -360.244088)
			(xy 21.091633 -360.211637) (xy 21.051484 -360.172928) (xy 21.017398 -360.128785) (xy 20.990102 -360.08015)
			(xy 20.970179 -360.028059) (xy 20.958053 -359.973622) (xy 20.953982 -359.918) (xy 19.42973 -359.918)
			(xy 19.42973 -361.061) (xy 20.953982 -361.061) (xy 20.958053 -361.005378) (xy 20.970179 -360.950941)
			(xy 20.990102 -360.89885) (xy 21.017398 -360.850215) (xy 21.051484 -360.806072) (xy 21.091633 -360.767363)
			(xy 21.136991 -360.734912) (xy 21.186591 -360.709411) (xy 21.239375 -360.691404) (xy 21.294218 -360.681274)
			(xy 21.349952 -360.679237) (xy 21.405389 -360.685337) (xy 21.459346 -360.699443) (xy 21.510675 -360.721255)
			(xy 21.558281 -360.750309) (xy 21.601149 -360.785984) (xy 21.638366 -360.827521) (xy 21.669139 -360.874034)
			(xy 21.692811 -360.924531) (xy 21.708879 -360.977938) (xy 21.716999 -361.033114) (xy 21.717508 -361.061)
			(xy 21.716999 -361.088886) (xy 21.708879 -361.144062) (xy 21.692811 -361.197469) (xy 21.669139 -361.247966)
			(xy 21.638366 -361.294479) (xy 21.601149 -361.336016) (xy 21.558281 -361.371691) (xy 21.510675 -361.400745)
			(xy 21.459346 -361.422557) (xy 21.405389 -361.436663) (xy 21.349952 -361.442763) (xy 21.294218 -361.440726)
			(xy 21.239375 -361.430596) (xy 21.186591 -361.412589) (xy 21.136991 -361.387088) (xy 21.091633 -361.354637)
			(xy 21.051484 -361.315928) (xy 21.017398 -361.271785) (xy 20.990102 -361.22315) (xy 20.970179 -361.171059)
			(xy 20.958053 -361.116622) (xy 20.953982 -361.061) (xy 19.42973 -361.061) (xy 19.42973 -362.56214)
			(xy 20.0787 -362.56214) (xy 20.079212 -362.529985) (xy 20.08731 -362.466187) (xy 20.103394 -362.403922)
			(xy 20.127207 -362.344183) (xy 20.158367 -362.287927) (xy 20.196378 -362.236054) (xy 20.218146 -362.212382)
			(xy 20.22475 -362.205524) (xy 20.231608 -362.188252) (xy 20.233894 -362.10113) (xy 20.227798 -362.083858)
			(xy 20.221448 -362.076492) (xy 20.202244 -362.053388) (xy 20.168791 -362.003484) (xy 20.141452 -361.949986)
			(xy 20.120606 -361.89364) (xy 20.106544 -361.83523) (xy 20.099461 -361.775569) (xy 20.09902 -361.74553)
			(xy 20.099466 -361.714797) (xy 20.106872 -361.65378) (xy 20.121579 -361.594101) (xy 20.143373 -361.536629)
			(xy 20.171936 -361.482204) (xy 20.206851 -361.431618) (xy 20.24761 -361.385611) (xy 20.293617 -361.344852)
			(xy 20.344202 -361.309937) (xy 20.398627 -361.281373) (xy 20.456099 -361.259579) (xy 20.515778 -361.244872)
			(xy 20.576795 -361.237466) (xy 20.607528 -361.237022) (xy 20.640487 -361.237517) (xy 20.705854 -361.246026)
			(xy 20.769573 -361.262911) (xy 20.830576 -361.287887) (xy 20.88784 -361.320537) (xy 20.940405 -361.360314)
			(xy 20.987389 -361.406549) (xy 21.028005 -361.458468) (xy 21.061571 -361.5152) (xy 21.087525 -361.575794)
			(xy 21.105431 -361.639234) (xy 21.114989 -361.704455) (xy 21.116036 -361.737402) (xy 21.116036 -361.749086)
			(xy 21.12645 -361.76966) (xy 21.208492 -361.832398) (xy 21.230844 -361.83697) (xy 21.242528 -361.834176)
			(xy 21.265511 -361.828724) (xy 21.312382 -361.822863) (xy 21.336 -361.822492) (xy 21.363251 -361.822978)
			(xy 21.417199 -361.830734) (xy 21.469494 -361.846089) (xy 21.519071 -361.868731) (xy 21.564921 -361.898197)
			(xy 21.606112 -361.933888) (xy 21.641803 -361.975079) (xy 21.671269 -362.020929) (xy 21.693911 -362.070506)
			(xy 21.709266 -362.122801) (xy 21.717022 -362.176749) (xy 21.717022 -362.231251) (xy 21.709266 -362.285199)
			(xy 21.693911 -362.337494) (xy 21.671269 -362.387071) (xy 21.641803 -362.432921) (xy 21.606112 -362.474112)
			(xy 21.564921 -362.509803) (xy 21.519071 -362.539269) (xy 21.469494 -362.561911) (xy 21.417199 -362.577266)
			(xy 21.363251 -362.585022) (xy 21.336 -362.585508) (xy 21.306436 -362.584966) (xy 21.248006 -362.575915)
			(xy 21.219668 -362.567474) (xy 21.209 -362.563918) (xy 21.18741 -362.566458) (xy 21.102574 -362.61802)
			(xy 21.090382 -362.636054) (xy 21.088604 -362.64723) (xy 21.08587 -362.66265) (xy 21.078754 -362.693152)
			(xy 21.07438 -362.70819) (xy 21.070824 -362.720128) (xy 21.075142 -362.744004) (xy 21.140928 -362.82884)
			(xy 21.163026 -362.839254) (xy 21.175472 -362.838746) (xy 21.194014 -362.838492) (xy 21.224745 -362.838943)
			(xy 21.28576 -362.846353) (xy 21.345436 -362.861063) (xy 21.402904 -362.882859) (xy 21.457326 -362.911424)
			(xy 21.507908 -362.946339) (xy 21.553913 -362.987097) (xy 21.594669 -363.033103) (xy 21.629584 -363.083686)
			(xy 21.658146 -363.138109) (xy 21.679941 -363.195578) (xy 21.69465 -363.255254) (xy 21.702058 -363.316269)
			(xy 21.702522 -363.347) (xy 23.239982 -363.347) (xy 23.244053 -363.291378) (xy 23.256179 -363.236941)
			(xy 23.276102 -363.18485) (xy 23.303398 -363.136215) (xy 23.337484 -363.092072) (xy 23.377633 -363.053363)
			(xy 23.422991 -363.020912) (xy 23.472591 -362.995411) (xy 23.525375 -362.977404) (xy 23.580218 -362.967274)
			(xy 23.635952 -362.965237) (xy 23.691389 -362.971337) (xy 23.745346 -362.985443) (xy 23.796675 -363.007255)
			(xy 23.844281 -363.036309) (xy 23.887149 -363.071984) (xy 23.924366 -363.113521) (xy 23.955139 -363.160034)
			(xy 23.978811 -363.210531) (xy 23.994879 -363.263938) (xy 24.002999 -363.319114) (xy 24.003508 -363.347)
			(xy 24.002999 -363.374886) (xy 23.994879 -363.430062) (xy 23.978811 -363.483469) (xy 23.955139 -363.533966)
			(xy 23.924366 -363.580479) (xy 23.887149 -363.622016) (xy 23.844281 -363.657691) (xy 23.796675 -363.686745)
			(xy 23.745346 -363.708557) (xy 23.691389 -363.722663) (xy 23.635952 -363.728763) (xy 23.580218 -363.726726)
			(xy 23.525375 -363.716596) (xy 23.472591 -363.698589) (xy 23.422991 -363.673088) (xy 23.377633 -363.640637)
			(xy 23.337484 -363.601928) (xy 23.303398 -363.557785) (xy 23.276102 -363.50915) (xy 23.256179 -363.457059)
			(xy 23.244053 -363.402622) (xy 23.239982 -363.347) (xy 21.702522 -363.347) (xy 21.702354 -363.365931)
			(xy 21.699559 -363.403689) (xy 21.696934 -363.422438) (xy 21.69595 -363.431591) (xy 21.699867 -363.449565)
			(xy 21.704554 -363.45749) (xy 21.721318 -363.483144) (xy 21.726733 -363.490681) (xy 21.741698 -363.501628)
			(xy 21.750528 -363.50448) (xy 21.782349 -363.513793) (xy 21.843474 -363.539479) (xy 21.900742 -363.572889)
			(xy 21.953183 -363.613459) (xy 21.999907 -363.6605) (xy 22.040122 -363.713213) (xy 22.073146 -363.770706)
			(xy 22.098418 -363.832003) (xy 22.11551 -363.896064) (xy 22.124132 -363.961803) (xy 22.12467 -363.994954)
			(xy 22.124168 -364.026915) (xy 22.116157 -364.090333) (xy 22.10026 -364.152247) (xy 22.076728 -364.21168)
			(xy 22.045934 -364.267695) (xy 22.008361 -364.31941) (xy 21.964604 -364.366007) (xy 21.915351 -364.406752)
			(xy 21.86138 -364.441003) (xy 21.803541 -364.46822) (xy 21.742748 -364.487973) (xy 21.679958 -364.499951)
			(xy 21.616162 -364.503965) (xy 21.552366 -364.499951) (xy 21.489576 -364.487973) (xy 21.428783 -364.46822)
			(xy 21.370944 -364.441003) (xy 21.316973 -364.406752) (xy 21.26772 -364.366007) (xy 21.223963 -364.31941)
			(xy 21.18639 -364.267695) (xy 21.155596 -364.21168) (xy 21.132064 -364.152247) (xy 21.116167 -364.090333)
			(xy 21.108156 -364.026915) (xy 21.107654 -363.994954) (xy 21.107818 -363.976023) (xy 21.110615 -363.938265)
			(xy 21.113242 -363.919516) (xy 21.114187 -363.910361) (xy 21.110294 -363.892392) (xy 21.105622 -363.884464)
			(xy 21.088858 -363.85881) (xy 21.083462 -363.851258) (xy 21.068483 -363.84032) (xy 21.059648 -363.837474)
			(xy 21.027809 -363.828218) (xy 20.966682 -363.802526) (xy 20.909413 -363.769109) (xy 20.856971 -363.728533)
			(xy 20.810248 -363.681486) (xy 20.770035 -363.628766) (xy 20.737014 -363.571266) (xy 20.711746 -363.509964)
			(xy 20.694658 -363.445897) (xy 20.686041 -363.380153) (xy 20.685506 -363.347) (xy 20.686156 -363.309952)
			(xy 20.696863 -363.236635) (xy 20.706842 -363.20095) (xy 20.710398 -363.189012) (xy 20.70608 -363.165136)
			(xy 20.640294 -363.0803) (xy 20.618196 -363.069886) (xy 20.60575 -363.070394) (xy 20.587208 -363.070648)
			(xy 20.556479 -363.070136) (xy 20.495468 -363.06273) (xy 20.435795 -363.048023) (xy 20.37833 -363.026231)
			(xy 20.32391 -362.997672) (xy 20.273329 -362.962762) (xy 20.227325 -362.922009) (xy 20.186568 -362.876009)
			(xy 20.151653 -362.825431) (xy 20.123088 -362.771014) (xy 20.101291 -362.713551) (xy 20.086579 -362.653879)
			(xy 20.079166 -362.592869) (xy 20.0787 -362.56214) (xy 19.42973 -362.56214) (xy 19.42973 -364.802631)
			(xy 20.167848 -364.802631) (xy 20.167848 -364.738709) (xy 20.175859 -364.675291) (xy 20.191756 -364.613377)
			(xy 20.215288 -364.553944) (xy 20.246082 -364.497929) (xy 20.283655 -364.446214) (xy 20.327412 -364.399617)
			(xy 20.376665 -364.358872) (xy 20.430636 -364.324621) (xy 20.488475 -364.297404) (xy 20.549268 -364.277651)
			(xy 20.612058 -364.265673) (xy 20.675854 -364.26166) (xy 20.73965 -364.265673) (xy 20.80244 -364.277651)
			(xy 20.863233 -364.297404) (xy 20.921072 -364.324621) (xy 20.975043 -364.358872) (xy 21.024296 -364.399617)
			(xy 21.068053 -364.446214) (xy 21.105626 -364.497929) (xy 21.13642 -364.553944) (xy 21.159952 -364.613377)
			(xy 21.160882 -364.617) (xy 23.239982 -364.617) (xy 23.244053 -364.561378) (xy 23.256179 -364.506941)
			(xy 23.276102 -364.45485) (xy 23.303398 -364.406215) (xy 23.337484 -364.362072) (xy 23.377633 -364.323363)
			(xy 23.422991 -364.290912) (xy 23.472591 -364.265411) (xy 23.525375 -364.247404) (xy 23.580218 -364.237274)
			(xy 23.635952 -364.235237) (xy 23.691389 -364.241337) (xy 23.745346 -364.255443) (xy 23.796675 -364.277255)
			(xy 23.844281 -364.306309) (xy 23.887149 -364.341984) (xy 23.924366 -364.383521) (xy 23.955139 -364.430034)
			(xy 23.978811 -364.480531) (xy 23.994879 -364.533938) (xy 24.002999 -364.589114) (xy 24.003508 -364.617)
			(xy 24.002999 -364.644886) (xy 23.994879 -364.700062) (xy 23.978811 -364.753469) (xy 23.955139 -364.803966)
			(xy 23.924366 -364.850479) (xy 23.887149 -364.892016) (xy 23.844281 -364.927691) (xy 23.796675 -364.956745)
			(xy 23.745346 -364.978557) (xy 23.691389 -364.992663) (xy 23.635952 -364.998763) (xy 23.580218 -364.996726)
			(xy 23.525375 -364.986596) (xy 23.472591 -364.968589) (xy 23.422991 -364.943088) (xy 23.377633 -364.910637)
			(xy 23.337484 -364.871928) (xy 23.303398 -364.827785) (xy 23.276102 -364.77915) (xy 23.256179 -364.727059)
			(xy 23.244053 -364.672622) (xy 23.239982 -364.617) (xy 21.160882 -364.617) (xy 21.175849 -364.675291)
			(xy 21.18386 -364.738709) (xy 21.184362 -364.77067) (xy 21.18386 -364.802631) (xy 21.175849 -364.866049)
			(xy 21.159952 -364.927963) (xy 21.13642 -364.987396) (xy 21.105626 -365.043411) (xy 21.068053 -365.095126)
			(xy 21.024296 -365.141723) (xy 20.975043 -365.182468) (xy 20.921072 -365.216719) (xy 20.863233 -365.243936)
			(xy 20.80244 -365.263689) (xy 20.73965 -365.275667) (xy 20.675854 -365.279681) (xy 20.612058 -365.275667)
			(xy 20.549268 -365.263689) (xy 20.488475 -365.243936) (xy 20.430636 -365.216719) (xy 20.376665 -365.182468)
			(xy 20.327412 -365.141723) (xy 20.283655 -365.095126) (xy 20.246082 -365.043411) (xy 20.215288 -364.987396)
			(xy 20.191756 -364.927963) (xy 20.175859 -364.866049) (xy 20.167848 -364.802631) (xy 19.42973 -364.802631)
			(xy 19.42973 -365.76) (xy 21.080982 -365.76) (xy 21.085053 -365.704378) (xy 21.097179 -365.649941)
			(xy 21.117102 -365.59785) (xy 21.144398 -365.549215) (xy 21.178484 -365.505072) (xy 21.218633 -365.466363)
			(xy 21.263991 -365.433912) (xy 21.313591 -365.408411) (xy 21.366375 -365.390404) (xy 21.421218 -365.380274)
			(xy 21.476952 -365.378237) (xy 21.532389 -365.384337) (xy 21.586346 -365.398443) (xy 21.637675 -365.420255)
			(xy 21.685281 -365.449309) (xy 21.728149 -365.484984) (xy 21.765366 -365.526521) (xy 21.796139 -365.573034)
			(xy 21.819811 -365.623531) (xy 21.835879 -365.676938) (xy 21.843999 -365.732114) (xy 21.844508 -365.76)
			(xy 23.239982 -365.76) (xy 23.244053 -365.704378) (xy 23.256179 -365.649941) (xy 23.276102 -365.59785)
			(xy 23.303398 -365.549215) (xy 23.337484 -365.505072) (xy 23.377633 -365.466363) (xy 23.422991 -365.433912)
			(xy 23.472591 -365.408411) (xy 23.525375 -365.390404) (xy 23.580218 -365.380274) (xy 23.635952 -365.378237)
			(xy 23.691389 -365.384337) (xy 23.745346 -365.398443) (xy 23.796675 -365.420255) (xy 23.844281 -365.449309)
			(xy 23.887149 -365.484984) (xy 23.924366 -365.526521) (xy 23.955139 -365.573034) (xy 23.978811 -365.623531)
			(xy 23.994879 -365.676938) (xy 24.002999 -365.732114) (xy 24.003508 -365.76) (xy 24.002999 -365.787886)
			(xy 23.994879 -365.843062) (xy 23.978811 -365.896469) (xy 23.955139 -365.946966) (xy 23.924366 -365.993479)
			(xy 23.887149 -366.035016) (xy 23.844281 -366.070691) (xy 23.796675 -366.099745) (xy 23.745346 -366.121557)
			(xy 23.691389 -366.135663) (xy 23.635952 -366.141763) (xy 23.580218 -366.139726) (xy 23.525375 -366.129596)
			(xy 23.472591 -366.111589) (xy 23.422991 -366.086088) (xy 23.377633 -366.053637) (xy 23.337484 -366.014928)
			(xy 23.303398 -365.970785) (xy 23.276102 -365.92215) (xy 23.256179 -365.870059) (xy 23.244053 -365.815622)
			(xy 23.239982 -365.76) (xy 21.844508 -365.76) (xy 21.843999 -365.787886) (xy 21.835879 -365.843062)
			(xy 21.819811 -365.896469) (xy 21.796139 -365.946966) (xy 21.765366 -365.993479) (xy 21.728149 -366.035016)
			(xy 21.685281 -366.070691) (xy 21.637675 -366.099745) (xy 21.586346 -366.121557) (xy 21.532389 -366.135663)
			(xy 21.476952 -366.141763) (xy 21.421218 -366.139726) (xy 21.366375 -366.129596) (xy 21.313591 -366.111589)
			(xy 21.263991 -366.086088) (xy 21.218633 -366.053637) (xy 21.178484 -366.014928) (xy 21.144398 -365.970785)
			(xy 21.117102 -365.92215) (xy 21.097179 -365.870059) (xy 21.085053 -365.815622) (xy 21.080982 -365.76)
			(xy 19.42973 -365.76) (xy 19.42973 -367.38941) (xy 19.430156 -367.399479) (xy 19.437876 -367.418078)
			(xy 19.444716 -367.425478) (xy 20.051522 -368.032284) (xy 20.058932 -368.038966) (xy 20.077368 -368.046543)
			(xy 20.087336 -368.047016) (xy 20.8534 -368.047016) (xy 20.863709 -368.046586) (xy 20.88271 -368.038588)
			(xy 20.89023 -368.031522) (xy 20.948142 -367.970816) (xy 20.955508 -367.951512) (xy 20.955 -367.941098)
			(xy 20.954492 -367.919) (xy 20.954976 -367.887725) (xy 20.962657 -367.825649) (xy 20.977892 -367.764983)
			(xy 21.00045 -367.706642) (xy 21.02999 -367.651508) (xy 21.066068 -367.600411) (xy 21.108139 -367.554124)
			(xy 21.155567 -367.513344) (xy 21.181314 -367.495582) (xy 21.191472 -367.48812) (xy 21.203494 -367.466001)
			(xy 21.204174 -367.453418) (xy 21.204174 -367.368582) (xy 21.20346 -367.356001) (xy 21.191474 -367.33387)
			(xy 21.181314 -367.326418) (xy 21.155532 -367.308699) (xy 21.108083 -367.267928) (xy 21.065995 -367.221642)
			(xy 21.029904 -367.170542) (xy 21.000358 -367.115399) (xy 20.977801 -367.057047) (xy 20.962575 -366.996369)
			(xy 20.954911 -366.93428) (xy 20.954492 -366.903) (xy 20.954994 -366.871039) (xy 20.963005 -366.807621)
			(xy 20.978902 -366.745707) (xy 21.002434 -366.686274) (xy 21.033228 -366.630259) (xy 21.070801 -366.578544)
			(xy 21.114558 -366.531947) (xy 21.163811 -366.491202) (xy 21.217782 -366.456951) (xy 21.275621 -366.429734)
			(xy 21.336414 -366.409981) (xy 21.399204 -366.398003) (xy 21.463 -366.39399) (xy 21.526796 -366.398003)
			(xy 21.589586 -366.409981) (xy 21.650379 -366.429734) (xy 21.708218 -366.456951) (xy 21.762189 -366.491202)
			(xy 21.811442 -366.531947) (xy 21.855199 -366.578544) (xy 21.892772 -366.630259) (xy 21.923566 -366.686274)
			(xy 21.947098 -366.745707) (xy 21.962995 -366.807621) (xy 21.971006 -366.871039) (xy 21.971508 -366.903)
			(xy 21.971024 -366.934275) (xy 21.963343 -366.996351) (xy 21.948108 -367.057017) (xy 21.92555 -367.115358)
			(xy 21.89601 -367.170492) (xy 21.859932 -367.221589) (xy 21.817861 -367.267876) (xy 21.770433 -367.308656)
			(xy 21.744686 -367.326418) (xy 21.734528 -367.33388) (xy 21.722506 -367.355999) (xy 21.721826 -367.368582)
			(xy 21.721826 -367.453418) (xy 21.72254 -367.465999) (xy 21.734526 -367.48813) (xy 21.744686 -367.495582)
			(xy 21.770468 -367.513301) (xy 21.817917 -367.554072) (xy 21.860005 -367.600358) (xy 21.896096 -367.651458)
			(xy 21.925642 -367.706601) (xy 21.948199 -367.764953) (xy 21.963425 -367.825631) (xy 21.971089 -367.88772)
			(xy 21.971508 -367.919) (xy 21.971 -367.941098) (xy 21.970492 -367.951512) (xy 21.977858 -367.970816)
			(xy 22.03577 -368.031522) (xy 22.043275 -368.038609) (xy 22.062286 -368.046599) (xy 22.0726 -368.047016)
			(xy 23.0124 -368.047016) (xy 23.022709 -368.046586) (xy 23.04171 -368.038588) (xy 23.04923 -368.031522)
			(xy 23.107142 -367.970816) (xy 23.114508 -367.951512) (xy 23.114 -367.941098) (xy 23.113492 -367.919)
			(xy 23.113976 -367.887725) (xy 23.121657 -367.825649) (xy 23.136892 -367.764983) (xy 23.15945 -367.706642)
			(xy 23.18899 -367.651508) (xy 23.225068 -367.600411) (xy 23.267139 -367.554124) (xy 23.314567 -367.513344)
			(xy 23.340314 -367.495582) (xy 23.350472 -367.48812) (xy 23.362494 -367.466001) (xy 23.363174 -367.453418)
			(xy 23.363174 -367.368582) (xy 23.36246 -367.356001) (xy 23.350474 -367.33387) (xy 23.340314 -367.326418)
			(xy 23.314532 -367.308699) (xy 23.267083 -367.267928) (xy 23.224995 -367.221642) (xy 23.188904 -367.170542)
			(xy 23.159358 -367.115399) (xy 23.136801 -367.057047) (xy 23.121575 -366.996369) (xy 23.113911 -366.93428)
			(xy 23.113492 -366.903) (xy 23.113994 -366.871039) (xy 23.122005 -366.807621) (xy 23.137902 -366.745707)
			(xy 23.161434 -366.686274) (xy 23.192228 -366.630259) (xy 23.229801 -366.578544) (xy 23.273558 -366.531947)
			(xy 23.322811 -366.491202) (xy 23.376782 -366.456951) (xy 23.434621 -366.429734) (xy 23.495414 -366.409981)
			(xy 23.558204 -366.398003) (xy 23.622 -366.39399) (xy 23.685796 -366.398003) (xy 23.748586 -366.409981)
			(xy 23.809379 -366.429734) (xy 23.867218 -366.456951) (xy 23.921189 -366.491202) (xy 23.970442 -366.531947)
			(xy 24.014199 -366.578544) (xy 24.051772 -366.630259) (xy 24.082566 -366.686274) (xy 24.106098 -366.745707)
			(xy 24.121995 -366.807621) (xy 24.130006 -366.871039) (xy 24.130508 -366.903) (xy 24.130024 -366.934275)
			(xy 24.122343 -366.996351) (xy 24.107108 -367.057017) (xy 24.08455 -367.115358) (xy 24.05501 -367.170492)
			(xy 24.018932 -367.221589) (xy 23.976861 -367.267876) (xy 23.929433 -367.308656) (xy 23.903686 -367.326418)
			(xy 23.893528 -367.33388) (xy 23.881506 -367.355999) (xy 23.880826 -367.368582) (xy 23.880826 -367.453418)
			(xy 23.88154 -367.465999) (xy 23.893526 -367.48813) (xy 23.903686 -367.495582) (xy 23.929468 -367.513301)
			(xy 23.976917 -367.554072) (xy 24.019005 -367.600358) (xy 24.055096 -367.651458) (xy 24.084642 -367.706601)
			(xy 24.107199 -367.764953) (xy 24.122425 -367.825631) (xy 24.130089 -367.88772) (xy 24.130508 -367.919)
			(xy 24.129492 -367.952782) (xy 24.12873 -367.963196) (xy 24.135842 -367.983008) (xy 24.193754 -368.044984)
			(xy 24.201254 -368.052247) (xy 24.220408 -368.060501) (xy 24.230838 -368.060986) (xy 24.308816 -368.060986)
			(xy 24.318885 -368.061411) (xy 24.337487 -368.069128) (xy 24.344884 -368.075972) (xy 25.034748 -368.765836)
			(xy 25.042146 -368.772682) (xy 25.060745 -368.780409) (xy 25.070816 -368.780822)
		)
		(stroke
			(width 0)
			(type solid)
		)
		(fill yes)
		(layer "In6.Cu")
		(net "P3V3_AUX")
	)
	(gr_poly
		(pts
			(xy 96.974152 -76.057252) (xy 96.984053 -76.05674) (xy 97.002356 -76.049166) (xy 97.009712 -76.04252)
			(xy 99.664266 -73.387966) (xy 99.671075 -73.380621) (xy 99.678801 -73.362158) (xy 99.679252 -73.352152)
			(xy 99.679252 -72.559164) (xy 99.678915 -72.54969) (xy 99.672125 -72.532005) (xy 99.659374 -72.517994)
			(xy 99.651058 -72.513444) (xy 99.556062 -72.466708) (xy 99.52736 -72.469502) (xy 99.51593 -72.478392)
			(xy 99.495879 -72.493274) (xy 99.452627 -72.518227) (xy 99.406487 -72.537321) (xy 99.35825 -72.550229)
			(xy 99.308741 -72.556731) (xy 99.283774 -72.557132) (xy 99.256523 -72.556644) (xy 99.202577 -72.548885)
			(xy 99.150284 -72.533528) (xy 99.100709 -72.510886) (xy 99.05486 -72.481419) (xy 99.013671 -72.445728)
			(xy 98.97798 -72.404539) (xy 98.948513 -72.35869) (xy 98.925871 -72.309114) (xy 98.910514 -72.256821)
			(xy 98.902755 -72.202875) (xy 98.902266 -72.175624) (xy 98.902795 -72.146852) (xy 98.911445 -72.089962)
			(xy 98.928539 -72.035015) (xy 98.953689 -71.983258) (xy 98.986324 -71.935863) (xy 99.025705 -71.893905)
			(xy 99.070938 -71.858335) (xy 99.121 -71.829959) (xy 99.174754 -71.809421) (xy 99.202748 -71.802752)
			(xy 99.210114 -71.801228) (xy 99.22256 -71.79437) (xy 99.664266 -71.352664) (xy 99.671075 -71.345319)
			(xy 99.6788 -71.326856) (xy 99.679252 -71.31685) (xy 99.679252 -71.130668) (xy 99.678821 -71.120628)
			(xy 99.671104 -71.10209) (xy 99.656864 -71.087932) (xy 99.647756 -71.083678) (xy 99.633532 -71.077836)
			(xy 99.603814 -71.083678) (xy 99.418902 -71.268844) (xy 99.412044 -71.28129) (xy 99.41052 -71.288656)
			(xy 99.4039 -71.316665) (xy 99.383373 -71.370431) (xy 99.355002 -71.420504) (xy 99.319429 -71.465745)
			(xy 99.277463 -71.505129) (xy 99.230057 -71.53776) (xy 99.178286 -71.562899) (xy 99.123326 -71.579974)
			(xy 99.066424 -71.588598) (xy 99.037648 -71.589138) (xy 99.010392 -71.588678) (xy 98.956434 -71.580927)
			(xy 98.904129 -71.565576) (xy 98.854541 -71.542936) (xy 98.808679 -71.51347) (xy 98.767479 -71.477777)
			(xy 98.731777 -71.436583) (xy 98.702301 -71.390728) (xy 98.679652 -71.341144) (xy 98.664289 -71.288842)
			(xy 98.656527 -71.234886) (xy 98.65614 -71.20763) (xy 98.656664 -71.178917) (xy 98.66528 -71.122142)
			(xy 98.682307 -71.067299) (xy 98.70736 -71.015627) (xy 98.739873 -70.968292) (xy 98.779113 -70.926365)
			(xy 98.824193 -70.890791) (xy 98.874094 -70.862374) (xy 98.927691 -70.841756) (xy 98.955606 -70.835012)
			(xy 98.962972 -70.833234) (xy 98.975418 -70.82663) (xy 99.6696 -70.132194) (xy 99.673971 -70.125618)
			(xy 99.678871 -70.110618) (xy 99.679252 -70.10273) (xy 99.679252 -58.325512) (xy 99.678611 -58.312956)
			(xy 99.666753 -58.290823) (xy 99.656646 -58.283348) (xy 99.57562 -58.229246) (xy 99.550728 -58.226706)
			(xy 99.53879 -58.231786) (xy 99.515551 -58.240974) (xy 99.467275 -58.25388) (xy 99.417726 -58.260372)
			(xy 99.39274 -58.260742) (xy 99.365483 -58.260282) (xy 99.311523 -58.252529) (xy 99.259215 -58.237175)
			(xy 99.209626 -58.214533) (xy 99.163763 -58.185063) (xy 99.122562 -58.149366) (xy 99.086861 -58.108169)
			(xy 99.057387 -58.062309) (xy 99.034739 -58.012722) (xy 99.01938 -57.960416) (xy 99.011621 -57.906457)
			(xy 99.011621 -57.851943) (xy 99.01938 -57.797984) (xy 99.034739 -57.745678) (xy 99.057387 -57.696091)
			(xy 99.086861 -57.650231) (xy 99.122562 -57.609034) (xy 99.163763 -57.573337) (xy 99.209626 -57.543867)
			(xy 99.259215 -57.521225) (xy 99.311523 -57.505871) (xy 99.365483 -57.498118) (xy 99.39274 -57.497726)
			(xy 99.417726 -57.4981) (xy 99.467275 -57.504589) (xy 99.515553 -57.517491) (xy 99.53879 -57.526682)
			(xy 99.550728 -57.531762) (xy 99.57562 -57.529222) (xy 99.656646 -57.47512) (xy 99.666711 -57.467605)
			(xy 99.678576 -57.445498) (xy 99.679252 -57.432956) (xy 99.679252 -56.015128) (xy 99.678814 -56.005065)
			(xy 99.671076 -55.986484) (xy 99.664266 -55.97906) (xy 98.028252 -54.343046) (xy 98.020853 -54.336202)
			(xy 98.002254 -54.328478) (xy 97.992184 -54.32806) (xy 81.110328 -54.32806) (xy 81.100265 -54.328498)
			(xy 81.081685 -54.336237) (xy 81.07426 -54.343046) (xy 80.261968 -55.155338) (xy 80.25512 -55.162735)
			(xy 80.247389 -55.181334) (xy 80.246982 -55.191406) (xy 80.246982 -55.98668) (xy 88.03716 -55.98668)
			(xy 88.041231 -55.931058) (xy 88.053357 -55.876621) (xy 88.07328 -55.82453) (xy 88.100576 -55.775895)
			(xy 88.134662 -55.731752) (xy 88.174811 -55.693043) (xy 88.220169 -55.660592) (xy 88.269769 -55.635091)
			(xy 88.322553 -55.617084) (xy 88.377396 -55.606954) (xy 88.43313 -55.604917) (xy 88.488567 -55.611017)
			(xy 88.542524 -55.625123) (xy 88.593853 -55.646935) (xy 88.641459 -55.675989) (xy 88.684327 -55.711664)
			(xy 88.721544 -55.753201) (xy 88.752317 -55.799714) (xy 88.775989 -55.850211) (xy 88.792057 -55.903618)
			(xy 88.800177 -55.958794) (xy 88.800686 -55.98668) (xy 88.800177 -56.014566) (xy 88.792057 -56.069742)
			(xy 88.775989 -56.123149) (xy 88.752317 -56.173646) (xy 88.721544 -56.220159) (xy 88.684327 -56.261696)
			(xy 88.641459 -56.297371) (xy 88.593853 -56.326425) (xy 88.542524 -56.348237) (xy 88.488567 -56.362343)
			(xy 88.43313 -56.368443) (xy 88.377396 -56.366406) (xy 88.322553 -56.356276) (xy 88.269769 -56.338269)
			(xy 88.220169 -56.312768) (xy 88.174811 -56.280317) (xy 88.134662 -56.241608) (xy 88.100576 -56.197465)
			(xy 88.07328 -56.14883) (xy 88.053357 -56.096739) (xy 88.041231 -56.042302) (xy 88.03716 -55.98668)
			(xy 80.246982 -55.98668) (xy 80.246982 -56.067706) (xy 80.246982 -56.070246) (xy 80.248226 -56.082148)
			(xy 80.260018 -56.102938) (xy 80.269588 -56.110124) (xy 80.275176 -56.113172) (xy 80.369156 -56.160162)
			(xy 80.397858 -56.157622) (xy 80.409542 -56.148986) (xy 80.434428 -56.131134) (xy 80.488702 -56.102765)
			(xy 80.546813 -56.083436) (xy 80.607267 -56.073644) (xy 80.637888 -56.07304) (xy 80.645254 -56.07304)
			(xy 80.672159 -56.074022) (xy 80.725305 -56.082618) (xy 80.776714 -56.098603) (xy 80.825366 -56.121657)
			(xy 80.870291 -56.151323) (xy 80.9106 -56.187012) (xy 80.945489 -56.228014) (xy 80.974266 -56.273515)
			(xy 80.996359 -56.32261) (xy 81.011329 -56.374324) (xy 81.018878 -56.427629) (xy 81.019396 -56.454548)
			(xy 81.01965 -56.454548) (xy 81.019176 -56.48202) (xy 81.011304 -56.536397) (xy 81.005686 -56.555386)
			(xy 87.020906 -56.555386) (xy 87.024977 -56.499764) (xy 87.037103 -56.445327) (xy 87.057026 -56.393236)
			(xy 87.084322 -56.344601) (xy 87.118408 -56.300458) (xy 87.158557 -56.261749) (xy 87.203915 -56.229298)
			(xy 87.253515 -56.203797) (xy 87.306299 -56.18579) (xy 87.361142 -56.17566) (xy 87.416876 -56.173623)
			(xy 87.472313 -56.179723) (xy 87.52627 -56.193829) (xy 87.577599 -56.215641) (xy 87.625205 -56.244695)
			(xy 87.668073 -56.28037) (xy 87.70529 -56.321907) (xy 87.736063 -56.36842) (xy 87.759735 -56.418917)
			(xy 87.775803 -56.472324) (xy 87.783923 -56.5275) (xy 87.784432 -56.555386) (xy 87.783923 -56.583272)
			(xy 87.775803 -56.638448) (xy 87.759735 -56.691855) (xy 87.736063 -56.742352) (xy 87.70529 -56.788865)
			(xy 87.668073 -56.830402) (xy 87.625205 -56.866077) (xy 87.595261 -56.884352) (xy 90.020093 -56.884352)
			(xy 90.020093 -56.829848) (xy 90.027851 -56.775899) (xy 90.043207 -56.723603) (xy 90.06585 -56.674025)
			(xy 90.095319 -56.628175) (xy 90.131014 -56.586985) (xy 90.172207 -56.551295) (xy 90.21806 -56.521831)
			(xy 90.267641 -56.499193) (xy 90.319938 -56.483842) (xy 90.373888 -56.476091) (xy 90.40114 -56.47563)
			(xy 90.428272 -56.476087) (xy 90.481991 -56.48376) (xy 90.534082 -56.49896) (xy 90.583498 -56.521381)
			(xy 90.606626 -56.535574) (xy 90.61577 -56.541416) (xy 90.636344 -56.544718) (xy 90.729816 -56.52008)
			(xy 90.746072 -56.506872) (xy 90.751152 -56.49722) (xy 90.763029 -56.47547) (xy 90.791567 -56.434955)
			(xy 90.808048 -56.416448) (xy 90.814398 -56.40959) (xy 90.821256 -56.392572) (xy 90.823288 -56.30672)
			(xy 90.816938 -56.289194) (xy 90.811096 -56.282082) (xy 90.794181 -56.261331) (xy 90.765678 -56.216014)
			(xy 90.743784 -56.16716) (xy 90.728928 -56.115727) (xy 90.721402 -56.062723) (xy 90.720926 -56.035956)
			(xy 90.721337 -56.008702) (xy 90.7291 -55.95475) (xy 90.744463 -55.902452) (xy 90.767112 -55.852872)
			(xy 90.796586 -55.80702) (xy 90.832285 -55.76583) (xy 90.873483 -55.730139) (xy 90.919341 -55.700674)
			(xy 90.968925 -55.678036) (xy 91.021226 -55.662684) (xy 91.07518 -55.654931) (xy 91.102434 -55.654448)
			(xy 91.129806 -55.654882) (xy 91.183986 -55.662706) (xy 91.23649 -55.678202) (xy 91.286237 -55.701051)
			(xy 91.332202 -55.730783) (xy 91.353132 -55.748428) (xy 91.360244 -55.754524) (xy 91.377262 -55.760874)
			(xy 91.462606 -55.760874) (xy 91.479624 -55.754524) (xy 91.486736 -55.748428) (xy 91.507685 -55.73081)
			(xy 91.553653 -55.701094) (xy 91.603396 -55.678253) (xy 91.655893 -55.662758) (xy 91.710066 -55.654924)
			(xy 91.737434 -55.654448) (xy 91.764684 -55.654946) (xy 91.818629 -55.662706) (xy 91.870921 -55.678063)
			(xy 91.920495 -55.700705) (xy 91.966343 -55.730171) (xy 92.007532 -55.765861) (xy 92.043223 -55.807049)
			(xy 92.07269 -55.852896) (xy 92.095333 -55.90247) (xy 92.110692 -55.954761) (xy 92.118453 -56.008706)
			(xy 92.118942 -56.035956) (xy 92.118464 -56.063326) (xy 92.110651 -56.117505) (xy 92.095166 -56.170009)
			(xy 92.072326 -56.219756) (xy 92.042603 -56.265723) (xy 92.024962 -56.286654) (xy 92.018866 -56.293766)
			(xy 92.012516 -56.310784) (xy 92.012516 -56.355234) (xy 92.515688 -56.355234) (xy 92.519759 -56.299612)
			(xy 92.531885 -56.245175) (xy 92.551808 -56.193084) (xy 92.579104 -56.144449) (xy 92.61319 -56.100306)
			(xy 92.653339 -56.061597) (xy 92.698697 -56.029146) (xy 92.748297 -56.003645) (xy 92.801081 -55.985638)
			(xy 92.855924 -55.975508) (xy 92.911658 -55.973471) (xy 92.967095 -55.979571) (xy 93.021052 -55.993677)
			(xy 93.072381 -56.015489) (xy 93.119987 -56.044543) (xy 93.162855 -56.080218) (xy 93.200072 -56.121755)
			(xy 93.230845 -56.168268) (xy 93.254517 -56.218765) (xy 93.270585 -56.272172) (xy 93.278705 -56.327348)
			(xy 93.279214 -56.355234) (xy 93.278705 -56.38312) (xy 93.270585 -56.438296) (xy 93.268217 -56.446166)
			(xy 95.405954 -56.446166) (xy 95.410025 -56.390544) (xy 95.422151 -56.336107) (xy 95.442074 -56.284016)
			(xy 95.46937 -56.235381) (xy 95.503456 -56.191238) (xy 95.543605 -56.152529) (xy 95.588963 -56.120078)
			(xy 95.638563 -56.094577) (xy 95.691347 -56.07657) (xy 95.74619 -56.06644) (xy 95.801924 -56.064403)
			(xy 95.857361 -56.070503) (xy 95.911318 -56.084609) (xy 95.962647 -56.106421) (xy 96.010253 -56.135475)
			(xy 96.053121 -56.17115) (xy 96.090338 -56.212687) (xy 96.121111 -56.2592) (xy 96.144783 -56.309697)
			(xy 96.160851 -56.363104) (xy 96.168971 -56.41828) (xy 96.16948 -56.446166) (xy 96.168971 -56.474052)
			(xy 96.160851 -56.529228) (xy 96.144783 -56.582635) (xy 96.121111 -56.633132) (xy 96.090338 -56.679645)
			(xy 96.053121 -56.721182) (xy 96.010253 -56.756857) (xy 95.962647 -56.785911) (xy 95.911318 -56.807723)
			(xy 95.857361 -56.821829) (xy 95.801924 -56.827929) (xy 95.74619 -56.825892) (xy 95.691347 -56.815762)
			(xy 95.638563 -56.797755) (xy 95.588963 -56.772254) (xy 95.543605 -56.739803) (xy 95.503456 -56.701094)
			(xy 95.46937 -56.656951) (xy 95.442074 -56.608316) (xy 95.422151 -56.556225) (xy 95.410025 -56.501788)
			(xy 95.405954 -56.446166) (xy 93.268217 -56.446166) (xy 93.254517 -56.491703) (xy 93.230845 -56.5422)
			(xy 93.200072 -56.588713) (xy 93.162855 -56.63025) (xy 93.119987 -56.665925) (xy 93.072381 -56.694979)
			(xy 93.021052 -56.716791) (xy 92.967095 -56.730897) (xy 92.911658 -56.736997) (xy 92.855924 -56.73496)
			(xy 92.801081 -56.72483) (xy 92.748297 -56.706823) (xy 92.698697 -56.681322) (xy 92.653339 -56.648871)
			(xy 92.61319 -56.610162) (xy 92.579104 -56.566019) (xy 92.551808 -56.517384) (xy 92.531885 -56.465293)
			(xy 92.519759 -56.410856) (xy 92.515688 -56.355234) (xy 92.012516 -56.355234) (xy 92.012516 -56.396128)
			(xy 92.018866 -56.413146) (xy 92.024962 -56.420258) (xy 92.042589 -56.4412) (xy 92.072304 -56.487169)
			(xy 92.095143 -56.536914) (xy 92.110637 -56.589413) (xy 92.118467 -56.643587) (xy 92.118942 -56.670956)
			(xy 92.118404 -56.698206) (xy 92.110654 -56.752153) (xy 92.095305 -56.804447) (xy 92.07267 -56.854025)
			(xy 92.04321 -56.899876) (xy 92.007524 -56.941069) (xy 91.966339 -56.976763) (xy 91.920493 -57.006233)
			(xy 91.87092 -57.028878) (xy 91.818629 -57.044237) (xy 91.764684 -57.051998) (xy 91.737434 -57.052464)
			(xy 91.709558 -57.051985) (xy 91.6544 -57.043873) (xy 91.601011 -57.027817) (xy 91.550529 -57.004159)
			(xy 91.504029 -56.973402) (xy 91.482926 -56.955182) (xy 91.475814 -56.948832) (xy 91.458542 -56.942228)
			(xy 91.370912 -56.942736) (xy 91.353894 -56.949594) (xy 91.346782 -56.956198) (xy 91.325525 -56.974907)
			(xy 91.278569 -57.006553) (xy 91.22745 -57.030907) (xy 91.173291 -57.047436) (xy 91.117284 -57.055775)
			(xy 91.088972 -57.056274) (xy 91.06184 -57.055811) (xy 91.008122 -57.04814) (xy 90.95603 -57.032942)
			(xy 90.906614 -57.010523) (xy 90.883486 -56.99633) (xy 90.874342 -56.990488) (xy 90.853768 -56.987186)
			(xy 90.760296 -57.011824) (xy 90.74404 -57.025032) (xy 90.73896 -57.034684) (xy 90.726471 -57.057411)
			(xy 90.696332 -57.099611) (xy 90.660759 -57.137343) (xy 90.620405 -57.169911) (xy 90.576014 -57.196717)
			(xy 90.528402 -57.217268) (xy 90.478447 -57.231183) (xy 90.427068 -57.238209) (xy 90.40114 -57.238646)
			(xy 90.373888 -57.238109) (xy 90.319938 -57.230358) (xy 90.267641 -57.215007) (xy 90.21806 -57.192369)
			(xy 90.172207 -57.162905) (xy 90.131014 -57.127215) (xy 90.095319 -57.086025) (xy 90.06585 -57.040175)
			(xy 90.043207 -56.990597) (xy 90.027851 -56.938301) (xy 90.020093 -56.884352) (xy 87.595261 -56.884352)
			(xy 87.577599 -56.895131) (xy 87.52627 -56.916943) (xy 87.472313 -56.931049) (xy 87.416876 -56.937149)
			(xy 87.361142 -56.935112) (xy 87.306299 -56.924982) (xy 87.253515 -56.906975) (xy 87.203915 -56.881474)
			(xy 87.158557 -56.849023) (xy 87.118408 -56.810314) (xy 87.084322 -56.766171) (xy 87.057026 -56.717536)
			(xy 87.037103 -56.665445) (xy 87.024977 -56.611008) (xy 87.020906 -56.555386) (xy 81.005686 -56.555386)
			(xy 80.995716 -56.589084) (xy 80.972734 -56.638991) (xy 80.942833 -56.685086) (xy 80.90663 -56.726417)
			(xy 80.886046 -56.744616) (xy 80.877918 -56.751474) (xy 80.864456 -56.779922) (xy 80.862131 -56.785084)
			(xy 80.85956 -56.796108) (xy 80.859376 -56.801766) (xy 80.859376 -56.8579) (xy 80.859557 -56.86356)
			(xy 80.862118 -56.874587) (xy 80.864456 -56.879744) (xy 80.877918 -56.908446) (xy 80.886046 -56.915304)
			(xy 80.90658 -56.933514) (xy 80.942721 -56.974815) (xy 80.972569 -57.02087) (xy 80.995507 -57.070729)
			(xy 81.011061 -57.12336) (xy 81.018911 -57.177677) (xy 81.019396 -57.205118) (xy 81.018908 -57.232368)
			(xy 81.01115 -57.286313) (xy 80.995793 -57.338605) (xy 80.973151 -57.388179) (xy 80.943684 -57.434026)
			(xy 80.907992 -57.475213) (xy 80.866802 -57.510902) (xy 80.820953 -57.540365) (xy 80.771377 -57.563004)
			(xy 80.719084 -57.578356) (xy 80.665138 -57.586111) (xy 80.637888 -57.586626) (xy 80.637634 -57.586626)
			(xy 80.607044 -57.586005) (xy 80.546655 -57.576203) (xy 80.488608 -57.556877) (xy 80.434395 -57.528524)
			(xy 80.409542 -57.51068) (xy 80.397858 -57.502044) (xy 80.369156 -57.499504) (xy 80.275176 -57.546494)
			(xy 80.269588 -57.549542) (xy 80.259978 -57.556692) (xy 80.248186 -57.577502) (xy 80.246982 -57.58942)
			(xy 80.246982 -57.954418) (xy 80.890362 -57.954418) (xy 80.894433 -57.898796) (xy 80.906559 -57.844359)
			(xy 80.926482 -57.792268) (xy 80.953778 -57.743633) (xy 80.987864 -57.69949) (xy 81.028013 -57.660781)
			(xy 81.073371 -57.62833) (xy 81.122971 -57.602829) (xy 81.175755 -57.584822) (xy 81.230598 -57.574692)
			(xy 81.286332 -57.572655) (xy 81.341769 -57.578755) (xy 81.395726 -57.592861) (xy 81.447055 -57.614673)
			(xy 81.494661 -57.643727) (xy 81.537529 -57.679402) (xy 81.574746 -57.720939) (xy 81.605519 -57.767452)
			(xy 81.629191 -57.817949) (xy 81.645259 -57.871356) (xy 81.653379 -57.926532) (xy 81.653888 -57.954418)
			(xy 81.653379 -57.982304) (xy 81.645259 -58.03748) (xy 81.629191 -58.090887) (xy 81.605519 -58.141384)
			(xy 81.574746 -58.187897) (xy 81.553401 -58.21172) (xy 88.173812 -58.21172) (xy 88.177883 -58.156098)
			(xy 88.190009 -58.101661) (xy 88.209932 -58.04957) (xy 88.237228 -58.000935) (xy 88.271314 -57.956792)
			(xy 88.311463 -57.918083) (xy 88.356821 -57.885632) (xy 88.406421 -57.860131) (xy 88.459205 -57.842124)
			(xy 88.514048 -57.831994) (xy 88.569782 -57.829957) (xy 88.625219 -57.836057) (xy 88.679176 -57.850163)
			(xy 88.730505 -57.871975) (xy 88.778111 -57.901029) (xy 88.820979 -57.936704) (xy 88.858196 -57.978241)
			(xy 88.888969 -58.024754) (xy 88.912641 -58.075251) (xy 88.928709 -58.128658) (xy 88.932373 -58.153554)
			(xy 93.68104 -58.153554) (xy 93.685111 -58.097932) (xy 93.697237 -58.043495) (xy 93.71716 -57.991404)
			(xy 93.744456 -57.942769) (xy 93.778542 -57.898626) (xy 93.818691 -57.859917) (xy 93.864049 -57.827466)
			(xy 93.913649 -57.801965) (xy 93.966433 -57.783958) (xy 94.021276 -57.773828) (xy 94.07701 -57.771791)
			(xy 94.132447 -57.777891) (xy 94.186404 -57.791997) (xy 94.237733 -57.813809) (xy 94.285339 -57.842863)
			(xy 94.328207 -57.878538) (xy 94.365424 -57.920075) (xy 94.396197 -57.966588) (xy 94.419869 -58.017085)
			(xy 94.435937 -58.070492) (xy 94.444057 -58.125668) (xy 94.444566 -58.153554) (xy 94.444057 -58.18144)
			(xy 94.435937 -58.236616) (xy 94.419869 -58.290023) (xy 94.396197 -58.34052) (xy 94.365424 -58.387033)
			(xy 94.328207 -58.42857) (xy 94.285339 -58.464245) (xy 94.237733 -58.493299) (xy 94.186404 -58.515111)
			(xy 94.132447 -58.529217) (xy 94.07701 -58.535317) (xy 94.021276 -58.53328) (xy 93.966433 -58.52315)
			(xy 93.913649 -58.505143) (xy 93.864049 -58.479642) (xy 93.818691 -58.447191) (xy 93.778542 -58.408482)
			(xy 93.744456 -58.364339) (xy 93.71716 -58.315704) (xy 93.697237 -58.263613) (xy 93.685111 -58.209176)
			(xy 93.68104 -58.153554) (xy 88.932373 -58.153554) (xy 88.936829 -58.183834) (xy 88.937338 -58.21172)
			(xy 88.936829 -58.239606) (xy 88.928709 -58.294782) (xy 88.912641 -58.348189) (xy 88.888969 -58.398686)
			(xy 88.858196 -58.445199) (xy 88.820979 -58.486736) (xy 88.778111 -58.522411) (xy 88.730505 -58.551465)
			(xy 88.679176 -58.573277) (xy 88.640753 -58.583322) (xy 89.025982 -58.583322) (xy 89.030053 -58.5277)
			(xy 89.042179 -58.473263) (xy 89.062102 -58.421172) (xy 89.089398 -58.372537) (xy 89.123484 -58.328394)
			(xy 89.163633 -58.289685) (xy 89.208991 -58.257234) (xy 89.258591 -58.231733) (xy 89.311375 -58.213726)
			(xy 89.366218 -58.203596) (xy 89.421952 -58.201559) (xy 89.477389 -58.207659) (xy 89.531346 -58.221765)
			(xy 89.582675 -58.243577) (xy 89.630281 -58.272631) (xy 89.673149 -58.308306) (xy 89.710366 -58.349843)
			(xy 89.741139 -58.396356) (xy 89.764811 -58.446853) (xy 89.780879 -58.50026) (xy 89.788999 -58.555436)
			(xy 89.789508 -58.583322) (xy 89.788999 -58.611208) (xy 89.780879 -58.666384) (xy 89.764811 -58.719791)
			(xy 89.741139 -58.770288) (xy 89.710366 -58.816801) (xy 89.673149 -58.858338) (xy 89.630281 -58.894013)
			(xy 89.582675 -58.923067) (xy 89.531346 -58.944879) (xy 89.477389 -58.958985) (xy 89.421952 -58.965085)
			(xy 89.366218 -58.963048) (xy 89.311375 -58.952918) (xy 89.258591 -58.934911) (xy 89.208991 -58.90941)
			(xy 89.163633 -58.876959) (xy 89.123484 -58.83825) (xy 89.089398 -58.794107) (xy 89.062102 -58.745472)
			(xy 89.042179 -58.693381) (xy 89.030053 -58.638944) (xy 89.025982 -58.583322) (xy 88.640753 -58.583322)
			(xy 88.625219 -58.587383) (xy 88.569782 -58.593483) (xy 88.514048 -58.591446) (xy 88.459205 -58.581316)
			(xy 88.406421 -58.563309) (xy 88.356821 -58.537808) (xy 88.311463 -58.505357) (xy 88.271314 -58.466648)
			(xy 88.237228 -58.422505) (xy 88.209932 -58.37387) (xy 88.190009 -58.321779) (xy 88.177883 -58.267342)
			(xy 88.173812 -58.21172) (xy 81.553401 -58.21172) (xy 81.537529 -58.229434) (xy 81.494661 -58.265109)
			(xy 81.447055 -58.294163) (xy 81.395726 -58.315975) (xy 81.341769 -58.330081) (xy 81.286332 -58.336181)
			(xy 81.230598 -58.334144) (xy 81.175755 -58.324014) (xy 81.122971 -58.306007) (xy 81.073371 -58.280506)
			(xy 81.028013 -58.248055) (xy 80.987864 -58.209346) (xy 80.953778 -58.165203) (xy 80.926482 -58.116568)
			(xy 80.906559 -58.064477) (xy 80.894433 -58.01004) (xy 80.890362 -57.954418) (xy 80.246982 -57.954418)
			(xy 80.246982 -58.87974) (xy 80.922112 -58.87974) (xy 80.926183 -58.824118) (xy 80.938309 -58.769681)
			(xy 80.958232 -58.71759) (xy 80.985528 -58.668955) (xy 81.019614 -58.624812) (xy 81.059763 -58.586103)
			(xy 81.105121 -58.553652) (xy 81.154721 -58.528151) (xy 81.207505 -58.510144) (xy 81.262348 -58.500014)
			(xy 81.318082 -58.497977) (xy 81.373519 -58.504077) (xy 81.427476 -58.518183) (xy 81.478805 -58.539995)
			(xy 81.526411 -58.569049) (xy 81.569279 -58.604724) (xy 81.606496 -58.646261) (xy 81.637269 -58.692774)
			(xy 81.660941 -58.743271) (xy 81.677009 -58.796678) (xy 81.685129 -58.851854) (xy 81.685638 -58.87974)
			(xy 81.685129 -58.907626) (xy 81.677009 -58.962802) (xy 81.660941 -59.016209) (xy 81.637269 -59.066706)
			(xy 81.606496 -59.113219) (xy 81.569279 -59.154756) (xy 81.526411 -59.190431) (xy 81.478805 -59.219485)
			(xy 81.427476 -59.241297) (xy 81.373519 -59.255403) (xy 81.318082 -59.261503) (xy 81.262348 -59.259466)
			(xy 81.207505 -59.249336) (xy 81.154721 -59.231329) (xy 81.105121 -59.205828) (xy 81.059763 -59.173377)
			(xy 81.019614 -59.134668) (xy 80.985528 -59.090525) (xy 80.958232 -59.04189) (xy 80.938309 -58.989799)
			(xy 80.926183 -58.935362) (xy 80.922112 -58.87974) (xy 80.246982 -58.87974) (xy 80.246982 -59.43092)
			(xy 86.459312 -59.43092) (xy 86.463383 -59.375298) (xy 86.475509 -59.320861) (xy 86.495432 -59.26877)
			(xy 86.522728 -59.220135) (xy 86.556814 -59.175992) (xy 86.596963 -59.137283) (xy 86.642321 -59.104832)
			(xy 86.691921 -59.079331) (xy 86.744705 -59.061324) (xy 86.799548 -59.051194) (xy 86.855282 -59.049157)
			(xy 86.910719 -59.055257) (xy 86.964676 -59.069363) (xy 87.016005 -59.091175) (xy 87.063611 -59.120229)
			(xy 87.106479 -59.155904) (xy 87.143696 -59.197441) (xy 87.174469 -59.243954) (xy 87.198141 -59.294451)
			(xy 87.214209 -59.347858) (xy 87.222329 -59.403034) (xy 87.222838 -59.43092) (xy 87.222329 -59.458806)
			(xy 87.214209 -59.513982) (xy 87.198141 -59.567389) (xy 87.174469 -59.617886) (xy 87.143696 -59.664399)
			(xy 87.106479 -59.705936) (xy 87.063611 -59.741611) (xy 87.016005 -59.770665) (xy 86.964676 -59.792477)
			(xy 86.910719 -59.806583) (xy 86.855282 -59.812683) (xy 86.799548 -59.810646) (xy 86.744705 -59.800516)
			(xy 86.691921 -59.782509) (xy 86.642321 -59.757008) (xy 86.596963 -59.724557) (xy 86.556814 -59.685848)
			(xy 86.522728 -59.641705) (xy 86.495432 -59.59307) (xy 86.475509 -59.540979) (xy 86.463383 -59.486542)
			(xy 86.459312 -59.43092) (xy 80.246982 -59.43092) (xy 80.246982 -59.853322) (xy 89.025982 -59.853322)
			(xy 89.030053 -59.7977) (xy 89.042179 -59.743263) (xy 89.062102 -59.691172) (xy 89.089398 -59.642537)
			(xy 89.123484 -59.598394) (xy 89.163633 -59.559685) (xy 89.208991 -59.527234) (xy 89.258591 -59.501733)
			(xy 89.311375 -59.483726) (xy 89.366218 -59.473596) (xy 89.421952 -59.471559) (xy 89.477389 -59.477659)
			(xy 89.531346 -59.491765) (xy 89.582675 -59.513577) (xy 89.630281 -59.542631) (xy 89.673149 -59.578306)
			(xy 89.710366 -59.619843) (xy 89.741139 -59.666356) (xy 89.764811 -59.716853) (xy 89.780879 -59.77026)
			(xy 89.786075 -59.80557) (xy 93.68739 -59.80557) (xy 93.691461 -59.749948) (xy 93.703587 -59.695511)
			(xy 93.72351 -59.64342) (xy 93.750806 -59.594785) (xy 93.784892 -59.550642) (xy 93.825041 -59.511933)
			(xy 93.870399 -59.479482) (xy 93.919999 -59.453981) (xy 93.972783 -59.435974) (xy 94.027626 -59.425844)
			(xy 94.08336 -59.423807) (xy 94.138797 -59.429907) (xy 94.192754 -59.444013) (xy 94.244083 -59.465825)
			(xy 94.291689 -59.494879) (xy 94.334557 -59.530554) (xy 94.371774 -59.572091) (xy 94.402547 -59.618604)
			(xy 94.426219 -59.669101) (xy 94.442287 -59.722508) (xy 94.450407 -59.777684) (xy 94.450916 -59.80557)
			(xy 94.450407 -59.833456) (xy 94.442287 -59.888632) (xy 94.426219 -59.942039) (xy 94.402547 -59.992536)
			(xy 94.371774 -60.039049) (xy 94.334557 -60.080586) (xy 94.291689 -60.116261) (xy 94.244083 -60.145315)
			(xy 94.192754 -60.167127) (xy 94.138797 -60.181233) (xy 94.08336 -60.187333) (xy 94.027626 -60.185296)
			(xy 93.972783 -60.175166) (xy 93.919999 -60.157159) (xy 93.870399 -60.131658) (xy 93.825041 -60.099207)
			(xy 93.784892 -60.060498) (xy 93.750806 -60.016355) (xy 93.72351 -59.96772) (xy 93.703587 -59.915629)
			(xy 93.691461 -59.861192) (xy 93.68739 -59.80557) (xy 89.786075 -59.80557) (xy 89.788999 -59.825436)
			(xy 89.789508 -59.853322) (xy 89.788999 -59.881208) (xy 89.780879 -59.936384) (xy 89.764811 -59.989791)
			(xy 89.741139 -60.040288) (xy 89.710366 -60.086801) (xy 89.673149 -60.128338) (xy 89.630281 -60.164013)
			(xy 89.582675 -60.193067) (xy 89.531346 -60.214879) (xy 89.477389 -60.228985) (xy 89.421952 -60.235085)
			(xy 89.366218 -60.233048) (xy 89.311375 -60.222918) (xy 89.258591 -60.204911) (xy 89.208991 -60.17941)
			(xy 89.163633 -60.146959) (xy 89.123484 -60.10825) (xy 89.089398 -60.064107) (xy 89.062102 -60.015472)
			(xy 89.042179 -59.963381) (xy 89.030053 -59.908944) (xy 89.025982 -59.853322) (xy 80.246982 -59.853322)
			(xy 80.246982 -60.679584) (xy 92.469968 -60.679584) (xy 92.474039 -60.623962) (xy 92.486165 -60.569525)
			(xy 92.506088 -60.517434) (xy 92.533384 -60.468799) (xy 92.56747 -60.424656) (xy 92.607619 -60.385947)
			(xy 92.652977 -60.353496) (xy 92.702577 -60.327995) (xy 92.755361 -60.309988) (xy 92.810204 -60.299858)
			(xy 92.865938 -60.297821) (xy 92.921375 -60.303921) (xy 92.975332 -60.318027) (xy 93.026661 -60.339839)
			(xy 93.074267 -60.368893) (xy 93.117135 -60.404568) (xy 93.154352 -60.446105) (xy 93.185125 -60.492618)
			(xy 93.208797 -60.543115) (xy 93.224865 -60.596522) (xy 93.232985 -60.651698) (xy 93.233494 -60.679584)
			(xy 93.232985 -60.70747) (xy 93.224865 -60.762646) (xy 93.208797 -60.816053) (xy 93.18716 -60.86221)
			(xy 96.14103 -60.86221) (xy 96.145101 -60.806588) (xy 96.157227 -60.752151) (xy 96.17715 -60.70006)
			(xy 96.204446 -60.651425) (xy 96.238532 -60.607282) (xy 96.278681 -60.568573) (xy 96.324039 -60.536122)
			(xy 96.373639 -60.510621) (xy 96.426423 -60.492614) (xy 96.481266 -60.482484) (xy 96.537 -60.480447)
			(xy 96.592437 -60.486547) (xy 96.646394 -60.500653) (xy 96.697723 -60.522465) (xy 96.745329 -60.551519)
			(xy 96.788197 -60.587194) (xy 96.825414 -60.628731) (xy 96.856187 -60.675244) (xy 96.879859 -60.725741)
			(xy 96.895927 -60.779148) (xy 96.904047 -60.834324) (xy 96.904556 -60.86221) (xy 96.904047 -60.890096)
			(xy 96.895927 -60.945272) (xy 96.879859 -60.998679) (xy 96.856187 -61.049176) (xy 96.825414 -61.095689)
			(xy 96.788197 -61.137226) (xy 96.745329 -61.172901) (xy 96.697723 -61.201955) (xy 96.646394 -61.223767)
			(xy 96.592437 -61.237873) (xy 96.537 -61.243973) (xy 96.481266 -61.241936) (xy 96.426423 -61.231806)
			(xy 96.373639 -61.213799) (xy 96.324039 -61.188298) (xy 96.278681 -61.155847) (xy 96.238532 -61.117138)
			(xy 96.204446 -61.072995) (xy 96.17715 -61.02436) (xy 96.157227 -60.972269) (xy 96.145101 -60.917832)
			(xy 96.14103 -60.86221) (xy 93.18716 -60.86221) (xy 93.185125 -60.86655) (xy 93.154352 -60.913063)
			(xy 93.117135 -60.9546) (xy 93.074267 -60.990275) (xy 93.026661 -61.019329) (xy 92.975332 -61.041141)
			(xy 92.921375 -61.055247) (xy 92.865938 -61.061347) (xy 92.810204 -61.05931) (xy 92.755361 -61.04918)
			(xy 92.702577 -61.031173) (xy 92.652977 -61.005672) (xy 92.607619 -60.973221) (xy 92.56747 -60.934512)
			(xy 92.533384 -60.890369) (xy 92.506088 -60.841734) (xy 92.486165 -60.789643) (xy 92.474039 -60.735206)
			(xy 92.469968 -60.679584) (xy 80.246982 -60.679584) (xy 80.246982 -66.05905) (xy 80.663032 -66.05905)
			(xy 80.667103 -66.003428) (xy 80.679229 -65.948991) (xy 80.699152 -65.8969) (xy 80.726448 -65.848265)
			(xy 80.760534 -65.804122) (xy 80.800683 -65.765413) (xy 80.846041 -65.732962) (xy 80.895641 -65.707461)
			(xy 80.948425 -65.689454) (xy 81.003268 -65.679324) (xy 81.059002 -65.677287) (xy 81.114439 -65.683387)
			(xy 81.168396 -65.697493) (xy 81.219725 -65.719305) (xy 81.267331 -65.748359) (xy 81.310199 -65.784034)
			(xy 81.347416 -65.825571) (xy 81.378189 -65.872084) (xy 81.401861 -65.922581) (xy 81.417929 -65.975988)
			(xy 81.426049 -66.031164) (xy 81.426558 -66.05905) (xy 81.426049 -66.086936) (xy 81.417929 -66.142112)
			(xy 81.401861 -66.195519) (xy 81.378189 -66.246016) (xy 81.347416 -66.292529) (xy 81.310199 -66.334066)
			(xy 81.267331 -66.369741) (xy 81.219725 -66.398795) (xy 81.168396 -66.420607) (xy 81.114439 -66.434713)
			(xy 81.059002 -66.440813) (xy 81.003268 -66.438776) (xy 80.948425 -66.428646) (xy 80.895641 -66.410639)
			(xy 80.846041 -66.385138) (xy 80.800683 -66.352687) (xy 80.760534 -66.313978) (xy 80.726448 -66.269835)
			(xy 80.699152 -66.2212) (xy 80.679229 -66.169109) (xy 80.667103 -66.114672) (xy 80.663032 -66.05905)
			(xy 80.246982 -66.05905) (xy 80.246982 -69.692012) (xy 80.247407 -69.702082) (xy 80.255122 -69.720685)
			(xy 80.261968 -69.72808) (xy 82.669888 -72.136) (xy 84.961982 -72.136) (xy 84.966053 -72.080378)
			(xy 84.978179 -72.025941) (xy 84.998102 -71.97385) (xy 85.025398 -71.925215) (xy 85.059484 -71.881072)
			(xy 85.099633 -71.842363) (xy 85.144991 -71.809912) (xy 85.194591 -71.784411) (xy 85.247375 -71.766404)
			(xy 85.302218 -71.756274) (xy 85.357952 -71.754237) (xy 85.413389 -71.760337) (xy 85.467346 -71.774443)
			(xy 85.486744 -71.782686) (xy 87.002618 -71.782686) (xy 87.006689 -71.727064) (xy 87.018815 -71.672627)
			(xy 87.038738 -71.620536) (xy 87.066034 -71.571901) (xy 87.10012 -71.527758) (xy 87.140269 -71.489049)
			(xy 87.185627 -71.456598) (xy 87.235227 -71.431097) (xy 87.288011 -71.41309) (xy 87.342854 -71.40296)
			(xy 87.398588 -71.400923) (xy 87.454025 -71.407023) (xy 87.507982 -71.421129) (xy 87.559311 -71.442941)
			(xy 87.606917 -71.471995) (xy 87.649785 -71.50767) (xy 87.687002 -71.549207) (xy 87.717775 -71.59572)
			(xy 87.741447 -71.646217) (xy 87.757515 -71.699624) (xy 87.765635 -71.7548) (xy 87.766144 -71.782686)
			(xy 87.765635 -71.810572) (xy 87.757515 -71.865748) (xy 87.741447 -71.919155) (xy 87.717775 -71.969652)
			(xy 87.687002 -72.016165) (xy 87.649785 -72.057702) (xy 87.606917 -72.093377) (xy 87.559311 -72.122431)
			(xy 87.507982 -72.144243) (xy 87.454025 -72.158349) (xy 87.398588 -72.164449) (xy 87.342854 -72.162412)
			(xy 87.288011 -72.152282) (xy 87.235227 -72.134275) (xy 87.185627 -72.108774) (xy 87.140269 -72.076323)
			(xy 87.10012 -72.037614) (xy 87.066034 -71.993471) (xy 87.038738 -71.944836) (xy 87.018815 -71.892745)
			(xy 87.006689 -71.838308) (xy 87.002618 -71.782686) (xy 85.486744 -71.782686) (xy 85.518675 -71.796255)
			(xy 85.566281 -71.825309) (xy 85.609149 -71.860984) (xy 85.646366 -71.902521) (xy 85.677139 -71.949034)
			(xy 85.700811 -71.999531) (xy 85.716879 -72.052938) (xy 85.724999 -72.108114) (xy 85.725508 -72.136)
			(xy 85.724999 -72.163886) (xy 85.716879 -72.219062) (xy 85.700811 -72.272469) (xy 85.677139 -72.322966)
			(xy 85.646366 -72.369479) (xy 85.609149 -72.411016) (xy 85.566281 -72.446691) (xy 85.518675 -72.475745)
			(xy 85.467346 -72.497557) (xy 85.413389 -72.511663) (xy 85.357952 -72.517763) (xy 85.302218 -72.515726)
			(xy 85.247375 -72.505596) (xy 85.194591 -72.487589) (xy 85.144991 -72.462088) (xy 85.099633 -72.429637)
			(xy 85.059484 -72.390928) (xy 85.025398 -72.346785) (xy 84.998102 -72.29815) (xy 84.978179 -72.246059)
			(xy 84.966053 -72.191622) (xy 84.961982 -72.136) (xy 82.669888 -72.136) (xy 86.028146 -75.494258)
			(xy 92.753311 -75.494258) (xy 92.753311 -75.439742) (xy 92.76107 -75.385782) (xy 92.776429 -75.333476)
			(xy 92.799077 -75.283887) (xy 92.828552 -75.238027) (xy 92.864253 -75.196829) (xy 92.905455 -75.161131)
			(xy 92.951317 -75.131661) (xy 93.000907 -75.109017) (xy 93.053216 -75.093663) (xy 93.107176 -75.085909)
			(xy 93.134434 -75.085448) (xy 93.161806 -75.085882) (xy 93.215986 -75.093706) (xy 93.26849 -75.109202)
			(xy 93.318237 -75.132051) (xy 93.364202 -75.161783) (xy 93.385132 -75.179428) (xy 93.392244 -75.185524)
			(xy 93.409262 -75.191874) (xy 93.494606 -75.191874) (xy 93.511624 -75.185524) (xy 93.518736 -75.179428)
			(xy 93.54185 -75.160632) (xy 93.549724 -75.155044) (xy 93.55963 -75.139296) (xy 93.576648 -75.053698)
			(xy 93.5736 -75.03541) (xy 93.568774 -75.027282) (xy 93.555984 -75.005049) (xy 93.535845 -74.957877)
			(xy 93.522215 -74.90843) (xy 93.515341 -74.857602) (xy 93.514926 -74.831956) (xy 93.515419 -74.804587)
			(xy 93.523229 -74.750408) (xy 93.538712 -74.697905) (xy 93.561548 -74.648158) (xy 93.591267 -74.60219)
			(xy 93.608906 -74.581258) (xy 93.615002 -74.574146) (xy 93.621352 -74.557128) (xy 93.621352 -74.471784)
			(xy 93.615002 -74.454766) (xy 93.608906 -74.447654) (xy 93.59128 -74.426712) (xy 93.561566 -74.380742)
			(xy 93.538727 -74.330997) (xy 93.523233 -74.278498) (xy 93.515402 -74.224324) (xy 93.514926 -74.196956)
			(xy 93.515412 -74.169705) (xy 93.523168 -74.115757) (xy 93.538523 -74.063462) (xy 93.561165 -74.013885)
			(xy 93.590631 -73.968035) (xy 93.626322 -73.926844) (xy 93.667513 -73.891153) (xy 93.713363 -73.861687)
			(xy 93.76294 -73.839045) (xy 93.815235 -73.82369) (xy 93.869183 -73.815934) (xy 93.923685 -73.815934)
			(xy 93.977633 -73.82369) (xy 94.029928 -73.839045) (xy 94.079505 -73.861687) (xy 94.125355 -73.891153)
			(xy 94.166546 -73.926844) (xy 94.202237 -73.968035) (xy 94.231703 -74.013885) (xy 94.254345 -74.063462)
			(xy 94.2697 -74.115757) (xy 94.277456 -74.169705) (xy 94.277942 -74.196956) (xy 94.277464 -74.224326)
			(xy 94.269651 -74.278505) (xy 94.254166 -74.331009) (xy 94.231326 -74.380756) (xy 94.201603 -74.426723)
			(xy 94.183962 -74.447654) (xy 94.177866 -74.454766) (xy 94.171516 -74.471784) (xy 94.171516 -74.557128)
			(xy 94.177866 -74.574146) (xy 94.183962 -74.581258) (xy 94.201589 -74.6022) (xy 94.231304 -74.648169)
			(xy 94.254143 -74.697914) (xy 94.269637 -74.750413) (xy 94.277467 -74.804587) (xy 94.277942 -74.831956)
			(xy 94.27736 -74.861599) (xy 94.268201 -74.920173) (xy 94.250096 -74.976627) (xy 94.223481 -75.029602)
			(xy 94.188995 -75.077826) (xy 94.147468 -75.120138) (xy 94.124018 -75.13828) (xy 94.116144 -75.143868)
			(xy 94.106238 -75.159616) (xy 94.08922 -75.245214) (xy 94.092268 -75.263502) (xy 94.097094 -75.27163)
			(xy 94.109895 -75.293856) (xy 94.130031 -75.341031) (xy 94.143657 -75.39048) (xy 94.150528 -75.44131)
			(xy 94.150942 -75.466956) (xy 94.150404 -75.494206) (xy 94.142654 -75.548153) (xy 94.127305 -75.600447)
			(xy 94.10467 -75.650025) (xy 94.07521 -75.695876) (xy 94.039524 -75.737069) (xy 93.998339 -75.772763)
			(xy 93.952493 -75.802233) (xy 93.90292 -75.824878) (xy 93.850629 -75.840237) (xy 93.796684 -75.847998)
			(xy 93.769434 -75.848464) (xy 93.742064 -75.847987) (xy 93.687885 -75.840173) (xy 93.635382 -75.824687)
			(xy 93.585635 -75.801848) (xy 93.539668 -75.772125) (xy 93.518736 -75.754484) (xy 93.511624 -75.748388)
			(xy 93.494606 -75.742038) (xy 93.409262 -75.742038) (xy 93.392244 -75.748388) (xy 93.385132 -75.754484)
			(xy 93.364197 -75.772119) (xy 93.318225 -75.801832) (xy 93.268478 -75.824669) (xy 93.215978 -75.840161)
			(xy 93.161803 -75.84799) (xy 93.134434 -75.848464) (xy 93.107176 -75.848091) (xy 93.053216 -75.840337)
			(xy 93.000907 -75.824983) (xy 92.951317 -75.802339) (xy 92.905455 -75.772869) (xy 92.864253 -75.737171)
			(xy 92.828552 -75.695973) (xy 92.799077 -75.650113) (xy 92.776429 -75.600524) (xy 92.76107 -75.548218)
			(xy 92.753311 -75.494258) (xy 86.028146 -75.494258) (xy 86.576154 -76.042266) (xy 86.583554 -76.049108)
			(xy 86.602152 -76.056828) (xy 86.612222 -76.057252)
		)
		(stroke
			(width 0)
			(type solid)
		)
		(fill yes)
		(layer "In6.Cu")
		(net "GND")
	)
	(gr_poly
		(pts
			(xy 71.834756 -26.038048) (xy 71.844366 -26.037636) (xy 71.862248 -26.030589) (xy 71.869554 -26.024332)
			(xy 71.900468 -25.99585) (xy 71.966794 -25.944203) (xy 72.037698 -25.899046) (xy 72.112547 -25.860781)
			(xy 72.190673 -25.82975) (xy 72.271378 -25.806231) (xy 72.353943 -25.790432) (xy 72.437631 -25.782496)
			(xy 72.479662 -25.782016) (xy 72.485758 -25.782016) (xy 72.524358 -25.782705) (xy 72.601225 -25.789944)
			(xy 72.677176 -25.803817) (xy 72.75164 -25.824217) (xy 72.824055 -25.850993) (xy 72.859138 -25.867106)
			(xy 72.864218 -25.869392) (xy 72.874886 -25.871678) (xy 72.880422 -25.87277) (xy 72.891702 -25.87277)
			(xy 72.897238 -25.871678) (xy 72.907906 -25.869392) (xy 72.912986 -25.867106) (xy 72.948629 -25.850752)
			(xy 73.022223 -25.823645) (xy 73.097918 -25.803128) (xy 73.175127 -25.78936) (xy 73.253249 -25.782447)
			(xy 73.292462 -25.782016) (xy 73.29805 -25.782016) (xy 73.339729 -25.78276) (xy 73.422679 -25.791075)
			(xy 73.504485 -25.807121) (xy 73.58443 -25.830757) (xy 73.66181 -25.861776) (xy 73.735945 -25.899904)
			(xy 73.806185 -25.944806) (xy 73.87191 -25.996089) (xy 73.90257 -26.024332) (xy 73.909857 -26.030624)
			(xy 73.927748 -26.037693) (xy 73.937368 -26.038048) (xy 77.894434 -26.038048) (xy 77.904311 -26.037586)
			(xy 77.92261 -26.030144) (xy 77.929994 -26.02357) (xy 77.930248 -26.023316) (xy 80.320134 -23.63343)
			(xy 80.32115 -23.632414) (xy 80.328725 -23.623486) (xy 80.335602 -23.60113) (xy 80.334358 -23.589488)
			(xy 80.333342 -23.584408) (xy 80.307434 -23.486618) (xy 80.288638 -23.467568) (xy 80.27543 -23.463758)
			(xy 80.234604 -23.451904) (xy 80.155231 -23.421442) (xy 80.079125 -23.383549) (xy 80.006979 -23.338571)
			(xy 79.972916 -23.313136) (xy 79.963565 -23.306701) (xy 79.941401 -23.301947) (xy 79.919353 -23.307218)
			(xy 79.910178 -23.313898) (xy 79.876298 -23.340539) (xy 79.80426 -23.387868) (xy 79.727983 -23.428008)
			(xy 79.648182 -23.460584) (xy 79.565605 -23.485291) (xy 79.481026 -23.501896) (xy 79.395237 -23.510245)
			(xy 79.35214 -23.510748) (xy 79.309788 -23.510262) (xy 79.225466 -23.502214) (xy 79.142292 -23.486186)
			(xy 79.061017 -23.462325) (xy 78.982379 -23.430846) (xy 78.907089 -23.392035) (xy 78.83583 -23.346242)
			(xy 78.769246 -23.293883) (xy 78.707941 -23.235431) (xy 78.65247 -23.171417) (xy 78.603335 -23.102419)
			(xy 78.560982 -23.029064) (xy 78.525793 -22.952014) (xy 78.498088 -22.871968) (xy 78.478118 -22.789651)
			(xy 78.466063 -22.705809) (xy 78.462032 -22.6212) (xy 78.466063 -22.536591) (xy 78.478118 -22.452749)
			(xy 78.498088 -22.370432) (xy 78.525793 -22.290386) (xy 78.560982 -22.213336) (xy 78.603335 -22.139981)
			(xy 78.65247 -22.070983) (xy 78.707941 -22.006969) (xy 78.769246 -21.948517) (xy 78.83583 -21.896158)
			(xy 78.907089 -21.850365) (xy 78.982379 -21.811554) (xy 79.061017 -21.780075) (xy 79.142292 -21.756214)
			(xy 79.225466 -21.740186) (xy 79.309788 -21.732138) (xy 79.35214 -21.731732) (xy 79.393647 -21.732209)
			(xy 79.476299 -21.739941) (xy 79.55787 -21.755343) (xy 79.637651 -21.778281) (xy 79.714947 -21.808555)
			(xy 79.789084 -21.845902) (xy 79.859418 -21.889997) (xy 79.892652 -21.914866) (xy 79.902002 -21.921285)
			(xy 79.924153 -21.926011) (xy 79.946176 -21.920722) (xy 79.95539 -21.914104) (xy 79.989271 -21.887465)
			(xy 80.06131 -21.840142) (xy 80.137587 -21.800008) (xy 80.217389 -21.767438) (xy 80.299966 -21.742737)
			(xy 80.384545 -21.726138) (xy 80.470332 -21.717796) (xy 80.513428 -21.717254) (xy 80.550887 -21.717674)
			(xy 80.625536 -21.724031) (xy 80.662526 -21.729954) (xy 80.673956 -21.731732) (xy 80.695292 -21.72589)
			(xy 80.763364 -21.668486) (xy 80.7715 -21.660896) (xy 80.78086 -21.640737) (xy 80.781398 -21.629624)
			(xy 80.781398 -20.459954) (xy 80.781271 -20.454308) (xy 80.778831 -20.443286) (xy 80.776572 -20.43811)
			(xy 80.765396 -20.414742) (xy 80.759046 -20.40636) (xy 80.754728 -20.402804) (xy 80.72216 -20.374682)
			(xy 80.662037 -20.313117) (xy 80.608138 -20.246035) (xy 80.560968 -20.174063) (xy 80.520967 -20.097873)
			(xy 80.488508 -20.018177) (xy 80.463894 -19.93572) (xy 80.447357 -19.851272) (xy 80.439049 -19.765621)
			(xy 80.43905 -19.679569) (xy 80.447358 -19.593918) (xy 80.463897 -19.50947) (xy 80.488511 -19.427013)
			(xy 80.520971 -19.347317) (xy 80.560973 -19.271128) (xy 80.608144 -19.199156) (xy 80.662044 -19.132075)
			(xy 80.722167 -19.070511) (xy 80.754728 -19.04238) (xy 80.759046 -19.038824) (xy 80.765396 -19.030442)
			(xy 80.776572 -19.007074) (xy 80.778834 -19.0019) (xy 80.781274 -18.990876) (xy 80.781398 -18.98523)
			(xy 80.781398 -17.314926) (xy 80.780961 -17.304862) (xy 80.773228 -17.286277) (xy 80.766412 -17.278858)
			(xy 79.096108 -15.608554) (xy 79.088996 -15.601188) (xy 79.0702 -15.593568) (xy 73.297034 -15.593568)
			(xy 73.285604 -15.594838) (xy 73.27392 -15.597632) (xy 73.26376 -15.601188) (xy 73.238076 -15.612817)
			(xy 73.184139 -15.629226) (xy 73.128373 -15.637512) (xy 73.100184 -15.638018) (xy 73.071104 -15.637467)
			(xy 73.013616 -15.628647) (xy 72.958126 -15.611229) (xy 72.931782 -15.598902) (xy 72.926448 -15.596108)
			(xy 72.915272 -15.593568) (xy 71.551038 -15.593568) (xy 71.540973 -15.593133) (xy 71.522388 -15.585399)
			(xy 71.51497 -15.578582) (xy 68.459858 -12.52347) (xy 68.452796 -12.51703) (xy 68.435264 -12.50945)
			(xy 68.416176 -12.508765) (xy 68.407026 -12.511532) (xy 68.30695 -12.547092) (xy 68.288662 -12.569952)
			(xy 68.287138 -12.58443) (xy 68.282013 -12.627346) (xy 68.26449 -12.711986) (xy 68.238837 -12.794527)
			(xy 68.205297 -12.874189) (xy 68.164185 -12.95022) (xy 68.115889 -13.021904) (xy 68.060866 -13.088564)
			(xy 67.999635 -13.14957) (xy 67.932773 -13.204347) (xy 67.860912 -13.252378) (xy 67.82308 -13.273278)
			(xy 67.813809 -13.278728) (xy 67.800642 -13.295706) (xy 67.79768 -13.306044) (xy 67.787278 -13.347142)
			(xy 67.759673 -13.427305) (xy 67.724562 -13.504477) (xy 67.682265 -13.577955) (xy 67.633164 -13.647073)
			(xy 67.577707 -13.711203) (xy 67.516397 -13.769762) (xy 67.44979 -13.822219) (xy 67.378493 -13.868097)
			(xy 67.303152 -13.90698) (xy 67.224451 -13.938514) (xy 67.143106 -13.962413) (xy 67.059856 -13.978459)
			(xy 66.975456 -13.986508) (xy 66.933064 -13.987018) (xy 66.894774 -13.98661) (xy 66.818479 -13.980007)
			(xy 66.743036 -13.96686) (xy 66.669004 -13.947269) (xy 66.632836 -13.934694) (xy 66.624398 -13.932052)
			(xy 66.60673 -13.932052) (xy 66.598292 -13.934694) (xy 66.562114 -13.947239) (xy 66.488082 -13.966817)
			(xy 66.412643 -13.979967) (xy 66.336352 -13.98659) (xy 66.298064 -13.987018) (xy 66.254268 -13.9865)
			(xy 66.167098 -13.977897) (xy 66.081199 -13.960757) (xy 65.997403 -13.935249) (xy 65.916523 -13.901618)
			(xy 65.877694 -13.881354) (xy 65.866228 -13.875936) (xy 65.8409 -13.875936) (xy 65.829434 -13.881354)
			(xy 65.79059 -13.901586) (xy 65.709706 -13.935193) (xy 65.625912 -13.960696) (xy 65.54002 -13.977848)
			(xy 65.452858 -13.986484) (xy 65.409064 -13.987018) (xy 65.365268 -13.9865) (xy 65.278098 -13.977897)
			(xy 65.192199 -13.960757) (xy 65.108403 -13.935249) (xy 65.027523 -13.901618) (xy 64.988694 -13.881354)
			(xy 64.977228 -13.875936) (xy 64.9519 -13.875936) (xy 64.940434 -13.881354) (xy 64.90159 -13.901586)
			(xy 64.820706 -13.935193) (xy 64.736912 -13.960696) (xy 64.65102 -13.977848) (xy 64.563858 -13.986484)
			(xy 64.520064 -13.987018) (xy 64.476268 -13.9865) (xy 64.389098 -13.977897) (xy 64.303199 -13.960757)
			(xy 64.219403 -13.935249) (xy 64.138523 -13.901618) (xy 64.099694 -13.881354) (xy 64.088228 -13.875936)
			(xy 64.0629 -13.875936) (xy 64.051434 -13.881354) (xy 64.01259 -13.901586) (xy 63.931706 -13.935193)
			(xy 63.847912 -13.960696) (xy 63.76202 -13.977848) (xy 63.674858 -13.986484) (xy 63.631064 -13.987018)
			(xy 63.588812 -13.986518) (xy 63.50469 -13.978502) (xy 63.421707 -13.962546) (xy 63.34061 -13.938794)
			(xy 63.262131 -13.907459) (xy 63.186977 -13.868825) (xy 63.115824 -13.823239) (xy 63.049315 -13.771112)
			(xy 62.988047 -13.712913) (xy 62.932574 -13.649167) (xy 62.883395 -13.580449) (xy 62.840953 -13.507377)
			(xy 62.80563 -13.43061) (xy 62.777746 -13.35084) (xy 62.757551 -13.268786) (xy 62.750954 -13.22705)
			(xy 62.748799 -13.216162) (xy 62.736685 -13.197592) (xy 62.727586 -13.191236) (xy 62.690792 -13.167583)
			(xy 62.62154 -13.114142) (xy 62.557859 -13.054171) (xy 62.528704 -13.021564) (xy 62.51829 -13.009626)
			(xy 62.487556 -13.002006) (xy 62.38367 -13.040868) (xy 62.374192 -13.04493) (xy 62.359282 -13.059147)
			(xy 62.351129 -13.078067) (xy 62.35065 -13.088366) (xy 62.35065 -14.926818) (xy 62.35065 -14.934946)
			(xy 62.355476 -14.950186) (xy 62.360302 -14.95679) (xy 62.375493 -14.978567) (xy 62.400348 -15.025485)
			(xy 62.418453 -15.075399) (xy 62.429458 -15.127341) (xy 62.433149 -15.180308) (xy 62.429456 -15.233275)
			(xy 62.418449 -15.285217) (xy 62.400342 -15.335129) (xy 62.375484 -15.382047) (xy 62.360302 -15.40383)
			(xy 62.355476 -15.410434) (xy 62.35065 -15.425674) (xy 62.35065 -16.368014) (xy 62.373256 -16.3957)
			(xy 62.39129 -16.39951) (xy 62.435403 -16.40914) (xy 62.521555 -16.436184) (xy 62.604522 -16.471822)
			(xy 62.683448 -16.515688) (xy 62.757521 -16.567328) (xy 62.792102 -16.59636) (xy 62.797944 -16.600678)
			(xy 62.803015 -16.60371) (xy 62.814179 -16.607569) (xy 62.820042 -16.608298) (xy 62.837059 -16.602421)
			(xy 62.871487 -16.591878) (xy 62.888876 -16.587216) (xy 62.894633 -16.585497) (xy 62.905166 -16.579723)
			(xy 62.909704 -16.575786) (xy 62.940288 -16.548949) (xy 63.005557 -16.500355) (xy 63.07499 -16.457922)
			(xy 63.148008 -16.422005) (xy 63.223999 -16.392904) (xy 63.302329 -16.370862) (xy 63.382345 -16.356063)
			(xy 63.463378 -16.348631) (xy 63.504064 -16.348202) (xy 63.545168 -16.348661) (xy 63.627026 -16.356243)
			(xy 63.707835 -16.371346) (xy 63.786905 -16.39384) (xy 63.863563 -16.423535) (xy 63.937153 -16.460177)
			(xy 64.007049 -16.503452) (xy 64.072654 -16.552992) (xy 64.133407 -16.608375) (xy 64.188791 -16.669126)
			(xy 64.238333 -16.734729) (xy 64.281611 -16.804624) (xy 64.318254 -16.878213) (xy 64.347951 -16.95487)
			(xy 64.370448 -17.03394) (xy 64.385554 -17.114748) (xy 64.393138 -17.196606) (xy 64.393572 -17.23771)
			(xy 64.393102 -17.279429) (xy 64.385295 -17.3625) (xy 64.369743 -17.444475) (xy 64.346581 -17.524632)
			(xy 64.316014 -17.602269) (xy 64.278309 -17.676701) (xy 64.233799 -17.747274) (xy 64.182875 -17.813369)
			(xy 64.125985 -17.874403) (xy 64.063627 -17.929841) (xy 63.996352 -17.979194) (xy 63.92475 -18.02203)
			(xy 63.849451 -18.057971) (xy 63.771116 -18.086702) (xy 63.730886 -18.097754) (xy 63.725152 -18.099526)
			(xy 63.714641 -18.105309) (xy 63.710058 -18.109184) (xy 63.677124 -18.13804) (xy 63.606523 -18.189847)
			(xy 63.531175 -18.234467) (xy 63.451807 -18.271468) (xy 63.369187 -18.300492) (xy 63.326772 -18.311368)
			(xy 63.317919 -18.31393) (xy 63.302708 -18.324313) (xy 63.292119 -18.339381) (xy 63.289434 -18.348198)
			(xy 63.282016 -18.375198) (xy 63.260355 -18.42683) (xy 63.231381 -18.474743) (xy 63.195715 -18.517906)
			(xy 63.194987 -18.518562) (xy 67.655436 -18.518562) (xy 67.655436 -18.433866) (xy 67.663487 -18.349552)
			(xy 67.679516 -18.266386) (xy 67.703377 -18.185119) (xy 67.734856 -18.106489) (xy 67.773667 -18.031208)
			(xy 67.819457 -17.959956) (xy 67.871813 -17.89338) (xy 67.930261 -17.832082) (xy 67.994271 -17.776617)
			(xy 68.063263 -17.727488) (xy 68.136613 -17.685139) (xy 68.213656 -17.649955) (xy 68.293695 -17.622253)
			(xy 68.376004 -17.602285) (xy 68.459839 -17.590232) (xy 68.54444 -17.586202) (xy 68.629041 -17.590232)
			(xy 68.712876 -17.602285) (xy 68.795185 -17.622253) (xy 68.875224 -17.649955) (xy 68.952267 -17.685139)
			(xy 69.025617 -17.727488) (xy 69.094609 -17.776617) (xy 69.158619 -17.832082) (xy 69.217067 -17.89338)
			(xy 69.269423 -17.959956) (xy 69.315213 -18.031208) (xy 69.354024 -18.106489) (xy 69.385503 -18.185119)
			(xy 69.409364 -18.266386) (xy 69.425393 -18.349552) (xy 69.433444 -18.433866) (xy 69.433948 -18.476214)
			(xy 69.43377 -18.4912) (xy 74.232262 -18.4912) (xy 74.232808 -18.448529) (xy 74.240982 -18.363579)
			(xy 74.257255 -18.279803) (xy 74.281476 -18.19797) (xy 74.313425 -18.118833) (xy 74.352806 -18.043121)
			(xy 74.399257 -17.971528) (xy 74.452352 -17.904713) (xy 74.511602 -17.843291) (xy 74.576463 -17.787826)
			(xy 74.646338 -17.738828) (xy 74.720585 -17.696748) (xy 74.79852 -17.661973) (xy 74.838814 -17.64792)
			(xy 74.849466 -17.643697) (xy 74.865885 -17.627756) (xy 74.873802 -17.606285) (xy 74.873358 -17.594834)
			(xy 74.87158 -17.558512) (xy 74.872066 -17.531261) (xy 74.879822 -17.477313) (xy 74.895177 -17.425018)
			(xy 74.917819 -17.375441) (xy 74.947285 -17.329591) (xy 74.982976 -17.2884) (xy 75.024167 -17.252709)
			(xy 75.070017 -17.223243) (xy 75.119594 -17.200601) (xy 75.171889 -17.185246) (xy 75.225837 -17.17749)
			(xy 75.280339 -17.17749) (xy 75.334287 -17.185246) (xy 75.386582 -17.200601) (xy 75.436159 -17.223243)
			(xy 75.482009 -17.252709) (xy 75.5232 -17.2884) (xy 75.558891 -17.329591) (xy 75.588357 -17.375441)
			(xy 75.610999 -17.425018) (xy 75.626354 -17.477313) (xy 75.63411 -17.531261) (xy 75.634596 -17.558512)
			(xy 75.634245 -17.582355) (xy 75.628321 -17.629672) (xy 75.616553 -17.675884) (xy 75.60818 -17.698212)
			(xy 75.604528 -17.709037) (xy 75.606167 -17.731801) (xy 75.617456 -17.751637) (xy 75.626468 -17.758664)
			(xy 75.661973 -17.783798) (xy 75.728437 -17.83993) (xy 75.789106 -17.90228) (xy 75.843402 -17.970251)
			(xy 75.890807 -18.043196) (xy 75.930868 -18.120419) (xy 75.963203 -18.201182) (xy 75.987504 -18.284714)
			(xy 75.996038 -18.32737) (xy 75.99807 -18.3388) (xy 76.011786 -18.357088) (xy 76.101702 -18.405602)
			(xy 76.124816 -18.406618) (xy 76.135484 -18.402046) (xy 76.176588 -18.385277) (xy 76.261424 -18.359109)
			(xy 76.348446 -18.341529) (xy 76.436788 -18.332715) (xy 76.481178 -18.332196) (xy 76.519228 -18.332603)
			(xy 76.59505 -18.339103) (xy 76.67004 -18.352057) (xy 76.743648 -18.371371) (xy 76.779628 -18.383758)
			(xy 76.788671 -18.386584) (xy 76.807592 -18.386078) (xy 76.816458 -18.382742) (xy 76.844144 -18.371058)
			(xy 76.852714 -18.367033) (xy 76.866288 -18.353853) (xy 76.87056 -18.345404) (xy 76.888685 -18.307284)
			(xy 76.931153 -18.234331) (xy 76.980341 -18.165729) (xy 77.035806 -18.102094) (xy 77.09705 -18.044001)
			(xy 77.163522 -17.99197) (xy 77.234624 -17.94647) (xy 77.309716 -17.907911) (xy 77.388123 -17.876638)
			(xy 77.469141 -17.852933) (xy 77.552039 -17.83701) (xy 77.636073 -17.829012) (xy 77.67828 -17.828514)
			(xy 77.718904 -17.829005) (xy 77.799814 -17.836411) (xy 77.879712 -17.851162) (xy 77.957932 -17.873137)
			(xy 78.033822 -17.902151) (xy 78.106752 -17.937964) (xy 78.176112 -17.980277) (xy 78.241326 -18.028738)
			(xy 78.30185 -18.082942) (xy 78.35718 -18.142438) (xy 78.406855 -18.206732) (xy 78.450461 -18.275286)
			(xy 78.487636 -18.347531) (xy 78.503272 -18.385028) (xy 78.507191 -18.393638) (xy 78.5201 -18.407444)
			(xy 78.528418 -18.411952) (xy 78.555596 -18.424906) (xy 78.564331 -18.428603) (xy 78.58323 -18.430026)
			(xy 78.592426 -18.4277) (xy 78.635129 -18.415046) (xy 78.722415 -18.39731) (xy 78.811035 -18.388381)
			(xy 78.85557 -18.387822) (xy 78.897922 -18.388249) (xy 78.982241 -18.396298) (xy 79.065414 -18.412325)
			(xy 79.146687 -18.436187) (xy 79.225324 -18.467666) (xy 79.300612 -18.506477) (xy 79.371869 -18.55227)
			(xy 79.438452 -18.604628) (xy 79.499755 -18.663079) (xy 79.555225 -18.727093) (xy 79.604359 -18.796089)
			(xy 79.646711 -18.869444) (xy 79.681899 -18.946492) (xy 79.709603 -19.026536) (xy 79.729573 -19.108852)
			(xy 79.741628 -19.192693) (xy 79.745658 -19.2773) (xy 79.741628 -19.361907) (xy 79.729573 -19.445748)
			(xy 79.709603 -19.528064) (xy 79.681899 -19.608108) (xy 79.646711 -19.685156) (xy 79.604359 -19.758511)
			(xy 79.555225 -19.827507) (xy 79.499755 -19.891521) (xy 79.438452 -19.949972) (xy 79.371869 -20.00233)
			(xy 79.300612 -20.048123) (xy 79.225324 -20.086934) (xy 79.146687 -20.118413) (xy 79.065414 -20.142275)
			(xy 78.982241 -20.158302) (xy 78.897922 -20.166351) (xy 78.85557 -20.166838) (xy 78.814944 -20.166421)
			(xy 78.734031 -20.15901) (xy 78.654131 -20.144254) (xy 78.575909 -20.122273) (xy 78.500016 -20.093253)
			(xy 78.427086 -20.057434) (xy 78.357725 -20.015115) (xy 78.292512 -19.966648) (xy 78.231988 -19.912437)
			(xy 78.17666 -19.852935) (xy 78.126987 -19.788635) (xy 78.083383 -19.720074) (xy 78.046212 -19.647824)
			(xy 78.030578 -19.610324) (xy 78.026625 -19.601733) (xy 78.01374 -19.587916) (xy 78.005432 -19.5834)
			(xy 77.978254 -19.570446) (xy 77.96951 -19.566775) (xy 77.950619 -19.565336) (xy 77.941424 -19.567652)
			(xy 77.898725 -19.58032) (xy 77.811437 -19.59805) (xy 77.722815 -19.606974) (xy 77.67828 -19.60753)
			(xy 77.64023 -19.607134) (xy 77.564407 -19.60063) (xy 77.489418 -19.587673) (xy 77.415809 -19.568357)
			(xy 77.37983 -19.555968) (xy 77.370793 -19.553118) (xy 77.351866 -19.553639) (xy 77.343 -19.556984)
			(xy 77.315314 -19.568668) (xy 77.306749 -19.572702) (xy 77.293171 -19.585874) (xy 77.288898 -19.594322)
			(xy 77.27115 -19.631643) (xy 77.229678 -19.703133) (xy 77.206094 -19.73707) (xy 77.200506 -19.744944)
			(xy 77.195934 -19.763232) (xy 77.206348 -19.8501) (xy 77.215238 -19.86661) (xy 77.22235 -19.87296)
			(xy 77.242703 -19.891142) (xy 77.278503 -19.932337) (xy 77.308061 -19.978215) (xy 77.330776 -20.02784)
			(xy 77.346182 -20.080197) (xy 77.353964 -20.134216) (xy 77.35443 -20.161504) (xy 77.353892 -20.19005)
			(xy 77.345374 -20.246504) (xy 77.328542 -20.301059) (xy 77.303773 -20.352499) (xy 77.288136 -20.376388)
			(xy 77.282126 -20.386323) (xy 77.27881 -20.409277) (xy 77.285868 -20.431368) (xy 77.29347 -20.440142)
			(xy 77.322601 -20.471192) (xy 77.375459 -20.537945) (xy 77.421699 -20.609442) (xy 77.460897 -20.685029)
			(xy 77.492695 -20.764015) (xy 77.516801 -20.845678) (xy 77.532995 -20.92927) (xy 77.541129 -21.014027)
			(xy 77.541628 -21.0566) (xy 77.54111 -21.09857) (xy 77.53322 -21.182138) (xy 77.517492 -21.26459)
			(xy 77.494064 -21.345194) (xy 77.463146 -21.423232) (xy 77.425013 -21.49801) (xy 77.380004 -21.568862)
			(xy 77.32852 -21.635158) (xy 77.271018 -21.696309) (xy 77.20801 -21.751769) (xy 77.140057 -21.801046)
			(xy 77.067763 -21.843701) (xy 76.991772 -21.879355) (xy 76.91276 -21.907691) (xy 76.831429 -21.928455)
			(xy 76.790042 -21.93544) (xy 76.777342 -21.937218) (xy 76.75753 -21.952204) (xy 76.710286 -22.050502)
			(xy 76.711302 -22.075394) (xy 76.717652 -22.086316) (xy 76.740279 -22.12687) (xy 76.777909 -22.211777)
			(xy 76.806498 -22.30014) (xy 76.825735 -22.390997) (xy 76.835411 -22.483364) (xy 76.836016 -22.5298)
			(xy 76.835585 -22.571119) (xy 76.827906 -22.6534) (xy 76.812632 -22.734614) (xy 76.789894 -22.814063)
			(xy 76.75989 -22.891061) (xy 76.722876 -22.964947) (xy 76.679172 -23.035083) (xy 76.629155 -23.100865)
			(xy 76.573254 -23.161728) (xy 76.511952 -23.217146) (xy 76.479146 -23.24227) (xy 76.472222 -23.247833)
			(xy 76.46247 -23.262667) (xy 76.460096 -23.271226) (xy 76.453238 -23.300182) (xy 76.451608 -23.308584)
			(xy 76.453418 -23.325592) (xy 76.456794 -23.333456) (xy 76.468356 -23.359066) (xy 76.484643 -23.412845)
			(xy 76.492874 -23.468429) (xy 76.49337 -23.496524) (xy 76.492884 -23.523775) (xy 76.485128 -23.577723)
			(xy 76.469773 -23.630018) (xy 76.447131 -23.679595) (xy 76.417665 -23.725445) (xy 76.381974 -23.766636)
			(xy 76.340783 -23.802327) (xy 76.294933 -23.831793) (xy 76.245356 -23.854435) (xy 76.193061 -23.86979)
			(xy 76.139113 -23.877546) (xy 76.084611 -23.877546) (xy 76.030663 -23.86979) (xy 75.978368 -23.854435)
			(xy 75.928791 -23.831793) (xy 75.882941 -23.802327) (xy 75.84175 -23.766636) (xy 75.806059 -23.725445)
			(xy 75.776593 -23.679595) (xy 75.753951 -23.630018) (xy 75.738596 -23.577723) (xy 75.73084 -23.523775)
			(xy 75.730354 -23.496524) (xy 75.730421 -23.486727) (xy 75.731436 -23.467159) (xy 75.732386 -23.457408)
			(xy 75.732877 -23.448872) (xy 75.728853 -23.432263) (xy 75.724512 -23.424896) (xy 75.70851 -23.39975)
			(xy 75.703416 -23.392507) (xy 75.68939 -23.381721) (xy 75.681078 -23.378668) (xy 75.63985 -23.365172)
			(xy 75.559959 -23.331355) (xy 75.483741 -23.289919) (xy 75.411919 -23.241259) (xy 75.345176 -23.185838)
			(xy 75.284147 -23.124181) (xy 75.229411 -23.056875) (xy 75.181488 -22.984559) (xy 75.140834 -22.90792)
			(xy 75.107836 -22.827688) (xy 75.082806 -22.744624) (xy 75.065983 -22.659517) (xy 75.057526 -22.573177)
			(xy 75.057 -22.5298) (xy 75.057494 -22.487829) (xy 75.065384 -22.40426) (xy 75.081114 -22.321806)
			(xy 75.104542 -22.241201) (xy 75.135461 -22.163162) (xy 75.173596 -22.088383) (xy 75.218606 -22.017531)
			(xy 75.270093 -21.951234) (xy 75.327597 -21.890084) (xy 75.390607 -21.834624) (xy 75.458562 -21.785347)
			(xy 75.530858 -21.742693) (xy 75.606851 -21.70704) (xy 75.685865 -21.678706) (xy 75.767198 -21.657943)
			(xy 75.808586 -21.65096) (xy 75.821286 -21.649182) (xy 75.841098 -21.634196) (xy 75.888342 -21.535898)
			(xy 75.887326 -21.511006) (xy 75.880976 -21.500084) (xy 75.858351 -21.459528) (xy 75.82072 -21.374622)
			(xy 75.792131 -21.28626) (xy 75.772893 -21.195402) (xy 75.763217 -21.103036) (xy 75.762612 -21.0566)
			(xy 75.763054 -21.015482) (xy 75.770647 -20.933596) (xy 75.785769 -20.852761) (xy 75.80829 -20.773668)
			(xy 75.838018 -20.696992) (xy 75.874698 -20.623388) (xy 75.918018 -20.553486) (xy 75.942444 -20.520406)
			(xy 75.947966 -20.51244) (xy 75.953053 -20.493752) (xy 75.95235 -20.484084) (xy 75.948794 -20.453604)
			(xy 75.947355 -20.444381) (xy 75.938741 -20.427836) (xy 75.93203 -20.421346) (xy 75.912273 -20.40315)
			(xy 75.877544 -20.362178) (xy 75.8489 -20.316742) (xy 75.826908 -20.26774) (xy 75.812 -20.21614)
			(xy 75.804471 -20.162959) (xy 75.804014 -20.136104) (xy 75.8045 -20.108014) (xy 75.812745 -20.052443)
			(xy 75.829057 -19.998683) (xy 75.853083 -19.9479) (xy 75.868276 -19.924268) (xy 75.874278 -19.914104)
			(xy 75.877174 -19.890704) (xy 75.869411 -19.868439) (xy 75.861418 -19.859752) (xy 75.829118 -19.827595)
			(xy 75.770579 -19.757729) (xy 75.719492 -19.682242) (xy 75.676392 -19.601927) (xy 75.64173 -19.517626)
			(xy 75.61587 -19.430223) (xy 75.60691 -19.385534) (xy 75.604878 -19.374104) (xy 75.591162 -19.355816)
			(xy 75.501246 -19.307302) (xy 75.478132 -19.306286) (xy 75.467464 -19.310858) (xy 75.426354 -19.327612)
			(xy 75.34152 -19.353784) (xy 75.2545 -19.371368) (xy 75.16616 -19.380187) (xy 75.12177 -19.380708)
			(xy 75.080667 -19.380262) (xy 74.998812 -19.372674) (xy 74.918006 -19.357567) (xy 74.838939 -19.335068)
			(xy 74.762285 -19.30537) (xy 74.688698 -19.268725) (xy 74.618806 -19.225448) (xy 74.553205 -19.175907)
			(xy 74.492455 -19.120524) (xy 74.437074 -19.059772) (xy 74.387535 -18.994169) (xy 74.34426 -18.924276)
			(xy 74.307618 -18.850688) (xy 74.277923 -18.774033) (xy 74.255426 -18.694965) (xy 74.240321 -18.614158)
			(xy 74.232737 -18.532303) (xy 74.232262 -18.4912) (xy 69.43377 -18.4912) (xy 69.433444 -18.518562)
			(xy 69.425393 -18.602876) (xy 69.409364 -18.686042) (xy 69.385503 -18.767309) (xy 69.354024 -18.845939)
			(xy 69.315213 -18.92122) (xy 69.269423 -18.992472) (xy 69.217067 -19.059048) (xy 69.158619 -19.120346)
			(xy 69.094609 -19.175811) (xy 69.025617 -19.22494) (xy 68.952267 -19.267289) (xy 68.875224 -19.302473)
			(xy 68.795185 -19.330175) (xy 68.712876 -19.350143) (xy 68.629041 -19.362196) (xy 68.54444 -19.366227)
			(xy 68.459839 -19.362196) (xy 68.376004 -19.350143) (xy 68.293695 -19.330175) (xy 68.213656 -19.302473)
			(xy 68.136613 -19.267289) (xy 68.063263 -19.22494) (xy 67.994271 -19.175811) (xy 67.930261 -19.120346)
			(xy 67.871813 -19.059048) (xy 67.819457 -18.992472) (xy 67.773667 -18.92122) (xy 67.734856 -18.845939)
			(xy 67.703377 -18.767309) (xy 67.679516 -18.686042) (xy 67.663487 -18.602876) (xy 67.655436 -18.518562)
			(xy 63.194987 -18.518562) (xy 63.154124 -18.555393) (xy 63.107501 -18.586399) (xy 63.056847 -18.610258)
			(xy 63.003249 -18.626458) (xy 62.94786 -18.63465) (xy 62.919864 -18.635218) (xy 62.892614 -18.63473)
			(xy 62.83867 -18.626969) (xy 62.786379 -18.611611) (xy 62.736805 -18.588968) (xy 62.690959 -18.559501)
			(xy 62.649772 -18.523809) (xy 62.614084 -18.48262) (xy 62.58462 -18.436772) (xy 62.56198 -18.387197)
			(xy 62.546625 -18.334905) (xy 62.538868 -18.28096) (xy 62.538356 -18.25371) (xy 62.53861 -18.239994)
			(xy 62.539118 -18.228056) (xy 62.529212 -18.206466) (xy 62.44844 -18.140172) (xy 62.42558 -18.134584)
			(xy 62.413896 -18.137378) (xy 62.391036 -18.142458) (xy 62.373256 -18.146268) (xy 62.35065 -18.173954)
			(xy 62.35065 -19.26971) (xy 62.537846 -19.26971) (xy 62.541917 -19.214088) (xy 62.554043 -19.159651)
			(xy 62.573966 -19.10756) (xy 62.601262 -19.058925) (xy 62.635348 -19.014782) (xy 62.675497 -18.976073)
			(xy 62.720855 -18.943622) (xy 62.770455 -18.918121) (xy 62.823239 -18.900114) (xy 62.878082 -18.889984)
			(xy 62.933816 -18.887947) (xy 62.989253 -18.894047) (xy 63.04321 -18.908153) (xy 63.094539 -18.929965)
			(xy 63.142145 -18.959019) (xy 63.185013 -18.994694) (xy 63.22223 -19.036231) (xy 63.253003 -19.082744)
			(xy 63.276675 -19.133241) (xy 63.292743 -19.186648) (xy 63.300863 -19.241824) (xy 63.301372 -19.26971)
			(xy 63.300863 -19.297596) (xy 63.292743 -19.352772) (xy 63.276675 -19.406179) (xy 63.253003 -19.456676)
			(xy 63.22223 -19.503189) (xy 63.185013 -19.544726) (xy 63.142145 -19.580401) (xy 63.094539 -19.609455)
			(xy 63.04321 -19.631267) (xy 62.989253 -19.645373) (xy 62.933816 -19.651473) (xy 62.878082 -19.649436)
			(xy 62.823239 -19.639306) (xy 62.770455 -19.621299) (xy 62.720855 -19.595798) (xy 62.675497 -19.563347)
			(xy 62.635348 -19.524638) (xy 62.601262 -19.480495) (xy 62.573966 -19.43186) (xy 62.554043 -19.379769)
			(xy 62.541917 -19.325332) (xy 62.537846 -19.26971) (xy 62.35065 -19.26971) (xy 62.35065 -19.958304)
			(xy 74.152504 -19.958304) (xy 74.156575 -19.902682) (xy 74.168701 -19.848245) (xy 74.188624 -19.796154)
			(xy 74.21592 -19.747519) (xy 74.250006 -19.703376) (xy 74.290155 -19.664667) (xy 74.335513 -19.632216)
			(xy 74.385113 -19.606715) (xy 74.437897 -19.588708) (xy 74.49274 -19.578578) (xy 74.548474 -19.576541)
			(xy 74.603911 -19.582641) (xy 74.657868 -19.596747) (xy 74.709197 -19.618559) (xy 74.756803 -19.647613)
			(xy 74.799671 -19.683288) (xy 74.836888 -19.724825) (xy 74.867661 -19.771338) (xy 74.891333 -19.821835)
			(xy 74.907401 -19.875242) (xy 74.915521 -19.930418) (xy 74.91603 -19.958304) (xy 74.915521 -19.98619)
			(xy 74.907401 -20.041366) (xy 74.891333 -20.094773) (xy 74.867661 -20.14527) (xy 74.836888 -20.191783)
			(xy 74.799671 -20.23332) (xy 74.756803 -20.268995) (xy 74.709197 -20.298049) (xy 74.657868 -20.319861)
			(xy 74.603911 -20.333967) (xy 74.548474 -20.340067) (xy 74.49274 -20.33803) (xy 74.437897 -20.3279)
			(xy 74.385113 -20.309893) (xy 74.335513 -20.284392) (xy 74.290155 -20.251941) (xy 74.250006 -20.213232)
			(xy 74.21592 -20.169089) (xy 74.188624 -20.120454) (xy 74.168701 -20.068363) (xy 74.156575 -20.013926)
			(xy 74.152504 -19.958304) (xy 62.35065 -19.958304) (xy 62.35065 -21.167344) (xy 62.351145 -21.177349)
			(xy 62.358811 -21.195835) (xy 62.37296 -21.209986) (xy 62.391445 -21.217654) (xy 62.40145 -21.218144)
			(xy 64.418972 -21.218144) (xy 64.456403 -21.218602) (xy 64.530902 -21.225968) (xy 64.604319 -21.240604)
			(xy 64.675948 -21.262366) (xy 64.745099 -21.291047) (xy 64.811104 -21.32637) (xy 64.873328 -21.367994)
			(xy 64.931171 -21.415518) (xy 64.95796 -21.441664) (xy 66.03746 -22.52091) (xy 66.044809 -22.52771)
			(xy 66.063271 -22.535419) (xy 66.073274 -22.535896) (xy 67.65925 -22.535896) (xy 67.669241 -22.535367)
			(xy 67.687686 -22.527666) (xy 67.695064 -22.52091) (xy 68.200016 -22.016212) (xy 68.226786 -21.990046)
			(xy 68.284635 -21.942527) (xy 68.346863 -21.900908) (xy 68.412871 -21.865589) (xy 68.482024 -21.836911)
			(xy 68.553654 -21.815149) (xy 68.627073 -21.800514) (xy 68.701573 -21.793147) (xy 68.739004 -21.792692)
			(xy 69.124068 -21.792692) (xy 69.133498 -21.792318) (xy 69.151082 -21.7855) (xy 69.165003 -21.772777)
			(xy 69.169534 -21.764498) (xy 69.21627 -21.669756) (xy 69.213476 -21.641054) (xy 69.204586 -21.62937)
			(xy 69.179673 -21.596087) (xy 69.135459 -21.525674) (xy 69.098009 -21.451443) (xy 69.06765 -21.374041)
			(xy 69.044645 -21.294143) (xy 69.029196 -21.212448) (xy 69.021438 -21.129668) (xy 69.020944 -21.088096)
			(xy 69.021419 -21.046993) (xy 69.029004 -20.965137) (xy 69.044109 -20.88433) (xy 69.066605 -20.805262)
			(xy 69.096301 -20.728607) (xy 69.132943 -20.655018) (xy 69.176218 -20.585124) (xy 69.225757 -20.519521)
			(xy 69.281137 -20.458769) (xy 69.341887 -20.403385) (xy 69.407488 -20.353843) (xy 69.47738 -20.310564)
			(xy 69.550966 -20.273919) (xy 69.62762 -20.244219) (xy 69.706688 -20.221719) (xy 69.787494 -20.20661)
			(xy 69.869349 -20.199021) (xy 69.910452 -20.198588) (xy 69.952896 -20.199078) (xy 70.037398 -20.207161)
			(xy 70.120746 -20.223257) (xy 70.202181 -20.24722) (xy 70.280963 -20.278832) (xy 70.318884 -20.297902)
			(xy 70.330048 -20.302883) (xy 70.354456 -20.302883) (xy 70.36562 -20.297902) (xy 70.40355 -20.278849)
			(xy 70.482329 -20.247229) (xy 70.563761 -20.223258) (xy 70.647107 -20.207153) (xy 70.731608 -20.199062)
			(xy 70.774052 -20.198588) (xy 70.815157 -20.199046) (xy 70.897016 -20.206627) (xy 70.977826 -20.221729)
			(xy 71.056898 -20.244223) (xy 71.133557 -20.273917) (xy 71.207149 -20.310558) (xy 71.277047 -20.353833)
			(xy 71.342653 -20.403373) (xy 71.403408 -20.458756) (xy 71.458793 -20.519507) (xy 71.508337 -20.585111)
			(xy 71.551616 -20.655005) (xy 71.588262 -20.728595) (xy 71.61796 -20.805253) (xy 71.640459 -20.884323)
			(xy 71.653007 -20.951444) (xy 74.153774 -20.951444) (xy 74.157845 -20.895822) (xy 74.169971 -20.841385)
			(xy 74.189894 -20.789294) (xy 74.21719 -20.740659) (xy 74.251276 -20.696516) (xy 74.291425 -20.657807)
			(xy 74.336783 -20.625356) (xy 74.386383 -20.599855) (xy 74.439167 -20.581848) (xy 74.49401 -20.571718)
			(xy 74.549744 -20.569681) (xy 74.605181 -20.575781) (xy 74.659138 -20.589887) (xy 74.710467 -20.611699)
			(xy 74.758073 -20.640753) (xy 74.800941 -20.676428) (xy 74.838158 -20.717965) (xy 74.868931 -20.764478)
			(xy 74.892603 -20.814975) (xy 74.908671 -20.868382) (xy 74.916791 -20.923558) (xy 74.9173 -20.951444)
			(xy 74.916791 -20.97933) (xy 74.908671 -21.034506) (xy 74.892603 -21.087913) (xy 74.868931 -21.13841)
			(xy 74.838158 -21.184923) (xy 74.800941 -21.22646) (xy 74.758073 -21.262135) (xy 74.710467 -21.291189)
			(xy 74.659138 -21.313001) (xy 74.605181 -21.327107) (xy 74.549744 -21.333207) (xy 74.49401 -21.33117)
			(xy 74.439167 -21.32104) (xy 74.386383 -21.303033) (xy 74.336783 -21.277532) (xy 74.291425 -21.245081)
			(xy 74.251276 -21.206372) (xy 74.21719 -21.162229) (xy 74.189894 -21.113594) (xy 74.169971 -21.061503)
			(xy 74.157845 -21.007066) (xy 74.153774 -20.951444) (xy 71.653007 -20.951444) (xy 71.655566 -20.965133)
			(xy 71.663152 -21.046991) (xy 71.66356 -21.088096) (xy 71.663096 -21.128888) (xy 71.655618 -21.210128)
			(xy 71.640735 -21.290342) (xy 71.618571 -21.368858) (xy 71.589312 -21.445014) (xy 71.553204 -21.518172)
			(xy 71.51055 -21.587717) (xy 71.461709 -21.653066) (xy 71.407091 -21.713669) (xy 71.347153 -21.769017)
			(xy 71.315072 -21.794216) (xy 71.306153 -21.801843) (xy 71.295806 -21.822881) (xy 71.29526 -21.834602)
			(xy 71.29526 -21.840444) (xy 74.153774 -21.840444) (xy 74.157845 -21.784822) (xy 74.169971 -21.730385)
			(xy 74.189894 -21.678294) (xy 74.21719 -21.629659) (xy 74.251276 -21.585516) (xy 74.291425 -21.546807)
			(xy 74.336783 -21.514356) (xy 74.386383 -21.488855) (xy 74.439167 -21.470848) (xy 74.49401 -21.460718)
			(xy 74.549744 -21.458681) (xy 74.605181 -21.464781) (xy 74.659138 -21.478887) (xy 74.710467 -21.500699)
			(xy 74.758073 -21.529753) (xy 74.800941 -21.565428) (xy 74.838158 -21.606965) (xy 74.868931 -21.653478)
			(xy 74.892603 -21.703975) (xy 74.908671 -21.757382) (xy 74.916791 -21.812558) (xy 74.9173 -21.840444)
			(xy 74.916791 -21.86833) (xy 74.908671 -21.923506) (xy 74.892603 -21.976913) (xy 74.868931 -22.02741)
			(xy 74.838158 -22.073923) (xy 74.800941 -22.11546) (xy 74.758073 -22.151135) (xy 74.710467 -22.180189)
			(xy 74.659138 -22.202001) (xy 74.605181 -22.216107) (xy 74.549744 -22.222207) (xy 74.49401 -22.22017)
			(xy 74.439167 -22.21004) (xy 74.386383 -22.192033) (xy 74.336783 -22.166532) (xy 74.291425 -22.134081)
			(xy 74.251276 -22.095372) (xy 74.21719 -22.051229) (xy 74.189894 -22.002594) (xy 74.169971 -21.950503)
			(xy 74.157845 -21.896066) (xy 74.153774 -21.840444) (xy 71.29526 -21.840444) (xy 71.29526 -22.459188)
			(xy 71.294801 -22.496619) (xy 71.287433 -22.571117) (xy 71.272797 -22.644534) (xy 71.251033 -22.716162)
			(xy 71.222351 -22.785311) (xy 71.187028 -22.851315) (xy 71.145404 -22.913538) (xy 71.097879 -22.97138)
			(xy 71.07174 -22.998176) (xy 70.594728 -23.475188) (xy 70.567958 -23.501356) (xy 70.510111 -23.548878)
			(xy 70.447883 -23.590501) (xy 70.381875 -23.625823) (xy 70.312723 -23.654506) (xy 70.241092 -23.676271)
			(xy 70.167673 -23.69091) (xy 70.093172 -23.698282) (xy 70.05574 -23.698708) (xy 69.233796 -23.698708)
			(xy 69.223829 -23.699183) (xy 69.205389 -23.706756) (xy 69.197982 -23.71344) (xy 68.69303 -24.218138)
			(xy 68.666242 -24.244276) (xy 68.608383 -24.29176) (xy 68.546149 -24.333344) (xy 68.501882 -24.357006)
			(xy 77.29626 -24.357006) (xy 77.29626 -24.27231) (xy 77.304311 -24.187996) (xy 77.32034 -24.10483)
			(xy 77.344201 -24.023563) (xy 77.37568 -23.944933) (xy 77.414491 -23.869652) (xy 77.460281 -23.7984)
			(xy 77.512637 -23.731824) (xy 77.571085 -23.670526) (xy 77.635095 -23.615061) (xy 77.704087 -23.565932)
			(xy 77.777437 -23.523583) (xy 77.85448 -23.488399) (xy 77.934519 -23.460697) (xy 78.016828 -23.440729)
			(xy 78.100663 -23.428676) (xy 78.185264 -23.424646) (xy 78.269865 -23.428676) (xy 78.3537 -23.440729)
			(xy 78.436009 -23.460697) (xy 78.516048 -23.488399) (xy 78.593091 -23.523583) (xy 78.666441 -23.565932)
			(xy 78.735433 -23.615061) (xy 78.799443 -23.670526) (xy 78.857891 -23.731824) (xy 78.910247 -23.7984)
			(xy 78.956037 -23.869652) (xy 78.994848 -23.944933) (xy 79.026327 -24.023563) (xy 79.050188 -24.10483)
			(xy 79.066217 -24.187996) (xy 79.074268 -24.27231) (xy 79.074772 -24.314658) (xy 79.074268 -24.357006)
			(xy 79.066217 -24.44132) (xy 79.050188 -24.524486) (xy 79.026327 -24.605753) (xy 78.994848 -24.684383)
			(xy 78.956037 -24.759664) (xy 78.910247 -24.830916) (xy 78.857891 -24.897492) (xy 78.799443 -24.95879)
			(xy 78.735433 -25.014255) (xy 78.666441 -25.063384) (xy 78.593091 -25.105733) (xy 78.516048 -25.140917)
			(xy 78.436009 -25.168619) (xy 78.3537 -25.188587) (xy 78.269865 -25.20064) (xy 78.185264 -25.204671)
			(xy 78.100663 -25.20064) (xy 78.016828 -25.188587) (xy 77.934519 -25.168619) (xy 77.85448 -25.140917)
			(xy 77.777437 -25.105733) (xy 77.704087 -25.063384) (xy 77.635095 -25.014255) (xy 77.571085 -24.95879)
			(xy 77.512637 -24.897492) (xy 77.460281 -24.830916) (xy 77.414491 -24.759664) (xy 77.37568 -24.684383)
			(xy 77.344201 -24.605753) (xy 77.32034 -24.524486) (xy 77.304311 -24.44132) (xy 77.29626 -24.357006)
			(xy 68.501882 -24.357006) (xy 68.480139 -24.368628) (xy 68.410989 -24.397273) (xy 68.339364 -24.419003)
			(xy 68.265954 -24.433608) (xy 68.191466 -24.440948) (xy 68.154042 -24.441404) (xy 65.578482 -24.441404)
			(xy 65.541057 -24.440959) (xy 65.466568 -24.43362) (xy 65.393158 -24.419015) (xy 65.321532 -24.397285)
			(xy 65.252381 -24.368638) (xy 65.186372 -24.333351) (xy 65.124139 -24.291764) (xy 65.066282 -24.244276)
			(xy 65.039494 -24.218138) (xy 64.07531 -23.254208) (xy 64.067632 -23.247278) (xy 64.04842 -23.239668)
			(xy 64.027763 -23.240203) (xy 64.01816 -23.244048) (xy 63.917068 -23.290784) (xy 63.901066 -23.318216)
			(xy 63.902336 -23.334218) (xy 63.903649 -23.351905) (xy 63.905045 -23.387348) (xy 63.90513 -23.405084)
			(xy 63.904656 -23.446187) (xy 63.897073 -23.528043) (xy 63.881969 -23.608851) (xy 63.859473 -23.68792)
			(xy 63.829778 -23.764576) (xy 63.793137 -23.838165) (xy 63.749862 -23.908059) (xy 63.700323 -23.973662)
			(xy 63.644942 -24.034415) (xy 63.584192 -24.089799) (xy 63.518591 -24.139341) (xy 63.448698 -24.182619)
			(xy 63.37511 -24.219263) (xy 63.298456 -24.248961) (xy 63.219388 -24.27146) (xy 63.138581 -24.286567)
			(xy 63.056725 -24.294154) (xy 63.015622 -24.294592) (xy 62.964822 -24.293068) (xy 62.929542 -24.29076)
			(xy 62.859481 -24.281224) (xy 62.824868 -24.274018) (xy 62.813438 -24.271478) (xy 62.79134 -24.276812)
			(xy 62.720474 -24.333708) (xy 62.711999 -24.341288) (xy 62.702109 -24.361728) (xy 62.701424 -24.373078)
			(xy 62.701424 -24.560784) (xy 62.701995 -24.571888) (xy 62.711358 -24.592027) (xy 62.719458 -24.599646)
			(xy 62.787276 -24.65705) (xy 62.808612 -24.662892) (xy 62.819788 -24.661114) (xy 62.854843 -24.655662)
			(xy 62.92554 -24.649687) (xy 62.961012 -24.649176) (xy 62.970156 -24.649176) (xy 63.013276 -24.649949)
			(xy 63.099068 -24.658819) (xy 63.183598 -24.675947) (xy 63.266075 -24.701172) (xy 63.345725 -24.734259)
			(xy 63.421801 -24.774896) (xy 63.493588 -24.822701) (xy 63.560414 -24.877228) (xy 63.621651 -24.937964)
			(xy 63.676725 -25.004339) (xy 63.72512 -25.07573) (xy 63.766381 -25.151469) (xy 63.783718 -25.190958)
			(xy 63.784647 -25.193244) (xy 70.553324 -25.193244) (xy 70.557395 -25.137622) (xy 70.569521 -25.083185)
			(xy 70.589444 -25.031094) (xy 70.61674 -24.982459) (xy 70.650826 -24.938316) (xy 70.690975 -24.899607)
			(xy 70.736333 -24.867156) (xy 70.785933 -24.841655) (xy 70.838717 -24.823648) (xy 70.89356 -24.813518)
			(xy 70.949294 -24.811481) (xy 71.004731 -24.817581) (xy 71.058688 -24.831687) (xy 71.110017 -24.853499)
			(xy 71.157623 -24.882553) (xy 71.200491 -24.918228) (xy 71.237708 -24.959765) (xy 71.268481 -25.006278)
			(xy 71.292153 -25.056775) (xy 71.308221 -25.110182) (xy 71.316341 -25.165358) (xy 71.31685 -25.193244)
			(xy 71.316341 -25.22113) (xy 71.308221 -25.276306) (xy 71.292153 -25.329713) (xy 71.268481 -25.38021)
			(xy 71.237708 -25.426723) (xy 71.200491 -25.46826) (xy 71.157623 -25.503935) (xy 71.110017 -25.532989)
			(xy 71.058688 -25.554801) (xy 71.004731 -25.568907) (xy 70.949294 -25.575007) (xy 70.89356 -25.57297)
			(xy 70.838717 -25.56284) (xy 70.785933 -25.544833) (xy 70.736333 -25.519332) (xy 70.690975 -25.486881)
			(xy 70.650826 -25.448172) (xy 70.61674 -25.404029) (xy 70.589444 -25.355394) (xy 70.569521 -25.303303)
			(xy 70.557395 -25.248866) (xy 70.553324 -25.193244) (xy 63.784647 -25.193244) (xy 63.78702 -25.199086)
			(xy 63.805054 -25.21839) (xy 63.808171 -25.221597) (xy 63.815327 -25.226962) (xy 63.819278 -25.229058)
			(xy 63.845948 -25.24252) (xy 63.862966 -25.244552) (xy 63.871856 -25.242774) (xy 63.892473 -25.238415)
			(xy 63.934351 -25.233704) (xy 63.955422 -25.233376) (xy 63.982673 -25.233863) (xy 64.036619 -25.241622)
			(xy 64.088912 -25.256979) (xy 64.138487 -25.279621) (xy 64.184336 -25.309088) (xy 64.225525 -25.344779)
			(xy 64.261216 -25.385969) (xy 64.290682 -25.431818) (xy 64.313323 -25.481394) (xy 64.328679 -25.533687)
			(xy 64.336437 -25.587633) (xy 64.33693 -25.614884) (xy 64.336429 -25.642688) (xy 64.328363 -25.697708)
			(xy 64.3124 -25.750975) (xy 64.288876 -25.801362) (xy 64.258291 -25.847803) (xy 64.240156 -25.868884)
			(xy 64.229996 -25.880314) (xy 64.225424 -25.909778) (xy 64.26962 -26.008076) (xy 64.274029 -26.016765)
			(xy 64.288073 -26.030248) (xy 64.306116 -26.037559) (xy 64.315848 -26.038048)
		)
		(stroke
			(width 0)
			(type solid)
		)
		(fill yes)
		(layer "In6.Cu")
		(net "P12V_OCP_V3_2")
	)
	(gr_poly
		(pts
			(xy 349.4659 -256.86131) (xy 349.477965 -256.860631) (xy 349.499432 -256.849613) (xy 349.507048 -256.840228)
			(xy 349.56115 -256.765298) (xy 349.56496 -256.741168) (xy 349.56115 -256.729484) (xy 349.554031 -256.706318)
			(xy 349.546372 -256.658465) (xy 349.54591 -256.634234) (xy 349.546432 -256.608979) (xy 349.554745 -256.559157)
			(xy 349.571146 -256.511383) (xy 349.595187 -256.46696) (xy 349.626211 -256.4271) (xy 349.663373 -256.39289)
			(xy 349.705659 -256.365264) (xy 349.751915 -256.344974) (xy 349.80088 -256.332574) (xy 349.851218 -256.328403)
			(xy 349.901556 -256.332574) (xy 349.950521 -256.344974) (xy 349.996777 -256.365264) (xy 350.039063 -256.39289)
			(xy 350.076225 -256.4271) (xy 350.107249 -256.46696) (xy 350.13129 -256.511383) (xy 350.147691 -256.559157)
			(xy 350.156004 -256.608979) (xy 350.156526 -256.634234) (xy 350.156058 -256.658464) (xy 350.148395 -256.706315)
			(xy 350.141286 -256.729484) (xy 350.137476 -256.741168) (xy 350.141286 -256.765298) (xy 350.195388 -256.840228)
			(xy 350.202993 -256.849624) (xy 350.224468 -256.86065) (xy 350.236536 -256.86131) (xy 350.4057 -256.86131)
			(xy 350.417765 -256.860631) (xy 350.439232 -256.849613) (xy 350.446848 -256.840228) (xy 350.50095 -256.765044)
			(xy 350.50476 -256.740914) (xy 350.50095 -256.72923) (xy 350.493629 -256.705773) (xy 350.485715 -256.657278)
			(xy 350.485202 -256.63271) (xy 350.485724 -256.607455) (xy 350.494037 -256.557633) (xy 350.510438 -256.509859)
			(xy 350.534479 -256.465436) (xy 350.565503 -256.425576) (xy 350.602665 -256.391366) (xy 350.644951 -256.36374)
			(xy 350.691207 -256.34345) (xy 350.740172 -256.33105) (xy 350.79051 -256.326879) (xy 350.840848 -256.33105)
			(xy 350.889813 -256.34345) (xy 350.936069 -256.36374) (xy 350.978355 -256.391366) (xy 351.015517 -256.425576)
			(xy 351.046541 -256.465436) (xy 351.070582 -256.509859) (xy 351.086983 -256.557633) (xy 351.095296 -256.607455)
			(xy 351.095818 -256.63271) (xy 351.095308 -256.657278) (xy 351.0874 -256.705775) (xy 351.08007 -256.72923)
			(xy 351.07626 -256.740914) (xy 351.08007 -256.765044) (xy 351.134172 -256.840228) (xy 351.141783 -256.84961)
			(xy 351.163259 -256.860601) (xy 351.17532 -256.86131) (xy 353.823778 -256.86131) (xy 353.833615 -256.860773)
			(xy 353.851775 -256.853185) (xy 353.859084 -256.846578) (xy 353.95662 -256.749042) (xy 353.963341 -256.741807)
			(xy 353.970953 -256.723602) (xy 353.971352 -256.713736) (xy 353.971352 -255.739392) (xy 353.970926 -255.729324)
			(xy 353.963204 -255.710726) (xy 353.956366 -255.703324) (xy 351.91446 -253.661418) (xy 351.881948 -253.656338)
			(xy 351.867216 -253.663958) (xy 351.845558 -253.674543) (xy 351.799734 -253.689496) (xy 351.752126 -253.697046)
			(xy 351.728024 -253.697486) (xy 351.72269 -253.697486) (xy 351.69663 -253.696503) (xy 351.645403 -253.686754)
			(xy 351.596576 -253.668446) (xy 351.551568 -253.642111) (xy 351.511686 -253.608515) (xy 351.47809 -253.568634)
			(xy 351.451755 -253.523626) (xy 351.433447 -253.474799) (xy 351.423698 -253.423572) (xy 351.422716 -253.397512)
			(xy 351.422716 -253.393702) (xy 351.422716 -253.392178) (xy 351.423176 -253.368079) (xy 351.430749 -253.32048)
			(xy 351.445688 -253.274655) (xy 351.456244 -253.252986) (xy 351.463864 -253.238254) (xy 351.458784 -253.205742)
			(xy 350.796606 -252.543564) (xy 350.789432 -252.536948) (xy 350.77152 -252.529248) (xy 350.752028 -252.52883)
			(xy 350.742758 -252.53188) (xy 350.64446 -252.568456) (xy 350.62668 -252.591824) (xy 350.625664 -252.60681)
			(xy 350.623285 -252.632112) (xy 350.611195 -252.681469) (xy 350.591097 -252.728142) (xy 350.563546 -252.770842)
			(xy 350.529303 -252.808389) (xy 350.489315 -252.839745) (xy 350.444685 -252.864045) (xy 350.396646 -252.880617)
			(xy 350.346527 -252.889004) (xy 350.321118 -252.889512) (xy 350.297124 -252.889067) (xy 350.249726 -252.881563)
			(xy 350.204086 -252.866736) (xy 350.161327 -252.844951) (xy 350.122502 -252.816746) (xy 350.088568 -252.782815)
			(xy 350.06036 -252.743992) (xy 350.038573 -252.701235) (xy 350.023742 -252.655596) (xy 350.016235 -252.608198)
			(xy 350.01581 -252.584204) (xy 350.015947 -252.571441) (xy 350.018105 -252.546006) (xy 350.020128 -252.533404)
			(xy 350.02485 -252.50849) (xy 350.041443 -252.460578) (xy 350.065716 -252.416061) (xy 350.097002 -252.376159)
			(xy 350.134443 -252.341967) (xy 350.177014 -252.314423) (xy 350.223546 -252.294281) (xy 350.272764 -252.282095)
			(xy 350.298004 -252.279658) (xy 350.307711 -252.278576) (xy 350.325283 -252.27009) (xy 350.338388 -252.255632)
			(xy 350.3422 -252.246638) (xy 350.373442 -252.162564) (xy 350.376429 -252.153292) (xy 350.375953 -252.133835)
			(xy 350.368295 -252.115941) (xy 350.361758 -252.108716) (xy 350.225614 -251.972572) (xy 350.217889 -251.965524)
			(xy 350.198478 -251.957805) (xy 350.188022 -251.957586) (xy 350.105472 -251.960126) (xy 350.086676 -251.968762)
			(xy 350.079564 -251.97689) (xy 350.062027 -251.995836) (xy 350.021754 -252.02813) (xy 349.976622 -252.053188)
			(xy 349.927917 -252.070296) (xy 349.877029 -252.078967) (xy 349.851218 -252.079506) (xy 349.827224 -252.079061)
			(xy 349.779826 -252.071557) (xy 349.734186 -252.05673) (xy 349.691428 -252.034945) (xy 349.652604 -252.00674)
			(xy 349.618671 -251.972808) (xy 349.590463 -251.933986) (xy 349.568676 -251.891228) (xy 349.553847 -251.845589)
			(xy 349.54634 -251.798192) (xy 349.54591 -251.774198) (xy 349.546047 -251.761435) (xy 349.548206 -251.736)
			(xy 349.550228 -251.723398) (xy 349.549974 -251.723398) (xy 349.554828 -251.697932) (xy 349.571957 -251.649006)
			(xy 349.597093 -251.60367) (xy 349.629514 -251.563223) (xy 349.648526 -251.545598) (xy 349.656654 -251.538486)
			(xy 349.66529 -251.519944) (xy 349.66783 -251.437394) (xy 349.667633 -251.426938) (xy 349.659888 -251.407534)
			(xy 349.652844 -251.399802) (xy 349.51162 -251.258578) (xy 349.484442 -251.25172) (xy 349.470726 -251.256038)
			(xy 349.448844 -251.262318) (xy 349.403825 -251.269073) (xy 349.381064 -251.2695) (xy 349.357075 -251.269027)
			(xy 349.309688 -251.261516) (xy 349.264059 -251.246685) (xy 349.221312 -251.2249) (xy 349.182499 -251.196696)
			(xy 349.148576 -251.162767) (xy 349.120377 -251.12395) (xy 349.098598 -251.0812) (xy 349.083774 -251.035569)
			(xy 349.07627 -250.988181) (xy 349.075756 -250.964192) (xy 349.076177 -250.94143) (xy 349.082937 -250.896412)
			(xy 349.089218 -250.87453) (xy 349.093536 -250.860814) (xy 349.086678 -250.833636) (xy 348.977458 -250.724416)
			(xy 348.970058 -250.717574) (xy 348.95146 -250.709853) (xy 348.94139 -250.70943) (xy 348.381066 -250.70943)
			(xy 348.371225 -250.708901) (xy 348.353052 -250.701327) (xy 348.34576 -250.694698) (xy 348.100142 -250.44908)
			(xy 348.073218 -250.442222) (xy 348.059502 -250.44654) (xy 348.037907 -250.452595) (xy 347.993534 -250.459097)
			(xy 347.97111 -250.459494) (xy 347.967808 -250.459494) (xy 347.944151 -250.458794) (xy 347.897473 -250.450988)
			(xy 347.852559 -250.436072) (xy 347.810485 -250.414405) (xy 347.772257 -250.386504) (xy 347.738793 -250.35304)
			(xy 347.710893 -250.314812) (xy 347.689226 -250.272737) (xy 347.674312 -250.227823) (xy 347.666506 -250.181145)
			(xy 347.665802 -250.157488) (xy 347.665802 -250.154948) (xy 347.666117 -250.13233) (xy 347.672626 -250.087568)
			(xy 347.678756 -250.065794) (xy 347.683074 -250.052078) (xy 347.676216 -250.025154) (xy 346.744798 -249.093736)
			(xy 346.737401 -249.086886) (xy 346.718803 -249.079147) (xy 346.70873 -249.07875) (xy 345.991688 -249.07875)
			(xy 345.978961 -249.079461) (xy 345.956586 -249.091605) (xy 345.949016 -249.101864) (xy 345.896692 -249.182636)
			(xy 345.89466 -249.208036) (xy 345.899994 -249.219974) (xy 345.908327 -249.23961) (xy 345.920083 -249.280613)
			(xy 345.926019 -249.322853) (xy 345.92641 -249.34418) (xy 345.925888 -249.369435) (xy 345.917575 -249.419257)
			(xy 345.901174 -249.467031) (xy 345.877133 -249.511454) (xy 345.846109 -249.551314) (xy 345.808947 -249.585524)
			(xy 345.766661 -249.61315) (xy 345.720405 -249.63344) (xy 345.67144 -249.64584) (xy 345.621102 -249.650011)
			(xy 345.570764 -249.64584) (xy 345.521799 -249.63344) (xy 345.475543 -249.61315) (xy 345.433257 -249.585524)
			(xy 345.396095 -249.551314) (xy 345.365071 -249.511454) (xy 345.34103 -249.467031) (xy 345.324629 -249.419257)
			(xy 345.316316 -249.369435) (xy 345.315794 -249.34418) (xy 345.316151 -249.322851) (xy 345.322096 -249.280609)
			(xy 345.333867 -249.239607) (xy 345.34221 -249.219974) (xy 345.347544 -249.208036) (xy 345.345512 -249.182636)
			(xy 345.293188 -249.101864) (xy 345.28833 -249.094926) (xy 345.274995 -249.084497) (xy 345.258981 -249.079011)
			(xy 345.250516 -249.07875) (xy 344.599006 -249.07875) (xy 344.589169 -249.079289) (xy 344.57101 -249.086877)
			(xy 344.5637 -249.093482) (xy 344.334084 -249.323098) (xy 344.327369 -249.330336) (xy 344.319771 -249.34854)
			(xy 344.319352 -249.358404) (xy 344.319352 -249.850148) (xy 344.334338 -249.874532) (xy 344.347546 -249.880882)
			(xy 344.368968 -249.892106) (xy 344.408277 -249.920274) (xy 344.442658 -249.954283) (xy 344.471254 -249.993282)
			(xy 344.49335 -250.036298) (xy 344.508395 -250.082258) (xy 344.516013 -250.130014) (xy 344.516013 -250.154186)
			(xy 345.785198 -250.154186) (xy 345.789158 -250.105132) (xy 345.800935 -250.057348) (xy 345.820226 -250.012072)
			(xy 345.846529 -249.970476) (xy 345.879164 -249.933639) (xy 345.917285 -249.902514) (xy 345.959906 -249.877907)
			(xy 346.005922 -249.860455) (xy 346.054141 -249.850611) (xy 346.103316 -249.84863) (xy 346.152171 -249.854562)
			(xy 346.199442 -249.868254) (xy 346.243904 -249.889352) (xy 346.284407 -249.917308) (xy 346.3199 -249.9514)
			(xy 346.349465 -249.990744) (xy 346.372336 -250.034321) (xy 346.38792 -250.081002) (xy 346.395815 -250.129579)
			(xy 346.39631 -250.154186) (xy 346.395815 -250.178793) (xy 346.38792 -250.22737) (xy 346.372336 -250.274051)
			(xy 346.349465 -250.317628) (xy 346.3199 -250.356972) (xy 346.284407 -250.391064) (xy 346.243904 -250.41902)
			(xy 346.199442 -250.440118) (xy 346.152171 -250.45381) (xy 346.103316 -250.459742) (xy 346.054141 -250.457761)
			(xy 346.005922 -250.447917) (xy 345.959906 -250.430465) (xy 345.917285 -250.405858) (xy 345.879164 -250.374733)
			(xy 345.846529 -250.337896) (xy 345.820226 -250.2963) (xy 345.800935 -250.251024) (xy 345.789158 -250.20324)
			(xy 345.785198 -250.154186) (xy 344.516013 -250.154186) (xy 344.516014 -250.178374) (xy 344.508398 -250.22613)
			(xy 344.493355 -250.27209) (xy 344.471261 -250.315107) (xy 344.442666 -250.354108) (xy 344.408286 -250.388118)
			(xy 344.368979 -250.416288) (xy 344.347546 -250.42749) (xy 344.334338 -250.43384) (xy 344.319352 -250.458224)
			(xy 344.319352 -250.964192) (xy 345.315298 -250.964192) (xy 345.319258 -250.915138) (xy 345.331035 -250.867354)
			(xy 345.350326 -250.822078) (xy 345.376629 -250.780482) (xy 345.409264 -250.743645) (xy 345.447385 -250.71252)
			(xy 345.490006 -250.687913) (xy 345.536022 -250.670461) (xy 345.584241 -250.660617) (xy 345.633416 -250.658636)
			(xy 345.682271 -250.664568) (xy 345.729542 -250.67826) (xy 345.774004 -250.699358) (xy 345.814507 -250.727314)
			(xy 345.85 -250.761406) (xy 345.879565 -250.80075) (xy 345.902436 -250.844327) (xy 345.91802 -250.891008)
			(xy 345.925915 -250.939585) (xy 345.92641 -250.964192) (xy 347.195406 -250.964192) (xy 347.199366 -250.915138)
			(xy 347.211143 -250.867354) (xy 347.230434 -250.822078) (xy 347.256737 -250.780482) (xy 347.289372 -250.743645)
			(xy 347.327493 -250.71252) (xy 347.370114 -250.687913) (xy 347.41613 -250.670461) (xy 347.464349 -250.660617)
			(xy 347.513524 -250.658636) (xy 347.562379 -250.664568) (xy 347.60965 -250.67826) (xy 347.654112 -250.699358)
			(xy 347.694615 -250.727314) (xy 347.730108 -250.761406) (xy 347.759673 -250.80075) (xy 347.782544 -250.844327)
			(xy 347.798128 -250.891008) (xy 347.806023 -250.939585) (xy 347.806518 -250.964192) (xy 347.806023 -250.988799)
			(xy 347.798128 -251.037376) (xy 347.782544 -251.084057) (xy 347.759673 -251.127634) (xy 347.730108 -251.166978)
			(xy 347.694615 -251.20107) (xy 347.654112 -251.229026) (xy 347.60965 -251.250124) (xy 347.562379 -251.263816)
			(xy 347.513524 -251.269748) (xy 347.464349 -251.267767) (xy 347.41613 -251.257923) (xy 347.370114 -251.240471)
			(xy 347.327493 -251.215864) (xy 347.289372 -251.184739) (xy 347.256737 -251.147902) (xy 347.230434 -251.106306)
			(xy 347.211143 -251.06103) (xy 347.199366 -251.013246) (xy 347.195406 -250.964192) (xy 345.92641 -250.964192)
			(xy 345.925915 -250.988799) (xy 345.91802 -251.037376) (xy 345.902436 -251.084057) (xy 345.879565 -251.127634)
			(xy 345.85 -251.166978) (xy 345.814507 -251.20107) (xy 345.774004 -251.229026) (xy 345.729542 -251.250124)
			(xy 345.682271 -251.263816) (xy 345.633416 -251.269748) (xy 345.584241 -251.267767) (xy 345.536022 -251.257923)
			(xy 345.490006 -251.240471) (xy 345.447385 -251.215864) (xy 345.409264 -251.184739) (xy 345.376629 -251.147902)
			(xy 345.350326 -251.106306) (xy 345.331035 -251.06103) (xy 345.319258 -251.013246) (xy 345.315298 -250.964192)
			(xy 344.319352 -250.964192) (xy 344.319352 -251.47016) (xy 344.334338 -251.494544) (xy 344.347546 -251.500894)
			(xy 344.368967 -251.512118) (xy 344.408274 -251.540286) (xy 344.442654 -251.574294) (xy 344.471248 -251.613292)
			(xy 344.493342 -251.656307) (xy 344.508386 -251.702266) (xy 344.516003 -251.75002) (xy 344.516003 -251.774198)
			(xy 345.785198 -251.774198) (xy 345.789158 -251.725144) (xy 345.800935 -251.67736) (xy 345.820226 -251.632084)
			(xy 345.846529 -251.590488) (xy 345.879164 -251.553651) (xy 345.917285 -251.522526) (xy 345.959906 -251.497919)
			(xy 346.005922 -251.480467) (xy 346.054141 -251.470623) (xy 346.103316 -251.468642) (xy 346.152171 -251.474574)
			(xy 346.199442 -251.488266) (xy 346.243904 -251.509364) (xy 346.284407 -251.53732) (xy 346.3199 -251.571412)
			(xy 346.349465 -251.610756) (xy 346.372336 -251.654333) (xy 346.38792 -251.701014) (xy 346.395815 -251.749591)
			(xy 346.39631 -251.774198) (xy 347.665306 -251.774198) (xy 347.669266 -251.725144) (xy 347.681043 -251.67736)
			(xy 347.700334 -251.632084) (xy 347.726637 -251.590488) (xy 347.759272 -251.553651) (xy 347.797393 -251.522526)
			(xy 347.840014 -251.497919) (xy 347.88603 -251.480467) (xy 347.934249 -251.470623) (xy 347.983424 -251.468642)
			(xy 348.032279 -251.474574) (xy 348.07955 -251.488266) (xy 348.124012 -251.509364) (xy 348.164515 -251.53732)
			(xy 348.200008 -251.571412) (xy 348.229573 -251.610756) (xy 348.252444 -251.654333) (xy 348.268028 -251.701014)
			(xy 348.275923 -251.749591) (xy 348.276418 -251.774198) (xy 348.275923 -251.798805) (xy 348.268028 -251.847382)
			(xy 348.252444 -251.894063) (xy 348.229573 -251.93764) (xy 348.200008 -251.976984) (xy 348.164515 -252.011076)
			(xy 348.124012 -252.039032) (xy 348.07955 -252.06013) (xy 348.032279 -252.073822) (xy 347.983424 -252.079754)
			(xy 347.934249 -252.077773) (xy 347.88603 -252.067929) (xy 347.840014 -252.050477) (xy 347.797393 -252.02587)
			(xy 347.759272 -251.994745) (xy 347.726637 -251.957908) (xy 347.700334 -251.916312) (xy 347.681043 -251.871036)
			(xy 347.669266 -251.823252) (xy 347.665306 -251.774198) (xy 346.39631 -251.774198) (xy 346.395815 -251.798805)
			(xy 346.38792 -251.847382) (xy 346.372336 -251.894063) (xy 346.349465 -251.93764) (xy 346.3199 -251.976984)
			(xy 346.284407 -252.011076) (xy 346.243904 -252.039032) (xy 346.199442 -252.06013) (xy 346.152171 -252.073822)
			(xy 346.103316 -252.079754) (xy 346.054141 -252.077773) (xy 346.005922 -252.067929) (xy 345.959906 -252.050477)
			(xy 345.917285 -252.02587) (xy 345.879164 -251.994745) (xy 345.846529 -251.957908) (xy 345.820226 -251.916312)
			(xy 345.800935 -251.871036) (xy 345.789158 -251.823252) (xy 345.785198 -251.774198) (xy 344.516003 -251.774198)
			(xy 344.516003 -251.798378) (xy 344.508386 -251.846132) (xy 344.493343 -251.892091) (xy 344.471249 -251.935106)
			(xy 344.442655 -251.974105) (xy 344.408275 -252.008113) (xy 344.368969 -252.036281) (xy 344.347546 -252.047502)
			(xy 344.334338 -252.053852) (xy 344.319352 -252.078236) (xy 344.319352 -252.584204) (xy 345.315298 -252.584204)
			(xy 345.319258 -252.53515) (xy 345.331035 -252.487366) (xy 345.350326 -252.44209) (xy 345.376629 -252.400494)
			(xy 345.409264 -252.363657) (xy 345.447385 -252.332532) (xy 345.490006 -252.307925) (xy 345.536022 -252.290473)
			(xy 345.584241 -252.280629) (xy 345.633416 -252.278648) (xy 345.682271 -252.28458) (xy 345.729542 -252.298272)
			(xy 345.774004 -252.31937) (xy 345.814507 -252.347326) (xy 345.85 -252.381418) (xy 345.879565 -252.420762)
			(xy 345.902436 -252.464339) (xy 345.91802 -252.51102) (xy 345.925915 -252.559597) (xy 345.92641 -252.584204)
			(xy 347.195406 -252.584204) (xy 347.199366 -252.53515) (xy 347.211143 -252.487366) (xy 347.230434 -252.44209)
			(xy 347.256737 -252.400494) (xy 347.289372 -252.363657) (xy 347.327493 -252.332532) (xy 347.370114 -252.307925)
			(xy 347.41613 -252.290473) (xy 347.464349 -252.280629) (xy 347.513524 -252.278648) (xy 347.562379 -252.28458)
			(xy 347.60965 -252.298272) (xy 347.654112 -252.31937) (xy 347.694615 -252.347326) (xy 347.730108 -252.381418)
			(xy 347.759673 -252.420762) (xy 347.782544 -252.464339) (xy 347.798128 -252.51102) (xy 347.806023 -252.559597)
			(xy 347.806518 -252.584204) (xy 349.07526 -252.584204) (xy 349.07922 -252.53515) (xy 349.090997 -252.487366)
			(xy 349.110288 -252.44209) (xy 349.136591 -252.400494) (xy 349.169226 -252.363657) (xy 349.207347 -252.332532)
			(xy 349.249968 -252.307925) (xy 349.295984 -252.290473) (xy 349.344203 -252.280629) (xy 349.393378 -252.278648)
			(xy 349.442233 -252.28458) (xy 349.489504 -252.298272) (xy 349.533966 -252.31937) (xy 349.574469 -252.347326)
			(xy 349.609962 -252.381418) (xy 349.639527 -252.420762) (xy 349.662398 -252.464339) (xy 349.677982 -252.51102)
			(xy 349.685877 -252.559597) (xy 349.686372 -252.584204) (xy 349.685877 -252.608811) (xy 349.677982 -252.657388)
			(xy 349.662398 -252.704069) (xy 349.639527 -252.747646) (xy 349.609962 -252.78699) (xy 349.574469 -252.821082)
			(xy 349.533966 -252.849038) (xy 349.489504 -252.870136) (xy 349.442233 -252.883828) (xy 349.393378 -252.88976)
			(xy 349.344203 -252.887779) (xy 349.295984 -252.877935) (xy 349.249968 -252.860483) (xy 349.207347 -252.835876)
			(xy 349.169226 -252.804751) (xy 349.136591 -252.767914) (xy 349.110288 -252.726318) (xy 349.090997 -252.681042)
			(xy 349.07922 -252.633258) (xy 349.07526 -252.584204) (xy 347.806518 -252.584204) (xy 347.806023 -252.608811)
			(xy 347.798128 -252.657388) (xy 347.782544 -252.704069) (xy 347.759673 -252.747646) (xy 347.730108 -252.78699)
			(xy 347.694615 -252.821082) (xy 347.654112 -252.849038) (xy 347.60965 -252.870136) (xy 347.562379 -252.883828)
			(xy 347.513524 -252.88976) (xy 347.464349 -252.887779) (xy 347.41613 -252.877935) (xy 347.370114 -252.860483)
			(xy 347.327493 -252.835876) (xy 347.289372 -252.804751) (xy 347.256737 -252.767914) (xy 347.230434 -252.726318)
			(xy 347.211143 -252.681042) (xy 347.199366 -252.633258) (xy 347.195406 -252.584204) (xy 345.92641 -252.584204)
			(xy 345.925915 -252.608811) (xy 345.91802 -252.657388) (xy 345.902436 -252.704069) (xy 345.879565 -252.747646)
			(xy 345.85 -252.78699) (xy 345.814507 -252.821082) (xy 345.774004 -252.849038) (xy 345.729542 -252.870136)
			(xy 345.682271 -252.883828) (xy 345.633416 -252.88976) (xy 345.584241 -252.887779) (xy 345.536022 -252.877935)
			(xy 345.490006 -252.860483) (xy 345.447385 -252.835876) (xy 345.409264 -252.804751) (xy 345.376629 -252.767914)
			(xy 345.350326 -252.726318) (xy 345.331035 -252.681042) (xy 345.319258 -252.633258) (xy 345.315298 -252.584204)
			(xy 344.319352 -252.584204) (xy 344.319352 -253.090172) (xy 344.334338 -253.114556) (xy 344.347546 -253.120906)
			(xy 344.368966 -253.13213) (xy 344.408271 -253.160298) (xy 344.442649 -253.194305) (xy 344.471241 -253.233302)
			(xy 344.493334 -253.276317) (xy 344.508377 -253.322274) (xy 344.515992 -253.370026) (xy 344.515992 -253.39421)
			(xy 345.785198 -253.39421) (xy 345.789158 -253.345156) (xy 345.800935 -253.297372) (xy 345.820226 -253.252096)
			(xy 345.846529 -253.2105) (xy 345.879164 -253.173663) (xy 345.917285 -253.142538) (xy 345.959906 -253.117931)
			(xy 346.005922 -253.100479) (xy 346.054141 -253.090635) (xy 346.103316 -253.088654) (xy 346.152171 -253.094586)
			(xy 346.199442 -253.108278) (xy 346.243904 -253.129376) (xy 346.284407 -253.157332) (xy 346.3199 -253.191424)
			(xy 346.349465 -253.230768) (xy 346.372336 -253.274345) (xy 346.38792 -253.321026) (xy 346.395815 -253.369603)
			(xy 346.39631 -253.39421) (xy 347.665306 -253.39421) (xy 347.669266 -253.345156) (xy 347.681043 -253.297372)
			(xy 347.700334 -253.252096) (xy 347.726637 -253.2105) (xy 347.759272 -253.173663) (xy 347.797393 -253.142538)
			(xy 347.840014 -253.117931) (xy 347.88603 -253.100479) (xy 347.934249 -253.090635) (xy 347.983424 -253.088654)
			(xy 348.032279 -253.094586) (xy 348.07955 -253.108278) (xy 348.124012 -253.129376) (xy 348.164515 -253.157332)
			(xy 348.200008 -253.191424) (xy 348.229573 -253.230768) (xy 348.252444 -253.274345) (xy 348.268028 -253.321026)
			(xy 348.275923 -253.369603) (xy 348.276418 -253.39421) (xy 348.60536 -253.39421) (xy 348.60932 -253.345156)
			(xy 348.621097 -253.297372) (xy 348.640388 -253.252096) (xy 348.666691 -253.2105) (xy 348.699326 -253.173663)
			(xy 348.737447 -253.142538) (xy 348.780068 -253.117931) (xy 348.826084 -253.100479) (xy 348.874303 -253.090635)
			(xy 348.923478 -253.088654) (xy 348.972333 -253.094586) (xy 349.019604 -253.108278) (xy 349.064066 -253.129376)
			(xy 349.104569 -253.157332) (xy 349.140062 -253.191424) (xy 349.169627 -253.230768) (xy 349.192498 -253.274345)
			(xy 349.208082 -253.321026) (xy 349.215977 -253.369603) (xy 349.216472 -253.39421) (xy 349.545414 -253.39421)
			(xy 349.549374 -253.345156) (xy 349.561151 -253.297372) (xy 349.580442 -253.252096) (xy 349.606745 -253.2105)
			(xy 349.63938 -253.173663) (xy 349.677501 -253.142538) (xy 349.720122 -253.117931) (xy 349.766138 -253.100479)
			(xy 349.814357 -253.090635) (xy 349.863532 -253.088654) (xy 349.912387 -253.094586) (xy 349.959658 -253.108278)
			(xy 350.00412 -253.129376) (xy 350.044623 -253.157332) (xy 350.080116 -253.191424) (xy 350.109681 -253.230768)
			(xy 350.132552 -253.274345) (xy 350.148136 -253.321026) (xy 350.156031 -253.369603) (xy 350.156526 -253.39421)
			(xy 350.156031 -253.418817) (xy 350.148136 -253.467394) (xy 350.132552 -253.514075) (xy 350.109681 -253.557652)
			(xy 350.080116 -253.596996) (xy 350.044623 -253.631088) (xy 350.00412 -253.659044) (xy 349.959658 -253.680142)
			(xy 349.912387 -253.693834) (xy 349.863532 -253.699766) (xy 349.814357 -253.697785) (xy 349.766138 -253.687941)
			(xy 349.720122 -253.670489) (xy 349.677501 -253.645882) (xy 349.63938 -253.614757) (xy 349.606745 -253.57792)
			(xy 349.580442 -253.536324) (xy 349.561151 -253.491048) (xy 349.549374 -253.443264) (xy 349.545414 -253.39421)
			(xy 349.216472 -253.39421) (xy 349.215977 -253.418817) (xy 349.208082 -253.467394) (xy 349.192498 -253.514075)
			(xy 349.169627 -253.557652) (xy 349.140062 -253.596996) (xy 349.104569 -253.631088) (xy 349.064066 -253.659044)
			(xy 349.019604 -253.680142) (xy 348.972333 -253.693834) (xy 348.923478 -253.699766) (xy 348.874303 -253.697785)
			(xy 348.826084 -253.687941) (xy 348.780068 -253.670489) (xy 348.737447 -253.645882) (xy 348.699326 -253.614757)
			(xy 348.666691 -253.57792) (xy 348.640388 -253.536324) (xy 348.621097 -253.491048) (xy 348.60932 -253.443264)
			(xy 348.60536 -253.39421) (xy 348.276418 -253.39421) (xy 348.275923 -253.418817) (xy 348.268028 -253.467394)
			(xy 348.252444 -253.514075) (xy 348.229573 -253.557652) (xy 348.200008 -253.596996) (xy 348.164515 -253.631088)
			(xy 348.124012 -253.659044) (xy 348.07955 -253.680142) (xy 348.032279 -253.693834) (xy 347.983424 -253.699766)
			(xy 347.934249 -253.697785) (xy 347.88603 -253.687941) (xy 347.840014 -253.670489) (xy 347.797393 -253.645882)
			(xy 347.759272 -253.614757) (xy 347.726637 -253.57792) (xy 347.700334 -253.536324) (xy 347.681043 -253.491048)
			(xy 347.669266 -253.443264) (xy 347.665306 -253.39421) (xy 346.39631 -253.39421) (xy 346.395815 -253.418817)
			(xy 346.38792 -253.467394) (xy 346.372336 -253.514075) (xy 346.349465 -253.557652) (xy 346.3199 -253.596996)
			(xy 346.284407 -253.631088) (xy 346.243904 -253.659044) (xy 346.199442 -253.680142) (xy 346.152171 -253.693834)
			(xy 346.103316 -253.699766) (xy 346.054141 -253.697785) (xy 346.005922 -253.687941) (xy 345.959906 -253.670489)
			(xy 345.917285 -253.645882) (xy 345.879164 -253.614757) (xy 345.846529 -253.57792) (xy 345.820226 -253.536324)
			(xy 345.800935 -253.491048) (xy 345.789158 -253.443264) (xy 345.785198 -253.39421) (xy 344.515992 -253.39421)
			(xy 344.515992 -253.418383) (xy 344.508374 -253.466135) (xy 344.493331 -253.512092) (xy 344.471237 -253.555105)
			(xy 344.442643 -253.594102) (xy 344.408264 -253.628108) (xy 344.368958 -253.656275) (xy 344.347546 -253.667514)
			(xy 344.334338 -253.673864) (xy 344.319352 -253.698248) (xy 344.319352 -254.204216) (xy 345.315298 -254.204216)
			(xy 345.319258 -254.155162) (xy 345.331035 -254.107378) (xy 345.350326 -254.062102) (xy 345.376629 -254.020506)
			(xy 345.409264 -253.983669) (xy 345.447385 -253.952544) (xy 345.490006 -253.927937) (xy 345.536022 -253.910485)
			(xy 345.584241 -253.900641) (xy 345.633416 -253.89866) (xy 345.682271 -253.904592) (xy 345.729542 -253.918284)
			(xy 345.774004 -253.939382) (xy 345.814507 -253.967338) (xy 345.85 -254.00143) (xy 345.879565 -254.040774)
			(xy 345.902436 -254.084351) (xy 345.91802 -254.131032) (xy 345.925915 -254.179609) (xy 345.92641 -254.204216)
			(xy 347.195406 -254.204216) (xy 347.199366 -254.155162) (xy 347.211143 -254.107378) (xy 347.230434 -254.062102)
			(xy 347.256737 -254.020506) (xy 347.289372 -253.983669) (xy 347.327493 -253.952544) (xy 347.370114 -253.927937)
			(xy 347.41613 -253.910485) (xy 347.464349 -253.900641) (xy 347.513524 -253.89866) (xy 347.562379 -253.904592)
			(xy 347.60965 -253.918284) (xy 347.654112 -253.939382) (xy 347.694615 -253.967338) (xy 347.730108 -254.00143)
			(xy 347.759673 -254.040774) (xy 347.782544 -254.084351) (xy 347.798128 -254.131032) (xy 347.806023 -254.179609)
			(xy 347.806518 -254.204216) (xy 349.07526 -254.204216) (xy 349.07922 -254.155162) (xy 349.090997 -254.107378)
			(xy 349.110288 -254.062102) (xy 349.136591 -254.020506) (xy 349.169226 -253.983669) (xy 349.207347 -253.952544)
			(xy 349.249968 -253.927937) (xy 349.295984 -253.910485) (xy 349.344203 -253.900641) (xy 349.393378 -253.89866)
			(xy 349.442233 -253.904592) (xy 349.489504 -253.918284) (xy 349.533966 -253.939382) (xy 349.574469 -253.967338)
			(xy 349.609962 -254.00143) (xy 349.639527 -254.040774) (xy 349.662398 -254.084351) (xy 349.677982 -254.131032)
			(xy 349.685877 -254.179609) (xy 349.686372 -254.204216) (xy 350.015314 -254.204216) (xy 350.019274 -254.155162)
			(xy 350.031051 -254.107378) (xy 350.050342 -254.062102) (xy 350.076645 -254.020506) (xy 350.10928 -253.983669)
			(xy 350.147401 -253.952544) (xy 350.190022 -253.927937) (xy 350.236038 -253.910485) (xy 350.284257 -253.900641)
			(xy 350.333432 -253.89866) (xy 350.382287 -253.904592) (xy 350.429558 -253.918284) (xy 350.47402 -253.939382)
			(xy 350.514523 -253.967338) (xy 350.550016 -254.00143) (xy 350.579581 -254.040774) (xy 350.602452 -254.084351)
			(xy 350.618036 -254.131032) (xy 350.625931 -254.179609) (xy 350.626426 -254.204216) (xy 350.625931 -254.228823)
			(xy 350.618036 -254.2774) (xy 350.602452 -254.324081) (xy 350.579581 -254.367658) (xy 350.550016 -254.407002)
			(xy 350.514523 -254.441094) (xy 350.47402 -254.46905) (xy 350.429558 -254.490148) (xy 350.382287 -254.50384)
			(xy 350.333432 -254.509772) (xy 350.284257 -254.507791) (xy 350.236038 -254.497947) (xy 350.190022 -254.480495)
			(xy 350.147401 -254.455888) (xy 350.10928 -254.424763) (xy 350.076645 -254.387926) (xy 350.050342 -254.34633)
			(xy 350.031051 -254.301054) (xy 350.019274 -254.25327) (xy 350.015314 -254.204216) (xy 349.686372 -254.204216)
			(xy 349.685877 -254.228823) (xy 349.677982 -254.2774) (xy 349.662398 -254.324081) (xy 349.639527 -254.367658)
			(xy 349.609962 -254.407002) (xy 349.574469 -254.441094) (xy 349.533966 -254.46905) (xy 349.489504 -254.490148)
			(xy 349.442233 -254.50384) (xy 349.393378 -254.509772) (xy 349.344203 -254.507791) (xy 349.295984 -254.497947)
			(xy 349.249968 -254.480495) (xy 349.207347 -254.455888) (xy 349.169226 -254.424763) (xy 349.136591 -254.387926)
			(xy 349.110288 -254.34633) (xy 349.090997 -254.301054) (xy 349.07922 -254.25327) (xy 349.07526 -254.204216)
			(xy 347.806518 -254.204216) (xy 347.806023 -254.228823) (xy 347.798128 -254.2774) (xy 347.782544 -254.324081)
			(xy 347.759673 -254.367658) (xy 347.730108 -254.407002) (xy 347.694615 -254.441094) (xy 347.654112 -254.46905)
			(xy 347.60965 -254.490148) (xy 347.562379 -254.50384) (xy 347.513524 -254.509772) (xy 347.464349 -254.507791)
			(xy 347.41613 -254.497947) (xy 347.370114 -254.480495) (xy 347.327493 -254.455888) (xy 347.289372 -254.424763)
			(xy 347.256737 -254.387926) (xy 347.230434 -254.34633) (xy 347.211143 -254.301054) (xy 347.199366 -254.25327)
			(xy 347.195406 -254.204216) (xy 345.92641 -254.204216) (xy 345.925915 -254.228823) (xy 345.91802 -254.2774)
			(xy 345.902436 -254.324081) (xy 345.879565 -254.367658) (xy 345.85 -254.407002) (xy 345.814507 -254.441094)
			(xy 345.774004 -254.46905) (xy 345.729542 -254.490148) (xy 345.682271 -254.50384) (xy 345.633416 -254.509772)
			(xy 345.584241 -254.507791) (xy 345.536022 -254.497947) (xy 345.490006 -254.480495) (xy 345.447385 -254.455888)
			(xy 345.409264 -254.424763) (xy 345.376629 -254.387926) (xy 345.350326 -254.34633) (xy 345.331035 -254.301054)
			(xy 345.319258 -254.25327) (xy 345.315298 -254.204216) (xy 344.319352 -254.204216) (xy 344.319352 -254.710184)
			(xy 344.334338 -254.734568) (xy 344.347546 -254.740918) (xy 344.368965 -254.752142) (xy 344.408268 -254.780309)
			(xy 344.442644 -254.814316) (xy 344.471235 -254.853313) (xy 344.493327 -254.896326) (xy 344.508367 -254.942281)
			(xy 344.515982 -254.990033) (xy 344.515981 -255.014222) (xy 345.785198 -255.014222) (xy 345.789158 -254.965168)
			(xy 345.800935 -254.917384) (xy 345.820226 -254.872108) (xy 345.846529 -254.830512) (xy 345.879164 -254.793675)
			(xy 345.917285 -254.76255) (xy 345.959906 -254.737943) (xy 346.005922 -254.720491) (xy 346.054141 -254.710647)
			(xy 346.103316 -254.708666) (xy 346.152171 -254.714598) (xy 346.199442 -254.72829) (xy 346.243904 -254.749388)
			(xy 346.284407 -254.777344) (xy 346.3199 -254.811436) (xy 346.349465 -254.85078) (xy 346.372336 -254.894357)
			(xy 346.38792 -254.941038) (xy 346.395815 -254.989615) (xy 346.39631 -255.014222) (xy 347.665306 -255.014222)
			(xy 347.669266 -254.965168) (xy 347.681043 -254.917384) (xy 347.700334 -254.872108) (xy 347.726637 -254.830512)
			(xy 347.759272 -254.793675) (xy 347.797393 -254.76255) (xy 347.840014 -254.737943) (xy 347.88603 -254.720491)
			(xy 347.934249 -254.710647) (xy 347.983424 -254.708666) (xy 348.032279 -254.714598) (xy 348.07955 -254.72829)
			(xy 348.124012 -254.749388) (xy 348.164515 -254.777344) (xy 348.200008 -254.811436) (xy 348.229573 -254.85078)
			(xy 348.252444 -254.894357) (xy 348.268028 -254.941038) (xy 348.275923 -254.989615) (xy 348.276418 -255.014222)
			(xy 348.60536 -255.014222) (xy 348.60932 -254.965168) (xy 348.621097 -254.917384) (xy 348.640388 -254.872108)
			(xy 348.666691 -254.830512) (xy 348.699326 -254.793675) (xy 348.737447 -254.76255) (xy 348.780068 -254.737943)
			(xy 348.826084 -254.720491) (xy 348.874303 -254.710647) (xy 348.923478 -254.708666) (xy 348.972333 -254.714598)
			(xy 349.019604 -254.72829) (xy 349.064066 -254.749388) (xy 349.104569 -254.777344) (xy 349.140062 -254.811436)
			(xy 349.169627 -254.85078) (xy 349.192498 -254.894357) (xy 349.208082 -254.941038) (xy 349.215977 -254.989615)
			(xy 349.216472 -255.014222) (xy 349.545414 -255.014222) (xy 349.549374 -254.965168) (xy 349.561151 -254.917384)
			(xy 349.580442 -254.872108) (xy 349.606745 -254.830512) (xy 349.63938 -254.793675) (xy 349.677501 -254.76255)
			(xy 349.720122 -254.737943) (xy 349.766138 -254.720491) (xy 349.814357 -254.710647) (xy 349.863532 -254.708666)
			(xy 349.912387 -254.714598) (xy 349.959658 -254.72829) (xy 350.00412 -254.749388) (xy 350.044623 -254.777344)
			(xy 350.080116 -254.811436) (xy 350.109681 -254.85078) (xy 350.132552 -254.894357) (xy 350.148136 -254.941038)
			(xy 350.156031 -254.989615) (xy 350.156526 -255.014222) (xy 350.156031 -255.038829) (xy 350.148136 -255.087406)
			(xy 350.132552 -255.134087) (xy 350.109681 -255.177664) (xy 350.080116 -255.217008) (xy 350.044623 -255.2511)
			(xy 350.00412 -255.279056) (xy 349.959658 -255.300154) (xy 349.912387 -255.313846) (xy 349.863532 -255.319778)
			(xy 349.814357 -255.317797) (xy 349.766138 -255.307953) (xy 349.720122 -255.290501) (xy 349.677501 -255.265894)
			(xy 349.63938 -255.234769) (xy 349.606745 -255.197932) (xy 349.580442 -255.156336) (xy 349.561151 -255.11106)
			(xy 349.549374 -255.063276) (xy 349.545414 -255.014222) (xy 349.216472 -255.014222) (xy 349.215977 -255.038829)
			(xy 349.208082 -255.087406) (xy 349.192498 -255.134087) (xy 349.169627 -255.177664) (xy 349.140062 -255.217008)
			(xy 349.104569 -255.2511) (xy 349.064066 -255.279056) (xy 349.019604 -255.300154) (xy 348.972333 -255.313846)
			(xy 348.923478 -255.319778) (xy 348.874303 -255.317797) (xy 348.826084 -255.307953) (xy 348.780068 -255.290501)
			(xy 348.737447 -255.265894) (xy 348.699326 -255.234769) (xy 348.666691 -255.197932) (xy 348.640388 -255.156336)
			(xy 348.621097 -255.11106) (xy 348.60932 -255.063276) (xy 348.60536 -255.014222) (xy 348.276418 -255.014222)
			(xy 348.275923 -255.038829) (xy 348.268028 -255.087406) (xy 348.252444 -255.134087) (xy 348.229573 -255.177664)
			(xy 348.200008 -255.217008) (xy 348.164515 -255.2511) (xy 348.124012 -255.279056) (xy 348.07955 -255.300154)
			(xy 348.032279 -255.313846) (xy 347.983424 -255.319778) (xy 347.934249 -255.317797) (xy 347.88603 -255.307953)
			(xy 347.840014 -255.290501) (xy 347.797393 -255.265894) (xy 347.759272 -255.234769) (xy 347.726637 -255.197932)
			(xy 347.700334 -255.156336) (xy 347.681043 -255.11106) (xy 347.669266 -255.063276) (xy 347.665306 -255.014222)
			(xy 346.39631 -255.014222) (xy 346.395815 -255.038829) (xy 346.38792 -255.087406) (xy 346.372336 -255.134087)
			(xy 346.349465 -255.177664) (xy 346.3199 -255.217008) (xy 346.284407 -255.2511) (xy 346.243904 -255.279056)
			(xy 346.199442 -255.300154) (xy 346.152171 -255.313846) (xy 346.103316 -255.319778) (xy 346.054141 -255.317797)
			(xy 346.005922 -255.307953) (xy 345.959906 -255.290501) (xy 345.917285 -255.265894) (xy 345.879164 -255.234769)
			(xy 345.846529 -255.197932) (xy 345.820226 -255.156336) (xy 345.800935 -255.11106) (xy 345.789158 -255.063276)
			(xy 345.785198 -255.014222) (xy 344.515981 -255.014222) (xy 344.515981 -255.038387) (xy 344.508363 -255.086138)
			(xy 344.493319 -255.132093) (xy 344.471225 -255.175104) (xy 344.442632 -255.214099) (xy 344.408253 -255.248103)
			(xy 344.368948 -255.276268) (xy 344.347546 -255.287526) (xy 344.334338 -255.293876) (xy 344.319352 -255.31826)
			(xy 344.319352 -255.951228) (xy 344.319782 -255.961295) (xy 344.327509 -255.979887) (xy 344.334338 -255.987296)
			(xy 344.431366 -256.084324) (xy 344.438764 -256.091168) (xy 344.457364 -256.09889) (xy 344.467434 -256.09931)
			(xy 345.255088 -256.09931) (xy 345.263646 -256.098923) (xy 345.279778 -256.093188) (xy 345.29314 -256.082481)
			(xy 345.298014 -256.075434) (xy 345.34983 -255.993392) (xy 345.3511 -255.967484) (xy 345.345512 -255.955546)
			(xy 345.336141 -255.934936) (xy 345.322908 -255.89164) (xy 345.316216 -255.846864) (xy 345.315794 -255.824228)
			(xy 345.316316 -255.798973) (xy 345.324629 -255.749151) (xy 345.34103 -255.701377) (xy 345.365071 -255.656954)
			(xy 345.396095 -255.617094) (xy 345.433257 -255.582884) (xy 345.475543 -255.555258) (xy 345.521799 -255.534968)
			(xy 345.570764 -255.522568) (xy 345.621102 -255.518397) (xy 345.67144 -255.522568) (xy 345.720405 -255.534968)
			(xy 345.766661 -255.555258) (xy 345.808947 -255.582884) (xy 345.846109 -255.617094) (xy 345.877133 -255.656954)
			(xy 345.901174 -255.701377) (xy 345.917575 -255.749151) (xy 345.925888 -255.798973) (xy 345.92641 -255.824228)
			(xy 345.925995 -255.846864) (xy 345.919297 -255.891639) (xy 345.906052 -255.934931) (xy 345.896692 -255.955546)
			(xy 345.891104 -255.967484) (xy 345.892374 -255.993392) (xy 345.94419 -256.075434) (xy 345.948998 -256.08254)
			(xy 345.962367 -256.093279) (xy 345.978542 -256.098969) (xy 345.987116 -256.09931) (xy 347.135196 -256.09931)
			(xy 347.143762 -256.098937) (xy 347.159916 -256.093222) (xy 347.173301 -256.082523) (xy 347.178122 -256.075434)
			(xy 347.229938 -255.993392) (xy 347.231208 -255.967484) (xy 347.22562 -255.955546) (xy 347.216249 -255.934936)
			(xy 347.203016 -255.89164) (xy 347.196323 -255.846865) (xy 347.195902 -255.824228) (xy 347.196424 -255.798973)
			(xy 347.204737 -255.749151) (xy 347.221138 -255.701377) (xy 347.245179 -255.656954) (xy 347.276203 -255.617094)
			(xy 347.313365 -255.582884) (xy 347.355651 -255.555258) (xy 347.401907 -255.534968) (xy 347.450872 -255.522568)
			(xy 347.50121 -255.518397) (xy 347.551548 -255.522568) (xy 347.600513 -255.534968) (xy 347.646769 -255.555258)
			(xy 347.689055 -255.582884) (xy 347.726217 -255.617094) (xy 347.757241 -255.656954) (xy 347.781282 -255.701377)
			(xy 347.797683 -255.749151) (xy 347.805996 -255.798973) (xy 347.806518 -255.824228) (xy 347.806103 -255.846864)
			(xy 347.799405 -255.891639) (xy 347.78616 -255.934931) (xy 347.7768 -255.955546) (xy 347.771212 -255.967484)
			(xy 347.772482 -255.993392) (xy 347.824298 -256.075434) (xy 347.829107 -256.082539) (xy 347.842475 -256.093276)
			(xy 347.858651 -256.098963) (xy 347.867224 -256.09931) (xy 348.074996 -256.09931) (xy 348.083562 -256.098937)
			(xy 348.099716 -256.093222) (xy 348.113101 -256.082523) (xy 348.117922 -256.075434) (xy 348.169738 -255.993392)
			(xy 348.171008 -255.967484) (xy 348.16542 -255.955546) (xy 348.156049 -255.934936) (xy 348.142816 -255.89164)
			(xy 348.136123 -255.846865) (xy 348.135702 -255.824228) (xy 348.136224 -255.798973) (xy 348.144537 -255.749151)
			(xy 348.160938 -255.701377) (xy 348.184979 -255.656954) (xy 348.216003 -255.617094) (xy 348.253165 -255.582884)
			(xy 348.295451 -255.555258) (xy 348.341707 -255.534968) (xy 348.390672 -255.522568) (xy 348.44101 -255.518397)
			(xy 348.491348 -255.522568) (xy 348.540313 -255.534968) (xy 348.586569 -255.555258) (xy 348.628855 -255.582884)
			(xy 348.666017 -255.617094) (xy 348.697041 -255.656954) (xy 348.721082 -255.701377) (xy 348.737483 -255.749151)
			(xy 348.745796 -255.798973) (xy 348.746318 -255.824228) (xy 349.07526 -255.824228) (xy 349.07922 -255.775174)
			(xy 349.090997 -255.72739) (xy 349.110288 -255.682114) (xy 349.136591 -255.640518) (xy 349.169226 -255.603681)
			(xy 349.207347 -255.572556) (xy 349.249968 -255.547949) (xy 349.295984 -255.530497) (xy 349.344203 -255.520653)
			(xy 349.393378 -255.518672) (xy 349.442233 -255.524604) (xy 349.489504 -255.538296) (xy 349.533966 -255.559394)
			(xy 349.574469 -255.58735) (xy 349.609962 -255.621442) (xy 349.639527 -255.660786) (xy 349.662398 -255.704363)
			(xy 349.677982 -255.751044) (xy 349.685877 -255.799621) (xy 349.686372 -255.824228) (xy 350.015314 -255.824228)
			(xy 350.019274 -255.775174) (xy 350.031051 -255.72739) (xy 350.050342 -255.682114) (xy 350.076645 -255.640518)
			(xy 350.10928 -255.603681) (xy 350.147401 -255.572556) (xy 350.190022 -255.547949) (xy 350.236038 -255.530497)
			(xy 350.284257 -255.520653) (xy 350.333432 -255.518672) (xy 350.382287 -255.524604) (xy 350.429558 -255.538296)
			(xy 350.47402 -255.559394) (xy 350.514523 -255.58735) (xy 350.550016 -255.621442) (xy 350.579581 -255.660786)
			(xy 350.602452 -255.704363) (xy 350.618036 -255.751044) (xy 350.625931 -255.799621) (xy 350.626385 -255.822196)
			(xy 350.952066 -255.822196) (xy 350.956026 -255.773142) (xy 350.967803 -255.725358) (xy 350.987094 -255.680082)
			(xy 351.013397 -255.638486) (xy 351.046032 -255.601649) (xy 351.084153 -255.570524) (xy 351.126774 -255.545917)
			(xy 351.17279 -255.528465) (xy 351.221009 -255.518621) (xy 351.270184 -255.51664) (xy 351.319039 -255.522572)
			(xy 351.36631 -255.536264) (xy 351.410772 -255.557362) (xy 351.451275 -255.585318) (xy 351.486768 -255.61941)
			(xy 351.516333 -255.658754) (xy 351.539204 -255.702331) (xy 351.554788 -255.749012) (xy 351.562683 -255.797589)
			(xy 351.563178 -255.822196) (xy 351.89212 -255.822196) (xy 351.89608 -255.773142) (xy 351.907857 -255.725358)
			(xy 351.927148 -255.680082) (xy 351.953451 -255.638486) (xy 351.986086 -255.601649) (xy 352.024207 -255.570524)
			(xy 352.066828 -255.545917) (xy 352.112844 -255.528465) (xy 352.161063 -255.518621) (xy 352.210238 -255.51664)
			(xy 352.259093 -255.522572) (xy 352.306364 -255.536264) (xy 352.350826 -255.557362) (xy 352.391329 -255.585318)
			(xy 352.426822 -255.61941) (xy 352.456387 -255.658754) (xy 352.479258 -255.702331) (xy 352.494842 -255.749012)
			(xy 352.502737 -255.797589) (xy 352.503232 -255.822196) (xy 352.502737 -255.846803) (xy 352.494842 -255.89538)
			(xy 352.479258 -255.942061) (xy 352.456387 -255.985638) (xy 352.426822 -256.024982) (xy 352.391329 -256.059074)
			(xy 352.350826 -256.08703) (xy 352.306364 -256.108128) (xy 352.259093 -256.12182) (xy 352.210238 -256.127752)
			(xy 352.161063 -256.125771) (xy 352.112844 -256.115927) (xy 352.066828 -256.098475) (xy 352.024207 -256.073868)
			(xy 351.986086 -256.042743) (xy 351.953451 -256.005906) (xy 351.927148 -255.96431) (xy 351.907857 -255.919034)
			(xy 351.89608 -255.87125) (xy 351.89212 -255.822196) (xy 351.563178 -255.822196) (xy 351.562683 -255.846803)
			(xy 351.554788 -255.89538) (xy 351.539204 -255.942061) (xy 351.516333 -255.985638) (xy 351.486768 -256.024982)
			(xy 351.451275 -256.059074) (xy 351.410772 -256.08703) (xy 351.36631 -256.108128) (xy 351.319039 -256.12182)
			(xy 351.270184 -256.127752) (xy 351.221009 -256.125771) (xy 351.17279 -256.115927) (xy 351.126774 -256.098475)
			(xy 351.084153 -256.073868) (xy 351.046032 -256.042743) (xy 351.013397 -256.005906) (xy 350.987094 -255.96431)
			(xy 350.967803 -255.919034) (xy 350.956026 -255.87125) (xy 350.952066 -255.822196) (xy 350.626385 -255.822196)
			(xy 350.626426 -255.824228) (xy 350.625931 -255.848835) (xy 350.618036 -255.897412) (xy 350.602452 -255.944093)
			(xy 350.579581 -255.98767) (xy 350.550016 -256.027014) (xy 350.514523 -256.061106) (xy 350.47402 -256.089062)
			(xy 350.429558 -256.11016) (xy 350.382287 -256.123852) (xy 350.333432 -256.129784) (xy 350.284257 -256.127803)
			(xy 350.236038 -256.117959) (xy 350.190022 -256.100507) (xy 350.147401 -256.0759) (xy 350.10928 -256.044775)
			(xy 350.076645 -256.007938) (xy 350.050342 -255.966342) (xy 350.031051 -255.921066) (xy 350.019274 -255.873282)
			(xy 350.015314 -255.824228) (xy 349.686372 -255.824228) (xy 349.685877 -255.848835) (xy 349.677982 -255.897412)
			(xy 349.662398 -255.944093) (xy 349.639527 -255.98767) (xy 349.609962 -256.027014) (xy 349.574469 -256.061106)
			(xy 349.533966 -256.089062) (xy 349.489504 -256.11016) (xy 349.442233 -256.123852) (xy 349.393378 -256.129784)
			(xy 349.344203 -256.127803) (xy 349.295984 -256.117959) (xy 349.249968 -256.100507) (xy 349.207347 -256.0759)
			(xy 349.169226 -256.044775) (xy 349.136591 -256.007938) (xy 349.110288 -255.966342) (xy 349.090997 -255.921066)
			(xy 349.07922 -255.873282) (xy 349.07526 -255.824228) (xy 348.746318 -255.824228) (xy 348.74618 -255.836991)
			(xy 348.744018 -255.862425) (xy 348.742 -255.875028) (xy 348.737066 -255.900882) (xy 348.719527 -255.950503)
			(xy 348.693751 -255.996388) (xy 348.6605 -256.037184) (xy 348.620756 -256.071684) (xy 348.575691 -256.09887)
			(xy 348.526638 -256.11794) (xy 348.500954 -256.123694) (xy 348.487238 -256.126488) (xy 348.466664 -256.145284)
			(xy 348.4372 -256.242058) (xy 348.434918 -256.25097) (xy 348.436128 -256.269314) (xy 348.44369 -256.286071)
			(xy 348.4499 -256.292858) (xy 348.564454 -256.407412) (xy 348.571677 -256.414063) (xy 348.589708 -256.421789)
			(xy 348.599506 -256.422398) (xy 348.678246 -256.423922) (xy 348.69628 -256.417064) (xy 348.703646 -256.410206)
			(xy 348.720686 -256.395015) (xy 348.75843 -256.36934) (xy 348.799573 -256.349565) (xy 348.8432 -256.33613)
			(xy 348.88834 -256.329335) (xy 348.911164 -256.328926) (xy 348.935158 -256.32937) (xy 348.982556 -256.336872)
			(xy 349.028196 -256.351698) (xy 349.070955 -256.373482) (xy 349.109779 -256.401687) (xy 349.143711 -256.43562)
			(xy 349.171917 -256.474443) (xy 349.193701 -256.517202) (xy 349.208528 -256.562842) (xy 349.21603 -256.61024)
			(xy 349.216472 -256.634234) (xy 349.216004 -256.658464) (xy 349.208343 -256.706316) (xy 349.201232 -256.729484)
			(xy 349.197422 -256.741168) (xy 349.201232 -256.765298) (xy 349.255334 -256.840228) (xy 349.262942 -256.849616)
			(xy 349.284418 -256.860623) (xy 349.296482 -256.86131)
		)
		(stroke
			(width 0)
			(type solid)
		)
		(fill yes)
		(layer "In6.Cu")
		(net "PVDD18_S5_P0")
	)
	(gr_poly
		(pts
			(xy 440.11469 -112.609884) (xy 440.124561 -112.609411) (xy 440.14284 -112.601947) (xy 440.15025 -112.595406)
			(xy 440.150504 -112.595152) (xy 441.67552 -111.070136) (xy 441.676028 -111.069628) (xy 441.68261 -111.062247)
			(xy 441.690057 -111.043948) (xy 441.690506 -111.034068) (xy 441.690506 -95.822008) (xy 441.690085 -95.811937)
			(xy 441.682373 -95.79333) (xy 441.67552 -95.78594) (xy 439.85942 -93.96984) (xy 439.852308 -93.962474)
			(xy 439.833512 -93.954854) (xy 437.113426 -93.954854) (xy 437.101996 -93.956124) (xy 437.090566 -93.958664)
			(xy 437.079644 -93.962728) (xy 437.07177 -93.966538) (xy 437.011826 -94.064328) (xy 437.01081 -94.09049)
			(xy 437.016906 -94.102428) (xy 437.029917 -94.129344) (xy 437.048343 -94.186214) (xy 437.057697 -94.245258)
			(xy 437.058308 -94.275148) (xy 437.057822 -94.302399) (xy 437.050066 -94.356347) (xy 437.034711 -94.408642)
			(xy 437.012069 -94.458219) (xy 436.982603 -94.504069) (xy 436.946912 -94.54526) (xy 436.905721 -94.580951)
			(xy 436.859871 -94.610417) (xy 436.810294 -94.633059) (xy 436.757999 -94.648414) (xy 436.704051 -94.65617)
			(xy 436.649549 -94.65617) (xy 436.595601 -94.648414) (xy 436.543306 -94.633059) (xy 436.493729 -94.610417)
			(xy 436.447879 -94.580951) (xy 436.406688 -94.54526) (xy 436.370997 -94.504069) (xy 436.341531 -94.458219)
			(xy 436.318889 -94.408642) (xy 436.303534 -94.356347) (xy 436.295778 -94.302399) (xy 436.295292 -94.275148)
			(xy 436.295866 -94.245254) (xy 436.305194 -94.186198) (xy 436.323643 -94.129329) (xy 436.336694 -94.102428)
			(xy 436.34279 -94.09049) (xy 436.341774 -94.064328) (xy 436.28945 -93.979238) (xy 436.285503 -93.973255)
			(xy 436.274937 -93.963578) (xy 436.268622 -93.960188) (xy 436.257954 -93.954854) (xy 431.764948 -93.954854)
			(xy 431.753868 -93.955418) (xy 431.733767 -93.964752) (xy 431.71945 -93.981669) (xy 431.715926 -93.992192)
			(xy 431.708162 -94.018738) (xy 431.686031 -94.069425) (xy 431.656813 -94.116385) (xy 431.621122 -94.158635)
			(xy 431.579704 -94.195289) (xy 431.533428 -94.225579) (xy 431.483264 -94.24887) (xy 431.430262 -94.264674)
			(xy 431.375534 -94.272659) (xy 431.320226 -94.272659) (xy 431.265498 -94.264674) (xy 431.212496 -94.24887)
			(xy 431.162332 -94.225579) (xy 431.116056 -94.195289) (xy 431.074638 -94.158635) (xy 431.038947 -94.116385)
			(xy 431.009729 -94.069425) (xy 430.987598 -94.018738) (xy 430.979834 -93.992192) (xy 430.976365 -93.981644)
			(xy 430.962034 -93.964714) (xy 430.941903 -93.955402) (xy 430.930812 -93.954854) (xy 416.886644 -93.954854)
			(xy 416.87658 -93.955289) (xy 416.857995 -93.963024) (xy 416.850576 -93.96984) (xy 415.364422 -95.455994)
			(xy 415.357729 -95.463438) (xy 415.35013 -95.481936) (xy 415.350144 -95.501934) (xy 415.3535 -95.511366)
			(xy 415.359342 -95.52559) (xy 415.384742 -95.542608) (xy 423.120312 -95.542608) (xy 423.144903 -95.543066)
			(xy 423.193477 -95.550765) (xy 423.240249 -95.56597) (xy 423.284065 -95.588307) (xy 423.323845 -95.617226)
			(xy 423.341546 -95.634302) (xy 423.665142 -95.957898) (xy 438.606182 -95.957898) (xy 438.610253 -95.902276)
			(xy 438.622379 -95.847839) (xy 438.642302 -95.795748) (xy 438.669598 -95.747113) (xy 438.703684 -95.70297)
			(xy 438.743833 -95.664261) (xy 438.789191 -95.63181) (xy 438.838791 -95.606309) (xy 438.891575 -95.588302)
			(xy 438.946418 -95.578172) (xy 439.002152 -95.576135) (xy 439.057589 -95.582235) (xy 439.111546 -95.596341)
			(xy 439.162875 -95.618153) (xy 439.210481 -95.647207) (xy 439.253349 -95.682882) (xy 439.290566 -95.724419)
			(xy 439.321339 -95.770932) (xy 439.345011 -95.821429) (xy 439.361079 -95.874836) (xy 439.369199 -95.930012)
			(xy 439.369708 -95.957898) (xy 439.369199 -95.985784) (xy 439.361079 -96.04096) (xy 439.345011 -96.094367)
			(xy 439.321339 -96.144864) (xy 439.290566 -96.191377) (xy 439.253349 -96.232914) (xy 439.210481 -96.268589)
			(xy 439.162875 -96.297643) (xy 439.111546 -96.319455) (xy 439.057589 -96.333561) (xy 439.002152 -96.339661)
			(xy 438.946418 -96.337624) (xy 438.891575 -96.327494) (xy 438.838791 -96.309487) (xy 438.789191 -96.283986)
			(xy 438.743833 -96.251535) (xy 438.703684 -96.212826) (xy 438.669598 -96.168683) (xy 438.642302 -96.120048)
			(xy 438.622379 -96.067957) (xy 438.610253 -96.01352) (xy 438.606182 -95.957898) (xy 423.665142 -95.957898)
			(xy 424.519852 -96.812608) (xy 434.902862 -96.812608) (xy 434.906933 -96.756986) (xy 434.919059 -96.702549)
			(xy 434.938982 -96.650458) (xy 434.966278 -96.601823) (xy 435.000364 -96.55768) (xy 435.040513 -96.518971)
			(xy 435.085871 -96.48652) (xy 435.135471 -96.461019) (xy 435.188255 -96.443012) (xy 435.243098 -96.432882)
			(xy 435.298832 -96.430845) (xy 435.354269 -96.436945) (xy 435.408226 -96.451051) (xy 435.459555 -96.472863)
			(xy 435.507161 -96.501917) (xy 435.550029 -96.537592) (xy 435.587246 -96.579129) (xy 435.618019 -96.625642)
			(xy 435.641691 -96.676139) (xy 435.657759 -96.729546) (xy 435.665879 -96.784722) (xy 435.666388 -96.812608)
			(xy 435.791862 -96.812608) (xy 435.795933 -96.756986) (xy 435.808059 -96.702549) (xy 435.827982 -96.650458)
			(xy 435.855278 -96.601823) (xy 435.889364 -96.55768) (xy 435.929513 -96.518971) (xy 435.974871 -96.48652)
			(xy 436.024471 -96.461019) (xy 436.077255 -96.443012) (xy 436.132098 -96.432882) (xy 436.187832 -96.430845)
			(xy 436.243269 -96.436945) (xy 436.297226 -96.451051) (xy 436.348555 -96.472863) (xy 436.396161 -96.501917)
			(xy 436.439029 -96.537592) (xy 436.476246 -96.579129) (xy 436.507019 -96.625642) (xy 436.530691 -96.676139)
			(xy 436.546759 -96.729546) (xy 436.554879 -96.784722) (xy 436.555388 -96.812608) (xy 436.554879 -96.840494)
			(xy 436.546759 -96.89567) (xy 436.530691 -96.949077) (xy 436.507019 -96.999574) (xy 436.476246 -97.046087)
			(xy 436.439029 -97.087624) (xy 436.396161 -97.123299) (xy 436.348555 -97.152353) (xy 436.297226 -97.174165)
			(xy 436.243269 -97.188271) (xy 436.187832 -97.194371) (xy 436.132098 -97.192334) (xy 436.077255 -97.182204)
			(xy 436.024471 -97.164197) (xy 435.974871 -97.138696) (xy 435.929513 -97.106245) (xy 435.889364 -97.067536)
			(xy 435.855278 -97.023393) (xy 435.827982 -96.974758) (xy 435.808059 -96.922667) (xy 435.795933 -96.86823)
			(xy 435.791862 -96.812608) (xy 435.666388 -96.812608) (xy 435.665879 -96.840494) (xy 435.657759 -96.89567)
			(xy 435.641691 -96.949077) (xy 435.618019 -96.999574) (xy 435.587246 -97.046087) (xy 435.550029 -97.087624)
			(xy 435.507161 -97.123299) (xy 435.459555 -97.152353) (xy 435.408226 -97.174165) (xy 435.354269 -97.188271)
			(xy 435.298832 -97.194371) (xy 435.243098 -97.192334) (xy 435.188255 -97.182204) (xy 435.135471 -97.164197)
			(xy 435.085871 -97.138696) (xy 435.040513 -97.106245) (xy 435.000364 -97.067536) (xy 434.966278 -97.023393)
			(xy 434.938982 -96.974758) (xy 434.919059 -96.922667) (xy 434.906933 -96.86823) (xy 434.902862 -96.812608)
			(xy 424.519852 -96.812608) (xy 425.408852 -97.701608) (xy 434.902862 -97.701608) (xy 434.906933 -97.645986)
			(xy 434.919059 -97.591549) (xy 434.938982 -97.539458) (xy 434.966278 -97.490823) (xy 435.000364 -97.44668)
			(xy 435.040513 -97.407971) (xy 435.085871 -97.37552) (xy 435.135471 -97.350019) (xy 435.188255 -97.332012)
			(xy 435.243098 -97.321882) (xy 435.298832 -97.319845) (xy 435.354269 -97.325945) (xy 435.408226 -97.340051)
			(xy 435.459555 -97.361863) (xy 435.507161 -97.390917) (xy 435.550029 -97.426592) (xy 435.587246 -97.468129)
			(xy 435.618019 -97.514642) (xy 435.641691 -97.565139) (xy 435.657759 -97.618546) (xy 435.665879 -97.673722)
			(xy 435.666388 -97.701608) (xy 435.791862 -97.701608) (xy 435.795933 -97.645986) (xy 435.808059 -97.591549)
			(xy 435.827982 -97.539458) (xy 435.855278 -97.490823) (xy 435.889364 -97.44668) (xy 435.929513 -97.407971)
			(xy 435.974871 -97.37552) (xy 436.024471 -97.350019) (xy 436.077255 -97.332012) (xy 436.132098 -97.321882)
			(xy 436.187832 -97.319845) (xy 436.243269 -97.325945) (xy 436.297226 -97.340051) (xy 436.348555 -97.361863)
			(xy 436.396161 -97.390917) (xy 436.439029 -97.426592) (xy 436.476246 -97.468129) (xy 436.507019 -97.514642)
			(xy 436.530691 -97.565139) (xy 436.546759 -97.618546) (xy 436.554879 -97.673722) (xy 436.555388 -97.701608)
			(xy 436.554879 -97.729494) (xy 436.546759 -97.78467) (xy 436.530691 -97.838077) (xy 436.507019 -97.888574)
			(xy 436.476246 -97.935087) (xy 436.439029 -97.976624) (xy 436.396161 -98.012299) (xy 436.348555 -98.041353)
			(xy 436.297226 -98.063165) (xy 436.243269 -98.077271) (xy 436.187832 -98.083371) (xy 436.132098 -98.081334)
			(xy 436.077255 -98.071204) (xy 436.024471 -98.053197) (xy 435.974871 -98.027696) (xy 435.929513 -97.995245)
			(xy 435.889364 -97.956536) (xy 435.855278 -97.912393) (xy 435.827982 -97.863758) (xy 435.808059 -97.811667)
			(xy 435.795933 -97.75723) (xy 435.791862 -97.701608) (xy 435.666388 -97.701608) (xy 435.665879 -97.729494)
			(xy 435.657759 -97.78467) (xy 435.641691 -97.838077) (xy 435.618019 -97.888574) (xy 435.587246 -97.935087)
			(xy 435.550029 -97.976624) (xy 435.507161 -98.012299) (xy 435.459555 -98.041353) (xy 435.408226 -98.063165)
			(xy 435.354269 -98.077271) (xy 435.298832 -98.083371) (xy 435.243098 -98.081334) (xy 435.188255 -98.071204)
			(xy 435.135471 -98.053197) (xy 435.085871 -98.027696) (xy 435.040513 -97.995245) (xy 435.000364 -97.956536)
			(xy 434.966278 -97.912393) (xy 434.938982 -97.863758) (xy 434.919059 -97.811667) (xy 434.906933 -97.75723)
			(xy 434.902862 -97.701608) (xy 425.408852 -97.701608) (xy 426.297852 -98.590608) (xy 434.902862 -98.590608)
			(xy 434.906933 -98.534986) (xy 434.919059 -98.480549) (xy 434.938982 -98.428458) (xy 434.966278 -98.379823)
			(xy 435.000364 -98.33568) (xy 435.040513 -98.296971) (xy 435.085871 -98.26452) (xy 435.135471 -98.239019)
			(xy 435.188255 -98.221012) (xy 435.243098 -98.210882) (xy 435.298832 -98.208845) (xy 435.354269 -98.214945)
			(xy 435.408226 -98.229051) (xy 435.459555 -98.250863) (xy 435.507161 -98.279917) (xy 435.550029 -98.315592)
			(xy 435.587246 -98.357129) (xy 435.618019 -98.403642) (xy 435.641691 -98.454139) (xy 435.657759 -98.507546)
			(xy 435.665879 -98.562722) (xy 435.666388 -98.590608) (xy 435.791862 -98.590608) (xy 435.795933 -98.534986)
			(xy 435.808059 -98.480549) (xy 435.827982 -98.428458) (xy 435.855278 -98.379823) (xy 435.889364 -98.33568)
			(xy 435.929513 -98.296971) (xy 435.974871 -98.26452) (xy 436.024471 -98.239019) (xy 436.077255 -98.221012)
			(xy 436.132098 -98.210882) (xy 436.187832 -98.208845) (xy 436.243269 -98.214945) (xy 436.297226 -98.229051)
			(xy 436.348555 -98.250863) (xy 436.396161 -98.279917) (xy 436.439029 -98.315592) (xy 436.476246 -98.357129)
			(xy 436.507019 -98.403642) (xy 436.530691 -98.454139) (xy 436.546759 -98.507546) (xy 436.554879 -98.562722)
			(xy 436.555388 -98.590608) (xy 436.554879 -98.618494) (xy 436.546759 -98.67367) (xy 436.530691 -98.727077)
			(xy 436.507019 -98.777574) (xy 436.476246 -98.824087) (xy 436.439029 -98.865624) (xy 436.396161 -98.901299)
			(xy 436.348555 -98.930353) (xy 436.297226 -98.952165) (xy 436.243269 -98.966271) (xy 436.187832 -98.972371)
			(xy 436.132098 -98.970334) (xy 436.077255 -98.960204) (xy 436.024471 -98.942197) (xy 435.974871 -98.916696)
			(xy 435.929513 -98.884245) (xy 435.889364 -98.845536) (xy 435.855278 -98.801393) (xy 435.827982 -98.752758)
			(xy 435.808059 -98.700667) (xy 435.795933 -98.64623) (xy 435.791862 -98.590608) (xy 435.666388 -98.590608)
			(xy 435.665879 -98.618494) (xy 435.657759 -98.67367) (xy 435.641691 -98.727077) (xy 435.618019 -98.777574)
			(xy 435.587246 -98.824087) (xy 435.550029 -98.865624) (xy 435.507161 -98.901299) (xy 435.459555 -98.930353)
			(xy 435.408226 -98.952165) (xy 435.354269 -98.966271) (xy 435.298832 -98.972371) (xy 435.243098 -98.970334)
			(xy 435.188255 -98.960204) (xy 435.135471 -98.942197) (xy 435.085871 -98.916696) (xy 435.040513 -98.884245)
			(xy 435.000364 -98.845536) (xy 434.966278 -98.801393) (xy 434.938982 -98.752758) (xy 434.919059 -98.700667)
			(xy 434.906933 -98.64623) (xy 434.902862 -98.590608) (xy 426.297852 -98.590608) (xy 427.186852 -99.479608)
			(xy 434.902862 -99.479608) (xy 434.906933 -99.423986) (xy 434.919059 -99.369549) (xy 434.938982 -99.317458)
			(xy 434.966278 -99.268823) (xy 435.000364 -99.22468) (xy 435.040513 -99.185971) (xy 435.085871 -99.15352)
			(xy 435.135471 -99.128019) (xy 435.188255 -99.110012) (xy 435.243098 -99.099882) (xy 435.298832 -99.097845)
			(xy 435.354269 -99.103945) (xy 435.408226 -99.118051) (xy 435.459555 -99.139863) (xy 435.507161 -99.168917)
			(xy 435.550029 -99.204592) (xy 435.587246 -99.246129) (xy 435.618019 -99.292642) (xy 435.641691 -99.343139)
			(xy 435.657759 -99.396546) (xy 435.665879 -99.451722) (xy 435.666388 -99.479608) (xy 435.791862 -99.479608)
			(xy 435.795933 -99.423986) (xy 435.808059 -99.369549) (xy 435.827982 -99.317458) (xy 435.855278 -99.268823)
			(xy 435.889364 -99.22468) (xy 435.929513 -99.185971) (xy 435.974871 -99.15352) (xy 436.024471 -99.128019)
			(xy 436.077255 -99.110012) (xy 436.132098 -99.099882) (xy 436.187832 -99.097845) (xy 436.243269 -99.103945)
			(xy 436.297226 -99.118051) (xy 436.348555 -99.139863) (xy 436.396161 -99.168917) (xy 436.439029 -99.204592)
			(xy 436.476246 -99.246129) (xy 436.507019 -99.292642) (xy 436.530691 -99.343139) (xy 436.546759 -99.396546)
			(xy 436.554879 -99.451722) (xy 436.555388 -99.479608) (xy 436.554879 -99.507494) (xy 436.546759 -99.56267)
			(xy 436.530691 -99.616077) (xy 436.507019 -99.666574) (xy 436.476246 -99.713087) (xy 436.439029 -99.754624)
			(xy 436.396161 -99.790299) (xy 436.348555 -99.819353) (xy 436.297226 -99.841165) (xy 436.243269 -99.855271)
			(xy 436.187832 -99.861371) (xy 436.132098 -99.859334) (xy 436.077255 -99.849204) (xy 436.024471 -99.831197)
			(xy 435.974871 -99.805696) (xy 435.929513 -99.773245) (xy 435.889364 -99.734536) (xy 435.855278 -99.690393)
			(xy 435.827982 -99.641758) (xy 435.808059 -99.589667) (xy 435.795933 -99.53523) (xy 435.791862 -99.479608)
			(xy 435.666388 -99.479608) (xy 435.665879 -99.507494) (xy 435.657759 -99.56267) (xy 435.641691 -99.616077)
			(xy 435.618019 -99.666574) (xy 435.587246 -99.713087) (xy 435.550029 -99.754624) (xy 435.507161 -99.790299)
			(xy 435.459555 -99.819353) (xy 435.408226 -99.841165) (xy 435.354269 -99.855271) (xy 435.298832 -99.861371)
			(xy 435.243098 -99.859334) (xy 435.188255 -99.849204) (xy 435.135471 -99.831197) (xy 435.085871 -99.805696)
			(xy 435.040513 -99.773245) (xy 435.000364 -99.734536) (xy 434.966278 -99.690393) (xy 434.938982 -99.641758)
			(xy 434.919059 -99.589667) (xy 434.906933 -99.53523) (xy 434.902862 -99.479608) (xy 427.186852 -99.479608)
			(xy 429.93818 -102.230936) (xy 429.950626 -102.237794) (xy 429.957992 -102.239318) (xy 429.985184 -102.245724)
			(xy 430.037461 -102.265421) (xy 430.086303 -102.292538) (xy 430.130664 -102.326494) (xy 430.169593 -102.366561)
			(xy 430.186338 -102.388924) (xy 430.189894 -102.39375) (xy 430.19853 -102.40137) (xy 430.223676 -102.414578)
			(xy 430.229245 -102.41738) (xy 430.241321 -102.420464) (xy 430.247552 -102.420674) (xy 430.30648 -102.420674)
			(xy 430.31271 -102.420459) (xy 430.324782 -102.417369) (xy 430.330356 -102.414578) (xy 430.355502 -102.40137)
			(xy 430.364138 -102.39375) (xy 430.367694 -102.388924) (xy 430.383125 -102.368266) (xy 430.418654 -102.330897)
			(xy 430.458893 -102.298656) (xy 430.50311 -102.272129) (xy 430.550497 -102.251802) (xy 430.60019 -102.238044)
			(xy 430.651284 -102.231106) (xy 430.677066 -102.230682) (xy 430.704321 -102.231143) (xy 430.758276 -102.238896)
			(xy 430.810578 -102.254249) (xy 430.860164 -102.276889) (xy 430.906022 -102.306356) (xy 430.947219 -102.342049)
			(xy 430.982918 -102.383243) (xy 431.01239 -102.429098) (xy 431.035036 -102.47868) (xy 431.050395 -102.530981)
			(xy 431.058154 -102.584935) (xy 431.058574 -102.61219) (xy 431.058155 -102.636996) (xy 431.057832 -102.639451)
			(xy 431.370468 -102.639451) (xy 431.370468 -102.584949) (xy 431.378224 -102.531001) (xy 431.393579 -102.478706)
			(xy 431.41622 -102.429128) (xy 431.445685 -102.383277) (xy 431.481376 -102.342086) (xy 431.522566 -102.306394)
			(xy 431.568416 -102.276926) (xy 431.617993 -102.254284) (xy 431.670287 -102.238927) (xy 431.724235 -102.231169)
			(xy 431.751486 -102.230682) (xy 431.780451 -102.231233) (xy 431.837715 -102.240002) (xy 431.892995 -102.257325)
			(xy 431.945022 -102.282805) (xy 431.9926 -102.315856) (xy 432.034635 -102.355719) (xy 432.070163 -102.401477)
			(xy 432.084734 -102.426516) (xy 432.092088 -102.438728) (xy 432.112316 -102.458797) (xy 432.137304 -102.472494)
			(xy 432.165104 -102.47875) (xy 432.19355 -102.47708) (xy 432.220426 -102.467612) (xy 432.243639 -102.451085)
			(xy 432.252882 -102.440232) (xy 432.271098 -102.418176) (xy 432.313 -102.379236) (xy 432.360242 -102.346983)
			(xy 432.411768 -102.322139) (xy 432.466423 -102.30526) (xy 432.522985 -102.296724) (xy 432.551586 -102.296214)
			(xy 432.578841 -102.296632) (xy 432.632797 -102.304388) (xy 432.685099 -102.319743) (xy 432.734684 -102.342386)
			(xy 432.780542 -102.371856) (xy 432.821738 -102.407552) (xy 432.857436 -102.448747) (xy 432.886907 -102.494604)
			(xy 432.909552 -102.544188) (xy 432.924909 -102.59649) (xy 432.932667 -102.650445) (xy 432.932667 -102.704955)
			(xy 432.924909 -102.75891) (xy 432.909552 -102.811212) (xy 432.886907 -102.860796) (xy 432.857436 -102.906653)
			(xy 432.821738 -102.947848) (xy 432.780542 -102.983544) (xy 432.734684 -103.013014) (xy 432.685099 -103.035657)
			(xy 432.632797 -103.051012) (xy 432.578841 -103.058768) (xy 432.551586 -103.05923) (xy 432.522618 -103.058746)
			(xy 432.465349 -103.049971) (xy 432.410065 -103.032639) (xy 432.358036 -103.007149) (xy 432.310459 -102.974086)
			(xy 432.268427 -102.934212) (xy 432.232905 -102.888441) (xy 432.218338 -102.863396) (xy 432.211021 -102.851159)
			(xy 432.190786 -102.831086) (xy 432.16579 -102.817388) (xy 432.137982 -102.811133) (xy 432.109529 -102.812809)
			(xy 432.082648 -102.822285) (xy 432.059433 -102.838822) (xy 432.05019 -102.84968) (xy 432.031993 -102.871752)
			(xy 431.990086 -102.91069) (xy 431.94284 -102.942941) (xy 431.891311 -102.967782) (xy 431.836652 -102.984658)
			(xy 431.780088 -102.99319) (xy 431.751486 -102.993698) (xy 431.724235 -102.993231) (xy 431.670287 -102.985473)
			(xy 431.617993 -102.970116) (xy 431.568416 -102.947474) (xy 431.522566 -102.918006) (xy 431.481376 -102.882314)
			(xy 431.445685 -102.841123) (xy 431.41622 -102.795272) (xy 431.393579 -102.745694) (xy 431.378224 -102.693399)
			(xy 431.370468 -102.639451) (xy 431.057832 -102.639451) (xy 431.051693 -102.686185) (xy 431.038929 -102.734127)
			(xy 431.029872 -102.757224) (xy 431.0253 -102.768654) (xy 431.027078 -102.79253) (xy 431.081942 -102.883208)
			(xy 431.102262 -102.895908) (xy 431.114454 -102.897178) (xy 431.142486 -102.900285) (xy 431.197264 -102.913706)
			(xy 431.249467 -102.935052) (xy 431.297955 -102.963857) (xy 431.341668 -102.999493) (xy 431.379653 -103.041182)
			(xy 431.411079 -103.088013) (xy 431.435262 -103.138963) (xy 431.451673 -103.192921) (xy 431.459953 -103.248709)
			(xy 431.460402 -103.276908) (xy 431.459916 -103.304159) (xy 431.45216 -103.358107) (xy 431.436805 -103.410402)
			(xy 431.414163 -103.459979) (xy 431.384697 -103.505829) (xy 431.349006 -103.54702) (xy 431.307815 -103.582711)
			(xy 431.261965 -103.612177) (xy 431.212388 -103.634819) (xy 431.160093 -103.650174) (xy 431.106145 -103.65793)
			(xy 431.051643 -103.65793) (xy 430.997695 -103.650174) (xy 430.9454 -103.634819) (xy 430.895823 -103.612177)
			(xy 430.849973 -103.582711) (xy 430.808782 -103.54702) (xy 430.773091 -103.505829) (xy 430.743625 -103.459979)
			(xy 430.720983 -103.410402) (xy 430.705628 -103.358107) (xy 430.697872 -103.304159) (xy 430.697386 -103.276908)
			(xy 430.697805 -103.252102) (xy 430.704268 -103.202913) (xy 430.717035 -103.154972) (xy 430.726088 -103.131874)
			(xy 430.73066 -103.120444) (xy 430.728882 -103.096568) (xy 430.674018 -103.00589) (xy 430.653698 -102.99319)
			(xy 430.641506 -102.99192) (xy 430.614559 -102.988941) (xy 430.561832 -102.976333) (xy 430.511424 -102.95638)
			(xy 430.464354 -102.929483) (xy 430.42157 -102.896186) (xy 430.383938 -102.857162) (xy 430.367694 -102.835456)
			(xy 430.364138 -102.83063) (xy 430.355756 -102.823264) (xy 430.330356 -102.809802) (xy 430.324787 -102.806997)
			(xy 430.312711 -102.803908) (xy 430.30648 -102.803706) (xy 430.247552 -102.803706) (xy 430.241321 -102.803917)
			(xy 430.229245 -102.806999) (xy 430.223676 -102.809802) (xy 430.19853 -102.82301) (xy 430.189894 -102.83063)
			(xy 430.186338 -102.835456) (xy 430.170905 -102.856112) (xy 430.135374 -102.893476) (xy 430.095133 -102.925714)
			(xy 430.050917 -102.952239) (xy 430.003531 -102.972565) (xy 429.953839 -102.986324) (xy 429.902747 -102.993265)
			(xy 429.876966 -102.993698) (xy 429.848191 -102.993172) (xy 429.791293 -102.984527) (xy 429.736339 -102.967439)
			(xy 429.684572 -102.942293) (xy 429.637167 -102.909662) (xy 429.595198 -102.870283) (xy 429.559617 -102.82505)
			(xy 429.531229 -102.774988) (xy 429.510679 -102.721232) (xy 429.504094 -102.693216) (xy 429.50257 -102.68585)
			(xy 429.495712 -102.673404) (xy 423.005758 -96.18345) (xy 422.99836 -96.176605) (xy 422.979761 -96.168878)
			(xy 422.96969 -96.168464) (xy 414.673034 -96.168464) (xy 414.663071 -96.168949) (xy 414.644643 -96.176533)
			(xy 414.63722 -96.183196) (xy 413.965644 -96.854772) (xy 413.958278 -96.861884) (xy 413.950658 -96.88068)
			(xy 413.950658 -99.80295) (xy 414.05886 -99.80295) (xy 414.062931 -99.747328) (xy 414.075057 -99.692891)
			(xy 414.09498 -99.6408) (xy 414.122276 -99.592165) (xy 414.156362 -99.548022) (xy 414.196511 -99.509313)
			(xy 414.241869 -99.476862) (xy 414.291469 -99.451361) (xy 414.344253 -99.433354) (xy 414.399096 -99.423224)
			(xy 414.45483 -99.421187) (xy 414.510267 -99.427287) (xy 414.564224 -99.441393) (xy 414.615553 -99.463205)
			(xy 414.663159 -99.492259) (xy 414.706027 -99.527934) (xy 414.743244 -99.569471) (xy 414.774017 -99.615984)
			(xy 414.797689 -99.666481) (xy 414.813757 -99.719888) (xy 414.821877 -99.775064) (xy 414.822386 -99.80295)
			(xy 414.821877 -99.830836) (xy 414.813757 -99.886012) (xy 414.797689 -99.939419) (xy 414.774017 -99.989916)
			(xy 414.743244 -100.036429) (xy 414.706027 -100.077966) (xy 414.663159 -100.113641) (xy 414.615553 -100.142695)
			(xy 414.564224 -100.164507) (xy 414.510267 -100.178613) (xy 414.45483 -100.184713) (xy 414.399096 -100.182676)
			(xy 414.344253 -100.172546) (xy 414.291469 -100.154539) (xy 414.241869 -100.129038) (xy 414.196511 -100.096587)
			(xy 414.156362 -100.057878) (xy 414.122276 -100.013735) (xy 414.09498 -99.9651) (xy 414.075057 -99.913009)
			(xy 414.062931 -99.858572) (xy 414.05886 -99.80295) (xy 413.950658 -99.80295) (xy 413.950658 -103.624126)
			(xy 413.951087 -103.634193) (xy 413.958815 -103.652785) (xy 413.965644 -103.660194) (xy 414.806638 -104.501188)
			(xy 418.035232 -104.501188) (xy 418.035683 -104.473817) (xy 418.043503 -104.419637) (xy 418.058996 -104.367134)
			(xy 418.081841 -104.317387) (xy 418.111569 -104.271421) (xy 418.129212 -104.25049) (xy 418.135308 -104.243378)
			(xy 418.141658 -104.22636) (xy 418.141658 -104.141016) (xy 418.135308 -104.123998) (xy 418.129212 -104.116886)
			(xy 418.111602 -104.095931) (xy 418.081885 -104.049965) (xy 418.059043 -104.000223) (xy 418.043546 -103.947727)
			(xy 418.03571 -103.893556) (xy 418.035232 -103.866188) (xy 418.035644 -103.838933) (xy 418.043403 -103.784978)
			(xy 418.058763 -103.732677) (xy 418.08141 -103.683094) (xy 418.110883 -103.637239) (xy 418.146582 -103.596045)
			(xy 418.187781 -103.560352) (xy 418.23364 -103.530885) (xy 418.283226 -103.508245) (xy 418.335529 -103.492892)
			(xy 418.389485 -103.48514) (xy 418.41674 -103.48468) (xy 418.442319 -103.485084) (xy 418.493018 -103.491932)
			(xy 418.542348 -103.505486) (xy 418.589428 -103.525504) (xy 418.633414 -103.551628) (xy 418.673519 -103.583389)
			(xy 418.691568 -103.60152) (xy 418.69868 -103.608886) (xy 418.717222 -103.617014) (xy 418.810186 -103.61803)
			(xy 418.828982 -103.61041) (xy 418.836348 -103.603044) (xy 418.857913 -103.582417) (xy 418.906289 -103.547481)
			(xy 418.959517 -103.520507) (xy 419.016298 -103.502155) (xy 419.075244 -103.492872) (xy 419.10508 -103.4923)
			(xy 419.132333 -103.492774) (xy 419.186284 -103.500528) (xy 419.238582 -103.515882) (xy 419.288162 -103.538523)
			(xy 419.334016 -103.56799) (xy 419.375209 -103.603682) (xy 419.410903 -103.644874) (xy 419.440371 -103.690727)
			(xy 419.463013 -103.740307) (xy 419.478369 -103.792605) (xy 419.486125 -103.846555) (xy 419.486588 -103.873808)
			(xy 419.48613 -103.901179) (xy 419.47831 -103.955358) (xy 419.46282 -104.007861) (xy 419.439976 -104.057608)
			(xy 419.41025 -104.103575) (xy 419.392608 -104.124506) (xy 419.386512 -104.131618) (xy 419.380162 -104.148636)
			(xy 419.380162 -104.23398) (xy 419.386512 -104.250998) (xy 419.392608 -104.25811) (xy 419.410266 -104.279026)
			(xy 419.439975 -104.325004) (xy 419.462807 -104.374755) (xy 419.478294 -104.427259) (xy 419.486117 -104.481438)
			(xy 419.486588 -104.508808) (xy 419.486152 -104.536062) (xy 419.478393 -104.590015) (xy 419.463035 -104.642314)
			(xy 419.440391 -104.691896) (xy 419.41092 -104.73775) (xy 419.375223 -104.778943) (xy 419.334028 -104.814637)
			(xy 419.288171 -104.844104) (xy 419.238588 -104.866745) (xy 419.186287 -104.882099) (xy 419.132334 -104.889854)
			(xy 419.10508 -104.890316) (xy 419.079501 -104.8899) (xy 419.028803 -104.883055) (xy 418.979473 -104.869503)
			(xy 418.932393 -104.849487) (xy 418.888407 -104.823365) (xy 418.848301 -104.791606) (xy 418.830252 -104.773476)
			(xy 418.82314 -104.76611) (xy 418.804598 -104.757982) (xy 418.711634 -104.756966) (xy 418.692838 -104.764586)
			(xy 418.685472 -104.771952) (xy 418.663898 -104.792569) (xy 418.615524 -104.827506) (xy 418.562298 -104.854482)
			(xy 418.50552 -104.872837) (xy 418.446576 -104.882123) (xy 418.41674 -104.882696) (xy 418.389488 -104.882207)
			(xy 418.335537 -104.874456) (xy 418.283239 -104.859104) (xy 418.233658 -104.836465) (xy 418.187804 -104.807)
			(xy 418.146611 -104.771309) (xy 418.110916 -104.730118) (xy 418.081448 -104.684267) (xy 418.058806 -104.634687)
			(xy 418.04345 -104.58239) (xy 418.035695 -104.52844) (xy 418.035232 -104.501188) (xy 414.806638 -104.501188)
			(xy 416.132772 -105.827322) (xy 429.906682 -105.827322) (xy 429.910753 -105.7717) (xy 429.922879 -105.717263)
			(xy 429.942802 -105.665172) (xy 429.970098 -105.616537) (xy 430.004184 -105.572394) (xy 430.044333 -105.533685)
			(xy 430.089691 -105.501234) (xy 430.139291 -105.475733) (xy 430.192075 -105.457726) (xy 430.246918 -105.447596)
			(xy 430.302652 -105.445559) (xy 430.358089 -105.451659) (xy 430.412046 -105.465765) (xy 430.463375 -105.487577)
			(xy 430.510981 -105.516631) (xy 430.553849 -105.552306) (xy 430.591066 -105.593843) (xy 430.614291 -105.628948)
			(xy 433.069492 -105.628948) (xy 433.069988 -105.601579) (xy 433.077799 -105.547401) (xy 433.093281 -105.494898)
			(xy 433.116116 -105.445151) (xy 433.145834 -105.399183) (xy 433.163472 -105.37825) (xy 433.169568 -105.371138)
			(xy 433.175918 -105.35412) (xy 433.175918 -105.268776) (xy 433.169568 -105.251758) (xy 433.163472 -105.244646)
			(xy 433.145837 -105.223711) (xy 433.116125 -105.177739) (xy 433.093289 -105.127992) (xy 433.077797 -105.075492)
			(xy 433.069967 -105.021317) (xy 433.069492 -104.993948) (xy 433.069991 -104.965775) (xy 433.078298 -104.910045)
			(xy 433.094709 -104.856142) (xy 433.118868 -104.805238) (xy 433.150249 -104.75844) (xy 433.188171 -104.716765)
			(xy 433.231808 -104.681118) (xy 433.280212 -104.652276) (xy 433.332331 -104.630864) (xy 433.35956 -104.623616)
			(xy 433.370482 -104.620822) (xy 433.388008 -104.606598) (xy 433.432204 -104.516174) (xy 433.432458 -104.493822)
			(xy 433.427886 -104.483408) (xy 433.417375 -104.458766) (xy 433.402561 -104.407283) (xy 433.395071 -104.354238)
			(xy 433.394612 -104.327452) (xy 433.395098 -104.300201) (xy 433.402854 -104.246253) (xy 433.418209 -104.193958)
			(xy 433.440851 -104.144381) (xy 433.470317 -104.098531) (xy 433.506008 -104.05734) (xy 433.547199 -104.021649)
			(xy 433.593049 -103.992183) (xy 433.642626 -103.969541) (xy 433.694921 -103.954186) (xy 433.748869 -103.94643)
			(xy 433.803371 -103.94643) (xy 433.857319 -103.954186) (xy 433.909614 -103.969541) (xy 433.959191 -103.992183)
			(xy 434.005041 -104.021649) (xy 434.046232 -104.05734) (xy 434.081923 -104.098531) (xy 434.111389 -104.144381)
			(xy 434.134031 -104.193958) (xy 434.149386 -104.246253) (xy 434.157142 -104.300201) (xy 434.157628 -104.327452)
			(xy 434.157175 -104.354753) (xy 434.149421 -104.4088) (xy 434.134021 -104.461184) (xy 434.123084 -104.486202)
			(xy 434.118258 -104.496362) (xy 434.118512 -104.51846) (xy 434.160422 -104.609138) (xy 434.17744 -104.623362)
			(xy 434.188108 -104.62641) (xy 434.214542 -104.634228) (xy 434.264983 -104.656465) (xy 434.311697 -104.685732)
			(xy 434.353711 -104.721419) (xy 434.390149 -104.762783) (xy 434.420254 -104.808961) (xy 434.443397 -104.858992)
			(xy 434.459097 -104.911834) (xy 434.467026 -104.966386) (xy 434.467508 -104.993948) (xy 434.467009 -105.021317)
			(xy 434.459199 -105.075495) (xy 434.443718 -105.127997) (xy 434.420883 -105.177745) (xy 434.391166 -105.223713)
			(xy 434.373528 -105.244646) (xy 434.367432 -105.251758) (xy 434.361082 -105.268776) (xy 434.361082 -105.35412)
			(xy 434.367432 -105.371138) (xy 434.373528 -105.37825) (xy 434.391161 -105.399187) (xy 434.420873 -105.445159)
			(xy 434.44371 -105.494905) (xy 434.459202 -105.547404) (xy 434.467033 -105.601579) (xy 434.467508 -105.628948)
			(xy 434.467067 -105.6562) (xy 434.459304 -105.71015) (xy 434.443943 -105.762445) (xy 434.421296 -105.812023)
			(xy 434.391825 -105.857873) (xy 434.356129 -105.899063) (xy 434.314934 -105.934753) (xy 434.269081 -105.964219)
			(xy 434.2195 -105.986859) (xy 434.167203 -106.002214) (xy 434.113252 -106.00997) (xy 434.086 -106.010456)
			(xy 434.058629 -106.010001) (xy 434.004449 -106.002182) (xy 433.951946 -105.986691) (xy 433.902199 -105.963847)
			(xy 433.856233 -105.934119) (xy 433.835302 -105.916476) (xy 433.82819 -105.91038) (xy 433.811172 -105.90403)
			(xy 433.725828 -105.90403) (xy 433.70881 -105.91038) (xy 433.701698 -105.916476) (xy 433.680774 -105.934126)
			(xy 433.6348 -105.963837) (xy 433.58505 -105.986671) (xy 433.532547 -106.00216) (xy 433.47837 -106.009984)
			(xy 433.451 -106.010456) (xy 433.423751 -106.009922) (xy 433.369807 -106.002167) (xy 433.317516 -105.986814)
			(xy 433.267942 -105.964177) (xy 433.222094 -105.934715) (xy 433.180905 -105.899029) (xy 433.145214 -105.857844)
			(xy 433.115746 -105.812) (xy 433.093102 -105.762429) (xy 433.077743 -105.71014) (xy 433.069981 -105.656197)
			(xy 433.069492 -105.628948) (xy 430.614291 -105.628948) (xy 430.621839 -105.640356) (xy 430.645511 -105.690853)
			(xy 430.661579 -105.74426) (xy 430.669699 -105.799436) (xy 430.670208 -105.827322) (xy 430.669699 -105.855208)
			(xy 430.661579 -105.910384) (xy 430.645511 -105.963791) (xy 430.621839 -106.014288) (xy 430.591066 -106.060801)
			(xy 430.553849 -106.102338) (xy 430.510981 -106.138013) (xy 430.463375 -106.167067) (xy 430.412046 -106.188879)
			(xy 430.358089 -106.202985) (xy 430.302652 -106.209085) (xy 430.246918 -106.207048) (xy 430.192075 -106.196918)
			(xy 430.139291 -106.178911) (xy 430.089691 -106.15341) (xy 430.044333 -106.120959) (xy 430.004184 -106.08225)
			(xy 429.970098 -106.038107) (xy 429.942802 -105.989472) (xy 429.922879 -105.937381) (xy 429.910753 -105.882944)
			(xy 429.906682 -105.827322) (xy 416.132772 -105.827322) (xy 417.45662 -107.15117) (xy 428.930814 -107.15117)
			(xy 428.934885 -107.095548) (xy 428.947011 -107.041111) (xy 428.966934 -106.98902) (xy 428.99423 -106.940385)
			(xy 429.028316 -106.896242) (xy 429.068465 -106.857533) (xy 429.113823 -106.825082) (xy 429.163423 -106.799581)
			(xy 429.216207 -106.781574) (xy 429.27105 -106.771444) (xy 429.326784 -106.769407) (xy 429.368344 -106.77398)
			(xy 433.340254 -106.77398) (xy 433.344325 -106.718358) (xy 433.356451 -106.663921) (xy 433.376374 -106.61183)
			(xy 433.40367 -106.563195) (xy 433.437756 -106.519052) (xy 433.477905 -106.480343) (xy 433.523263 -106.447892)
			(xy 433.572863 -106.422391) (xy 433.625647 -106.404384) (xy 433.68049 -106.394254) (xy 433.736224 -106.392217)
			(xy 433.791661 -106.398317) (xy 433.845618 -106.412423) (xy 433.896947 -106.434235) (xy 433.944553 -106.463289)
			(xy 433.987421 -106.498964) (xy 434.024638 -106.540501) (xy 434.055411 -106.587014) (xy 434.079083 -106.637511)
			(xy 434.095151 -106.690918) (xy 434.103271 -106.746094) (xy 434.10378 -106.77398) (xy 434.103271 -106.801866)
			(xy 434.095151 -106.857042) (xy 434.079083 -106.910449) (xy 434.055411 -106.960946) (xy 434.024638 -107.007459)
			(xy 433.987421 -107.048996) (xy 433.944553 -107.084671) (xy 433.896947 -107.113725) (xy 433.845618 -107.135537)
			(xy 433.791661 -107.149643) (xy 433.736224 -107.155743) (xy 433.68049 -107.153706) (xy 433.625647 -107.143576)
			(xy 433.572863 -107.125569) (xy 433.523263 -107.100068) (xy 433.477905 -107.067617) (xy 433.437756 -107.028908)
			(xy 433.40367 -106.984765) (xy 433.376374 -106.93613) (xy 433.356451 -106.884039) (xy 433.344325 -106.829602)
			(xy 433.340254 -106.77398) (xy 429.368344 -106.77398) (xy 429.382221 -106.775507) (xy 429.436178 -106.789613)
			(xy 429.487507 -106.811425) (xy 429.535113 -106.840479) (xy 429.577981 -106.876154) (xy 429.615198 -106.917691)
			(xy 429.645971 -106.964204) (xy 429.669643 -107.014701) (xy 429.685711 -107.068108) (xy 429.693831 -107.123284)
			(xy 429.69434 -107.15117) (xy 429.693831 -107.179056) (xy 429.685711 -107.234232) (xy 429.677688 -107.260898)
			(xy 430.263552 -107.260898) (xy 430.267623 -107.205276) (xy 430.279749 -107.150839) (xy 430.299672 -107.098748)
			(xy 430.326968 -107.050113) (xy 430.361054 -107.00597) (xy 430.401203 -106.967261) (xy 430.446561 -106.93481)
			(xy 430.496161 -106.909309) (xy 430.548945 -106.891302) (xy 430.603788 -106.881172) (xy 430.659522 -106.879135)
			(xy 430.714959 -106.885235) (xy 430.768916 -106.899341) (xy 430.820245 -106.921153) (xy 430.867851 -106.950207)
			(xy 430.910719 -106.985882) (xy 430.947936 -107.027419) (xy 430.978709 -107.073932) (xy 431.002381 -107.124429)
			(xy 431.018449 -107.177836) (xy 431.026569 -107.233012) (xy 431.027078 -107.260898) (xy 431.026569 -107.288784)
			(xy 431.018449 -107.34396) (xy 431.002381 -107.397367) (xy 430.978709 -107.447864) (xy 430.947936 -107.494377)
			(xy 430.910719 -107.535914) (xy 430.867851 -107.571589) (xy 430.820245 -107.600643) (xy 430.768916 -107.622455)
			(xy 430.714959 -107.636561) (xy 430.659522 -107.642661) (xy 430.603788 -107.640624) (xy 430.548945 -107.630494)
			(xy 430.496161 -107.612487) (xy 430.446561 -107.586986) (xy 430.401203 -107.554535) (xy 430.361054 -107.515826)
			(xy 430.326968 -107.471683) (xy 430.299672 -107.423048) (xy 430.279749 -107.370957) (xy 430.267623 -107.31652)
			(xy 430.263552 -107.260898) (xy 429.677688 -107.260898) (xy 429.669643 -107.287639) (xy 429.645971 -107.338136)
			(xy 429.615198 -107.384649) (xy 429.577981 -107.426186) (xy 429.535113 -107.461861) (xy 429.487507 -107.490915)
			(xy 429.436178 -107.512727) (xy 429.382221 -107.526833) (xy 429.326784 -107.532933) (xy 429.27105 -107.530896)
			(xy 429.216207 -107.520766) (xy 429.163423 -107.502759) (xy 429.113823 -107.477258) (xy 429.068465 -107.444807)
			(xy 429.028316 -107.406098) (xy 428.99423 -107.361955) (xy 428.966934 -107.31332) (xy 428.947011 -107.261229)
			(xy 428.934885 -107.206792) (xy 428.930814 -107.15117) (xy 417.45662 -107.15117) (xy 417.951158 -107.645708)
			(xy 431.703478 -107.645708) (xy 431.707549 -107.590086) (xy 431.719675 -107.535649) (xy 431.739598 -107.483558)
			(xy 431.766894 -107.434923) (xy 431.80098 -107.39078) (xy 431.841129 -107.352071) (xy 431.886487 -107.31962)
			(xy 431.936087 -107.294119) (xy 431.988871 -107.276112) (xy 432.043714 -107.265982) (xy 432.099448 -107.263945)
			(xy 432.154885 -107.270045) (xy 432.208842 -107.284151) (xy 432.260171 -107.305963) (xy 432.307777 -107.335017)
			(xy 432.350645 -107.370692) (xy 432.387862 -107.412229) (xy 432.418635 -107.458742) (xy 432.442307 -107.509239)
			(xy 432.458375 -107.562646) (xy 432.466495 -107.617822) (xy 432.467004 -107.645708) (xy 432.466495 -107.673594)
			(xy 432.458375 -107.72877) (xy 432.442307 -107.782177) (xy 432.418635 -107.832674) (xy 432.387862 -107.879187)
			(xy 432.350645 -107.920724) (xy 432.307777 -107.956399) (xy 432.260171 -107.985453) (xy 432.208842 -108.007265)
			(xy 432.154885 -108.021371) (xy 432.099448 -108.027471) (xy 432.043714 -108.025434) (xy 431.988871 -108.015304)
			(xy 431.936087 -107.997297) (xy 431.886487 -107.971796) (xy 431.841129 -107.939345) (xy 431.80098 -107.900636)
			(xy 431.766894 -107.856493) (xy 431.739598 -107.807858) (xy 431.719675 -107.755767) (xy 431.707549 -107.70133)
			(xy 431.703478 -107.645708) (xy 417.951158 -107.645708) (xy 419.96868 -109.66323) (xy 433.334158 -109.66323)
			(xy 433.338229 -109.607608) (xy 433.350355 -109.553171) (xy 433.370278 -109.50108) (xy 433.397574 -109.452445)
			(xy 433.43166 -109.408302) (xy 433.471809 -109.369593) (xy 433.517167 -109.337142) (xy 433.566767 -109.311641)
			(xy 433.619551 -109.293634) (xy 433.674394 -109.283504) (xy 433.730128 -109.281467) (xy 433.785565 -109.287567)
			(xy 433.839522 -109.301673) (xy 433.890851 -109.323485) (xy 433.938457 -109.352539) (xy 433.981325 -109.388214)
			(xy 434.018542 -109.429751) (xy 434.049315 -109.476264) (xy 434.072987 -109.526761) (xy 434.089055 -109.580168)
			(xy 434.097175 -109.635344) (xy 434.097684 -109.66323) (xy 434.097175 -109.691116) (xy 434.089055 -109.746292)
			(xy 434.072987 -109.799699) (xy 434.049315 -109.850196) (xy 434.018542 -109.896709) (xy 433.981325 -109.938246)
			(xy 433.938457 -109.973921) (xy 433.890851 -110.002975) (xy 433.839522 -110.024787) (xy 433.785565 -110.038893)
			(xy 433.730128 -110.044993) (xy 433.674394 -110.042956) (xy 433.619551 -110.032826) (xy 433.566767 -110.014819)
			(xy 433.517167 -109.989318) (xy 433.471809 -109.956867) (xy 433.43166 -109.918158) (xy 433.397574 -109.874015)
			(xy 433.370278 -109.82538) (xy 433.350355 -109.773289) (xy 433.338229 -109.718852) (xy 433.334158 -109.66323)
			(xy 419.96868 -109.66323) (xy 420.205154 -109.899704) (xy 420.2176 -109.906562) (xy 420.224966 -109.908086)
			(xy 420.252974 -109.914707) (xy 420.306739 -109.935235) (xy 420.35681 -109.963607) (xy 420.402049 -109.99918)
			(xy 420.441431 -110.041146) (xy 420.474061 -110.088552) (xy 420.499198 -110.140322) (xy 420.516272 -110.195282)
			(xy 420.524894 -110.252183) (xy 420.525448 -110.280958) (xy 420.524988 -110.308214) (xy 420.517236 -110.362172)
			(xy 420.516546 -110.364524) (xy 420.634412 -110.364524) (xy 420.638483 -110.308902) (xy 420.650609 -110.254465)
			(xy 420.670532 -110.202374) (xy 420.697828 -110.153739) (xy 420.731914 -110.109596) (xy 420.772063 -110.070887)
			(xy 420.817421 -110.038436) (xy 420.867021 -110.012935) (xy 420.919805 -109.994928) (xy 420.974648 -109.984798)
			(xy 421.030382 -109.982761) (xy 421.085819 -109.988861) (xy 421.139776 -110.002967) (xy 421.191105 -110.024779)
			(xy 421.238711 -110.053833) (xy 421.281579 -110.089508) (xy 421.318796 -110.131045) (xy 421.349569 -110.177558)
			(xy 421.373241 -110.228055) (xy 421.387858 -110.27664) (xy 428.913542 -110.27664) (xy 428.917613 -110.221018)
			(xy 428.929739 -110.166581) (xy 428.949662 -110.11449) (xy 428.976958 -110.065855) (xy 429.011044 -110.021712)
			(xy 429.051193 -109.983003) (xy 429.096551 -109.950552) (xy 429.146151 -109.925051) (xy 429.198935 -109.907044)
			(xy 429.253778 -109.896914) (xy 429.309512 -109.894877) (xy 429.364949 -109.900977) (xy 429.418906 -109.915083)
			(xy 429.470235 -109.936895) (xy 429.517841 -109.965949) (xy 429.560709 -110.001624) (xy 429.597926 -110.043161)
			(xy 429.628699 -110.089674) (xy 429.652371 -110.140171) (xy 429.668439 -110.193578) (xy 429.676559 -110.248754)
			(xy 429.677068 -110.27664) (xy 429.676559 -110.304526) (xy 429.668439 -110.359702) (xy 429.652371 -110.413109)
			(xy 429.628699 -110.463606) (xy 429.597926 -110.510119) (xy 429.560709 -110.551656) (xy 429.517841 -110.587331)
			(xy 429.470235 -110.616385) (xy 429.418906 -110.638197) (xy 429.364949 -110.652303) (xy 429.309512 -110.658403)
			(xy 429.253778 -110.656366) (xy 429.198935 -110.646236) (xy 429.146151 -110.628229) (xy 429.096551 -110.602728)
			(xy 429.051193 -110.570277) (xy 429.011044 -110.531568) (xy 428.976958 -110.487425) (xy 428.949662 -110.43879)
			(xy 428.929739 -110.386699) (xy 428.917613 -110.332262) (xy 428.913542 -110.27664) (xy 421.387858 -110.27664)
			(xy 421.389309 -110.281462) (xy 421.397429 -110.336638) (xy 421.397938 -110.364524) (xy 421.397429 -110.39241)
			(xy 421.389309 -110.447586) (xy 421.373241 -110.500993) (xy 421.349569 -110.55149) (xy 421.318796 -110.598003)
			(xy 421.281579 -110.63954) (xy 421.238711 -110.675215) (xy 421.191105 -110.704269) (xy 421.139776 -110.726081)
			(xy 421.085819 -110.740187) (xy 421.030382 -110.746287) (xy 420.974648 -110.74425) (xy 420.919805 -110.73412)
			(xy 420.867021 -110.716113) (xy 420.817421 -110.690612) (xy 420.772063 -110.658161) (xy 420.731914 -110.619452)
			(xy 420.697828 -110.575309) (xy 420.670532 -110.526674) (xy 420.650609 -110.474583) (xy 420.638483 -110.420146)
			(xy 420.634412 -110.364524) (xy 420.516546 -110.364524) (xy 420.501884 -110.414477) (xy 420.479245 -110.464065)
			(xy 420.449778 -110.509926) (xy 420.414085 -110.551127) (xy 420.372892 -110.586829) (xy 420.327037 -110.616305)
			(xy 420.277454 -110.638955) (xy 420.225152 -110.654319) (xy 420.171196 -110.662082) (xy 420.14394 -110.662466)
			(xy 420.115167 -110.661938) (xy 420.058273 -110.65329) (xy 420.003323 -110.636198) (xy 419.951562 -110.611051)
			(xy 419.904163 -110.578417) (xy 419.8622 -110.539037) (xy 419.826625 -110.493804) (xy 419.798243 -110.443743)
			(xy 419.7777 -110.389988) (xy 419.771068 -110.361984) (xy 419.769544 -110.354618) (xy 419.762686 -110.342172)
			(xy 414.037272 -104.616758) (xy 414.029829 -104.610067) (xy 414.011333 -104.602475) (xy 413.991339 -104.6025)
			(xy 413.9819 -104.605836) (xy 413.967676 -104.611678) (xy 413.950658 -104.637078) (xy 413.950658 -110.4265)
			(xy 418.726872 -110.4265) (xy 418.730943 -110.370878) (xy 418.743069 -110.316441) (xy 418.762992 -110.26435)
			(xy 418.790288 -110.215715) (xy 418.824374 -110.171572) (xy 418.864523 -110.132863) (xy 418.909881 -110.100412)
			(xy 418.959481 -110.074911) (xy 419.012265 -110.056904) (xy 419.067108 -110.046774) (xy 419.122842 -110.044737)
			(xy 419.178279 -110.050837) (xy 419.232236 -110.064943) (xy 419.283565 -110.086755) (xy 419.331171 -110.115809)
			(xy 419.374039 -110.151484) (xy 419.411256 -110.193021) (xy 419.442029 -110.239534) (xy 419.465701 -110.290031)
			(xy 419.481769 -110.343438) (xy 419.489889 -110.398614) (xy 419.490398 -110.4265) (xy 419.489889 -110.454386)
			(xy 419.481769 -110.509562) (xy 419.465701 -110.562969) (xy 419.442029 -110.613466) (xy 419.411256 -110.659979)
			(xy 419.374039 -110.701516) (xy 419.331171 -110.737191) (xy 419.283565 -110.766245) (xy 419.232236 -110.788057)
			(xy 419.178279 -110.802163) (xy 419.122842 -110.808263) (xy 419.067108 -110.806226) (xy 419.012265 -110.796096)
			(xy 418.959481 -110.778089) (xy 418.909881 -110.752588) (xy 418.864523 -110.720137) (xy 418.824374 -110.681428)
			(xy 418.790288 -110.637285) (xy 418.762992 -110.58865) (xy 418.743069 -110.536559) (xy 418.730943 -110.482122)
			(xy 418.726872 -110.4265) (xy 413.950658 -110.4265) (xy 413.950658 -110.940088) (xy 429.500282 -110.940088)
			(xy 429.504353 -110.884466) (xy 429.516479 -110.830029) (xy 429.536402 -110.777938) (xy 429.563698 -110.729303)
			(xy 429.597784 -110.68516) (xy 429.637933 -110.646451) (xy 429.683291 -110.614) (xy 429.732891 -110.588499)
			(xy 429.785675 -110.570492) (xy 429.840518 -110.560362) (xy 429.896252 -110.558325) (xy 429.951689 -110.564425)
			(xy 430.005646 -110.578531) (xy 430.056975 -110.600343) (xy 430.104581 -110.629397) (xy 430.147449 -110.665072)
			(xy 430.184666 -110.706609) (xy 430.215439 -110.753122) (xy 430.239111 -110.803619) (xy 430.255179 -110.857026)
			(xy 430.263299 -110.912202) (xy 430.263808 -110.940088) (xy 430.263299 -110.967974) (xy 430.255179 -111.02315)
			(xy 430.239111 -111.076557) (xy 430.215439 -111.127054) (xy 430.184666 -111.173567) (xy 430.147449 -111.215104)
			(xy 430.104581 -111.250779) (xy 430.056975 -111.279833) (xy 430.005646 -111.301645) (xy 429.951689 -111.315751)
			(xy 429.896252 -111.321851) (xy 429.840518 -111.319814) (xy 429.785675 -111.309684) (xy 429.732891 -111.291677)
			(xy 429.683291 -111.266176) (xy 429.637933 -111.233725) (xy 429.597784 -111.195016) (xy 429.563698 -111.150873)
			(xy 429.536402 -111.102238) (xy 429.516479 -111.050147) (xy 429.504353 -110.99571) (xy 429.500282 -110.940088)
			(xy 413.950658 -110.940088) (xy 413.950658 -110.985808) (xy 413.951115 -110.995687) (xy 413.958551 -111.013992)
			(xy 413.965136 -111.021368) (xy 413.96539 -111.021622) (xy 415.538666 -112.594898) (xy 415.539174 -112.595406)
			(xy 415.546554 -112.60199) (xy 415.564854 -112.60944) (xy 415.574734 -112.609884)
		)
		(stroke
			(width 0)
			(type solid)
		)
		(fill yes)
		(layer "In6.Cu")
		(net "GND")
	)
	(gr_poly
		(pts
			(xy 201.766932 -399.318988) (xy 201.776999 -399.318559) (xy 201.795594 -399.310835) (xy 201.803 -399.304002)
			(xy 203.3778 -397.729202) (xy 203.385198 -397.722355) (xy 203.403796 -397.71462) (xy 203.413868 -397.714216)
			(xy 206.779876 -397.714216) (xy 206.78994 -397.714653) (xy 206.808523 -397.722389) (xy 206.815944 -397.729202)
			(xy 208.390744 -399.304002) (xy 208.398145 -399.310841) (xy 208.416743 -399.318559) (xy 208.426812 -399.318988)
			(xy 212.484462 -399.318988) (xy 212.494527 -399.318553) (xy 212.513114 -399.310822) (xy 212.52053 -399.304002)
			(xy 213.827868 -397.996664) (xy 213.835267 -397.989821) (xy 213.853866 -397.982101) (xy 213.863936 -397.981678)
			(xy 217.608912 -397.981678) (xy 217.618982 -397.982103) (xy 217.637585 -397.989818) (xy 217.64498 -397.996664)
			(xy 218.952318 -399.304002) (xy 218.959718 -399.310845) (xy 218.978316 -399.318573) (xy 218.988386 -399.318988)
			(xy 223.134936 -399.318988) (xy 223.145003 -399.318558) (xy 223.163597 -399.310833) (xy 223.171004 -399.304002)
			(xy 224.45599 -398.019016) (xy 224.463387 -398.012166) (xy 224.481985 -398.004425) (xy 224.492058 -398.00403)
			(xy 228.370892 -398.00403) (xy 228.380962 -398.004452) (xy 228.399566 -398.012168) (xy 228.40696 -398.019016)
			(xy 229.691946 -399.304002) (xy 229.699347 -399.310841) (xy 229.717945 -399.318558) (xy 229.728014 -399.318988)
			(xy 234.185968 -399.318988) (xy 234.196032 -399.318552) (xy 234.214618 -399.310819) (xy 234.222036 -399.304002)
			(xy 238.249206 -395.276832) (xy 238.256041 -395.26943) (xy 238.26375 -395.250831) (xy 238.264192 -395.240764)
			(xy 238.264192 -385.379468) (xy 238.261144 -385.37642) (xy 238.261144 -382.991614) (xy 238.261584 -382.981552)
			(xy 238.269325 -382.962974) (xy 238.27613 -382.955546) (xy 238.323882 -382.907794) (xy 238.331285 -382.900961)
			(xy 238.349883 -382.893258) (xy 238.35995 -382.892808) (xy 278.090122 -382.892808) (xy 278.100191 -382.892381)
			(xy 278.11879 -382.884662) (xy 278.12619 -382.877822) (xy 278.196294 -382.807718) (xy 278.203128 -382.800315)
			(xy 278.210834 -382.781717) (xy 278.21128 -382.77165) (xy 278.21128 -382.71704) (xy 278.211373 -382.712021)
			(xy 278.213294 -382.70217) (xy 278.21509 -382.697482) (xy 278.222456 -382.68021) (xy 278.224257 -382.675524)
			(xy 278.226178 -382.665671) (xy 278.226266 -382.660652) (xy 278.226266 -376.7201) (xy 278.225842 -376.71003)
			(xy 278.218124 -376.691429) (xy 278.21128 -376.684032) (xy 277.45182 -375.924572) (xy 277.444421 -375.91773)
			(xy 277.425821 -375.910014) (xy 277.415752 -375.909586) (xy 225.825304 -375.909586) (xy 225.815233 -375.910008)
			(xy 225.796626 -375.91772) (xy 225.789236 -375.924572) (xy 222.37446 -379.339348) (xy 222.367062 -379.346194)
			(xy 222.348463 -379.353922) (xy 222.338392 -379.354334) (xy 209.8802 -379.354334) (xy 209.874553 -379.354456)
			(xy 209.863527 -379.356888) (xy 209.858356 -379.35916) (xy 209.843891 -379.36597) (xy 209.814547 -379.378674)
			(xy 209.799682 -379.38456) (xy 209.790285 -379.388669) (xy 209.775568 -379.402924) (xy 209.767624 -379.421811)
			(xy 209.76717 -379.432058) (xy 209.76717 -379.45695) (xy 209.767636 -379.467188) (xy 209.775618 -379.486044)
			(xy 209.790306 -379.500311) (xy 209.799682 -379.504448) (xy 209.837783 -379.519766) (xy 209.911258 -379.556451)
			(xy 209.981039 -379.599752) (xy 210.046532 -379.649302) (xy 210.107178 -379.704678) (xy 210.162462 -379.765408)
			(xy 210.211912 -379.830975) (xy 210.255107 -379.900822) (xy 210.29168 -379.974353) (xy 210.321319 -380.050943)
			(xy 210.343772 -380.129938) (xy 210.358848 -380.210667) (xy 210.366418 -380.292442) (xy 210.366864 -380.333504)
			(xy 210.366279 -380.3799) (xy 210.356645 -380.47219) (xy 210.33745 -380.562975) (xy 210.308905 -380.651266)
			(xy 210.290664 -380.69393) (xy 210.286846 -380.70387) (xy 210.286847 -380.725137) (xy 210.290664 -380.735078)
			(xy 210.308902 -380.777743) (xy 210.337442 -380.866036) (xy 210.356638 -380.95682) (xy 210.366283 -381.049108)
			(xy 210.366864 -381.095504) (xy 210.366352 -381.138362) (xy 210.358109 -381.223681) (xy 210.342093 -381.3058)
			(xy 242.544088 -381.3058) (xy 242.548118 -381.221198) (xy 242.560172 -381.137363) (xy 242.58014 -381.055053)
			(xy 242.607842 -380.975014) (xy 242.643027 -380.897971) (xy 242.685376 -380.824621) (xy 242.734505 -380.755628)
			(xy 242.789971 -380.691619) (xy 242.851269 -380.633171) (xy 242.917846 -380.580815) (xy 242.989099 -380.535024)
			(xy 243.064381 -380.496214) (xy 243.143012 -380.464736) (xy 243.224278 -380.440874) (xy 243.307445 -380.424846)
			(xy 243.391759 -380.416796) (xy 243.434108 -380.416308) (xy 243.474162 -380.41672) (xy 243.553944 -380.423932)
			(xy 243.632755 -380.438288) (xy 243.709956 -380.459672) (xy 243.784921 -380.48791) (xy 243.857045 -380.522773)
			(xy 243.925741 -380.56398) (xy 243.990455 -380.611197) (xy 244.020848 -380.637288) (xy 244.027964 -380.642979)
			(xy 244.045018 -380.649358) (xy 244.054122 -380.649734) (xy 244.084094 -380.649734) (xy 244.093196 -380.64935)
			(xy 244.110247 -380.64297) (xy 244.117368 -380.637288) (xy 244.147764 -380.611201) (xy 244.212475 -380.563983)
			(xy 244.281171 -380.522776) (xy 244.353294 -380.487914) (xy 244.42826 -380.459679) (xy 244.505461 -380.4383)
			(xy 244.584272 -380.423951) (xy 244.664055 -380.416748) (xy 244.704108 -380.416308) (xy 244.746457 -380.41678)
			(xy 244.830771 -380.424832) (xy 244.913939 -380.440862) (xy 244.995206 -380.464724) (xy 245.073836 -380.496204)
			(xy 245.149119 -380.535015) (xy 245.220371 -380.580807) (xy 245.286948 -380.633164) (xy 245.348247 -380.691613)
			(xy 245.403712 -380.755624) (xy 245.452841 -380.824617) (xy 245.49519 -380.897967) (xy 245.530375 -380.975012)
			(xy 245.558077 -381.055051) (xy 245.578045 -381.137362) (xy 245.590098 -381.221198) (xy 245.594129 -381.3058)
			(xy 248.479103 -381.3058) (xy 248.483133 -381.221202) (xy 248.495186 -381.13737) (xy 248.515153 -381.055064)
			(xy 248.542853 -380.975028) (xy 248.578036 -380.897988) (xy 248.620382 -380.82464) (xy 248.669508 -380.75565)
			(xy 248.72497 -380.691642) (xy 248.786265 -380.633196) (xy 248.852838 -380.58084) (xy 248.924086 -380.53505)
			(xy 248.999364 -380.496239) (xy 249.07799 -380.46476) (xy 249.159252 -380.440897) (xy 249.242415 -380.424866)
			(xy 249.326725 -380.416813) (xy 249.369072 -380.416308) (xy 249.409125 -380.416742) (xy 249.488907 -380.423951)
			(xy 249.567717 -380.438304) (xy 249.644918 -380.459684) (xy 249.719884 -380.487919) (xy 249.792007 -380.52278)
			(xy 249.860704 -380.563984) (xy 249.925418 -380.611198) (xy 249.955812 -380.637288) (xy 249.962939 -380.642963)
			(xy 249.979984 -380.649352) (xy 249.989086 -380.649734) (xy 250.019058 -380.649734) (xy 250.028158 -380.649333)
			(xy 250.045209 -380.642965) (xy 250.052332 -380.637288) (xy 250.082702 -380.61117) (xy 250.147418 -380.563954)
			(xy 250.216118 -380.522751) (xy 250.288245 -380.487892) (xy 250.363214 -380.459661) (xy 250.440419 -380.438287)
			(xy 250.519233 -380.423943) (xy 250.599018 -380.416745) (xy 250.639072 -380.416308) (xy 250.681423 -380.416763)
			(xy 250.765741 -380.424812) (xy 250.848913 -380.440839) (xy 250.930184 -380.4647) (xy 251.008819 -380.496179)
			(xy 251.084106 -380.53499) (xy 251.155362 -380.580782) (xy 251.221943 -380.63314) (xy 251.283246 -380.691589)
			(xy 251.338714 -380.755602) (xy 251.387847 -380.824597) (xy 251.430199 -380.897951) (xy 251.465386 -380.974998)
			(xy 251.49309 -381.055041) (xy 251.513059 -381.137355) (xy 251.525114 -381.221194) (xy 251.529144 -381.3058)
			(xy 254.413988 -381.3058) (xy 254.418018 -381.221197) (xy 254.430073 -381.13736) (xy 254.450042 -381.055048)
			(xy 254.477745 -380.975008) (xy 254.512931 -380.897963) (xy 254.555281 -380.824612) (xy 254.604413 -380.755619)
			(xy 254.65988 -380.691609) (xy 254.721181 -380.633161) (xy 254.78776 -380.580805) (xy 254.859015 -380.535015)
			(xy 254.934299 -380.496206) (xy 255.012932 -380.464729) (xy 255.094201 -380.440869) (xy 255.17737 -380.424842)
			(xy 255.261686 -380.416794) (xy 255.304036 -380.416308) (xy 255.344089 -380.416764) (xy 255.42387 -380.42397)
			(xy 255.502679 -380.43832) (xy 255.57988 -380.459697) (xy 255.654846 -380.487929) (xy 255.726969 -380.522787)
			(xy 255.795667 -380.563988) (xy 255.860382 -380.6112) (xy 255.890776 -380.637288) (xy 255.897884 -380.64299)
			(xy 255.914944 -380.649363) (xy 255.92405 -380.649734) (xy 255.954022 -380.649734) (xy 255.963125 -380.649364)
			(xy 255.980176 -380.642974) (xy 255.987296 -380.637288) (xy 256.017681 -380.611187) (xy 256.082394 -380.56397)
			(xy 256.151091 -380.522765) (xy 256.223216 -380.487904) (xy 256.298184 -380.459671) (xy 256.375386 -380.438295)
			(xy 256.454199 -380.423948) (xy 256.533982 -380.416747) (xy 256.574036 -380.416308) (xy 256.616384 -380.416781)
			(xy 256.700697 -380.424835) (xy 256.783862 -380.440867) (xy 256.865127 -380.464732) (xy 256.943755 -380.496212)
			(xy 257.019035 -380.535025) (xy 257.090285 -380.580817) (xy 257.15686 -380.633174) (xy 257.218156 -380.691623)
			(xy 257.273619 -380.755633) (xy 257.322747 -380.824625) (xy 257.365094 -380.897975) (xy 257.400277 -380.975018)
			(xy 257.427978 -381.055056) (xy 257.447945 -381.137365) (xy 257.459999 -381.2212) (xy 257.464029 -381.3058)
			(xy 260.349004 -381.3058) (xy 260.353033 -381.2212) (xy 260.365087 -381.137367) (xy 260.385055 -381.055059)
			(xy 260.412756 -380.975022) (xy 260.44794 -380.89798) (xy 260.490287 -380.824632) (xy 260.539415 -380.755641)
			(xy 260.594879 -380.691632) (xy 260.656176 -380.633186) (xy 260.722751 -380.58083) (xy 260.794002 -380.53504)
			(xy 260.869282 -380.496231) (xy 260.947911 -380.464753) (xy 261.029175 -380.440891) (xy 261.11234 -380.424862)
			(xy 261.196652 -380.416812) (xy 261.239 -380.416308) (xy 261.279054 -380.416725) (xy 261.358836 -380.423936)
			(xy 261.437646 -380.438292) (xy 261.514847 -380.459674) (xy 261.589813 -380.487912) (xy 261.661936 -380.522775)
			(xy 261.730633 -380.563981) (xy 261.795346 -380.611197) (xy 261.82574 -380.637288) (xy 261.832859 -380.642975)
			(xy 261.84991 -380.649357) (xy 261.859014 -380.649734) (xy 261.888986 -380.649734) (xy 261.898088 -380.649346)
			(xy 261.915138 -380.642969) (xy 261.92226 -380.637288) (xy 261.952659 -380.611204) (xy 262.01737 -380.563986)
			(xy 262.086065 -380.522779) (xy 262.158188 -380.487916) (xy 262.233153 -380.459681) (xy 262.310354 -380.438302)
			(xy 262.389165 -380.423952) (xy 262.468947 -380.416748) (xy 262.509 -380.416308) (xy 262.551349 -380.41678)
			(xy 262.635664 -380.424831) (xy 262.718832 -380.44086) (xy 262.8001 -380.464722) (xy 262.878731 -380.496202)
			(xy 262.954014 -380.535013) (xy 263.025267 -380.580804) (xy 263.091845 -380.633161) (xy 263.153144 -380.69161)
			(xy 263.20861 -380.755621) (xy 263.25774 -380.824614) (xy 263.300089 -380.897965) (xy 263.335274 -380.97501)
			(xy 263.362976 -381.05505) (xy 263.382945 -381.137361) (xy 263.394998 -381.221197) (xy 263.399029 -381.3058)
			(xy 266.284003 -381.3058) (xy 266.288033 -381.221203) (xy 266.300086 -381.137371) (xy 266.320053 -381.055065)
			(xy 266.347753 -380.97503) (xy 266.382935 -380.89799) (xy 266.42528 -380.824643) (xy 266.474406 -380.755653)
			(xy 266.529867 -380.691645) (xy 266.591161 -380.633198) (xy 266.657734 -380.580843) (xy 266.728981 -380.535052)
			(xy 266.804258 -380.496242) (xy 266.882884 -380.464762) (xy 266.964146 -380.440898) (xy 267.047308 -380.424867)
			(xy 267.131617 -380.416813) (xy 267.173964 -380.416308) (xy 267.214017 -380.416747) (xy 267.293799 -380.423955)
			(xy 267.372609 -380.438307) (xy 267.449809 -380.459687) (xy 267.524775 -380.487921) (xy 267.596899 -380.522782)
			(xy 267.665596 -380.563985) (xy 267.73031 -380.611199) (xy 267.760704 -380.637288) (xy 267.767804 -380.643002)
			(xy 267.78487 -380.649368) (xy 267.793978 -380.649734) (xy 267.82395 -380.649734) (xy 267.83305 -380.649329)
			(xy 267.850101 -380.642964) (xy 267.857224 -380.637288) (xy 267.887598 -380.611174) (xy 267.952313 -380.563958)
			(xy 268.021012 -380.522754) (xy 268.093138 -380.487895) (xy 268.168107 -380.459664) (xy 268.245312 -380.438289)
			(xy 268.324125 -380.423944) (xy 268.40391 -380.416746) (xy 268.443964 -380.416308) (xy 268.486315 -380.416762)
			(xy 268.570634 -380.424811) (xy 268.653806 -380.440838) (xy 268.735078 -380.464698) (xy 268.813714 -380.496177)
			(xy 268.889001 -380.534987) (xy 268.960258 -380.580779) (xy 269.02684 -380.633137) (xy 269.088143 -380.691587)
			(xy 269.143612 -380.755599) (xy 269.192746 -380.824595) (xy 269.235098 -380.897949) (xy 269.270285 -380.974996)
			(xy 269.297989 -381.055039) (xy 269.317959 -381.137354) (xy 269.330014 -381.221194) (xy 269.334044 -381.3058)
			(xy 272.218888 -381.3058) (xy 272.222918 -381.221197) (xy 272.234972 -381.137361) (xy 272.254941 -381.05505)
			(xy 272.282644 -380.97501) (xy 272.31783 -380.897965) (xy 272.36018 -380.824615) (xy 272.409311 -380.755622)
			(xy 272.464777 -380.691612) (xy 272.526078 -380.633164) (xy 272.592656 -380.580808) (xy 272.66391 -380.535018)
			(xy 272.739194 -380.496208) (xy 272.817826 -380.464731) (xy 272.899095 -380.44087) (xy 272.982263 -380.424843)
			(xy 273.066579 -380.416795) (xy 273.108928 -380.416308) (xy 273.148981 -380.416769) (xy 273.228761 -380.423974)
			(xy 273.307571 -380.438323) (xy 273.384772 -380.4597) (xy 273.459737 -380.487931) (xy 273.531861 -380.522788)
			(xy 273.600559 -380.563989) (xy 273.665274 -380.6112) (xy 273.695668 -380.637288) (xy 273.702779 -380.642987)
			(xy 273.719837 -380.649362) (xy 273.728942 -380.649734) (xy 273.758914 -380.649734) (xy 273.768017 -380.64936)
			(xy 273.785068 -380.642973) (xy 273.792188 -380.637288) (xy 273.822576 -380.611191) (xy 273.887289 -380.563974)
			(xy 273.955986 -380.522768) (xy 274.02811 -380.487907) (xy 274.103077 -380.459673) (xy 274.180279 -380.438296)
			(xy 274.259091 -380.423949) (xy 274.338874 -380.416747) (xy 274.378928 -380.416308) (xy 274.421276 -380.416781)
			(xy 274.505589 -380.424834) (xy 274.588755 -380.440866) (xy 274.670021 -380.46473) (xy 274.74865 -380.49621)
			(xy 274.82393 -380.535022) (xy 274.895181 -380.580814) (xy 274.961756 -380.633171) (xy 275.023053 -380.69162)
			(xy 275.078517 -380.75563) (xy 275.127645 -380.824623) (xy 275.169993 -380.897973) (xy 275.205176 -380.975016)
			(xy 275.232878 -381.055055) (xy 275.252845 -381.137364) (xy 275.264899 -381.221199) (xy 275.268929 -381.3058)
			(xy 275.264899 -381.390401) (xy 275.252845 -381.474236) (xy 275.232878 -381.556545) (xy 275.205176 -381.636584)
			(xy 275.169993 -381.713627) (xy 275.127645 -381.786977) (xy 275.078517 -381.85597) (xy 275.023053 -381.91998)
			(xy 274.961756 -381.978429) (xy 274.895181 -382.030786) (xy 274.82393 -382.076578) (xy 274.74865 -382.11539)
			(xy 274.670021 -382.14687) (xy 274.588755 -382.170734) (xy 274.505589 -382.186766) (xy 274.421276 -382.194819)
			(xy 274.378928 -382.195324) (xy 274.338875 -382.194882) (xy 274.259094 -382.187673) (xy 274.180284 -382.173321)
			(xy 274.103083 -382.151941) (xy 274.028118 -382.123707) (xy 273.955994 -382.088848) (xy 273.887297 -382.047645)
			(xy 273.822582 -382.000433) (xy 273.792188 -381.974344) (xy 273.785058 -381.968672) (xy 273.768015 -381.96228)
			(xy 273.758914 -381.961898) (xy 273.728942 -381.961898) (xy 273.719844 -381.962314) (xy 273.702793 -381.968673)
			(xy 273.695668 -381.974344) (xy 273.665302 -382.000468) (xy 273.600585 -382.047682) (xy 273.531885 -382.088884)
			(xy 273.459757 -382.123742) (xy 273.384787 -382.151972) (xy 273.307582 -382.173345) (xy 273.228767 -382.187689)
			(xy 273.148983 -382.194887) (xy 273.108928 -382.195324) (xy 273.066579 -382.194805) (xy 272.982263 -382.186757)
			(xy 272.899095 -382.17073) (xy 272.817826 -382.146869) (xy 272.739194 -382.115392) (xy 272.66391 -382.076582)
			(xy 272.592656 -382.030792) (xy 272.526078 -381.978436) (xy 272.464777 -381.919988) (xy 272.409311 -381.855978)
			(xy 272.36018 -381.786985) (xy 272.31783 -381.713635) (xy 272.282644 -381.63659) (xy 272.254941 -381.55655)
			(xy 272.234972 -381.474239) (xy 272.222918 -381.390403) (xy 272.218888 -381.3058) (xy 269.334044 -381.3058)
			(xy 269.330014 -381.390406) (xy 269.317959 -381.474246) (xy 269.297989 -381.556561) (xy 269.270285 -381.636604)
			(xy 269.235098 -381.713651) (xy 269.192746 -381.787005) (xy 269.143612 -381.856001) (xy 269.088143 -381.920013)
			(xy 269.02684 -381.978463) (xy 268.960258 -382.030821) (xy 268.889001 -382.076613) (xy 268.813714 -382.115423)
			(xy 268.735078 -382.146902) (xy 268.653806 -382.170762) (xy 268.570634 -382.186789) (xy 268.486315 -382.194838)
			(xy 268.443964 -382.195324) (xy 268.403911 -382.19486) (xy 268.324131 -382.187654) (xy 268.245322 -382.173305)
			(xy 268.168121 -382.151929) (xy 268.093156 -382.123698) (xy 268.021032 -382.088841) (xy 267.952334 -382.047641)
			(xy 267.887619 -382.000432) (xy 267.857224 -381.974344) (xy 267.850113 -381.968645) (xy 267.833056 -381.962269)
			(xy 267.82395 -381.961898) (xy 267.793978 -381.961898) (xy 267.784876 -381.962283) (xy 267.767826 -381.968664)
			(xy 267.760704 -381.974344) (xy 267.730324 -382.00045) (xy 267.665609 -382.047666) (xy 267.596911 -382.08887)
			(xy 267.524786 -382.12373) (xy 267.449817 -382.151962) (xy 267.372614 -382.173338) (xy 267.293802 -382.187684)
			(xy 267.214018 -382.194885) (xy 267.173964 -382.195324) (xy 267.131617 -382.194787) (xy 267.047308 -382.186733)
			(xy 266.964146 -382.170702) (xy 266.882884 -382.146838) (xy 266.804258 -382.115358) (xy 266.728981 -382.076548)
			(xy 266.657734 -382.030757) (xy 266.591161 -381.978402) (xy 266.529867 -381.919955) (xy 266.474406 -381.855947)
			(xy 266.42528 -381.786957) (xy 266.382935 -381.71361) (xy 266.347753 -381.63657) (xy 266.320053 -381.556535)
			(xy 266.300086 -381.474229) (xy 266.288033 -381.390397) (xy 266.284003 -381.3058) (xy 263.399029 -381.3058)
			(xy 263.394998 -381.390403) (xy 263.382945 -381.474239) (xy 263.362976 -381.55655) (xy 263.335274 -381.63659)
			(xy 263.300089 -381.713635) (xy 263.25774 -381.786986) (xy 263.20861 -381.855979) (xy 263.153144 -381.91999)
			(xy 263.091845 -381.978439) (xy 263.025267 -382.030796) (xy 262.954014 -382.076587) (xy 262.878731 -382.115398)
			(xy 262.8001 -382.146878) (xy 262.718832 -382.17074) (xy 262.635664 -382.186769) (xy 262.551349 -382.19482)
			(xy 262.509 -382.195324) (xy 262.468947 -382.194899) (xy 262.389165 -382.187688) (xy 262.310355 -382.173333)
			(xy 262.233154 -382.151951) (xy 262.158188 -382.123715) (xy 262.086065 -382.088853) (xy 262.017368 -382.047648)
			(xy 261.952654 -382.000434) (xy 261.92226 -381.974344) (xy 261.915138 -381.96866) (xy 261.898089 -381.962275)
			(xy 261.888986 -381.961898) (xy 261.859014 -381.961898) (xy 261.849914 -381.962301) (xy 261.832864 -381.968669)
			(xy 261.82574 -381.974344) (xy 261.795345 -382.000433) (xy 261.730633 -382.04765) (xy 261.661937 -382.088856)
			(xy 261.589814 -382.123718) (xy 261.514848 -382.151952) (xy 261.437647 -382.173331) (xy 261.358836 -382.18768)
			(xy 261.279053 -382.194884) (xy 261.239 -382.195324) (xy 261.196652 -382.194788) (xy 261.11234 -382.186738)
			(xy 261.029175 -382.170709) (xy 260.947911 -382.146847) (xy 260.869282 -382.115369) (xy 260.794002 -382.07656)
			(xy 260.722751 -382.03077) (xy 260.656176 -381.978414) (xy 260.594879 -381.919968) (xy 260.539415 -381.855959)
			(xy 260.490287 -381.786968) (xy 260.44794 -381.71362) (xy 260.412756 -381.636578) (xy 260.385055 -381.556541)
			(xy 260.365087 -381.474233) (xy 260.353033 -381.3904) (xy 260.349004 -381.3058) (xy 257.464029 -381.3058)
			(xy 257.459999 -381.3904) (xy 257.447945 -381.474235) (xy 257.427978 -381.556544) (xy 257.400277 -381.636582)
			(xy 257.365094 -381.713625) (xy 257.322747 -381.786975) (xy 257.273619 -381.855967) (xy 257.218156 -381.919977)
			(xy 257.15686 -381.978426) (xy 257.090285 -382.030783) (xy 257.019035 -382.076575) (xy 256.943755 -382.115388)
			(xy 256.865127 -382.146868) (xy 256.783862 -382.170733) (xy 256.700697 -382.186765) (xy 256.616384 -382.194819)
			(xy 256.574036 -382.195324) (xy 256.533983 -382.194877) (xy 256.454202 -382.187669) (xy 256.375392 -382.173318)
			(xy 256.298192 -382.151939) (xy 256.223226 -382.123705) (xy 256.151103 -382.088846) (xy 256.082405 -382.047644)
			(xy 256.01769 -382.000433) (xy 255.987296 -381.974344) (xy 255.980193 -381.968633) (xy 255.963129 -381.962264)
			(xy 255.954022 -381.961898) (xy 255.92405 -381.961898) (xy 255.914952 -381.962318) (xy 255.897902 -381.968675)
			(xy 255.890776 -381.974344) (xy 255.860407 -382.000464) (xy 255.795691 -382.047678) (xy 255.726991 -382.088881)
			(xy 255.654863 -382.123739) (xy 255.579894 -382.15197) (xy 255.502689 -382.173344) (xy 255.423875 -382.187688)
			(xy 255.34409 -382.194886) (xy 255.304036 -382.195324) (xy 255.261686 -382.194806) (xy 255.17737 -382.186758)
			(xy 255.094201 -382.170731) (xy 255.012932 -382.146871) (xy 254.934299 -382.115394) (xy 254.859015 -382.076585)
			(xy 254.78776 -382.030795) (xy 254.721181 -381.978439) (xy 254.65988 -381.919991) (xy 254.604413 -381.855981)
			(xy 254.555281 -381.786988) (xy 254.512931 -381.713637) (xy 254.477745 -381.636592) (xy 254.450042 -381.556552)
			(xy 254.430073 -381.47424) (xy 254.418018 -381.390403) (xy 254.413988 -381.3058) (xy 251.529144 -381.3058)
			(xy 251.525114 -381.390406) (xy 251.513059 -381.474245) (xy 251.49309 -381.556559) (xy 251.465386 -381.636602)
			(xy 251.430199 -381.713649) (xy 251.387847 -381.787003) (xy 251.338714 -381.855998) (xy 251.283246 -381.920011)
			(xy 251.221943 -381.97846) (xy 251.155362 -382.030818) (xy 251.084106 -382.07661) (xy 251.008819 -382.115421)
			(xy 250.930184 -382.1469) (xy 250.848913 -382.170761) (xy 250.765741 -382.186788) (xy 250.681423 -382.194837)
			(xy 250.639072 -382.195324) (xy 250.59902 -382.194855) (xy 250.519239 -382.18765) (xy 250.44043 -382.173302)
			(xy 250.36323 -382.151926) (xy 250.288264 -382.123696) (xy 250.21614 -382.08884) (xy 250.147442 -382.04764)
			(xy 250.082727 -382.000431) (xy 250.052332 -381.974344) (xy 250.045219 -381.968649) (xy 250.028163 -381.962271)
			(xy 250.019058 -381.961898) (xy 249.989086 -381.961898) (xy 249.979985 -381.962287) (xy 249.962935 -381.968665)
			(xy 249.955812 -381.974344) (xy 249.925429 -382.000446) (xy 249.860715 -382.047662) (xy 249.792017 -382.088867)
			(xy 249.719892 -382.123727) (xy 249.644924 -382.15196) (xy 249.567721 -382.173336) (xy 249.488909 -382.187683)
			(xy 249.409126 -382.194885) (xy 249.369072 -382.195324) (xy 249.326725 -382.194787) (xy 249.242415 -382.186734)
			(xy 249.159252 -382.170703) (xy 249.07799 -382.14684) (xy 248.999364 -382.115361) (xy 248.924086 -382.07655)
			(xy 248.852838 -382.03076) (xy 248.786265 -381.978404) (xy 248.72497 -381.919958) (xy 248.669508 -381.85595)
			(xy 248.620382 -381.78696) (xy 248.578036 -381.713612) (xy 248.542853 -381.636572) (xy 248.515153 -381.556536)
			(xy 248.495186 -381.47423) (xy 248.483133 -381.390398) (xy 248.479103 -381.3058) (xy 245.594129 -381.3058)
			(xy 245.590098 -381.390402) (xy 245.578045 -381.474238) (xy 245.558077 -381.556549) (xy 245.530375 -381.636588)
			(xy 245.49519 -381.713633) (xy 245.452841 -381.786983) (xy 245.403712 -381.855976) (xy 245.348247 -381.919987)
			(xy 245.286948 -381.978436) (xy 245.220371 -382.030793) (xy 245.149119 -382.076585) (xy 245.073836 -382.115396)
			(xy 244.995206 -382.146876) (xy 244.913939 -382.170738) (xy 244.830771 -382.186768) (xy 244.746457 -382.19482)
			(xy 244.704108 -382.195324) (xy 244.664055 -382.194894) (xy 244.584273 -382.187684) (xy 244.505463 -382.17333)
			(xy 244.428262 -382.151948) (xy 244.353297 -382.123713) (xy 244.281173 -382.088852) (xy 244.212476 -382.047647)
			(xy 244.147762 -382.000434) (xy 244.117368 -381.974344) (xy 244.110244 -381.968664) (xy 244.093196 -381.962277)
			(xy 244.084094 -381.961898) (xy 244.054122 -381.961898) (xy 244.045023 -381.962304) (xy 244.027972 -381.968671)
			(xy 244.020848 -381.974344) (xy 243.99045 -382.000429) (xy 243.925739 -382.047646) (xy 243.857043 -382.088853)
			(xy 243.78492 -382.123715) (xy 243.709955 -382.15195) (xy 243.632754 -382.173329) (xy 243.553943 -382.187679)
			(xy 243.474161 -382.194883) (xy 243.434108 -382.195324) (xy 243.391759 -382.194804) (xy 243.307445 -382.186754)
			(xy 243.224278 -382.170726) (xy 243.143012 -382.146864) (xy 243.064381 -382.115386) (xy 242.989099 -382.076576)
			(xy 242.917846 -382.030785) (xy 242.851269 -381.978429) (xy 242.789971 -381.919981) (xy 242.734505 -381.855972)
			(xy 242.685376 -381.786979) (xy 242.643027 -381.713629) (xy 242.607842 -381.636586) (xy 242.58014 -381.556547)
			(xy 242.560172 -381.474237) (xy 242.548118 -381.390402) (xy 242.544088 -381.3058) (xy 210.342093 -381.3058)
			(xy 210.341701 -381.307812) (xy 210.317278 -381.389976) (xy 210.285069 -381.46941) (xy 210.24537 -381.545379)
			(xy 210.19855 -381.617179) (xy 210.145043 -381.684144) (xy 210.085345 -381.745654) (xy 210.020009 -381.801138)
			(xy 209.985102 -381.826008) (xy 209.974688 -381.83312) (xy 209.963258 -381.854964) (xy 209.963258 -381.963676)
			(xy 209.974688 -381.98552) (xy 209.985102 -381.992632) (xy 210.01406 -382.013222) (xy 210.068951 -382.058351)
			(xy 210.12007 -382.10771) (xy 210.143852 -382.13411) (xy 210.151218 -382.142238) (xy 210.17103 -382.151128)
			(xy 210.185254 -382.151128) (xy 210.222685 -382.151585) (xy 210.297185 -382.15895) (xy 210.370604 -382.173583)
			(xy 210.442234 -382.195344) (xy 210.511386 -382.224024) (xy 210.577393 -382.259345) (xy 210.639619 -382.300967)
			(xy 210.697464 -382.34849) (xy 210.724242 -382.374648) (xy 211.201254 -382.85166) (xy 211.227392 -382.878448)
			(xy 211.274875 -382.936307) (xy 211.316459 -382.998541) (xy 211.351744 -383.064551) (xy 211.380389 -383.133701)
			(xy 211.402119 -383.205326) (xy 211.416725 -383.278736) (xy 211.424066 -383.353224) (xy 211.42452 -383.390648)
			(xy 211.42452 -384.066034) (xy 211.424074 -384.103459) (xy 211.416734 -384.177947) (xy 211.402128 -384.251357)
			(xy 211.380397 -384.322982) (xy 211.35175 -384.392132) (xy 211.316462 -384.458141) (xy 211.274875 -384.520373)
			(xy 211.227388 -384.578229) (xy 211.201254 -384.605022) (xy 210.724242 -385.082034) (xy 210.697064 -385.108539)
			(xy 210.638306 -385.156617) (xy 210.575065 -385.198622) (xy 210.507965 -385.234141) (xy 210.43767 -385.262821)
			(xy 210.401408 -385.274058) (xy 210.391605 -385.277473) (xy 210.37566 -385.290734) (xy 210.366237 -385.309208)
			(xy 210.365086 -385.319524) (xy 210.362173 -385.358757) (xy 210.350296 -385.436532) (xy 210.331593 -385.512953)
			(xy 210.30621 -385.587423) (xy 210.290664 -385.623562) (xy 210.286853 -385.633502) (xy 210.286866 -385.654763)
			(xy 210.290664 -385.66471) (xy 210.308901 -385.707375) (xy 210.337437 -385.795669) (xy 210.35663 -385.886452)
			(xy 210.366272 -385.978741) (xy 210.366864 -386.025136) (xy 210.366399 -386.06639) (xy 210.358762 -386.148545)
			(xy 210.343548 -386.229638) (xy 210.320887 -386.308974) (xy 210.290975 -386.385869) (xy 210.254068 -386.459663)
			(xy 210.247232 -386.470652) (xy 212.630512 -386.470652) (xy 212.631082 -386.4416) (xy 212.639874 -386.384165)
			(xy 212.657276 -386.328728) (xy 212.682887 -386.276573) (xy 212.716113 -386.228907) (xy 212.756186 -386.186832)
			(xy 212.778848 -386.168646) (xy 212.788246 -386.16128) (xy 212.79866 -386.14096) (xy 212.79993 -386.037582)
			(xy 212.790278 -386.017008) (xy 212.781134 -386.009388) (xy 212.75957 -385.991198) (xy 212.721564 -385.949506)
			(xy 212.690115 -385.902669) (xy 212.66591 -385.85171) (xy 212.649478 -385.797741) (xy 212.641176 -385.74194)
			(xy 212.640672 -385.713732) (xy 212.641185 -385.686481) (xy 212.648937 -385.632533) (xy 212.664288 -385.580237)
			(xy 212.686925 -385.530658) (xy 212.716388 -385.484806) (xy 212.752077 -385.443614) (xy 212.793264 -385.407919)
			(xy 212.839113 -385.37845) (xy 212.888688 -385.355806) (xy 212.940982 -385.340448) (xy 212.994929 -385.332689)
			(xy 213.02218 -385.332224) (xy 213.052195 -385.332809) (xy 213.111482 -385.342219) (xy 213.168566 -385.360794)
			(xy 213.222038 -385.388076) (xy 213.270579 -385.423393) (xy 213.292182 -385.444238) (xy 213.299294 -385.45135)
			(xy 213.317074 -385.45897) (xy 213.407752 -385.460494) (xy 213.425786 -385.453636) (xy 213.433152 -385.446778)
			(xy 213.454444 -385.427736) (xy 213.501644 -385.395567) (xy 213.553112 -385.370791) (xy 213.607696 -385.353961)
			(xy 213.66418 -385.345455) (xy 213.69274 -385.344924) (xy 213.719815 -385.345382) (xy 213.77342 -385.353036)
			(xy 213.825402 -385.368199) (xy 213.874716 -385.390566) (xy 213.920368 -385.419687) (xy 213.96144 -385.454975)
			(xy 213.997104 -385.49572) (xy 214.012272 -385.518152) (xy 214.01913 -385.528312) (xy 214.039704 -385.54025)
			(xy 214.145876 -385.5466) (xy 214.16772 -385.536948) (xy 214.175594 -385.52755) (xy 214.193806 -385.50636)
			(xy 214.23537 -385.469019) (xy 214.281936 -385.438141) (xy 214.332508 -385.414386) (xy 214.386005 -385.398262)
			(xy 214.441281 -385.390115) (xy 214.469218 -385.389628) (xy 214.499234 -385.390188) (xy 214.558522 -385.399603)
			(xy 214.615606 -385.418184) (xy 214.669078 -385.445472) (xy 214.717618 -385.480794) (xy 214.73922 -385.501642)
			(xy 214.746332 -385.508754) (xy 214.764112 -385.516374) (xy 214.85479 -385.517898) (xy 214.872824 -385.51104)
			(xy 214.88019 -385.504182) (xy 214.901508 -385.48517) (xy 214.948701 -385.452996) (xy 215.000162 -385.428214)
			(xy 215.054741 -385.411378) (xy 215.11122 -385.402863) (xy 215.139778 -385.402328) (xy 215.168755 -385.402882)
			(xy 215.226044 -385.411639) (xy 215.281351 -385.428954) (xy 215.333406 -385.45443) (xy 215.381011 -385.487481)
			(xy 215.423074 -385.527349) (xy 215.441276 -385.549902) (xy 215.448896 -385.559808) (xy 215.471756 -385.570222)
			(xy 215.580976 -385.563364) (xy 215.602312 -385.550156) (xy 215.608916 -385.539488) (xy 215.623759 -385.515449)
			(xy 215.65937 -385.471594) (xy 215.701063 -385.433474) (xy 215.747926 -385.401925) (xy 215.798932 -385.377637)
			(xy 215.852963 -385.361143) (xy 215.908837 -385.352803) (xy 215.937084 -385.35229) (xy 215.96688 -385.352819)
			(xy 216.025747 -385.362083) (xy 216.082457 -385.380389) (xy 216.135631 -385.407291) (xy 216.183975 -385.442135)
			(xy 216.226312 -385.484072) (xy 216.244424 -385.507738) (xy 216.25179 -385.517644) (xy 216.273126 -385.528566)
			(xy 216.379552 -385.528312) (xy 216.401142 -385.517644) (xy 216.408254 -385.507738) (xy 216.426378 -385.48399)
			(xy 216.468729 -385.441863) (xy 216.517131 -385.406854) (xy 216.570398 -385.37982) (xy 216.62723 -385.361421)
			(xy 216.686234 -385.352108) (xy 216.716102 -385.351528) (xy 216.746117 -385.352098) (xy 216.805406 -385.361511)
			(xy 216.862489 -385.38009) (xy 216.915961 -385.407375) (xy 216.964502 -385.442695) (xy 216.986104 -385.463542)
			(xy 216.993216 -385.470654) (xy 217.010996 -385.478274) (xy 217.101674 -385.479798) (xy 217.119708 -385.47294)
			(xy 217.127074 -385.466082) (xy 217.148399 -385.447078) (xy 217.19559 -385.414903) (xy 217.247049 -385.39012)
			(xy 217.301627 -385.373281) (xy 217.358104 -385.364764) (xy 217.386662 -385.364228) (xy 217.415602 -385.36477)
			(xy 217.472819 -385.373499) (xy 217.528064 -385.390763) (xy 217.580071 -385.416167) (xy 217.627648 -385.449128)
			(xy 217.649044 -385.468622) (xy 217.65641 -385.475734) (xy 217.675714 -385.4831) (xy 217.769186 -385.479036)
			(xy 217.787728 -385.470146) (xy 217.794586 -385.462526) (xy 217.812785 -385.442813) (xy 217.853733 -385.408151)
			(xy 217.899131 -385.379564) (xy 217.948085 -385.357615) (xy 217.999629 -385.342736) (xy 218.052749 -385.335221)
			(xy 218.079574 -385.334764) (xy 218.106823 -385.335302) (xy 218.160768 -385.343055) (xy 218.21306 -385.358405)
			(xy 218.262635 -385.381041) (xy 218.308484 -385.410502) (xy 218.349674 -385.446188) (xy 218.385366 -385.487373)
			(xy 218.414833 -385.533218) (xy 218.437476 -385.58279) (xy 218.452834 -385.63508) (xy 218.460594 -385.689023)
			(xy 218.461082 -385.716272) (xy 218.460594 -385.743332) (xy 218.452933 -385.796908) (xy 218.437775 -385.848862)
			(xy 218.415424 -385.898151) (xy 218.386329 -385.943786) (xy 218.351075 -385.984849) (xy 218.331034 -386.003038)
			(xy 218.322906 -386.010404) (xy 218.313762 -386.030216) (xy 218.313254 -386.128006) (xy 218.322144 -386.148072)
			(xy 218.330272 -386.155184) (xy 218.349929 -386.173354) (xy 218.384451 -386.214263) (xy 218.412919 -386.259594)
			(xy 218.434775 -386.308458) (xy 218.449589 -386.359896) (xy 218.457073 -386.4129) (xy 218.457526 -386.439664)
			(xy 218.457011 -386.466915) (xy 218.44926 -386.520863) (xy 218.433909 -386.573159) (xy 218.411272 -386.622738)
			(xy 218.38181 -386.66859) (xy 218.346121 -386.709783) (xy 218.304934 -386.745477) (xy 218.259085 -386.774946)
			(xy 218.20951 -386.79759) (xy 218.157216 -386.812948) (xy 218.103269 -386.820707) (xy 218.076018 -386.821172)
			(xy 218.049468 -386.820714) (xy 217.996882 -386.813336) (xy 217.945828 -386.798735) (xy 217.897294 -386.777192)
			(xy 217.852218 -386.749124) (xy 217.811471 -386.715075) (xy 217.793316 -386.695696) (xy 217.786204 -386.688076)
			(xy 217.767916 -386.67944) (xy 217.674698 -386.67563) (xy 217.655902 -386.682742) (xy 217.648282 -386.689854)
			(xy 217.626916 -386.70924) (xy 217.57946 -386.742042) (xy 217.527606 -386.767324) (xy 217.472536 -386.78451)
			(xy 217.415506 -386.793206) (xy 217.386662 -386.79374) (xy 217.356645 -386.793202) (xy 217.297355 -386.783782)
			(xy 217.240271 -386.765197) (xy 217.1868 -386.737904) (xy 217.138261 -386.702576) (xy 217.11666 -386.681726)
			(xy 217.109548 -386.674614) (xy 217.091768 -386.666994) (xy 217.00109 -386.66547) (xy 216.983056 -386.672328)
			(xy 216.97569 -386.679186) (xy 216.95439 -386.698218) (xy 216.907191 -386.730387) (xy 216.855725 -386.755164)
			(xy 216.801143 -386.771995) (xy 216.744661 -386.780507) (xy 216.716102 -386.78104) (xy 216.686306 -386.780509)
			(xy 216.62744 -386.771244) (xy 216.57073 -386.752937) (xy 216.517557 -386.726035) (xy 216.469213 -386.691193)
			(xy 216.426875 -386.649257) (xy 216.408762 -386.625592) (xy 216.401396 -386.615686) (xy 216.38006 -386.604764)
			(xy 216.273634 -386.605018) (xy 216.252044 -386.615686) (xy 216.244932 -386.625592) (xy 216.226824 -386.649353)
			(xy 216.184469 -386.691478) (xy 216.136064 -386.726484) (xy 216.082793 -386.753516) (xy 216.025959 -386.771912)
			(xy 215.966952 -386.781223) (xy 215.937084 -386.781802) (xy 215.908105 -386.781302) (xy 215.850812 -386.772538)
			(xy 215.795503 -386.755214) (xy 215.743448 -386.729728) (xy 215.695844 -386.696665) (xy 215.653785 -386.656787)
			(xy 215.635586 -386.634228) (xy 215.627966 -386.624322) (xy 215.605106 -386.613908) (xy 215.495886 -386.620766)
			(xy 215.47455 -386.633974) (xy 215.467946 -386.644642) (xy 215.45314 -386.668704) (xy 215.417522 -386.712559)
			(xy 215.375822 -386.750676) (xy 215.328953 -386.782222) (xy 215.277941 -386.806506) (xy 215.223905 -386.822995)
			(xy 215.168026 -386.83133) (xy 215.139778 -386.83184) (xy 215.109762 -386.831292) (xy 215.050472 -386.821875)
			(xy 214.993388 -386.803292) (xy 214.939916 -386.776001) (xy 214.891377 -386.740675) (xy 214.869776 -386.719826)
			(xy 214.862664 -386.712714) (xy 214.844884 -386.705094) (xy 214.754206 -386.70357) (xy 214.736172 -386.710428)
			(xy 214.728806 -386.717286) (xy 214.707499 -386.736311) (xy 214.660302 -386.76848) (xy 214.608838 -386.793259)
			(xy 214.554257 -386.810092) (xy 214.497777 -386.818605) (xy 214.469218 -386.81914) (xy 214.440741 -386.818606)
			(xy 214.384418 -386.810148) (xy 214.329981 -386.793403) (xy 214.278642 -386.768743) (xy 214.231544 -386.736718)
			(xy 214.189737 -386.698041) (xy 214.17153 -386.676138) (xy 214.163656 -386.666232) (xy 214.141304 -386.656326)
			(xy 214.033608 -386.662676) (xy 214.012526 -386.675122) (xy 214.005922 -386.68579) (xy 213.990893 -386.708914)
			(xy 213.955204 -386.750959) (xy 213.913833 -386.787427) (xy 213.867642 -386.817557) (xy 213.817593 -386.840721)
			(xy 213.76473 -386.856436) (xy 213.710155 -386.864375) (xy 213.68258 -386.86486) (xy 213.652564 -386.864305)
			(xy 213.593275 -386.854889) (xy 213.536191 -386.836307) (xy 213.48272 -386.809018) (xy 213.43418 -386.773694)
			(xy 213.412578 -386.752846) (xy 213.405466 -386.745734) (xy 213.387686 -386.738114) (xy 213.297008 -386.73659)
			(xy 213.278974 -386.743448) (xy 213.271608 -386.750306) (xy 213.250289 -386.769317) (xy 213.203096 -386.801491)
			(xy 213.151636 -386.826274) (xy 213.097057 -386.84311) (xy 213.040578 -386.851625) (xy 213.01202 -386.85216)
			(xy 212.984765 -386.851726) (xy 212.930811 -386.84397) (xy 212.87851 -386.828615) (xy 212.828926 -386.805971)
			(xy 212.783071 -386.7765) (xy 212.741877 -386.740803) (xy 212.706183 -386.699607) (xy 212.676716 -386.653749)
			(xy 212.654076 -386.604164) (xy 212.638724 -386.551862) (xy 212.630972 -386.497907) (xy 212.630512 -386.470652)
			(xy 210.247232 -386.470652) (xy 210.210484 -386.529721) (xy 210.160598 -386.59544) (xy 210.104839 -386.656256)
			(xy 210.043686 -386.711645) (xy 209.977665 -386.761132) (xy 209.907344 -386.80429) (xy 209.870548 -386.82295)
			(xy 209.862237 -386.82751) (xy 209.849486 -386.841519) (xy 209.842679 -386.859197) (xy 209.842354 -386.86867)
			(xy 209.842354 -386.959602) (xy 209.842685 -386.969079) (xy 209.849468 -386.986774) (xy 209.862218 -387.000793)
			(xy 209.870548 -387.005322) (xy 209.907343 -387.02398) (xy 209.97765 -387.067153) (xy 210.043658 -387.11665)
			(xy 210.104799 -387.172046) (xy 210.16055 -387.232865) (xy 210.210429 -387.298584) (xy 210.25401 -387.36864)
			(xy 210.290917 -387.442429) (xy 210.320833 -387.519319) (xy 210.343503 -387.598648) (xy 210.35873 -387.679735)
			(xy 210.366384 -387.761884) (xy 210.366864 -387.803136) (xy 210.366277 -387.849532) (xy 210.35664 -387.941821)
			(xy 210.337443 -388.032604) (xy 210.308894 -388.120894) (xy 210.291966 -388.160514) (xy 221.30132 -388.160514)
			(xy 221.305305 -387.979173) (xy 221.317251 -387.798181) (xy 221.337135 -387.617889) (xy 221.364919 -387.438645)
			(xy 221.40055 -387.260793) (xy 221.443958 -387.084679) (xy 221.49506 -386.910641) (xy 221.553758 -386.739016)
			(xy 221.619937 -386.570135) (xy 221.69347 -386.404323) (xy 221.774215 -386.241902) (xy 221.862017 -386.083183)
			(xy 221.956706 -385.928475) (xy 222.058098 -385.778075) (xy 222.165999 -385.632274) (xy 222.2802 -385.491353)
			(xy 222.400481 -385.355584) (xy 222.526609 -385.22523) (xy 222.658341 -385.100541) (xy 222.795423 -384.981759)
			(xy 222.93759 -384.869113) (xy 223.084567 -384.76282) (xy 223.236072 -384.663086) (xy 223.391811 -384.570102)
			(xy 223.551484 -384.484049) (xy 223.714783 -384.405093) (xy 223.881392 -384.333385) (xy 224.05099 -384.269065)
			(xy 224.22325 -384.212257) (xy 224.397838 -384.163069) (xy 224.574419 -384.121598) (xy 224.752651 -384.087923)
			(xy 224.93219 -384.062109) (xy 225.112689 -384.044207) (xy 225.293801 -384.034249) (xy 225.475175 -384.032257)
			(xy 225.656462 -384.038233) (xy 225.837311 -384.052167) (xy 226.017374 -384.07403) (xy 226.196302 -384.103782)
			(xy 226.373751 -384.141364) (xy 226.549378 -384.186704) (xy 226.722844 -384.239715) (xy 226.893814 -384.300294)
			(xy 227.061959 -384.368324) (xy 227.226952 -384.443674) (xy 227.388477 -384.526199) (xy 227.546221 -384.615739)
			(xy 227.69988 -384.712121) (xy 227.849157 -384.815159) (xy 227.993764 -384.924655) (xy 228.133422 -385.040397)
			(xy 228.267862 -385.162162) (xy 228.396823 -385.289714) (xy 228.520057 -385.422808) (xy 228.637326 -385.561186)
			(xy 228.748404 -385.704582) (xy 228.853076 -385.852718) (xy 228.95114 -386.005309) (xy 229.042407 -386.16206)
			(xy 229.126701 -386.322669) (xy 229.203859 -386.486825) (xy 229.273732 -386.654212) (xy 229.336186 -386.824506)
			(xy 229.391098 -386.997379) (xy 229.438365 -387.172498) (xy 229.477894 -387.349523) (xy 229.509609 -387.528114)
			(xy 229.53345 -387.707926) (xy 229.549369 -387.888611) (xy 229.557336 -388.069821) (xy 229.557834 -388.160514)
			(xy 229.557336 -388.251207) (xy 229.549369 -388.432417) (xy 229.53345 -388.613102) (xy 229.509609 -388.792914)
			(xy 229.477894 -388.971505) (xy 229.438365 -389.14853) (xy 229.391098 -389.323649) (xy 229.336186 -389.496522)
			(xy 229.273732 -389.666816) (xy 229.203859 -389.834203) (xy 229.126701 -389.998359) (xy 229.042407 -390.158968)
			(xy 228.95114 -390.315719) (xy 228.853076 -390.46831) (xy 228.748404 -390.616446) (xy 228.637326 -390.759842)
			(xy 228.520057 -390.89822) (xy 228.396823 -391.031314) (xy 228.267862 -391.158866) (xy 228.133422 -391.280631)
			(xy 227.993764 -391.396373) (xy 227.849157 -391.505869) (xy 227.69988 -391.608907) (xy 227.546221 -391.705289)
			(xy 227.388477 -391.794829) (xy 227.226952 -391.877354) (xy 227.061959 -391.952704) (xy 226.893814 -392.020734)
			(xy 226.722844 -392.081313) (xy 226.549378 -392.134324) (xy 226.373751 -392.179664) (xy 226.196302 -392.217246)
			(xy 226.017374 -392.246998) (xy 225.837311 -392.268861) (xy 225.656462 -392.282795) (xy 225.475175 -392.288771)
			(xy 225.293801 -392.286779) (xy 225.112689 -392.276821) (xy 224.93219 -392.258919) (xy 224.752651 -392.233105)
			(xy 224.574419 -392.19943) (xy 224.397838 -392.157959) (xy 224.22325 -392.108771) (xy 224.05099 -392.051963)
			(xy 223.881392 -391.987643) (xy 223.714783 -391.915935) (xy 223.551484 -391.836979) (xy 223.391811 -391.750926)
			(xy 223.236072 -391.657942) (xy 223.084567 -391.558208) (xy 222.93759 -391.451915) (xy 222.795423 -391.339269)
			(xy 222.658341 -391.220487) (xy 222.526609 -391.095798) (xy 222.400481 -390.965444) (xy 222.2802 -390.829675)
			(xy 222.165999 -390.688754) (xy 222.058098 -390.542953) (xy 221.956706 -390.392553) (xy 221.862017 -390.237845)
			(xy 221.774215 -390.079126) (xy 221.69347 -389.916705) (xy 221.619937 -389.750893) (xy 221.553758 -389.582012)
			(xy 221.49506 -389.410387) (xy 221.443958 -389.236349) (xy 221.40055 -389.060235) (xy 221.364919 -388.882383)
			(xy 221.337135 -388.703139) (xy 221.317251 -388.522847) (xy 221.305305 -388.341855) (xy 221.30132 -388.160514)
			(xy 210.291966 -388.160514) (xy 210.290664 -388.163562) (xy 210.286853 -388.173502) (xy 210.286866 -388.194763)
			(xy 210.290664 -388.20471) (xy 210.308901 -388.247375) (xy 210.337437 -388.335669) (xy 210.35663 -388.426452)
			(xy 210.366272 -388.518741) (xy 210.366864 -388.565136) (xy 210.36636 -388.607484) (xy 210.358309 -388.691798)
			(xy 210.34228 -388.774964) (xy 210.318419 -388.856231) (xy 210.28694 -388.934861) (xy 210.248129 -389.010142)
			(xy 210.202339 -389.081394) (xy 210.149983 -389.14797) (xy 210.091535 -389.209268) (xy 210.027525 -389.264733)
			(xy 209.958533 -389.313862) (xy 209.885183 -389.356211) (xy 209.80814 -389.391395) (xy 209.728101 -389.419097)
			(xy 209.645792 -389.439065) (xy 209.561957 -389.451118) (xy 209.477356 -389.455149) (xy 209.392755 -389.451118)
			(xy 209.30892 -389.439065) (xy 209.226611 -389.419097) (xy 209.146572 -389.391395) (xy 209.069529 -389.356211)
			(xy 208.996179 -389.313862) (xy 208.927187 -389.264733) (xy 208.863177 -389.209268) (xy 208.804729 -389.14797)
			(xy 208.752373 -389.081394) (xy 208.706583 -389.010142) (xy 208.667772 -388.934861) (xy 208.636293 -388.856231)
			(xy 208.612432 -388.774964) (xy 208.596403 -388.691798) (xy 208.588352 -388.607484) (xy 208.587848 -388.565136)
			(xy 208.588431 -388.51874) (xy 208.598061 -388.426448) (xy 208.617252 -388.335662) (xy 208.645795 -388.247369)
			(xy 208.664048 -388.20471) (xy 208.667874 -388.19477) (xy 208.667888 -388.173496) (xy 208.664048 -388.163562)
			(xy 208.645812 -388.120897) (xy 208.617278 -388.032603) (xy 208.598088 -387.941819) (xy 208.588449 -387.849531)
			(xy 208.587848 -387.803136) (xy 208.588314 -387.761882) (xy 208.595954 -387.67973) (xy 208.61117 -387.598638)
			(xy 208.633833 -387.519305) (xy 208.663747 -387.442412) (xy 208.700655 -387.36862) (xy 208.74424 -387.298565)
			(xy 208.794127 -387.232848) (xy 208.849887 -387.172035) (xy 208.911041 -387.116648) (xy 208.977062 -387.067165)
			(xy 209.047382 -387.02401) (xy 209.084164 -387.005322) (xy 209.09247 -387.000759) (xy 209.10521 -386.986748)
			(xy 209.112006 -386.969072) (xy 209.112358 -386.959602) (xy 209.112358 -386.86867) (xy 209.112022 -386.859195)
			(xy 209.105234 -386.841507) (xy 209.092484 -386.827494) (xy 209.084164 -386.82295) (xy 209.04737 -386.804292)
			(xy 208.977063 -386.761119) (xy 208.911056 -386.711622) (xy 208.849915 -386.656226) (xy 208.794166 -386.595407)
			(xy 208.744288 -386.529687) (xy 208.700709 -386.459632) (xy 208.663804 -386.385842) (xy 208.633889 -386.308953)
			(xy 208.611222 -386.229623) (xy 208.595997 -386.148536) (xy 208.588346 -386.066388) (xy 208.587848 -386.025136)
			(xy 208.588431 -385.97874) (xy 208.598061 -385.886448) (xy 208.617252 -385.795662) (xy 208.645795 -385.707369)
			(xy 208.664048 -385.66471) (xy 208.667874 -385.65477) (xy 208.667888 -385.633496) (xy 208.664048 -385.623562)
			(xy 208.645511 -385.580209) (xy 208.616646 -385.490444) (xy 208.597448 -385.398127) (xy 208.592166 -385.351274)
			(xy 208.590134 -385.331462) (xy 208.561432 -385.3053) (xy 208.355946 -385.3053) (xy 208.327244 -385.331462)
			(xy 208.325212 -385.351274) (xy 208.319873 -385.398267) (xy 208.300515 -385.490847) (xy 208.271456 -385.580854)
			(xy 208.252822 -385.624324) (xy 208.248897 -385.634388) (xy 208.249017 -385.65597) (xy 208.253076 -385.66598)
			(xy 208.272159 -385.709456) (xy 208.302017 -385.799591) (xy 208.322114 -385.892392) (xy 208.33222 -385.986804)
			(xy 208.332832 -386.03428) (xy 208.332371 -386.075107) (xy 208.324887 -386.156419) (xy 208.309981 -386.236702)
			(xy 208.287779 -386.31528) (xy 208.258466 -386.391492) (xy 208.222291 -386.464696) (xy 208.179557 -386.534276)
			(xy 208.130625 -386.599646) (xy 208.075906 -386.660254) (xy 208.015862 -386.715591) (xy 207.950998 -386.765191)
			(xy 207.88186 -386.808636) (xy 207.84566 -386.827522) (xy 207.832706 -386.834126) (xy 207.81772 -386.85851)
			(xy 207.817974 -386.978144) (xy 207.83296 -387.002274) (xy 207.845914 -387.008878) (xy 207.882235 -387.027718)
			(xy 207.951602 -387.071122) (xy 208.01669 -387.120714) (xy 208.076947 -387.176075) (xy 208.131863 -387.236737)
			(xy 208.180976 -387.302186) (xy 208.223869 -387.371871) (xy 208.26018 -387.445201) (xy 208.289601 -387.521556)
			(xy 208.311884 -387.600291) (xy 208.326841 -387.68074) (xy 208.334345 -387.762222) (xy 208.334864 -387.803136)
			(xy 208.334277 -387.849532) (xy 208.32464 -387.941821) (xy 208.305443 -388.032604) (xy 208.276894 -388.120894)
			(xy 208.258664 -388.163562) (xy 208.254853 -388.173502) (xy 208.254866 -388.194763) (xy 208.258664 -388.20471)
			(xy 208.276901 -388.247375) (xy 208.305437 -388.335669) (xy 208.32463 -388.426452) (xy 208.334272 -388.518741)
			(xy 208.334864 -388.565136) (xy 208.33436 -388.607484) (xy 208.326309 -388.691798) (xy 208.31028 -388.774964)
			(xy 208.286419 -388.856231) (xy 208.25494 -388.934861) (xy 208.216129 -389.010142) (xy 208.170339 -389.081394)
			(xy 208.117983 -389.14797) (xy 208.059535 -389.209268) (xy 207.995525 -389.264733) (xy 207.926533 -389.313862)
			(xy 207.853183 -389.356211) (xy 207.77614 -389.391395) (xy 207.696101 -389.419097) (xy 207.613792 -389.439065)
			(xy 207.529957 -389.451118) (xy 207.445356 -389.455149) (xy 207.360755 -389.451118) (xy 207.27692 -389.439065)
			(xy 207.194611 -389.419097) (xy 207.114572 -389.391395) (xy 207.037529 -389.356211) (xy 206.964179 -389.313862)
			(xy 206.895187 -389.264733) (xy 206.831177 -389.209268) (xy 206.772729 -389.14797) (xy 206.720373 -389.081394)
			(xy 206.674583 -389.010142) (xy 206.635772 -388.934861) (xy 206.604293 -388.856231) (xy 206.580432 -388.774964)
			(xy 206.564403 -388.691798) (xy 206.556352 -388.607484) (xy 206.555848 -388.565136) (xy 206.556431 -388.51874)
			(xy 206.566061 -388.426448) (xy 206.585252 -388.335662) (xy 206.613795 -388.247369) (xy 206.632048 -388.20471)
			(xy 206.635874 -388.19477) (xy 206.635888 -388.173496) (xy 206.632048 -388.163562) (xy 206.613812 -388.120897)
			(xy 206.585278 -388.032603) (xy 206.566088 -387.941819) (xy 206.556449 -387.849531) (xy 206.555848 -387.803136)
			(xy 206.556309 -387.762309) (xy 206.563791 -387.680998) (xy 206.578697 -387.600716) (xy 206.600899 -387.522138)
			(xy 206.630213 -387.445927) (xy 206.666389 -387.372724) (xy 206.709124 -387.303146) (xy 206.758058 -387.237779)
			(xy 206.812779 -387.177173) (xy 206.872826 -387.121839) (xy 206.937692 -387.072243) (xy 207.006832 -387.028803)
			(xy 207.04302 -387.009894) (xy 207.055974 -387.00329) (xy 207.07096 -386.978906) (xy 207.070706 -386.859272)
			(xy 207.05572 -386.835142) (xy 207.042766 -386.828538) (xy 207.006442 -386.8097) (xy 206.937068 -386.766301)
			(xy 206.871975 -386.716712) (xy 206.811711 -386.661353) (xy 206.756788 -386.600692) (xy 206.70767 -386.535243)
			(xy 206.664772 -386.465558) (xy 206.628456 -386.392227) (xy 206.59903 -386.31587) (xy 206.576743 -386.237133)
			(xy 206.561784 -386.156681) (xy 206.554277 -386.075195) (xy 206.553816 -386.03428) (xy 206.554436 -385.987776)
			(xy 206.564166 -385.895279) (xy 206.583486 -385.8043) (xy 206.612186 -385.715832) (xy 206.630524 -385.673092)
			(xy 206.634456 -385.663028) (xy 206.634342 -385.641442) (xy 206.63027 -385.631436) (xy 206.610743 -385.586941)
			(xy 206.580388 -385.49463) (xy 206.560278 -385.399559) (xy 206.554832 -385.351274) (xy 206.5528 -385.331462)
			(xy 206.524098 -385.3053) (xy 206.32928 -385.3053) (xy 206.300578 -385.331462) (xy 206.298546 -385.351274)
			(xy 206.29326 -385.398127) (xy 206.274055 -385.490441) (xy 206.245203 -385.58021) (xy 206.226664 -385.623562)
			(xy 206.222853 -385.633502) (xy 206.222866 -385.654763) (xy 206.226664 -385.66471) (xy 206.244901 -385.707375)
			(xy 206.273437 -385.795669) (xy 206.29263 -385.886452) (xy 206.302272 -385.978741) (xy 206.302864 -386.025136)
			(xy 206.30236 -386.067484) (xy 206.294309 -386.151798) (xy 206.27828 -386.234964) (xy 206.254419 -386.316231)
			(xy 206.22294 -386.394861) (xy 206.184129 -386.470142) (xy 206.138339 -386.541394) (xy 206.085983 -386.60797)
			(xy 206.027535 -386.669268) (xy 205.963525 -386.724733) (xy 205.894533 -386.773862) (xy 205.821183 -386.816211)
			(xy 205.74414 -386.851395) (xy 205.664101 -386.879097) (xy 205.581792 -386.899065) (xy 205.497957 -386.911118)
			(xy 205.413356 -386.915149) (xy 205.328755 -386.911118) (xy 205.24492 -386.899065) (xy 205.162611 -386.879097)
			(xy 205.082572 -386.851395) (xy 205.005529 -386.816211) (xy 204.932179 -386.773862) (xy 204.863187 -386.724733)
			(xy 204.799177 -386.669268) (xy 204.740729 -386.60797) (xy 204.688373 -386.541394) (xy 204.642583 -386.470142)
			(xy 204.603772 -386.394861) (xy 204.572293 -386.316231) (xy 204.548432 -386.234964) (xy 204.532403 -386.151798)
			(xy 204.524352 -386.067484) (xy 204.523848 -386.025136) (xy 204.524431 -385.97874) (xy 204.534061 -385.886448)
			(xy 204.553252 -385.795662) (xy 204.581795 -385.707369) (xy 204.600048 -385.66471) (xy 204.603874 -385.65477)
			(xy 204.603888 -385.633496) (xy 204.600048 -385.623562) (xy 204.581511 -385.580209) (xy 204.552646 -385.490444)
			(xy 204.533448 -385.398127) (xy 204.528166 -385.351274) (xy 204.526134 -385.331462) (xy 204.497432 -385.3053)
			(xy 203.042012 -385.3053) (xy 203.031989 -385.305717) (xy 203.013468 -385.313385) (xy 202.999292 -385.327558)
			(xy 202.99162 -385.346077) (xy 202.991212 -385.3561) (xy 202.991212 -389.760968) (xy 202.990777 -389.771033)
			(xy 202.983047 -389.789621) (xy 202.976226 -389.797036) (xy 200.82256 -391.950702) (xy 200.815159 -391.957542)
			(xy 200.796561 -391.965261) (xy 200.786492 -391.965688) (xy 199.179942 -391.965688) (xy 199.169876 -391.966121)
			(xy 199.151286 -391.973849) (xy 199.143874 -391.980674) (xy 196.179694 -394.944854) (xy 196.172857 -394.952256)
			(xy 196.165143 -394.970854) (xy 196.164708 -394.980922) (xy 196.164708 -397.79067) (xy 196.165144 -397.800734)
			(xy 196.172877 -397.81932) (xy 196.179694 -397.826738) (xy 197.656704 -399.304002) (xy 197.664103 -399.310848)
			(xy 197.682701 -399.31858) (xy 197.692772 -399.318988)
		)
		(stroke
			(width 0)
			(type solid)
		)
		(fill yes)
		(layer "In6.Cu")
		(net "P12V_AUX")
	)
	(gr_poly
		(pts
			(xy 259.281168 -136.761982) (xy 259.290524 -136.761508) (xy 259.307975 -136.754733) (xy 259.315204 -136.748774)
			(xy 259.372862 -136.695942) (xy 259.381498 -136.678924) (xy 259.38226 -136.669272) (xy 259.385279 -136.641145)
			(xy 259.398558 -136.586159) (xy 259.419811 -136.533736) (xy 259.44857 -136.485025) (xy 259.484206 -136.441094)
			(xy 259.525938 -136.402906) (xy 259.572851 -136.371299) (xy 259.623916 -136.346964) (xy 259.678014 -136.330435)
			(xy 259.73396 -136.322075) (xy 259.762244 -136.321546) (xy 259.789494 -136.322035) (xy 259.84344 -136.329796)
			(xy 259.895732 -136.345155) (xy 259.945307 -136.367798) (xy 259.991155 -136.397264) (xy 260.032343 -136.432955)
			(xy 260.068034 -136.474144) (xy 260.097501 -136.519992) (xy 260.120145 -136.569566) (xy 260.135503 -136.621858)
			(xy 260.143265 -136.675804) (xy 260.143752 -136.703054) (xy 260.143752 -136.711182) (xy 260.144236 -136.721196)
			(xy 260.151891 -136.739702) (xy 260.166043 -136.753872) (xy 260.184539 -136.761551) (xy 260.194552 -136.761982)
			(xy 260.222492 -136.761982) (xy 260.236208 -136.758172) (xy 260.24205 -136.754362) (xy 260.268979 -136.738202)
			(xy 260.326017 -136.711911) (xy 260.385856 -136.692841) (xy 260.447589 -136.681282) (xy 260.510274 -136.677409)
			(xy 260.572959 -136.681282) (xy 260.634692 -136.692841) (xy 260.694531 -136.711911) (xy 260.751569 -136.738202)
			(xy 260.778498 -136.754362) (xy 260.805168 -136.761982) (xy 261.73684 -136.761982) (xy 261.746198 -136.761513)
			(xy 261.763655 -136.754745) (xy 261.770876 -136.748774) (xy 261.828534 -136.695942) (xy 261.83717 -136.678924)
			(xy 261.837932 -136.669272) (xy 261.840769 -136.642563) (xy 261.852986 -136.59026) (xy 261.872417 -136.540188)
			(xy 261.898678 -136.493335) (xy 261.931249 -136.450627) (xy 261.969488 -136.41291) (xy 262.012639 -136.380928)
			(xy 262.059848 -136.355312) (xy 262.110183 -136.336571) (xy 262.162648 -136.325073) (xy 262.216208 -136.321046)
			(xy 262.269802 -136.32457) (xy 262.322374 -136.335575) (xy 262.372882 -136.353844) (xy 262.420329 -136.379015)
			(xy 262.463778 -136.410591) (xy 262.483346 -136.428988) (xy 262.498586 -136.413748) (xy 269.100554 -136.413748)
			(xy 270.43888 -136.413748) (xy 270.789908 -136.06272) (xy 276.6314 -136.06272) (xy 276.76348 -135.93064)
			(xy 276.76348 -134.247382) (xy 276.770326 -134.239983) (xy 276.778057 -134.221385) (xy 276.778466 -134.211314)
			(xy 276.778466 -131.255008) (xy 276.778044 -131.244938) (xy 276.770327 -131.226334) (xy 276.76348 -131.21894)
			(xy 275.981668 -130.437128) (xy 275.974269 -130.430283) (xy 275.955671 -130.422556) (xy 275.9456 -130.422142)
			(xy 269.871444 -130.422142) (xy 269.859507 -130.422785) (xy 269.838178 -130.433512) (xy 269.83055 -130.442716)
			(xy 269.812033 -130.466889) (xy 269.770137 -130.511077) (xy 269.746984 -130.530854) (xy 269.738654 -130.538423)
			(xy 269.729023 -130.558731) (xy 269.728442 -130.56997) (xy 269.728442 -130.648202) (xy 269.729095 -130.659422)
			(xy 269.738714 -130.679707) (xy 269.746984 -130.687318) (xy 269.771271 -130.708075) (xy 269.814991 -130.754664)
			(xy 269.852528 -130.806363) (xy 269.883292 -130.862359) (xy 269.906796 -130.921768) (xy 269.922671 -130.983654)
			(xy 269.930666 -131.047041) (xy 269.931134 -131.078986) (xy 269.930632 -131.110947) (xy 269.922621 -131.174365)
			(xy 269.906724 -131.236279) (xy 269.883192 -131.295712) (xy 269.852398 -131.351727) (xy 269.814825 -131.403442)
			(xy 269.771068 -131.450039) (xy 269.721815 -131.490784) (xy 269.667844 -131.525035) (xy 269.610005 -131.552252)
			(xy 269.549212 -131.572005) (xy 269.486422 -131.583983) (xy 269.422626 -131.587997) (xy 269.35883 -131.583983)
			(xy 269.29604 -131.572005) (xy 269.235247 -131.552252) (xy 269.177408 -131.525035) (xy 269.123437 -131.490784)
			(xy 269.074184 -131.450039) (xy 269.030427 -131.403442) (xy 268.992854 -131.351727) (xy 268.96206 -131.295712)
			(xy 268.938528 -131.236279) (xy 268.922631 -131.174365) (xy 268.91462 -131.110947) (xy 268.914118 -131.078986)
			(xy 268.914619 -131.047043) (xy 268.922621 -130.983659) (xy 268.938496 -130.921777) (xy 268.961996 -130.862369)
			(xy 268.99275 -130.806372) (xy 269.030273 -130.754667) (xy 269.073976 -130.708067) (xy 269.098268 -130.687318)
			(xy 269.106586 -130.679744) (xy 269.116196 -130.659437) (xy 269.11681 -130.648202) (xy 269.11681 -130.56997)
			(xy 269.11617 -130.558744) (xy 269.106563 -130.538443) (xy 269.098268 -130.530854) (xy 269.075118 -130.511074)
			(xy 269.033222 -130.466886) (xy 269.014702 -130.442716) (xy 269.007093 -130.433487) (xy 268.985754 -130.422754)
			(xy 268.973808 -130.422142) (xy 268.694916 -130.422142) (xy 268.681748 -130.446776) (xy 268.649303 -130.492243)
			(xy 268.610576 -130.532495) (xy 268.566395 -130.566671) (xy 268.517704 -130.59404) (xy 268.465542 -130.614019)
			(xy 268.411025 -130.626179) (xy 268.355318 -130.630262) (xy 268.299611 -130.626179) (xy 268.245094 -130.614019)
			(xy 268.192932 -130.59404) (xy 268.144241 -130.566671) (xy 268.10006 -130.532495) (xy 268.061333 -130.492243)
			(xy 268.028888 -130.446776) (xy 268.01572 -130.422142) (xy 263.877298 -130.422142) (xy 263.868809 -130.422448)
			(xy 263.852763 -130.427995) (xy 263.839431 -130.438506) (xy 263.834626 -130.44551) (xy 263.78154 -130.528822)
			(xy 263.779762 -130.554476) (xy 263.785096 -130.566414) (xy 263.800005 -130.600076) (xy 263.821045 -130.670625)
			(xy 263.831678 -130.743472) (xy 263.83234 -130.780282) (xy 263.831838 -130.812243) (xy 263.823827 -130.875661)
			(xy 263.80793 -130.937575) (xy 263.784398 -130.997008) (xy 263.753604 -131.053023) (xy 263.719824 -131.099517)
			(xy 264.98651 -131.099517) (xy 264.98651 -131.035595) (xy 264.994521 -130.972177) (xy 265.010418 -130.910263)
			(xy 265.03395 -130.85083) (xy 265.064744 -130.794815) (xy 265.102317 -130.7431) (xy 265.146074 -130.696503)
			(xy 265.195327 -130.655758) (xy 265.249298 -130.621507) (xy 265.307137 -130.59429) (xy 265.36793 -130.574537)
			(xy 265.43072 -130.562559) (xy 265.494516 -130.558546) (xy 265.558312 -130.562559) (xy 265.621102 -130.574537)
			(xy 265.681895 -130.59429) (xy 265.739734 -130.621507) (xy 265.793705 -130.655758) (xy 265.842958 -130.696503)
			(xy 265.886715 -130.7431) (xy 265.924288 -130.794815) (xy 265.955082 -130.85083) (xy 265.978614 -130.910263)
			(xy 265.994511 -130.972177) (xy 266.002522 -131.035595) (xy 266.003024 -131.067556) (xy 266.002522 -131.099517)
			(xy 265.994511 -131.162935) (xy 265.978614 -131.224849) (xy 265.955082 -131.284282) (xy 265.924288 -131.340297)
			(xy 265.886715 -131.392012) (xy 265.842958 -131.438609) (xy 265.793705 -131.479354) (xy 265.739734 -131.513605)
			(xy 265.681895 -131.540822) (xy 265.621102 -131.560575) (xy 265.558312 -131.572553) (xy 265.494516 -131.576567)
			(xy 265.43072 -131.572553) (xy 265.36793 -131.560575) (xy 265.307137 -131.540822) (xy 265.249298 -131.513605)
			(xy 265.195327 -131.479354) (xy 265.146074 -131.438609) (xy 265.102317 -131.392012) (xy 265.064744 -131.340297)
			(xy 265.03395 -131.284282) (xy 265.010418 -131.224849) (xy 264.994521 -131.162935) (xy 264.98651 -131.099517)
			(xy 263.719824 -131.099517) (xy 263.716031 -131.104738) (xy 263.672274 -131.151335) (xy 263.623021 -131.19208)
			(xy 263.56905 -131.226331) (xy 263.511211 -131.253548) (xy 263.450418 -131.273301) (xy 263.387628 -131.285279)
			(xy 263.323832 -131.289293) (xy 263.260036 -131.285279) (xy 263.197246 -131.273301) (xy 263.136453 -131.253548)
			(xy 263.078614 -131.226331) (xy 263.024643 -131.19208) (xy 262.97539 -131.151335) (xy 262.931633 -131.104738)
			(xy 262.89406 -131.053023) (xy 262.863266 -130.997008) (xy 262.839734 -130.937575) (xy 262.823837 -130.875661)
			(xy 262.815826 -130.812243) (xy 262.815324 -130.780282) (xy 262.815996 -130.743474) (xy 262.826644 -130.67063)
			(xy 262.84767 -130.600079) (xy 262.862568 -130.566414) (xy 262.867902 -130.554476) (xy 262.866124 -130.528822)
			(xy 262.813038 -130.44551) (xy 262.808178 -130.438561) (xy 262.794848 -130.428093) (xy 262.778839 -130.42253)
			(xy 262.770366 -130.422142) (xy 255.625092 -130.422142) (xy 255.615024 -130.421716) (xy 255.596427 -130.413993)
			(xy 255.589024 -130.407156) (xy 254.057404 -128.875536) (xy 254.050007 -128.868685) (xy 254.031409 -128.860944)
			(xy 254.021336 -128.86055) (xy 249.847608 -128.86055) (xy 249.837538 -128.860127) (xy 249.818936 -128.852409)
			(xy 249.81154 -128.845564) (xy 247.953022 -126.987046) (xy 247.945675 -126.980243) (xy 247.927212 -126.972531)
			(xy 247.917208 -126.97206) (xy 236.59973 -126.97206) (xy 236.563626 -126.97148) (xy 236.492007 -126.962276)
			(xy 236.42214 -126.944038) (xy 236.35516 -126.917063) (xy 236.323378 -126.899924) (xy 236.298486 -126.89332)
			(xy 232.921048 -126.89332) (xy 232.910982 -126.893753) (xy 232.892394 -126.901483) (xy 232.88498 -126.908306)
			(xy 232.633774 -127.159512) (xy 232.626922 -127.166908) (xy 232.61918 -127.185506) (xy 232.618788 -127.19558)
			(xy 232.618788 -130.776218) (xy 232.619214 -130.786287) (xy 232.626932 -130.804888) (xy 232.633774 -130.812286)
			(xy 233.63428 -131.812792) (xy 233.641683 -131.819627) (xy 233.660281 -131.827333) (xy 233.670348 -131.827778)
			(xy 243.499132 -131.827778) (xy 243.509134 -131.827284) (xy 243.527611 -131.819618) (xy 243.541748 -131.805466)
			(xy 243.549395 -131.78698) (xy 243.549932 -131.776978) (xy 243.549932 -131.73456) (xy 243.540534 -131.71424)
			(xy 243.53139 -131.706874) (xy 243.507262 -131.686495) (xy 243.463735 -131.64073) (xy 243.426217 -131.589923)
			(xy 243.395285 -131.534857) (xy 243.371417 -131.476382) (xy 243.362734 -131.446016) (xy 243.360448 -131.436872)
			(xy 243.349526 -131.421886) (xy 243.277136 -131.374642) (xy 243.259102 -131.370578) (xy 243.249704 -131.372102)
			(xy 243.231019 -131.374724) (xy 243.193388 -131.377524) (xy 243.17452 -131.37769) (xy 243.143787 -131.377246)
			(xy 243.08277 -131.369839) (xy 243.023091 -131.355131) (xy 242.96562 -131.333336) (xy 242.911195 -131.304773)
			(xy 242.86061 -131.269858) (xy 242.814602 -131.229099) (xy 242.773844 -131.183092) (xy 242.738928 -131.132507)
			(xy 242.710364 -131.078082) (xy 242.68857 -131.020611) (xy 242.673862 -130.960932) (xy 242.666455 -130.899915)
			(xy 242.666012 -130.869182) (xy 242.666266 -130.856228) (xy 242.666092 -130.846976) (xy 242.65997 -130.829528)
			(xy 242.654328 -130.822192) (xy 242.63477 -130.798824) (xy 242.603274 -130.781298) (xy 242.570845 -130.775898)
			(xy 242.507637 -130.757822) (xy 242.447286 -130.731749) (xy 242.390799 -130.698116) (xy 242.339117 -130.657483)
			(xy 242.293104 -130.610527) (xy 242.253527 -130.558032) (xy 242.221047 -130.500874) (xy 242.196204 -130.440007)
			(xy 242.179413 -130.376445) (xy 242.170955 -130.311249) (xy 242.170458 -130.278378) (xy 242.17096 -130.246417)
			(xy 242.178971 -130.182999) (xy 242.194868 -130.121085) (xy 242.2184 -130.061652) (xy 242.249194 -130.005637)
			(xy 242.286767 -129.953922) (xy 242.330524 -129.907325) (xy 242.379777 -129.86658) (xy 242.433748 -129.832329)
			(xy 242.491587 -129.805112) (xy 242.55238 -129.785359) (xy 242.61517 -129.773381) (xy 242.678966 -129.769368)
			(xy 242.742762 -129.773381) (xy 242.805552 -129.785359) (xy 242.866345 -129.805112) (xy 242.924184 -129.832329)
			(xy 242.978155 -129.86658) (xy 243.027408 -129.907325) (xy 243.071165 -129.953922) (xy 243.108738 -130.005637)
			(xy 243.139532 -130.061652) (xy 243.163064 -130.121085) (xy 243.178961 -130.182999) (xy 243.186972 -130.246417)
			(xy 243.187474 -130.278378) (xy 243.18722 -130.291332) (xy 243.187388 -130.300586) (xy 243.193508 -130.318037)
			(xy 243.199158 -130.325368) (xy 243.218716 -130.348736) (xy 243.250212 -130.366262) (xy 243.282491 -130.371635)
			(xy 243.345417 -130.389599) (xy 243.405517 -130.415487) (xy 243.461801 -130.448872) (xy 243.513336 -130.4892)
			(xy 243.559272 -130.535807) (xy 243.598849 -130.587922) (xy 243.631414 -130.644683) (xy 243.656428 -130.705153)
			(xy 243.665502 -130.736594) (xy 243.667788 -130.745738) (xy 243.67871 -130.760724) (xy 243.7511 -130.807968)
			(xy 243.769134 -130.812032) (xy 243.778532 -130.810508) (xy 243.797217 -130.807888) (xy 243.834849 -130.805091)
			(xy 243.853716 -130.80492) (xy 243.885219 -130.805394) (xy 243.947742 -130.813179) (xy 244.008825 -130.828627)
			(xy 244.067532 -130.851503) (xy 244.122963 -130.881455) (xy 244.17427 -130.918025) (xy 244.220667 -130.960653)
			(xy 244.261442 -131.008686) (xy 244.295972 -131.061387) (xy 244.314682 -131.099517) (xy 249.950218 -131.099517)
			(xy 249.950218 -131.035595) (xy 249.958229 -130.972177) (xy 249.974126 -130.910263) (xy 249.997658 -130.85083)
			(xy 250.028452 -130.794815) (xy 250.066025 -130.7431) (xy 250.109782 -130.696503) (xy 250.159035 -130.655758)
			(xy 250.213006 -130.621507) (xy 250.270845 -130.59429) (xy 250.331638 -130.574537) (xy 250.394428 -130.562559)
			(xy 250.458224 -130.558546) (xy 250.52202 -130.562559) (xy 250.58481 -130.574537) (xy 250.645603 -130.59429)
			(xy 250.703442 -130.621507) (xy 250.757413 -130.655758) (xy 250.806666 -130.696503) (xy 250.850423 -130.7431)
			(xy 250.887996 -130.794815) (xy 250.91879 -130.85083) (xy 250.942322 -130.910263) (xy 250.958219 -130.972177)
			(xy 250.96623 -131.035595) (xy 250.966732 -131.067556) (xy 250.96623 -131.099517) (xy 251.982218 -131.099517)
			(xy 251.982218 -131.035595) (xy 251.990229 -130.972177) (xy 252.006126 -130.910263) (xy 252.029658 -130.85083)
			(xy 252.060452 -130.794815) (xy 252.098025 -130.7431) (xy 252.141782 -130.696503) (xy 252.191035 -130.655758)
			(xy 252.245006 -130.621507) (xy 252.302845 -130.59429) (xy 252.363638 -130.574537) (xy 252.426428 -130.562559)
			(xy 252.490224 -130.558546) (xy 252.55402 -130.562559) (xy 252.61681 -130.574537) (xy 252.677603 -130.59429)
			(xy 252.735442 -130.621507) (xy 252.789413 -130.655758) (xy 252.838666 -130.696503) (xy 252.882423 -130.7431)
			(xy 252.919996 -130.794815) (xy 252.95079 -130.85083) (xy 252.974322 -130.910263) (xy 252.990219 -130.972177)
			(xy 252.99823 -131.035595) (xy 252.998732 -131.067556) (xy 252.99823 -131.099517) (xy 254.014218 -131.099517)
			(xy 254.014218 -131.035595) (xy 254.022229 -130.972177) (xy 254.038126 -130.910263) (xy 254.061658 -130.85083)
			(xy 254.092452 -130.794815) (xy 254.130025 -130.7431) (xy 254.173782 -130.696503) (xy 254.223035 -130.655758)
			(xy 254.277006 -130.621507) (xy 254.334845 -130.59429) (xy 254.395638 -130.574537) (xy 254.458428 -130.562559)
			(xy 254.522224 -130.558546) (xy 254.58602 -130.562559) (xy 254.64881 -130.574537) (xy 254.709603 -130.59429)
			(xy 254.767442 -130.621507) (xy 254.821413 -130.655758) (xy 254.870666 -130.696503) (xy 254.914423 -130.7431)
			(xy 254.951996 -130.794815) (xy 254.98279 -130.85083) (xy 255.006322 -130.910263) (xy 255.022219 -130.972177)
			(xy 255.03023 -131.035595) (xy 255.030732 -131.067556) (xy 255.03023 -131.099517) (xy 255.022219 -131.162935)
			(xy 255.006322 -131.224849) (xy 254.98279 -131.284282) (xy 254.951996 -131.340297) (xy 254.914423 -131.392012)
			(xy 254.870666 -131.438609) (xy 254.821413 -131.479354) (xy 254.767442 -131.513605) (xy 254.709603 -131.540822)
			(xy 254.64881 -131.560575) (xy 254.58602 -131.572553) (xy 254.522224 -131.576567) (xy 254.458428 -131.572553)
			(xy 254.395638 -131.560575) (xy 254.334845 -131.540822) (xy 254.277006 -131.513605) (xy 254.223035 -131.479354)
			(xy 254.173782 -131.438609) (xy 254.130025 -131.392012) (xy 254.092452 -131.340297) (xy 254.061658 -131.284282)
			(xy 254.038126 -131.224849) (xy 254.022229 -131.162935) (xy 254.014218 -131.099517) (xy 252.99823 -131.099517)
			(xy 252.990219 -131.162935) (xy 252.974322 -131.224849) (xy 252.95079 -131.284282) (xy 252.919996 -131.340297)
			(xy 252.882423 -131.392012) (xy 252.838666 -131.438609) (xy 252.789413 -131.479354) (xy 252.735442 -131.513605)
			(xy 252.677603 -131.540822) (xy 252.61681 -131.560575) (xy 252.55402 -131.572553) (xy 252.490224 -131.576567)
			(xy 252.426428 -131.572553) (xy 252.363638 -131.560575) (xy 252.302845 -131.540822) (xy 252.245006 -131.513605)
			(xy 252.191035 -131.479354) (xy 252.141782 -131.438609) (xy 252.098025 -131.392012) (xy 252.060452 -131.340297)
			(xy 252.029658 -131.284282) (xy 252.006126 -131.224849) (xy 251.990229 -131.162935) (xy 251.982218 -131.099517)
			(xy 250.96623 -131.099517) (xy 250.958219 -131.162935) (xy 250.942322 -131.224849) (xy 250.91879 -131.284282)
			(xy 250.887996 -131.340297) (xy 250.850423 -131.392012) (xy 250.806666 -131.438609) (xy 250.757413 -131.479354)
			(xy 250.703442 -131.513605) (xy 250.645603 -131.540822) (xy 250.58481 -131.560575) (xy 250.52202 -131.572553)
			(xy 250.458224 -131.576567) (xy 250.394428 -131.572553) (xy 250.331638 -131.560575) (xy 250.270845 -131.540822)
			(xy 250.213006 -131.513605) (xy 250.159035 -131.479354) (xy 250.109782 -131.438609) (xy 250.066025 -131.392012)
			(xy 250.028452 -131.340297) (xy 249.997658 -131.284282) (xy 249.974126 -131.224849) (xy 249.958229 -131.162935)
			(xy 249.950218 -131.099517) (xy 244.314682 -131.099517) (xy 244.323727 -131.11795) (xy 244.344283 -131.177509)
			(xy 244.357325 -131.239151) (xy 244.360446 -131.270502) (xy 244.406166 -131.31673) (xy 244.438139 -131.320335)
			(xy 244.500883 -131.334592) (xy 244.561325 -131.356655) (xy 244.6185 -131.38617) (xy 244.671492 -131.422665)
			(xy 244.719455 -131.465556) (xy 244.76162 -131.514158) (xy 244.797314 -131.567693) (xy 244.825965 -131.625305)
			(xy 244.826331 -131.626356) (xy 253.124206 -131.626356) (xy 253.128277 -131.570734) (xy 253.140403 -131.516297)
			(xy 253.160326 -131.464206) (xy 253.187622 -131.415571) (xy 253.221708 -131.371428) (xy 253.261857 -131.332719)
			(xy 253.307215 -131.300268) (xy 253.356815 -131.274767) (xy 253.409599 -131.25676) (xy 253.464442 -131.24663)
			(xy 253.520176 -131.244593) (xy 253.575613 -131.250693) (xy 253.62957 -131.264799) (xy 253.680899 -131.286611)
			(xy 253.728505 -131.315665) (xy 253.771373 -131.35134) (xy 253.80859 -131.392877) (xy 253.839363 -131.43939)
			(xy 253.863035 -131.489887) (xy 253.879103 -131.543294) (xy 253.887223 -131.59847) (xy 253.887732 -131.626356)
			(xy 253.887464 -131.641045) (xy 256.871718 -131.641045) (xy 256.871718 -131.577123) (xy 256.879729 -131.513705)
			(xy 256.895626 -131.451791) (xy 256.919158 -131.392358) (xy 256.949952 -131.336343) (xy 256.987525 -131.284628)
			(xy 257.031282 -131.238031) (xy 257.080535 -131.197286) (xy 257.134506 -131.163035) (xy 257.192345 -131.135818)
			(xy 257.253138 -131.116065) (xy 257.315928 -131.104087) (xy 257.379724 -131.100074) (xy 257.44352 -131.104087)
			(xy 257.50631 -131.116065) (xy 257.567103 -131.135818) (xy 257.624942 -131.163035) (xy 257.678913 -131.197286)
			(xy 257.728166 -131.238031) (xy 257.771923 -131.284628) (xy 257.809496 -131.336343) (xy 257.84029 -131.392358)
			(xy 257.863822 -131.451791) (xy 257.879719 -131.513705) (xy 257.88773 -131.577123) (xy 257.888232 -131.609084)
			(xy 257.88773 -131.641045) (xy 257.879719 -131.704463) (xy 257.863822 -131.766377) (xy 257.84029 -131.82581)
			(xy 257.809496 -131.881825) (xy 257.771923 -131.93354) (xy 257.728166 -131.980137) (xy 257.678913 -132.020882)
			(xy 257.624942 -132.055133) (xy 257.567103 -132.08235) (xy 257.50631 -132.102103) (xy 257.44352 -132.114081)
			(xy 257.379724 -132.118095) (xy 257.315928 -132.114081) (xy 257.253138 -132.102103) (xy 257.192345 -132.08235)
			(xy 257.134506 -132.055133) (xy 257.080535 -132.020882) (xy 257.031282 -131.980137) (xy 256.987525 -131.93354)
			(xy 256.949952 -131.881825) (xy 256.919158 -131.82581) (xy 256.895626 -131.766377) (xy 256.879729 -131.704463)
			(xy 256.871718 -131.641045) (xy 253.887464 -131.641045) (xy 253.887223 -131.654242) (xy 253.879103 -131.709418)
			(xy 253.863035 -131.762825) (xy 253.839363 -131.813322) (xy 253.80859 -131.859835) (xy 253.771373 -131.901372)
			(xy 253.728505 -131.937047) (xy 253.680899 -131.966101) (xy 253.62957 -131.987913) (xy 253.575613 -132.002019)
			(xy 253.520176 -132.008119) (xy 253.464442 -132.006082) (xy 253.409599 -131.995952) (xy 253.356815 -131.977945)
			(xy 253.307215 -131.952444) (xy 253.261857 -131.919993) (xy 253.221708 -131.881284) (xy 253.187622 -131.837141)
			(xy 253.160326 -131.788506) (xy 253.140403 -131.736415) (xy 253.128277 -131.681978) (xy 253.124206 -131.626356)
			(xy 244.826331 -131.626356) (xy 244.847116 -131.686073) (xy 244.860428 -131.749024) (xy 244.86362 -131.781042)
			(xy 244.865398 -131.800854) (xy 244.894354 -131.827778) (xy 244.964966 -131.827778) (xy 244.975031 -131.828213)
			(xy 244.993621 -131.835941) (xy 245.001034 -131.842764) (xy 245.527787 -132.369517) (xy 251.982218 -132.369517)
			(xy 251.982218 -132.305595) (xy 251.990229 -132.242177) (xy 252.006126 -132.180263) (xy 252.029658 -132.12083)
			(xy 252.060452 -132.064815) (xy 252.098025 -132.0131) (xy 252.141782 -131.966503) (xy 252.191035 -131.925758)
			(xy 252.245006 -131.891507) (xy 252.302845 -131.86429) (xy 252.363638 -131.844537) (xy 252.426428 -131.832559)
			(xy 252.490224 -131.828546) (xy 252.55402 -131.832559) (xy 252.61681 -131.844537) (xy 252.677603 -131.86429)
			(xy 252.735442 -131.891507) (xy 252.789413 -131.925758) (xy 252.838666 -131.966503) (xy 252.882423 -132.0131)
			(xy 252.919996 -132.064815) (xy 252.95079 -132.12083) (xy 252.974322 -132.180263) (xy 252.990219 -132.242177)
			(xy 252.99823 -132.305595) (xy 252.998732 -132.337556) (xy 252.99823 -132.369517) (xy 254.014218 -132.369517)
			(xy 254.014218 -132.305595) (xy 254.022229 -132.242177) (xy 254.038126 -132.180263) (xy 254.061658 -132.12083)
			(xy 254.092452 -132.064815) (xy 254.130025 -132.0131) (xy 254.173782 -131.966503) (xy 254.223035 -131.925758)
			(xy 254.277006 -131.891507) (xy 254.334845 -131.86429) (xy 254.395638 -131.844537) (xy 254.458428 -131.832559)
			(xy 254.522224 -131.828546) (xy 254.58602 -131.832559) (xy 254.64881 -131.844537) (xy 254.709603 -131.86429)
			(xy 254.767442 -131.891507) (xy 254.821413 -131.925758) (xy 254.870666 -131.966503) (xy 254.914423 -132.0131)
			(xy 254.951996 -132.064815) (xy 254.98279 -132.12083) (xy 255.006322 -132.180263) (xy 255.022219 -132.242177)
			(xy 255.03023 -132.305595) (xy 255.030732 -132.337556) (xy 255.03023 -132.369517) (xy 262.95451 -132.369517)
			(xy 262.95451 -132.305595) (xy 262.962521 -132.242177) (xy 262.978418 -132.180263) (xy 263.00195 -132.12083)
			(xy 263.032744 -132.064815) (xy 263.070317 -132.0131) (xy 263.114074 -131.966503) (xy 263.163327 -131.925758)
			(xy 263.217298 -131.891507) (xy 263.275137 -131.86429) (xy 263.33593 -131.844537) (xy 263.39872 -131.832559)
			(xy 263.462516 -131.828546) (xy 263.526312 -131.832559) (xy 263.589102 -131.844537) (xy 263.649895 -131.86429)
			(xy 263.707734 -131.891507) (xy 263.761705 -131.925758) (xy 263.810958 -131.966503) (xy 263.854715 -132.0131)
			(xy 263.892288 -132.064815) (xy 263.923082 -132.12083) (xy 263.946614 -132.180263) (xy 263.962511 -132.242177)
			(xy 263.970522 -132.305595) (xy 263.971024 -132.337556) (xy 263.970785 -132.352796) (xy 265.112498 -132.352796)
			(xy 265.116569 -132.297174) (xy 265.128695 -132.242737) (xy 265.148618 -132.190646) (xy 265.175914 -132.142011)
			(xy 265.21 -132.097868) (xy 265.250149 -132.059159) (xy 265.295507 -132.026708) (xy 265.345107 -132.001207)
			(xy 265.397891 -131.9832) (xy 265.452734 -131.97307) (xy 265.508468 -131.971033) (xy 265.563905 -131.977133)
			(xy 265.617862 -131.991239) (xy 265.649214 -132.004562) (xy 269.324326 -132.004562) (xy 269.328399 -131.948903)
			(xy 269.340534 -131.89443) (xy 269.36047 -131.842304) (xy 269.387784 -131.793636) (xy 269.421892 -131.749464)
			(xy 269.462069 -131.710729) (xy 269.507457 -131.678257) (xy 269.557089 -131.652739) (xy 269.609909 -131.63472)
			(xy 269.664788 -131.624583) (xy 269.720559 -131.622545) (xy 269.776033 -131.628648) (xy 269.830026 -131.642764)
			(xy 269.881389 -131.664591) (xy 269.929027 -131.693664) (xy 269.971923 -131.729363) (xy 270.009165 -131.770927)
			(xy 270.039959 -131.817471) (xy 270.063647 -131.868002) (xy 270.079725 -131.921444) (xy 270.087851 -131.976658)
			(xy 270.08836 -132.004562) (xy 270.087851 -132.032466) (xy 270.079725 -132.08768) (xy 270.063647 -132.141122)
			(xy 270.039959 -132.191653) (xy 270.009165 -132.238197) (xy 269.971923 -132.279761) (xy 269.929027 -132.31546)
			(xy 269.881389 -132.344533) (xy 269.830026 -132.36636) (xy 269.776033 -132.380476) (xy 269.720559 -132.386579)
			(xy 269.664788 -132.384541) (xy 269.609909 -132.374404) (xy 269.557089 -132.356385) (xy 269.507457 -132.330867)
			(xy 269.462069 -132.298395) (xy 269.421892 -132.25966) (xy 269.387784 -132.215488) (xy 269.36047 -132.16682)
			(xy 269.340534 -132.114694) (xy 269.328399 -132.060221) (xy 269.324326 -132.004562) (xy 265.649214 -132.004562)
			(xy 265.669191 -132.013051) (xy 265.716797 -132.042105) (xy 265.759665 -132.07778) (xy 265.796882 -132.119317)
			(xy 265.827655 -132.16583) (xy 265.851327 -132.216327) (xy 265.867395 -132.269734) (xy 265.875515 -132.32491)
			(xy 265.876024 -132.352796) (xy 265.875515 -132.380682) (xy 265.867395 -132.435858) (xy 265.851327 -132.489265)
			(xy 265.827655 -132.539762) (xy 265.796882 -132.586275) (xy 265.759665 -132.627812) (xy 265.716797 -132.663487)
			(xy 265.669191 -132.692541) (xy 265.617862 -132.714353) (xy 265.563905 -132.728459) (xy 265.508468 -132.734559)
			(xy 265.452734 -132.732522) (xy 265.397891 -132.722392) (xy 265.345107 -132.704385) (xy 265.295507 -132.678884)
			(xy 265.250149 -132.646433) (xy 265.21 -132.607724) (xy 265.175914 -132.563581) (xy 265.148618 -132.514946)
			(xy 265.128695 -132.462855) (xy 265.116569 -132.408418) (xy 265.112498 -132.352796) (xy 263.970785 -132.352796)
			(xy 263.970522 -132.369517) (xy 263.962511 -132.432935) (xy 263.946614 -132.494849) (xy 263.923082 -132.554282)
			(xy 263.892288 -132.610297) (xy 263.854715 -132.662012) (xy 263.810958 -132.708609) (xy 263.761705 -132.749354)
			(xy 263.707734 -132.783605) (xy 263.649895 -132.810822) (xy 263.589102 -132.830575) (xy 263.526312 -132.842553)
			(xy 263.462516 -132.846567) (xy 263.39872 -132.842553) (xy 263.33593 -132.830575) (xy 263.275137 -132.810822)
			(xy 263.217298 -132.783605) (xy 263.163327 -132.749354) (xy 263.114074 -132.708609) (xy 263.070317 -132.662012)
			(xy 263.032744 -132.610297) (xy 263.00195 -132.554282) (xy 262.978418 -132.494849) (xy 262.962521 -132.432935)
			(xy 262.95451 -132.369517) (xy 255.03023 -132.369517) (xy 255.022219 -132.432935) (xy 255.006322 -132.494849)
			(xy 254.98279 -132.554282) (xy 254.951996 -132.610297) (xy 254.914423 -132.662012) (xy 254.870666 -132.708609)
			(xy 254.821413 -132.749354) (xy 254.767442 -132.783605) (xy 254.709603 -132.810822) (xy 254.64881 -132.830575)
			(xy 254.58602 -132.842553) (xy 254.522224 -132.846567) (xy 254.458428 -132.842553) (xy 254.395638 -132.830575)
			(xy 254.334845 -132.810822) (xy 254.277006 -132.783605) (xy 254.223035 -132.749354) (xy 254.173782 -132.708609)
			(xy 254.130025 -132.662012) (xy 254.092452 -132.610297) (xy 254.061658 -132.554282) (xy 254.038126 -132.494849)
			(xy 254.022229 -132.432935) (xy 254.014218 -132.369517) (xy 252.99823 -132.369517) (xy 252.990219 -132.432935)
			(xy 252.974322 -132.494849) (xy 252.95079 -132.554282) (xy 252.919996 -132.610297) (xy 252.882423 -132.662012)
			(xy 252.838666 -132.708609) (xy 252.789413 -132.749354) (xy 252.735442 -132.783605) (xy 252.677603 -132.810822)
			(xy 252.61681 -132.830575) (xy 252.55402 -132.842553) (xy 252.490224 -132.846567) (xy 252.426428 -132.842553)
			(xy 252.363638 -132.830575) (xy 252.302845 -132.810822) (xy 252.245006 -132.783605) (xy 252.191035 -132.749354)
			(xy 252.141782 -132.708609) (xy 252.098025 -132.662012) (xy 252.060452 -132.610297) (xy 252.029658 -132.554282)
			(xy 252.006126 -132.494849) (xy 251.990229 -132.432935) (xy 251.982218 -132.369517) (xy 245.527787 -132.369517)
			(xy 246.222266 -133.063996) (xy 253.124206 -133.063996) (xy 253.128277 -133.008374) (xy 253.140403 -132.953937)
			(xy 253.160326 -132.901846) (xy 253.187622 -132.853211) (xy 253.221708 -132.809068) (xy 253.261857 -132.770359)
			(xy 253.307215 -132.737908) (xy 253.356815 -132.712407) (xy 253.409599 -132.6944) (xy 253.464442 -132.68427)
			(xy 253.520176 -132.682233) (xy 253.575613 -132.688333) (xy 253.62957 -132.702439) (xy 253.680899 -132.724251)
			(xy 253.728505 -132.753305) (xy 253.771373 -132.78898) (xy 253.80859 -132.830517) (xy 253.839363 -132.87703)
			(xy 253.863035 -132.927527) (xy 253.879103 -132.980934) (xy 253.887223 -133.03611) (xy 253.887732 -133.063996)
			(xy 264.096498 -133.063996) (xy 264.100569 -133.008374) (xy 264.112695 -132.953937) (xy 264.132618 -132.901846)
			(xy 264.159914 -132.853211) (xy 264.194 -132.809068) (xy 264.234149 -132.770359) (xy 264.279507 -132.737908)
			(xy 264.329107 -132.712407) (xy 264.381891 -132.6944) (xy 264.436734 -132.68427) (xy 264.492468 -132.682233)
			(xy 264.547905 -132.688333) (xy 264.601862 -132.702439) (xy 264.653191 -132.724251) (xy 264.700797 -132.753305)
			(xy 264.743665 -132.78898) (xy 264.780882 -132.830517) (xy 264.811655 -132.87703) (xy 264.835327 -132.927527)
			(xy 264.837399 -132.934413) (xy 268.282668 -132.934413) (xy 268.282668 -132.870491) (xy 268.290679 -132.807073)
			(xy 268.306576 -132.745159) (xy 268.330108 -132.685726) (xy 268.360902 -132.629711) (xy 268.398475 -132.577996)
			(xy 268.442232 -132.531399) (xy 268.491485 -132.490654) (xy 268.545456 -132.456403) (xy 268.603295 -132.429186)
			(xy 268.664088 -132.409433) (xy 268.726878 -132.397455) (xy 268.790674 -132.393442) (xy 268.85447 -132.397455)
			(xy 268.91726 -132.409433) (xy 268.978053 -132.429186) (xy 269.035892 -132.456403) (xy 269.089863 -132.490654)
			(xy 269.139116 -132.531399) (xy 269.182873 -132.577996) (xy 269.220446 -132.629711) (xy 269.25124 -132.685726)
			(xy 269.274772 -132.745159) (xy 269.290669 -132.807073) (xy 269.29868 -132.870491) (xy 269.299182 -132.902452)
			(xy 269.29868 -132.934413) (xy 269.290669 -132.997831) (xy 269.274772 -133.059745) (xy 269.25124 -133.119178)
			(xy 269.220446 -133.175193) (xy 269.182873 -133.226908) (xy 269.139116 -133.273505) (xy 269.089863 -133.31425)
			(xy 269.035892 -133.348501) (xy 268.978053 -133.375718) (xy 268.91726 -133.395471) (xy 268.85447 -133.407449)
			(xy 268.790674 -133.411463) (xy 268.726878 -133.407449) (xy 268.664088 -133.395471) (xy 268.603295 -133.375718)
			(xy 268.545456 -133.348501) (xy 268.491485 -133.31425) (xy 268.442232 -133.273505) (xy 268.398475 -133.226908)
			(xy 268.360902 -133.175193) (xy 268.330108 -133.119178) (xy 268.306576 -133.059745) (xy 268.290679 -132.997831)
			(xy 268.282668 -132.934413) (xy 264.837399 -132.934413) (xy 264.851395 -132.980934) (xy 264.859515 -133.03611)
			(xy 264.860024 -133.063996) (xy 264.859515 -133.091882) (xy 264.851395 -133.147058) (xy 264.835327 -133.200465)
			(xy 264.811655 -133.250962) (xy 264.780882 -133.297475) (xy 264.743665 -133.339012) (xy 264.700797 -133.374687)
			(xy 264.653191 -133.403741) (xy 264.601862 -133.425553) (xy 264.547905 -133.439659) (xy 264.492468 -133.445759)
			(xy 264.436734 -133.443722) (xy 264.381891 -133.433592) (xy 264.329107 -133.415585) (xy 264.279507 -133.390084)
			(xy 264.234149 -133.357633) (xy 264.194 -133.318924) (xy 264.159914 -133.274781) (xy 264.132618 -133.226146)
			(xy 264.112695 -133.174055) (xy 264.100569 -133.119618) (xy 264.096498 -133.063996) (xy 253.887732 -133.063996)
			(xy 253.887223 -133.091882) (xy 253.879103 -133.147058) (xy 253.863035 -133.200465) (xy 253.839363 -133.250962)
			(xy 253.80859 -133.297475) (xy 253.771373 -133.339012) (xy 253.728505 -133.374687) (xy 253.680899 -133.403741)
			(xy 253.62957 -133.425553) (xy 253.575613 -133.439659) (xy 253.520176 -133.445759) (xy 253.464442 -133.443722)
			(xy 253.409599 -133.433592) (xy 253.356815 -133.415585) (xy 253.307215 -133.390084) (xy 253.261857 -133.357633)
			(xy 253.221708 -133.318924) (xy 253.187622 -133.274781) (xy 253.160326 -133.226146) (xy 253.140403 -133.174055)
			(xy 253.128277 -133.119618) (xy 253.124206 -133.063996) (xy 246.222266 -133.063996) (xy 246.813027 -133.654757)
			(xy 251.982218 -133.654757) (xy 251.982218 -133.590835) (xy 251.990229 -133.527417) (xy 252.006126 -133.465503)
			(xy 252.029658 -133.40607) (xy 252.060452 -133.350055) (xy 252.098025 -133.29834) (xy 252.141782 -133.251743)
			(xy 252.191035 -133.210998) (xy 252.245006 -133.176747) (xy 252.302845 -133.14953) (xy 252.363638 -133.129777)
			(xy 252.426428 -133.117799) (xy 252.490224 -133.113786) (xy 252.55402 -133.117799) (xy 252.61681 -133.129777)
			(xy 252.677603 -133.14953) (xy 252.735442 -133.176747) (xy 252.789413 -133.210998) (xy 252.838666 -133.251743)
			(xy 252.882423 -133.29834) (xy 252.919996 -133.350055) (xy 252.95079 -133.40607) (xy 252.974322 -133.465503)
			(xy 252.990219 -133.527417) (xy 252.99823 -133.590835) (xy 252.998732 -133.622796) (xy 252.99823 -133.654757)
			(xy 254.014218 -133.654757) (xy 254.014218 -133.590835) (xy 254.022229 -133.527417) (xy 254.038126 -133.465503)
			(xy 254.061658 -133.40607) (xy 254.092452 -133.350055) (xy 254.130025 -133.29834) (xy 254.173782 -133.251743)
			(xy 254.223035 -133.210998) (xy 254.277006 -133.176747) (xy 254.334845 -133.14953) (xy 254.395638 -133.129777)
			(xy 254.458428 -133.117799) (xy 254.522224 -133.113786) (xy 254.58602 -133.117799) (xy 254.64881 -133.129777)
			(xy 254.709603 -133.14953) (xy 254.767442 -133.176747) (xy 254.821413 -133.210998) (xy 254.870666 -133.251743)
			(xy 254.914423 -133.29834) (xy 254.951996 -133.350055) (xy 254.98279 -133.40607) (xy 255.006322 -133.465503)
			(xy 255.022219 -133.527417) (xy 255.03023 -133.590835) (xy 255.030732 -133.622796) (xy 255.03023 -133.654757)
			(xy 255.022219 -133.718175) (xy 255.006322 -133.780089) (xy 254.98279 -133.839522) (xy 254.951996 -133.895537)
			(xy 254.914423 -133.947252) (xy 254.870666 -133.993849) (xy 254.821413 -134.034594) (xy 254.767442 -134.068845)
			(xy 254.709603 -134.096062) (xy 254.64881 -134.115815) (xy 254.58602 -134.127793) (xy 254.522224 -134.131807)
			(xy 254.458428 -134.127793) (xy 254.395638 -134.115815) (xy 254.334845 -134.096062) (xy 254.277006 -134.068845)
			(xy 254.223035 -134.034594) (xy 254.173782 -133.993849) (xy 254.130025 -133.947252) (xy 254.092452 -133.895537)
			(xy 254.061658 -133.839522) (xy 254.038126 -133.780089) (xy 254.022229 -133.718175) (xy 254.014218 -133.654757)
			(xy 252.99823 -133.654757) (xy 252.990219 -133.718175) (xy 252.974322 -133.780089) (xy 252.95079 -133.839522)
			(xy 252.919996 -133.895537) (xy 252.882423 -133.947252) (xy 252.838666 -133.993849) (xy 252.789413 -134.034594)
			(xy 252.735442 -134.068845) (xy 252.677603 -134.096062) (xy 252.61681 -134.115815) (xy 252.55402 -134.127793)
			(xy 252.490224 -134.131807) (xy 252.426428 -134.127793) (xy 252.363638 -134.115815) (xy 252.302845 -134.096062)
			(xy 252.245006 -134.068845) (xy 252.191035 -134.034594) (xy 252.141782 -133.993849) (xy 252.098025 -133.947252)
			(xy 252.060452 -133.895537) (xy 252.029658 -133.839522) (xy 252.006126 -133.780089) (xy 251.990229 -133.718175)
			(xy 251.982218 -133.654757) (xy 246.813027 -133.654757) (xy 247.416066 -134.257796) (xy 251.339856 -134.257796)
			(xy 251.343927 -134.202174) (xy 251.356053 -134.147737) (xy 251.375976 -134.095646) (xy 251.403272 -134.047011)
			(xy 251.437358 -134.002868) (xy 251.477507 -133.964159) (xy 251.522865 -133.931708) (xy 251.572465 -133.906207)
			(xy 251.625249 -133.8882) (xy 251.680092 -133.87807) (xy 251.735826 -133.876033) (xy 251.791263 -133.882133)
			(xy 251.84522 -133.896239) (xy 251.896549 -133.918051) (xy 251.944155 -133.947105) (xy 251.987023 -133.98278)
			(xy 252.02424 -134.024317) (xy 252.055013 -134.07083) (xy 252.078685 -134.121327) (xy 252.094753 -134.174734)
			(xy 252.102873 -134.22991) (xy 252.103382 -134.257796) (xy 253.371856 -134.257796) (xy 253.375927 -134.202174)
			(xy 253.388053 -134.147737) (xy 253.407976 -134.095646) (xy 253.435272 -134.047011) (xy 253.469358 -134.002868)
			(xy 253.509507 -133.964159) (xy 253.554865 -133.931708) (xy 253.604465 -133.906207) (xy 253.657249 -133.8882)
			(xy 253.712092 -133.87807) (xy 253.767826 -133.876033) (xy 253.823263 -133.882133) (xy 253.87722 -133.896239)
			(xy 253.928549 -133.918051) (xy 253.976155 -133.947105) (xy 254.019023 -133.98278) (xy 254.05624 -134.024317)
			(xy 254.087013 -134.07083) (xy 254.110685 -134.121327) (xy 254.126753 -134.174734) (xy 254.134873 -134.22991)
			(xy 254.135382 -134.257796) (xy 254.134873 -134.285682) (xy 254.126753 -134.340858) (xy 254.110685 -134.394265)
			(xy 254.087013 -134.444762) (xy 254.05624 -134.491275) (xy 254.019023 -134.532812) (xy 253.976155 -134.568487)
			(xy 253.928549 -134.597541) (xy 253.87722 -134.619353) (xy 253.823263 -134.633459) (xy 253.767826 -134.639559)
			(xy 253.712092 -134.637522) (xy 253.657249 -134.627392) (xy 253.604465 -134.609385) (xy 253.554865 -134.583884)
			(xy 253.509507 -134.551433) (xy 253.469358 -134.512724) (xy 253.435272 -134.468581) (xy 253.407976 -134.419946)
			(xy 253.388053 -134.367855) (xy 253.375927 -134.313418) (xy 253.371856 -134.257796) (xy 252.103382 -134.257796)
			(xy 252.102873 -134.285682) (xy 252.094753 -134.340858) (xy 252.078685 -134.394265) (xy 252.055013 -134.444762)
			(xy 252.02424 -134.491275) (xy 251.987023 -134.532812) (xy 251.944155 -134.568487) (xy 251.896549 -134.597541)
			(xy 251.84522 -134.619353) (xy 251.791263 -134.633459) (xy 251.735826 -134.639559) (xy 251.680092 -134.637522)
			(xy 251.625249 -134.627392) (xy 251.572465 -134.609385) (xy 251.522865 -134.583884) (xy 251.477507 -134.551433)
			(xy 251.437358 -134.512724) (xy 251.403272 -134.468581) (xy 251.375976 -134.419946) (xy 251.356053 -134.367855)
			(xy 251.343927 -134.313418) (xy 251.339856 -134.257796) (xy 247.416066 -134.257796) (xy 248.083027 -134.924757)
			(xy 251.982218 -134.924757) (xy 251.982218 -134.860835) (xy 251.990229 -134.797417) (xy 252.006126 -134.735503)
			(xy 252.029658 -134.67607) (xy 252.060452 -134.620055) (xy 252.098025 -134.56834) (xy 252.141782 -134.521743)
			(xy 252.191035 -134.480998) (xy 252.245006 -134.446747) (xy 252.302845 -134.41953) (xy 252.363638 -134.399777)
			(xy 252.426428 -134.387799) (xy 252.490224 -134.383786) (xy 252.55402 -134.387799) (xy 252.61681 -134.399777)
			(xy 252.677603 -134.41953) (xy 252.735442 -134.446747) (xy 252.789413 -134.480998) (xy 252.838666 -134.521743)
			(xy 252.882423 -134.56834) (xy 252.919996 -134.620055) (xy 252.95079 -134.67607) (xy 252.974322 -134.735503)
			(xy 252.990219 -134.797417) (xy 252.99823 -134.860835) (xy 252.998732 -134.892796) (xy 252.99823 -134.924757)
			(xy 254.014218 -134.924757) (xy 254.014218 -134.860835) (xy 254.022229 -134.797417) (xy 254.038126 -134.735503)
			(xy 254.061658 -134.67607) (xy 254.092452 -134.620055) (xy 254.130025 -134.56834) (xy 254.173782 -134.521743)
			(xy 254.223035 -134.480998) (xy 254.277006 -134.446747) (xy 254.334845 -134.41953) (xy 254.395638 -134.399777)
			(xy 254.458428 -134.387799) (xy 254.522224 -134.383786) (xy 254.58602 -134.387799) (xy 254.64881 -134.399777)
			(xy 254.709603 -134.41953) (xy 254.767442 -134.446747) (xy 254.821413 -134.480998) (xy 254.870666 -134.521743)
			(xy 254.914423 -134.56834) (xy 254.951996 -134.620055) (xy 254.98279 -134.67607) (xy 255.006322 -134.735503)
			(xy 255.022219 -134.797417) (xy 255.03023 -134.860835) (xy 255.030732 -134.892796) (xy 255.03023 -134.924757)
			(xy 255.022219 -134.988175) (xy 255.006322 -135.050089) (xy 254.98279 -135.109522) (xy 254.951996 -135.165537)
			(xy 254.914423 -135.217252) (xy 254.878737 -135.255254) (xy 256.871216 -135.255254) (xy 256.871757 -135.221922)
			(xy 256.880462 -135.155827) (xy 256.897729 -135.091438) (xy 256.923263 -135.029857) (xy 256.956626 -134.972141)
			(xy 256.997245 -134.91928) (xy 257.044424 -134.872181) (xy 257.097353 -134.83165) (xy 257.125978 -134.814564)
			(xy 257.137154 -134.808214) (xy 257.150362 -134.787386) (xy 257.158998 -134.67842) (xy 257.149346 -134.65556)
			(xy 257.13944 -134.647686) (xy 257.117794 -134.629451) (xy 257.079584 -134.5877) (xy 257.047959 -134.540764)
			(xy 257.023614 -134.489671) (xy 257.007083 -134.435543) (xy 256.998728 -134.379566) (xy 256.998216 -134.351268)
			(xy 256.998669 -134.325001) (xy 257.005875 -134.272964) (xy 257.020158 -134.222409) (xy 257.041248 -134.174295)
			(xy 257.068746 -134.129533) (xy 257.102131 -134.088972) (xy 257.121152 -134.070852) (xy 257.128478 -134.063296)
			(xy 257.136878 -134.044024) (xy 257.137408 -134.033514) (xy 257.137408 -133.958838) (xy 257.136911 -133.948317)
			(xy 257.12852 -133.929026) (xy 257.121152 -133.9215) (xy 257.102123 -133.903388) (xy 257.06874 -133.862823)
			(xy 257.041243 -133.818059) (xy 257.020151 -133.769944) (xy 257.005864 -133.719389) (xy 256.998654 -133.667351)
			(xy 256.998216 -133.641084) (xy 256.998702 -133.613833) (xy 257.006458 -133.559885) (xy 257.021813 -133.50759)
			(xy 257.044455 -133.458013) (xy 257.073921 -133.412163) (xy 257.109612 -133.370972) (xy 257.150803 -133.335281)
			(xy 257.196653 -133.305815) (xy 257.24623 -133.283173) (xy 257.298525 -133.267818) (xy 257.352473 -133.260062)
			(xy 257.406975 -133.260062) (xy 257.460923 -133.267818) (xy 257.513218 -133.283173) (xy 257.562795 -133.305815)
			(xy 257.608645 -133.335281) (xy 257.649836 -133.370972) (xy 257.685527 -133.412163) (xy 257.714993 -133.458013)
			(xy 257.737635 -133.50759) (xy 257.75299 -133.559885) (xy 257.760746 -133.613833) (xy 257.761232 -133.641084)
			(xy 257.761006 -133.654757) (xy 262.95451 -133.654757) (xy 262.95451 -133.590835) (xy 262.962521 -133.527417)
			(xy 262.978418 -133.465503) (xy 263.00195 -133.40607) (xy 263.032744 -133.350055) (xy 263.070317 -133.29834)
			(xy 263.114074 -133.251743) (xy 263.163327 -133.210998) (xy 263.217298 -133.176747) (xy 263.275137 -133.14953)
			(xy 263.33593 -133.129777) (xy 263.39872 -133.117799) (xy 263.462516 -133.113786) (xy 263.526312 -133.117799)
			(xy 263.589102 -133.129777) (xy 263.649895 -133.14953) (xy 263.707734 -133.176747) (xy 263.761705 -133.210998)
			(xy 263.810958 -133.251743) (xy 263.854715 -133.29834) (xy 263.892288 -133.350055) (xy 263.923082 -133.40607)
			(xy 263.946614 -133.465503) (xy 263.962511 -133.527417) (xy 263.970522 -133.590835) (xy 263.971024 -133.622796)
			(xy 263.970522 -133.654757) (xy 264.98651 -133.654757) (xy 264.98651 -133.590835) (xy 264.994521 -133.527417)
			(xy 265.010418 -133.465503) (xy 265.03395 -133.40607) (xy 265.064744 -133.350055) (xy 265.102317 -133.29834)
			(xy 265.146074 -133.251743) (xy 265.195327 -133.210998) (xy 265.249298 -133.176747) (xy 265.307137 -133.14953)
			(xy 265.36793 -133.129777) (xy 265.43072 -133.117799) (xy 265.494516 -133.113786) (xy 265.558312 -133.117799)
			(xy 265.621102 -133.129777) (xy 265.681895 -133.14953) (xy 265.739734 -133.176747) (xy 265.793705 -133.210998)
			(xy 265.842958 -133.251743) (xy 265.886715 -133.29834) (xy 265.924288 -133.350055) (xy 265.955082 -133.40607)
			(xy 265.978614 -133.465503) (xy 265.994511 -133.527417) (xy 266.002522 -133.590835) (xy 266.003024 -133.622796)
			(xy 266.002522 -133.654757) (xy 265.994511 -133.718175) (xy 265.978614 -133.780089) (xy 265.955082 -133.839522)
			(xy 265.924288 -133.895537) (xy 265.886715 -133.947252) (xy 265.842958 -133.993849) (xy 265.793705 -134.034594)
			(xy 265.739734 -134.068845) (xy 265.681895 -134.096062) (xy 265.621102 -134.115815) (xy 265.558312 -134.127793)
			(xy 265.494516 -134.131807) (xy 265.43072 -134.127793) (xy 265.36793 -134.115815) (xy 265.307137 -134.096062)
			(xy 265.249298 -134.068845) (xy 265.195327 -134.034594) (xy 265.146074 -133.993849) (xy 265.102317 -133.947252)
			(xy 265.064744 -133.895537) (xy 265.03395 -133.839522) (xy 265.010418 -133.780089) (xy 264.994521 -133.718175)
			(xy 264.98651 -133.654757) (xy 263.970522 -133.654757) (xy 263.962511 -133.718175) (xy 263.946614 -133.780089)
			(xy 263.923082 -133.839522) (xy 263.892288 -133.895537) (xy 263.854715 -133.947252) (xy 263.810958 -133.993849)
			(xy 263.761705 -134.034594) (xy 263.707734 -134.068845) (xy 263.649895 -134.096062) (xy 263.589102 -134.115815)
			(xy 263.526312 -134.127793) (xy 263.462516 -134.131807) (xy 263.39872 -134.127793) (xy 263.33593 -134.115815)
			(xy 263.275137 -134.096062) (xy 263.217298 -134.068845) (xy 263.163327 -134.034594) (xy 263.114074 -133.993849)
			(xy 263.070317 -133.947252) (xy 263.032744 -133.895537) (xy 263.00195 -133.839522) (xy 262.978418 -133.780089)
			(xy 262.962521 -133.718175) (xy 262.95451 -133.654757) (xy 257.761006 -133.654757) (xy 257.760798 -133.667351)
			(xy 257.753587 -133.719389) (xy 257.739299 -133.769943) (xy 257.718205 -133.818057) (xy 257.690704 -133.862818)
			(xy 257.657318 -133.90338) (xy 257.638296 -133.9215) (xy 257.630954 -133.929043) (xy 257.622561 -133.948324)
			(xy 257.62204 -133.958838) (xy 257.62204 -134.033514) (xy 257.622495 -134.04404) (xy 257.630914 -134.063332)
			(xy 257.638296 -134.070852) (xy 257.657311 -134.088978) (xy 257.690693 -134.129541) (xy 257.718191 -134.174302)
			(xy 257.739285 -134.222414) (xy 257.753575 -134.272966) (xy 257.760791 -134.325002) (xy 257.761232 -134.351268)
			(xy 257.760715 -134.379565) (xy 257.752351 -134.435539) (xy 257.735817 -134.489665) (xy 257.73326 -134.495032)
			(xy 263.80262 -134.495032) (xy 263.806691 -134.43941) (xy 263.818817 -134.384973) (xy 263.83874 -134.332882)
			(xy 263.866036 -134.284247) (xy 263.900122 -134.240104) (xy 263.940271 -134.201395) (xy 263.985629 -134.168944)
			(xy 264.035229 -134.143443) (xy 264.088013 -134.125436) (xy 264.142856 -134.115306) (xy 264.19859 -134.113269)
			(xy 264.254027 -134.119369) (xy 264.307984 -134.133475) (xy 264.359313 -134.155287) (xy 264.406919 -134.184341)
			(xy 264.449787 -134.220016) (xy 264.487004 -134.261553) (xy 264.517777 -134.308066) (xy 264.541449 -134.358563)
			(xy 264.557517 -134.41197) (xy 264.565637 -134.467146) (xy 264.566146 -134.495032) (xy 264.565637 -134.522918)
			(xy 264.557517 -134.578094) (xy 264.541449 -134.631501) (xy 264.517777 -134.681998) (xy 264.487004 -134.728511)
			(xy 264.449787 -134.770048) (xy 264.406919 -134.805723) (xy 264.359313 -134.834777) (xy 264.307984 -134.856589)
			(xy 264.254027 -134.870695) (xy 264.19859 -134.876795) (xy 264.142856 -134.874758) (xy 264.088013 -134.864628)
			(xy 264.035229 -134.846621) (xy 263.985629 -134.82112) (xy 263.940271 -134.788669) (xy 263.900122 -134.74996)
			(xy 263.866036 -134.705817) (xy 263.83874 -134.657182) (xy 263.818817 -134.605091) (xy 263.806691 -134.550654)
			(xy 263.80262 -134.495032) (xy 257.73326 -134.495032) (xy 257.711474 -134.540758) (xy 257.679857 -134.587697)
			(xy 257.641657 -134.629456) (xy 257.620008 -134.647686) (xy 257.610102 -134.65556) (xy 257.60045 -134.67842)
			(xy 257.609086 -134.787386) (xy 257.622294 -134.808214) (xy 257.63347 -134.814564) (xy 257.662073 -134.831686)
			(xy 257.715002 -134.872212) (xy 257.762182 -134.919307) (xy 257.802804 -134.972163) (xy 257.836172 -135.029873)
			(xy 257.861713 -135.091448) (xy 257.87899 -135.155833) (xy 257.887706 -135.221923) (xy 257.888232 -135.255254)
			(xy 257.88773 -135.287215) (xy 257.879719 -135.350633) (xy 257.863822 -135.412547) (xy 257.84029 -135.47198)
			(xy 257.809496 -135.527995) (xy 257.771923 -135.57971) (xy 257.728166 -135.626307) (xy 257.678913 -135.667052)
			(xy 257.624942 -135.701303) (xy 257.567103 -135.72852) (xy 257.50631 -135.748273) (xy 257.44352 -135.760251)
			(xy 257.379724 -135.764265) (xy 257.315928 -135.760251) (xy 257.253138 -135.748273) (xy 257.192345 -135.72852)
			(xy 257.134506 -135.701303) (xy 257.080535 -135.667052) (xy 257.031282 -135.626307) (xy 256.987525 -135.57971)
			(xy 256.949952 -135.527995) (xy 256.919158 -135.47198) (xy 256.895626 -135.412547) (xy 256.879729 -135.350633)
			(xy 256.871718 -135.287215) (xy 256.871216 -135.255254) (xy 254.878737 -135.255254) (xy 254.870666 -135.263849)
			(xy 254.821413 -135.304594) (xy 254.767442 -135.338845) (xy 254.709603 -135.366062) (xy 254.64881 -135.385815)
			(xy 254.58602 -135.397793) (xy 254.522224 -135.401807) (xy 254.458428 -135.397793) (xy 254.395638 -135.385815)
			(xy 254.334845 -135.366062) (xy 254.277006 -135.338845) (xy 254.223035 -135.304594) (xy 254.173782 -135.263849)
			(xy 254.130025 -135.217252) (xy 254.092452 -135.165537) (xy 254.061658 -135.109522) (xy 254.038126 -135.050089)
			(xy 254.022229 -134.988175) (xy 254.014218 -134.924757) (xy 252.99823 -134.924757) (xy 252.990219 -134.988175)
			(xy 252.974322 -135.050089) (xy 252.95079 -135.109522) (xy 252.919996 -135.165537) (xy 252.882423 -135.217252)
			(xy 252.838666 -135.263849) (xy 252.789413 -135.304594) (xy 252.735442 -135.338845) (xy 252.677603 -135.366062)
			(xy 252.61681 -135.385815) (xy 252.55402 -135.397793) (xy 252.490224 -135.401807) (xy 252.426428 -135.397793)
			(xy 252.363638 -135.385815) (xy 252.302845 -135.366062) (xy 252.245006 -135.338845) (xy 252.191035 -135.304594)
			(xy 252.141782 -135.263849) (xy 252.098025 -135.217252) (xy 252.060452 -135.165537) (xy 252.029658 -135.109522)
			(xy 252.006126 -135.050089) (xy 251.990229 -134.988175) (xy 251.982218 -134.924757) (xy 248.083027 -134.924757)
			(xy 249.077691 -135.919421) (xy 262.641328 -135.919421) (xy 262.641328 -135.855499) (xy 262.649339 -135.792081)
			(xy 262.665236 -135.730167) (xy 262.688768 -135.670734) (xy 262.719562 -135.614719) (xy 262.757135 -135.563004)
			(xy 262.800892 -135.516407) (xy 262.850145 -135.475662) (xy 262.904116 -135.441411) (xy 262.961955 -135.414194)
			(xy 263.022748 -135.394441) (xy 263.085538 -135.382463) (xy 263.149334 -135.37845) (xy 263.21313 -135.382463)
			(xy 263.27592 -135.394441) (xy 263.336713 -135.414194) (xy 263.394552 -135.441411) (xy 263.448523 -135.475662)
			(xy 263.497776 -135.516407) (xy 263.541533 -135.563004) (xy 263.579106 -135.614719) (xy 263.6099 -135.670734)
			(xy 263.616244 -135.686757) (xy 264.98651 -135.686757) (xy 264.98651 -135.622835) (xy 264.994521 -135.559417)
			(xy 265.010418 -135.497503) (xy 265.03395 -135.43807) (xy 265.064744 -135.382055) (xy 265.102317 -135.33034)
			(xy 265.146074 -135.283743) (xy 265.195327 -135.242998) (xy 265.249298 -135.208747) (xy 265.307137 -135.18153)
			(xy 265.36793 -135.161777) (xy 265.43072 -135.149799) (xy 265.494516 -135.145786) (xy 265.558312 -135.149799)
			(xy 265.621102 -135.161777) (xy 265.681895 -135.18153) (xy 265.739734 -135.208747) (xy 265.793705 -135.242998)
			(xy 265.842958 -135.283743) (xy 265.886715 -135.33034) (xy 265.924288 -135.382055) (xy 265.955082 -135.43807)
			(xy 265.978614 -135.497503) (xy 265.994511 -135.559417) (xy 266.002522 -135.622835) (xy 266.003024 -135.654796)
			(xy 266.002522 -135.686757) (xy 265.994511 -135.750175) (xy 265.978614 -135.812089) (xy 265.955082 -135.871522)
			(xy 265.924288 -135.927537) (xy 265.886715 -135.979252) (xy 265.842958 -136.025849) (xy 265.793705 -136.066594)
			(xy 265.739734 -136.100845) (xy 265.681895 -136.128062) (xy 265.621102 -136.147815) (xy 265.558312 -136.159793)
			(xy 265.494516 -136.163807) (xy 265.43072 -136.159793) (xy 265.36793 -136.147815) (xy 265.307137 -136.128062)
			(xy 265.249298 -136.100845) (xy 265.195327 -136.066594) (xy 265.146074 -136.025849) (xy 265.102317 -135.979252)
			(xy 265.064744 -135.927537) (xy 265.03395 -135.871522) (xy 265.010418 -135.812089) (xy 264.994521 -135.750175)
			(xy 264.98651 -135.686757) (xy 263.616244 -135.686757) (xy 263.633432 -135.730167) (xy 263.649329 -135.792081)
			(xy 263.65734 -135.855499) (xy 263.657842 -135.88746) (xy 263.65734 -135.919421) (xy 263.649329 -135.982839)
			(xy 263.633432 -136.044753) (xy 263.6099 -136.104186) (xy 263.579106 -136.160201) (xy 263.541533 -136.211916)
			(xy 263.497776 -136.258513) (xy 263.448523 -136.299258) (xy 263.394552 -136.333509) (xy 263.336713 -136.360726)
			(xy 263.27592 -136.380479) (xy 263.21313 -136.392457) (xy 263.149334 -136.396471) (xy 263.085538 -136.392457)
			(xy 263.022748 -136.380479) (xy 262.961955 -136.360726) (xy 262.904116 -136.333509) (xy 262.850145 -136.299258)
			(xy 262.800892 -136.258513) (xy 262.757135 -136.211916) (xy 262.719562 -136.160201) (xy 262.688768 -136.104186)
			(xy 262.665236 -136.044753) (xy 262.649339 -135.982839) (xy 262.641328 -135.919421) (xy 249.077691 -135.919421)
			(xy 249.905266 -136.746996) (xy 249.912668 -136.753833) (xy 249.931266 -136.761544) (xy 249.941334 -136.761982)
		)
		(stroke
			(width 0)
			(type solid)
		)
		(fill yes)
		(layer "In6.Cu")
		(net "P5V_AUX")
	)
	(gr_poly
		(pts
			(xy 109.364018 -258.2164) (xy 109.374087 -258.215973) (xy 109.392686 -258.208254) (xy 109.400086 -258.201414)
			(xy 109.720634 -257.880866) (xy 109.727482 -257.873469) (xy 109.735215 -257.85487) (xy 109.73562 -257.844798)
			(xy 109.73562 -256.824226) (xy 109.735022 -256.812934) (xy 109.725414 -256.792494) (xy 109.717078 -256.784856)
			(xy 109.647482 -256.727706) (xy 109.625638 -256.722372) (xy 109.614462 -256.724404) (xy 109.597996 -256.727478)
			(xy 109.564663 -256.730786) (xy 109.547914 -256.731008) (xy 109.520926 -256.730507) (xy 109.467614 -256.722065)
			(xy 109.416279 -256.705388) (xy 109.368186 -256.680884) (xy 109.324517 -256.649159) (xy 109.28635 -256.610993)
			(xy 109.254623 -256.567326) (xy 109.230118 -256.519234) (xy 109.213438 -256.467899) (xy 109.204994 -256.414588)
			(xy 109.204506 -256.3876) (xy 109.205007 -256.36091) (xy 109.213269 -256.308174) (xy 109.229607 -256.257357)
			(xy 109.253627 -256.209687) (xy 109.268768 -256.187702) (xy 109.27715 -256.175764) (xy 109.279182 -256.147824)
			(xy 109.231176 -256.054606) (xy 109.226584 -256.046532) (xy 109.212799 -256.034104) (xy 109.195495 -256.027393)
			(xy 109.186218 -256.02692) (xy 108.95965 -256.02692) (xy 108.950372 -256.027376) (xy 108.933067 -256.034089)
			(xy 108.9193 -256.046538) (xy 108.914692 -256.054606) (xy 108.866686 -256.147824) (xy 108.868718 -256.175764)
			(xy 108.8771 -256.187702) (xy 108.892219 -256.209697) (xy 108.916201 -256.257378) (xy 108.932531 -256.30819)
			(xy 108.940819 -256.360915) (xy 108.941362 -256.3876) (xy 108.940882 -256.413299) (xy 108.933221 -256.464123)
			(xy 108.918072 -256.513237) (xy 108.895771 -256.559545) (xy 108.866818 -256.602012) (xy 108.831858 -256.639689)
			(xy 108.791674 -256.671735) (xy 108.747162 -256.697434) (xy 108.699317 -256.716211) (xy 108.649208 -256.727649)
			(xy 108.597954 -256.73149) (xy 108.5467 -256.727649) (xy 108.496591 -256.716211) (xy 108.448746 -256.697434)
			(xy 108.404234 -256.671735) (xy 108.36405 -256.639689) (xy 108.32909 -256.602012) (xy 108.300137 -256.559545)
			(xy 108.277836 -256.513237) (xy 108.262687 -256.464123) (xy 108.255026 -256.413299) (xy 108.254546 -256.3876)
			(xy 108.255048 -256.36091) (xy 108.26331 -256.308175) (xy 108.279649 -256.257358) (xy 108.303671 -256.20969)
			(xy 108.318808 -256.187702) (xy 108.32719 -256.175764) (xy 108.329222 -256.147824) (xy 108.281216 -256.054606)
			(xy 108.276626 -256.046527) (xy 108.262843 -256.034089) (xy 108.245538 -256.027365) (xy 108.236258 -256.02692)
			(xy 108.00969 -256.02692) (xy 108.000408 -256.02737) (xy 107.983092 -256.034074) (xy 107.969314 -256.046521)
			(xy 107.964732 -256.054606) (xy 107.916726 -256.147824) (xy 107.918758 -256.175764) (xy 107.92714 -256.187702)
			(xy 107.942258 -256.209698) (xy 107.966236 -256.257379) (xy 107.982565 -256.308191) (xy 107.990852 -256.360915)
			(xy 107.991402 -256.3876) (xy 107.990922 -256.413299) (xy 107.983261 -256.464123) (xy 107.968112 -256.513237)
			(xy 107.945811 -256.559545) (xy 107.916858 -256.602012) (xy 107.881898 -256.639689) (xy 107.841714 -256.671735)
			(xy 107.797202 -256.697434) (xy 107.749357 -256.716211) (xy 107.699248 -256.727649) (xy 107.647994 -256.73149)
			(xy 107.59674 -256.727649) (xy 107.546631 -256.716211) (xy 107.498786 -256.697434) (xy 107.454274 -256.671735)
			(xy 107.41409 -256.639689) (xy 107.37913 -256.602012) (xy 107.350177 -256.559545) (xy 107.327876 -256.513237)
			(xy 107.312727 -256.464123) (xy 107.305066 -256.413299) (xy 107.304586 -256.3876) (xy 107.305087 -256.36091)
			(xy 107.313348 -256.308174) (xy 107.329686 -256.257356) (xy 107.353704 -256.209685) (xy 107.368848 -256.187702)
			(xy 107.37723 -256.175764) (xy 107.379262 -256.147824) (xy 107.331256 -256.054606) (xy 107.326663 -256.046534)
			(xy 107.312877 -256.034112) (xy 107.295574 -256.027407) (xy 107.286298 -256.02692) (xy 107.264962 -256.02692)
			(xy 107.254894 -256.026491) (xy 107.236298 -256.018769) (xy 107.228894 -256.011934) (xy 106.874818 -255.657858)
			(xy 106.865799 -255.649846) (xy 106.842878 -255.642419) (xy 106.830876 -255.643634) (xy 106.737404 -255.658874)
			(xy 106.717592 -255.673352) (xy 106.712258 -255.684274) (xy 106.699614 -255.708304) (xy 106.667918 -255.752391)
			(xy 106.629685 -255.790945) (xy 106.585866 -255.82301) (xy 106.537551 -255.847786) (xy 106.485941 -255.864658)
			(xy 106.432321 -255.873206) (xy 106.405172 -255.873758) (xy 106.378187 -255.873227) (xy 106.324881 -255.864781)
			(xy 106.273553 -255.848101) (xy 106.225466 -255.823598) (xy 106.181802 -255.791876) (xy 106.143638 -255.753714)
			(xy 106.111913 -255.710053) (xy 106.087407 -255.661967) (xy 106.070724 -255.61064) (xy 106.062275 -255.557335)
			(xy 106.061764 -255.53035) (xy 106.062274 -255.503197) (xy 106.07081 -255.449566) (xy 106.087678 -255.397947)
			(xy 106.112456 -255.349623) (xy 106.144529 -255.3058) (xy 106.183097 -255.267569) (xy 106.2272 -255.235882)
			(xy 106.251248 -255.223264) (xy 106.26217 -255.21793) (xy 106.276648 -255.198118) (xy 106.291888 -255.104646)
			(xy 106.293159 -255.092636) (xy 106.285728 -255.069695) (xy 106.277664 -255.060704) (xy 106.148886 -254.931926)
			(xy 106.141488 -254.925079) (xy 106.12289 -254.917346) (xy 106.112818 -254.91694) (xy 105.250742 -254.91694)
			(xy 105.240678 -254.916505) (xy 105.222094 -254.908769) (xy 105.214674 -254.901954) (xy 103.974392 -253.661672)
			(xy 103.94188 -253.656592) (xy 103.927148 -253.664212) (xy 103.90549 -253.674797) (xy 103.859666 -253.689753)
			(xy 103.812058 -253.697306) (xy 103.787956 -253.69774) (xy 103.782622 -253.69774) (xy 103.756564 -253.696752)
			(xy 103.705343 -253.686994) (xy 103.656522 -253.668682) (xy 103.611519 -253.642345) (xy 103.571642 -253.60875)
			(xy 103.538048 -253.568871) (xy 103.511713 -253.523867) (xy 103.493402 -253.475046) (xy 103.483647 -253.423824)
			(xy 103.482648 -253.397766) (xy 103.482648 -253.392432) (xy 103.483104 -253.368332) (xy 103.49067 -253.32073)
			(xy 103.505604 -253.274902) (xy 103.516176 -253.25324) (xy 103.523796 -253.238508) (xy 103.518716 -253.205996)
			(xy 102.856538 -252.543818) (xy 102.849367 -252.537191) (xy 102.831452 -252.529471) (xy 102.811949 -252.529042)
			(xy 102.80269 -252.532134) (xy 102.704392 -252.56871) (xy 102.686612 -252.592078) (xy 102.685596 -252.607064)
			(xy 102.683214 -252.632364) (xy 102.671118 -252.681716) (xy 102.651016 -252.728384) (xy 102.623463 -252.771079)
			(xy 102.589221 -252.808622) (xy 102.549234 -252.839976) (xy 102.504607 -252.864275) (xy 102.456573 -252.880848)
			(xy 102.406457 -252.889238) (xy 102.38105 -252.889766) (xy 102.357063 -252.889292) (xy 102.309679 -252.881779)
			(xy 102.264055 -252.866947) (xy 102.221312 -252.84516) (xy 102.182504 -252.816955) (xy 102.148585 -252.783026)
			(xy 102.120392 -252.744209) (xy 102.098618 -252.70146) (xy 102.083799 -252.655831) (xy 102.076301 -252.608446)
			(xy 102.075742 -252.584458) (xy 102.075742 -252.583696) (xy 102.07587 -252.571319) (xy 102.077902 -252.54665)
			(xy 102.079806 -252.53442) (xy 102.084474 -252.509423) (xy 102.101004 -252.461335) (xy 102.125269 -252.416649)
			(xy 102.156599 -252.376599) (xy 102.19413 -252.34229) (xy 102.236824 -252.31467) (xy 102.283503 -252.294503)
			(xy 102.332877 -252.282344) (xy 102.35819 -252.279912) (xy 102.373176 -252.278642) (xy 102.396798 -252.261116)
			(xy 102.433374 -252.162818) (xy 102.43637 -252.153543) (xy 102.435912 -252.134074) (xy 102.428268 -252.116161)
			(xy 102.42169 -252.10897) (xy 102.285546 -251.972826) (xy 102.277826 -251.965767) (xy 102.258414 -251.958027)
			(xy 102.247954 -251.95784) (xy 102.165404 -251.96038) (xy 102.146608 -251.969016) (xy 102.139496 -251.977144)
			(xy 102.121958 -251.996089) (xy 102.081684 -252.028382) (xy 102.036552 -252.05344) (xy 101.987849 -252.070551)
			(xy 101.936961 -252.079225) (xy 101.91115 -252.07976) (xy 101.887163 -252.079286) (xy 101.83978 -252.071773)
			(xy 101.794156 -252.056941) (xy 101.751413 -252.035154) (xy 101.712606 -252.006949) (xy 101.678688 -251.97302)
			(xy 101.650495 -251.934203) (xy 101.628722 -251.891454) (xy 101.613904 -251.845825) (xy 101.606407 -251.798439)
			(xy 101.605842 -251.774452) (xy 101.605842 -251.77369) (xy 101.60597 -251.761313) (xy 101.608003 -251.736644)
			(xy 101.609906 -251.724414) (xy 101.614673 -251.698865) (xy 101.631738 -251.649778) (xy 101.656873 -251.604293)
			(xy 101.689352 -251.563724) (xy 101.708458 -251.546106) (xy 101.716586 -251.538994) (xy 101.725222 -251.520452)
			(xy 101.727762 -251.437648) (xy 101.727576 -251.427186) (xy 101.719849 -251.407765) (xy 101.712776 -251.400056)
			(xy 101.571552 -251.258832) (xy 101.544374 -251.251974) (xy 101.530658 -251.256292) (xy 101.508777 -251.262575)
			(xy 101.463758 -251.269336) (xy 101.440996 -251.269754) (xy 101.417004 -251.269283) (xy 101.36961 -251.261777)
			(xy 101.323973 -251.24695) (xy 101.281218 -251.225167) (xy 101.242396 -251.196964) (xy 101.208463 -251.163036)
			(xy 101.180255 -251.124218) (xy 101.158466 -251.081466) (xy 101.143633 -251.035831) (xy 101.13612 -250.988438)
			(xy 101.135688 -250.964446) (xy 101.136105 -250.941684) (xy 101.142858 -250.896663) (xy 101.14915 -250.874784)
			(xy 101.153468 -250.861068) (xy 101.14661 -250.83389) (xy 101.03739 -250.72467) (xy 101.029994 -250.717818)
			(xy 101.011395 -250.710076) (xy 101.001322 -250.709684) (xy 100.440998 -250.709684) (xy 100.431164 -250.709142)
			(xy 100.413012 -250.701545) (xy 100.405692 -250.694952) (xy 100.160074 -250.449334) (xy 100.13315 -250.442476)
			(xy 100.119434 -250.446794) (xy 100.097844 -250.452871) (xy 100.053468 -250.459379) (xy 100.031042 -250.459748)
			(xy 100.02774 -250.459748) (xy 100.00408 -250.45905) (xy 99.957395 -250.451248) (xy 99.912474 -250.436336)
			(xy 99.870391 -250.414671) (xy 99.832155 -250.386773) (xy 99.798681 -250.353308) (xy 99.770772 -250.31508)
			(xy 99.749096 -250.273003) (xy 99.734172 -250.228085) (xy 99.726357 -250.181403) (xy 99.725734 -250.157742)
			(xy 99.725734 -250.155202) (xy 99.726046 -250.132583) (xy 99.732547 -250.087819) (xy 99.738688 -250.066048)
			(xy 99.743006 -250.052332) (xy 99.736148 -250.025408) (xy 98.80473 -249.09399) (xy 98.797332 -249.087145)
			(xy 98.778733 -249.079422) (xy 98.768662 -249.079004) (xy 98.05162 -249.079004) (xy 98.038887 -249.079706)
			(xy 98.016492 -249.091836) (xy 98.008948 -249.102118) (xy 97.956624 -249.18289) (xy 97.954592 -249.20829)
			(xy 97.959926 -249.220228) (xy 97.968264 -249.239863) (xy 97.980028 -249.280865) (xy 97.985973 -249.323106)
			(xy 97.986342 -249.344434) (xy 97.98582 -249.369689) (xy 97.977507 -249.419511) (xy 97.961106 -249.467285)
			(xy 97.937065 -249.511708) (xy 97.906041 -249.551568) (xy 97.868879 -249.585778) (xy 97.826593 -249.613404)
			(xy 97.780337 -249.633694) (xy 97.731372 -249.646094) (xy 97.681034 -249.650265) (xy 97.630696 -249.646094)
			(xy 97.581731 -249.633694) (xy 97.535475 -249.613404) (xy 97.493189 -249.585778) (xy 97.456027 -249.551568)
			(xy 97.425003 -249.511708) (xy 97.400962 -249.467285) (xy 97.384561 -249.419511) (xy 97.376248 -249.369689)
			(xy 97.375726 -249.344434) (xy 97.37608 -249.323104) (xy 97.382018 -249.28086) (xy 97.393784 -249.239855)
			(xy 97.402142 -249.220228) (xy 97.407476 -249.20829) (xy 97.405444 -249.18289) (xy 97.35312 -249.102118)
			(xy 97.34826 -249.095181) (xy 97.334925 -249.084754) (xy 97.318913 -249.079263) (xy 97.310448 -249.079004)
			(xy 96.659446 -249.079004) (xy 96.64938 -249.079437) (xy 96.63079 -249.087166) (xy 96.623378 -249.09399)
			(xy 96.394016 -249.323352) (xy 96.387306 -249.330591) (xy 96.379722 -249.348796) (xy 96.379284 -249.358658)
			(xy 96.379284 -249.850402) (xy 96.39427 -249.874786) (xy 96.407478 -249.881136) (xy 96.428894 -249.892361)
			(xy 96.468191 -249.92053) (xy 96.50256 -249.954537) (xy 96.531145 -249.993532) (xy 96.553232 -250.036543)
			(xy 96.568269 -250.082496) (xy 96.575881 -250.130243) (xy 96.575879 -250.15444) (xy 97.84513 -250.15444)
			(xy 97.84909 -250.105386) (xy 97.860867 -250.057602) (xy 97.880158 -250.012326) (xy 97.906461 -249.97073)
			(xy 97.939096 -249.933893) (xy 97.977217 -249.902768) (xy 98.019838 -249.878161) (xy 98.065854 -249.860709)
			(xy 98.114073 -249.850865) (xy 98.163248 -249.848884) (xy 98.212103 -249.854816) (xy 98.259374 -249.868508)
			(xy 98.303836 -249.889606) (xy 98.344339 -249.917562) (xy 98.379832 -249.951654) (xy 98.409397 -249.990998)
			(xy 98.432268 -250.034575) (xy 98.447852 -250.081256) (xy 98.455747 -250.129833) (xy 98.456242 -250.15444)
			(xy 98.455747 -250.179047) (xy 98.447852 -250.227624) (xy 98.432268 -250.274305) (xy 98.409397 -250.317882)
			(xy 98.379832 -250.357226) (xy 98.344339 -250.391318) (xy 98.303836 -250.419274) (xy 98.259374 -250.440372)
			(xy 98.212103 -250.454064) (xy 98.163248 -250.459996) (xy 98.114073 -250.458015) (xy 98.065854 -250.448171)
			(xy 98.019838 -250.430719) (xy 97.977217 -250.406112) (xy 97.939096 -250.374987) (xy 97.906461 -250.33815)
			(xy 97.880158 -250.296554) (xy 97.860867 -250.251278) (xy 97.84909 -250.203494) (xy 97.84513 -250.15444)
			(xy 96.575879 -250.15444) (xy 96.575878 -250.178593) (xy 96.568261 -250.226339) (xy 96.553218 -250.27229)
			(xy 96.531126 -250.315298) (xy 96.502537 -250.35429) (xy 96.468163 -250.388293) (xy 96.428863 -250.416457)
			(xy 96.407478 -250.427744) (xy 96.39427 -250.434094) (xy 96.379284 -250.458478) (xy 96.379284 -250.964446)
			(xy 97.37523 -250.964446) (xy 97.37919 -250.915392) (xy 97.390967 -250.867608) (xy 97.410258 -250.822332)
			(xy 97.436561 -250.780736) (xy 97.469196 -250.743899) (xy 97.507317 -250.712774) (xy 97.549938 -250.688167)
			(xy 97.595954 -250.670715) (xy 97.644173 -250.660871) (xy 97.693348 -250.65889) (xy 97.742203 -250.664822)
			(xy 97.789474 -250.678514) (xy 97.833936 -250.699612) (xy 97.874439 -250.727568) (xy 97.909932 -250.76166)
			(xy 97.939497 -250.801004) (xy 97.962368 -250.844581) (xy 97.977952 -250.891262) (xy 97.985847 -250.939839)
			(xy 97.986342 -250.964446) (xy 99.255338 -250.964446) (xy 99.259298 -250.915392) (xy 99.271075 -250.867608)
			(xy 99.290366 -250.822332) (xy 99.316669 -250.780736) (xy 99.349304 -250.743899) (xy 99.387425 -250.712774)
			(xy 99.430046 -250.688167) (xy 99.476062 -250.670715) (xy 99.524281 -250.660871) (xy 99.573456 -250.65889)
			(xy 99.622311 -250.664822) (xy 99.669582 -250.678514) (xy 99.714044 -250.699612) (xy 99.754547 -250.727568)
			(xy 99.79004 -250.76166) (xy 99.819605 -250.801004) (xy 99.842476 -250.844581) (xy 99.85806 -250.891262)
			(xy 99.865955 -250.939839) (xy 99.86645 -250.964446) (xy 99.865955 -250.989053) (xy 99.85806 -251.03763)
			(xy 99.842476 -251.084311) (xy 99.819605 -251.127888) (xy 99.79004 -251.167232) (xy 99.754547 -251.201324)
			(xy 99.714044 -251.22928) (xy 99.669582 -251.250378) (xy 99.622311 -251.26407) (xy 99.573456 -251.270002)
			(xy 99.524281 -251.268021) (xy 99.476062 -251.258177) (xy 99.430046 -251.240725) (xy 99.387425 -251.216118)
			(xy 99.349304 -251.184993) (xy 99.316669 -251.148156) (xy 99.290366 -251.10656) (xy 99.271075 -251.061284)
			(xy 99.259298 -251.0135) (xy 99.255338 -250.964446) (xy 97.986342 -250.964446) (xy 97.985847 -250.989053)
			(xy 97.977952 -251.03763) (xy 97.962368 -251.084311) (xy 97.939497 -251.127888) (xy 97.909932 -251.167232)
			(xy 97.874439 -251.201324) (xy 97.833936 -251.22928) (xy 97.789474 -251.250378) (xy 97.742203 -251.26407)
			(xy 97.693348 -251.270002) (xy 97.644173 -251.268021) (xy 97.595954 -251.258177) (xy 97.549938 -251.240725)
			(xy 97.507317 -251.216118) (xy 97.469196 -251.184993) (xy 97.436561 -251.148156) (xy 97.410258 -251.10656)
			(xy 97.390967 -251.061284) (xy 97.37919 -251.0135) (xy 97.37523 -250.964446) (xy 96.379284 -250.964446)
			(xy 96.379284 -251.470414) (xy 96.39427 -251.494798) (xy 96.407478 -251.501148) (xy 96.428901 -251.512373)
			(xy 96.468211 -251.540545) (xy 96.502594 -251.574556) (xy 96.531192 -251.613558) (xy 96.553289 -251.656576)
			(xy 96.568336 -251.702539) (xy 96.575956 -251.750297) (xy 96.575958 -251.774452) (xy 97.84513 -251.774452)
			(xy 97.84909 -251.725398) (xy 97.860867 -251.677614) (xy 97.880158 -251.632338) (xy 97.906461 -251.590742)
			(xy 97.939096 -251.553905) (xy 97.977217 -251.52278) (xy 98.019838 -251.498173) (xy 98.065854 -251.480721)
			(xy 98.114073 -251.470877) (xy 98.163248 -251.468896) (xy 98.212103 -251.474828) (xy 98.259374 -251.48852)
			(xy 98.303836 -251.509618) (xy 98.344339 -251.537574) (xy 98.379832 -251.571666) (xy 98.409397 -251.61101)
			(xy 98.432268 -251.654587) (xy 98.447852 -251.701268) (xy 98.455747 -251.749845) (xy 98.456242 -251.774452)
			(xy 99.725238 -251.774452) (xy 99.729198 -251.725398) (xy 99.740975 -251.677614) (xy 99.760266 -251.632338)
			(xy 99.786569 -251.590742) (xy 99.819204 -251.553905) (xy 99.857325 -251.52278) (xy 99.899946 -251.498173)
			(xy 99.945962 -251.480721) (xy 99.994181 -251.470877) (xy 100.043356 -251.468896) (xy 100.092211 -251.474828)
			(xy 100.139482 -251.48852) (xy 100.183944 -251.509618) (xy 100.224447 -251.537574) (xy 100.25994 -251.571666)
			(xy 100.289505 -251.61101) (xy 100.312376 -251.654587) (xy 100.32796 -251.701268) (xy 100.335855 -251.749845)
			(xy 100.33635 -251.774452) (xy 100.335855 -251.799059) (xy 100.32796 -251.847636) (xy 100.312376 -251.894317)
			(xy 100.289505 -251.937894) (xy 100.25994 -251.977238) (xy 100.224447 -252.01133) (xy 100.183944 -252.039286)
			(xy 100.139482 -252.060384) (xy 100.092211 -252.074076) (xy 100.043356 -252.080008) (xy 99.994181 -252.078027)
			(xy 99.945962 -252.068183) (xy 99.899946 -252.050731) (xy 99.857325 -252.026124) (xy 99.819204 -251.994999)
			(xy 99.786569 -251.958162) (xy 99.760266 -251.916566) (xy 99.740975 -251.87129) (xy 99.729198 -251.823506)
			(xy 99.725238 -251.774452) (xy 98.456242 -251.774452) (xy 98.455747 -251.799059) (xy 98.447852 -251.847636)
			(xy 98.432268 -251.894317) (xy 98.409397 -251.937894) (xy 98.379832 -251.977238) (xy 98.344339 -252.01133)
			(xy 98.303836 -252.039286) (xy 98.259374 -252.060384) (xy 98.212103 -252.074076) (xy 98.163248 -252.080008)
			(xy 98.114073 -252.078027) (xy 98.065854 -252.068183) (xy 98.019838 -252.050731) (xy 97.977217 -252.026124)
			(xy 97.939096 -251.994999) (xy 97.906461 -251.958162) (xy 97.880158 -251.916566) (xy 97.860867 -251.87129)
			(xy 97.84909 -251.823506) (xy 97.84513 -251.774452) (xy 96.575958 -251.774452) (xy 96.57596 -251.79866)
			(xy 96.568346 -251.846419) (xy 96.553306 -251.892384) (xy 96.531214 -251.935406) (xy 96.502622 -251.974412)
			(xy 96.468244 -252.008427) (xy 96.428938 -252.036604) (xy 96.407478 -252.047756) (xy 96.39427 -252.054106)
			(xy 96.379284 -252.07849) (xy 96.379284 -252.584458) (xy 97.37523 -252.584458) (xy 97.37919 -252.535404)
			(xy 97.390967 -252.48762) (xy 97.410258 -252.442344) (xy 97.436561 -252.400748) (xy 97.469196 -252.363911)
			(xy 97.507317 -252.332786) (xy 97.549938 -252.308179) (xy 97.595954 -252.290727) (xy 97.644173 -252.280883)
			(xy 97.693348 -252.278902) (xy 97.742203 -252.284834) (xy 97.789474 -252.298526) (xy 97.833936 -252.319624)
			(xy 97.874439 -252.34758) (xy 97.909932 -252.381672) (xy 97.939497 -252.421016) (xy 97.962368 -252.464593)
			(xy 97.977952 -252.511274) (xy 97.985847 -252.559851) (xy 97.986342 -252.584458) (xy 99.255338 -252.584458)
			(xy 99.259298 -252.535404) (xy 99.271075 -252.48762) (xy 99.290366 -252.442344) (xy 99.316669 -252.400748)
			(xy 99.349304 -252.363911) (xy 99.387425 -252.332786) (xy 99.430046 -252.308179) (xy 99.476062 -252.290727)
			(xy 99.524281 -252.280883) (xy 99.573456 -252.278902) (xy 99.622311 -252.284834) (xy 99.669582 -252.298526)
			(xy 99.714044 -252.319624) (xy 99.754547 -252.34758) (xy 99.79004 -252.381672) (xy 99.819605 -252.421016)
			(xy 99.842476 -252.464593) (xy 99.85806 -252.511274) (xy 99.865955 -252.559851) (xy 99.86645 -252.584458)
			(xy 101.135192 -252.584458) (xy 101.139152 -252.535404) (xy 101.150929 -252.48762) (xy 101.17022 -252.442344)
			(xy 101.196523 -252.400748) (xy 101.229158 -252.363911) (xy 101.267279 -252.332786) (xy 101.3099 -252.308179)
			(xy 101.355916 -252.290727) (xy 101.404135 -252.280883) (xy 101.45331 -252.278902) (xy 101.502165 -252.284834)
			(xy 101.549436 -252.298526) (xy 101.593898 -252.319624) (xy 101.634401 -252.34758) (xy 101.669894 -252.381672)
			(xy 101.699459 -252.421016) (xy 101.72233 -252.464593) (xy 101.737914 -252.511274) (xy 101.745809 -252.559851)
			(xy 101.746304 -252.584458) (xy 101.745809 -252.609065) (xy 101.737914 -252.657642) (xy 101.72233 -252.704323)
			(xy 101.699459 -252.7479) (xy 101.669894 -252.787244) (xy 101.634401 -252.821336) (xy 101.593898 -252.849292)
			(xy 101.549436 -252.87039) (xy 101.502165 -252.884082) (xy 101.45331 -252.890014) (xy 101.404135 -252.888033)
			(xy 101.355916 -252.878189) (xy 101.3099 -252.860737) (xy 101.267279 -252.83613) (xy 101.229158 -252.805005)
			(xy 101.196523 -252.768168) (xy 101.17022 -252.726572) (xy 101.150929 -252.681296) (xy 101.139152 -252.633512)
			(xy 101.135192 -252.584458) (xy 99.86645 -252.584458) (xy 99.865955 -252.609065) (xy 99.85806 -252.657642)
			(xy 99.842476 -252.704323) (xy 99.819605 -252.7479) (xy 99.79004 -252.787244) (xy 99.754547 -252.821336)
			(xy 99.714044 -252.849292) (xy 99.669582 -252.87039) (xy 99.622311 -252.884082) (xy 99.573456 -252.890014)
			(xy 99.524281 -252.888033) (xy 99.476062 -252.878189) (xy 99.430046 -252.860737) (xy 99.387425 -252.83613)
			(xy 99.349304 -252.805005) (xy 99.316669 -252.768168) (xy 99.290366 -252.726572) (xy 99.271075 -252.681296)
			(xy 99.259298 -252.633512) (xy 99.255338 -252.584458) (xy 97.986342 -252.584458) (xy 97.985847 -252.609065)
			(xy 97.977952 -252.657642) (xy 97.962368 -252.704323) (xy 97.939497 -252.7479) (xy 97.909932 -252.787244)
			(xy 97.874439 -252.821336) (xy 97.833936 -252.849292) (xy 97.789474 -252.87039) (xy 97.742203 -252.884082)
			(xy 97.693348 -252.890014) (xy 97.644173 -252.888033) (xy 97.595954 -252.878189) (xy 97.549938 -252.860737)
			(xy 97.507317 -252.83613) (xy 97.469196 -252.805005) (xy 97.436561 -252.768168) (xy 97.410258 -252.726572)
			(xy 97.390967 -252.681296) (xy 97.37919 -252.633512) (xy 97.37523 -252.584458) (xy 96.379284 -252.584458)
			(xy 96.379284 -253.090426) (xy 96.39427 -253.11481) (xy 96.407478 -253.12116) (xy 96.4289 -253.132385)
			(xy 96.468208 -253.160556) (xy 96.50259 -253.194567) (xy 96.531185 -253.233568) (xy 96.553282 -253.276586)
			(xy 96.568327 -253.322547) (xy 96.575946 -253.370303) (xy 96.575947 -253.394464) (xy 97.84513 -253.394464)
			(xy 97.84909 -253.34541) (xy 97.860867 -253.297626) (xy 97.880158 -253.25235) (xy 97.906461 -253.210754)
			(xy 97.939096 -253.173917) (xy 97.977217 -253.142792) (xy 98.019838 -253.118185) (xy 98.065854 -253.100733)
			(xy 98.114073 -253.090889) (xy 98.163248 -253.088908) (xy 98.212103 -253.09484) (xy 98.259374 -253.108532)
			(xy 98.303836 -253.12963) (xy 98.344339 -253.157586) (xy 98.379832 -253.191678) (xy 98.409397 -253.231022)
			(xy 98.432268 -253.274599) (xy 98.447852 -253.32128) (xy 98.455747 -253.369857) (xy 98.456242 -253.394464)
			(xy 99.725238 -253.394464) (xy 99.729198 -253.34541) (xy 99.740975 -253.297626) (xy 99.760266 -253.25235)
			(xy 99.786569 -253.210754) (xy 99.819204 -253.173917) (xy 99.857325 -253.142792) (xy 99.899946 -253.118185)
			(xy 99.945962 -253.100733) (xy 99.994181 -253.090889) (xy 100.043356 -253.088908) (xy 100.092211 -253.09484)
			(xy 100.139482 -253.108532) (xy 100.183944 -253.12963) (xy 100.224447 -253.157586) (xy 100.25994 -253.191678)
			(xy 100.289505 -253.231022) (xy 100.312376 -253.274599) (xy 100.32796 -253.32128) (xy 100.335855 -253.369857)
			(xy 100.33635 -253.394464) (xy 100.665292 -253.394464) (xy 100.669252 -253.34541) (xy 100.681029 -253.297626)
			(xy 100.70032 -253.25235) (xy 100.726623 -253.210754) (xy 100.759258 -253.173917) (xy 100.797379 -253.142792)
			(xy 100.84 -253.118185) (xy 100.886016 -253.100733) (xy 100.934235 -253.090889) (xy 100.98341 -253.088908)
			(xy 101.032265 -253.09484) (xy 101.079536 -253.108532) (xy 101.123998 -253.12963) (xy 101.164501 -253.157586)
			(xy 101.199994 -253.191678) (xy 101.229559 -253.231022) (xy 101.25243 -253.274599) (xy 101.268014 -253.32128)
			(xy 101.275909 -253.369857) (xy 101.276404 -253.394464) (xy 101.605346 -253.394464) (xy 101.609306 -253.34541)
			(xy 101.621083 -253.297626) (xy 101.640374 -253.25235) (xy 101.666677 -253.210754) (xy 101.699312 -253.173917)
			(xy 101.737433 -253.142792) (xy 101.780054 -253.118185) (xy 101.82607 -253.100733) (xy 101.874289 -253.090889)
			(xy 101.923464 -253.088908) (xy 101.972319 -253.09484) (xy 102.01959 -253.108532) (xy 102.064052 -253.12963)
			(xy 102.104555 -253.157586) (xy 102.140048 -253.191678) (xy 102.169613 -253.231022) (xy 102.192484 -253.274599)
			(xy 102.208068 -253.32128) (xy 102.215963 -253.369857) (xy 102.216458 -253.394464) (xy 102.215963 -253.419071)
			(xy 102.208068 -253.467648) (xy 102.192484 -253.514329) (xy 102.169613 -253.557906) (xy 102.140048 -253.59725)
			(xy 102.104555 -253.631342) (xy 102.064052 -253.659298) (xy 102.01959 -253.680396) (xy 101.972319 -253.694088)
			(xy 101.923464 -253.70002) (xy 101.874289 -253.698039) (xy 101.82607 -253.688195) (xy 101.780054 -253.670743)
			(xy 101.737433 -253.646136) (xy 101.699312 -253.615011) (xy 101.666677 -253.578174) (xy 101.640374 -253.536578)
			(xy 101.621083 -253.491302) (xy 101.609306 -253.443518) (xy 101.605346 -253.394464) (xy 101.276404 -253.394464)
			(xy 101.275909 -253.419071) (xy 101.268014 -253.467648) (xy 101.25243 -253.514329) (xy 101.229559 -253.557906)
			(xy 101.199994 -253.59725) (xy 101.164501 -253.631342) (xy 101.123998 -253.659298) (xy 101.079536 -253.680396)
			(xy 101.032265 -253.694088) (xy 100.98341 -253.70002) (xy 100.934235 -253.698039) (xy 100.886016 -253.688195)
			(xy 100.84 -253.670743) (xy 100.797379 -253.646136) (xy 100.759258 -253.615011) (xy 100.726623 -253.578174)
			(xy 100.70032 -253.536578) (xy 100.681029 -253.491302) (xy 100.669252 -253.443518) (xy 100.665292 -253.394464)
			(xy 100.33635 -253.394464) (xy 100.335855 -253.419071) (xy 100.32796 -253.467648) (xy 100.312376 -253.514329)
			(xy 100.289505 -253.557906) (xy 100.25994 -253.59725) (xy 100.224447 -253.631342) (xy 100.183944 -253.659298)
			(xy 100.139482 -253.680396) (xy 100.092211 -253.694088) (xy 100.043356 -253.70002) (xy 99.994181 -253.698039)
			(xy 99.945962 -253.688195) (xy 99.899946 -253.670743) (xy 99.857325 -253.646136) (xy 99.819204 -253.615011)
			(xy 99.786569 -253.578174) (xy 99.760266 -253.536578) (xy 99.740975 -253.491302) (xy 99.729198 -253.443518)
			(xy 99.725238 -253.394464) (xy 98.456242 -253.394464) (xy 98.455747 -253.419071) (xy 98.447852 -253.467648)
			(xy 98.432268 -253.514329) (xy 98.409397 -253.557906) (xy 98.379832 -253.59725) (xy 98.344339 -253.631342)
			(xy 98.303836 -253.659298) (xy 98.259374 -253.680396) (xy 98.212103 -253.694088) (xy 98.163248 -253.70002)
			(xy 98.114073 -253.698039) (xy 98.065854 -253.688195) (xy 98.019838 -253.670743) (xy 97.977217 -253.646136)
			(xy 97.939096 -253.615011) (xy 97.906461 -253.578174) (xy 97.880158 -253.536578) (xy 97.860867 -253.491302)
			(xy 97.84909 -253.443518) (xy 97.84513 -253.394464) (xy 96.575947 -253.394464) (xy 96.575949 -253.418664)
			(xy 96.568335 -253.466422) (xy 96.553294 -253.512385) (xy 96.531202 -253.555405) (xy 96.502611 -253.594409)
			(xy 96.468233 -253.628423) (xy 96.428927 -253.656598) (xy 96.407478 -253.667768) (xy 96.39427 -253.674118)
			(xy 96.379284 -253.698502) (xy 96.379284 -254.20447) (xy 97.37523 -254.20447) (xy 97.37919 -254.155416)
			(xy 97.390967 -254.107632) (xy 97.410258 -254.062356) (xy 97.436561 -254.02076) (xy 97.469196 -253.983923)
			(xy 97.507317 -253.952798) (xy 97.549938 -253.928191) (xy 97.595954 -253.910739) (xy 97.644173 -253.900895)
			(xy 97.693348 -253.898914) (xy 97.742203 -253.904846) (xy 97.789474 -253.918538) (xy 97.833936 -253.939636)
			(xy 97.874439 -253.967592) (xy 97.909932 -254.001684) (xy 97.939497 -254.041028) (xy 97.962368 -254.084605)
			(xy 97.977952 -254.131286) (xy 97.985847 -254.179863) (xy 97.986342 -254.20447) (xy 99.255338 -254.20447)
			(xy 99.259298 -254.155416) (xy 99.271075 -254.107632) (xy 99.290366 -254.062356) (xy 99.316669 -254.02076)
			(xy 99.349304 -253.983923) (xy 99.387425 -253.952798) (xy 99.430046 -253.928191) (xy 99.476062 -253.910739)
			(xy 99.524281 -253.900895) (xy 99.573456 -253.898914) (xy 99.622311 -253.904846) (xy 99.669582 -253.918538)
			(xy 99.714044 -253.939636) (xy 99.754547 -253.967592) (xy 99.79004 -254.001684) (xy 99.819605 -254.041028)
			(xy 99.842476 -254.084605) (xy 99.85806 -254.131286) (xy 99.865955 -254.179863) (xy 99.86645 -254.20447)
			(xy 101.135192 -254.20447) (xy 101.139152 -254.155416) (xy 101.150929 -254.107632) (xy 101.17022 -254.062356)
			(xy 101.196523 -254.02076) (xy 101.229158 -253.983923) (xy 101.267279 -253.952798) (xy 101.3099 -253.928191)
			(xy 101.355916 -253.910739) (xy 101.404135 -253.900895) (xy 101.45331 -253.898914) (xy 101.502165 -253.904846)
			(xy 101.549436 -253.918538) (xy 101.593898 -253.939636) (xy 101.634401 -253.967592) (xy 101.669894 -254.001684)
			(xy 101.699459 -254.041028) (xy 101.72233 -254.084605) (xy 101.737914 -254.131286) (xy 101.745809 -254.179863)
			(xy 101.746304 -254.20447) (xy 102.075246 -254.20447) (xy 102.079206 -254.155416) (xy 102.090983 -254.107632)
			(xy 102.110274 -254.062356) (xy 102.136577 -254.02076) (xy 102.169212 -253.983923) (xy 102.207333 -253.952798)
			(xy 102.249954 -253.928191) (xy 102.29597 -253.910739) (xy 102.344189 -253.900895) (xy 102.393364 -253.898914)
			(xy 102.442219 -253.904846) (xy 102.48949 -253.918538) (xy 102.533952 -253.939636) (xy 102.574455 -253.967592)
			(xy 102.609948 -254.001684) (xy 102.639513 -254.041028) (xy 102.662384 -254.084605) (xy 102.677968 -254.131286)
			(xy 102.685863 -254.179863) (xy 102.686358 -254.20447) (xy 102.685863 -254.229077) (xy 102.677968 -254.277654)
			(xy 102.662384 -254.324335) (xy 102.639513 -254.367912) (xy 102.609948 -254.407256) (xy 102.574455 -254.441348)
			(xy 102.533952 -254.469304) (xy 102.48949 -254.490402) (xy 102.442219 -254.504094) (xy 102.393364 -254.510026)
			(xy 102.344189 -254.508045) (xy 102.29597 -254.498201) (xy 102.249954 -254.480749) (xy 102.207333 -254.456142)
			(xy 102.169212 -254.425017) (xy 102.136577 -254.38818) (xy 102.110274 -254.346584) (xy 102.090983 -254.301308)
			(xy 102.079206 -254.253524) (xy 102.075246 -254.20447) (xy 101.746304 -254.20447) (xy 101.745809 -254.229077)
			(xy 101.737914 -254.277654) (xy 101.72233 -254.324335) (xy 101.699459 -254.367912) (xy 101.669894 -254.407256)
			(xy 101.634401 -254.441348) (xy 101.593898 -254.469304) (xy 101.549436 -254.490402) (xy 101.502165 -254.504094)
			(xy 101.45331 -254.510026) (xy 101.404135 -254.508045) (xy 101.355916 -254.498201) (xy 101.3099 -254.480749)
			(xy 101.267279 -254.456142) (xy 101.229158 -254.425017) (xy 101.196523 -254.38818) (xy 101.17022 -254.346584)
			(xy 101.150929 -254.301308) (xy 101.139152 -254.253524) (xy 101.135192 -254.20447) (xy 99.86645 -254.20447)
			(xy 99.865955 -254.229077) (xy 99.85806 -254.277654) (xy 99.842476 -254.324335) (xy 99.819605 -254.367912)
			(xy 99.79004 -254.407256) (xy 99.754547 -254.441348) (xy 99.714044 -254.469304) (xy 99.669582 -254.490402)
			(xy 99.622311 -254.504094) (xy 99.573456 -254.510026) (xy 99.524281 -254.508045) (xy 99.476062 -254.498201)
			(xy 99.430046 -254.480749) (xy 99.387425 -254.456142) (xy 99.349304 -254.425017) (xy 99.316669 -254.38818)
			(xy 99.290366 -254.346584) (xy 99.271075 -254.301308) (xy 99.259298 -254.253524) (xy 99.255338 -254.20447)
			(xy 97.986342 -254.20447) (xy 97.985847 -254.229077) (xy 97.977952 -254.277654) (xy 97.962368 -254.324335)
			(xy 97.939497 -254.367912) (xy 97.909932 -254.407256) (xy 97.874439 -254.441348) (xy 97.833936 -254.469304)
			(xy 97.789474 -254.490402) (xy 97.742203 -254.504094) (xy 97.693348 -254.510026) (xy 97.644173 -254.508045)
			(xy 97.595954 -254.498201) (xy 97.549938 -254.480749) (xy 97.507317 -254.456142) (xy 97.469196 -254.425017)
			(xy 97.436561 -254.38818) (xy 97.410258 -254.346584) (xy 97.390967 -254.301308) (xy 97.37919 -254.253524)
			(xy 97.37523 -254.20447) (xy 96.379284 -254.20447) (xy 96.379284 -254.710438) (xy 96.39427 -254.734822)
			(xy 96.407478 -254.741172) (xy 96.428899 -254.752397) (xy 96.468206 -254.780568) (xy 96.502585 -254.814578)
			(xy 96.531179 -254.853578) (xy 96.553274 -254.896595) (xy 96.568318 -254.942554) (xy 96.575936 -254.99031)
			(xy 96.575937 -255.014476) (xy 97.84513 -255.014476) (xy 97.84909 -254.965422) (xy 97.860867 -254.917638)
			(xy 97.880158 -254.872362) (xy 97.906461 -254.830766) (xy 97.939096 -254.793929) (xy 97.977217 -254.762804)
			(xy 98.019838 -254.738197) (xy 98.065854 -254.720745) (xy 98.114073 -254.710901) (xy 98.163248 -254.70892)
			(xy 98.212103 -254.714852) (xy 98.259374 -254.728544) (xy 98.303836 -254.749642) (xy 98.344339 -254.777598)
			(xy 98.379832 -254.81169) (xy 98.409397 -254.851034) (xy 98.432268 -254.894611) (xy 98.447852 -254.941292)
			(xy 98.455747 -254.989869) (xy 98.456242 -255.014476) (xy 99.725238 -255.014476) (xy 99.729198 -254.965422)
			(xy 99.740975 -254.917638) (xy 99.760266 -254.872362) (xy 99.786569 -254.830766) (xy 99.819204 -254.793929)
			(xy 99.857325 -254.762804) (xy 99.899946 -254.738197) (xy 99.945962 -254.720745) (xy 99.994181 -254.710901)
			(xy 100.043356 -254.70892) (xy 100.092211 -254.714852) (xy 100.139482 -254.728544) (xy 100.183944 -254.749642)
			(xy 100.224447 -254.777598) (xy 100.25994 -254.81169) (xy 100.289505 -254.851034) (xy 100.312376 -254.894611)
			(xy 100.32796 -254.941292) (xy 100.335855 -254.989869) (xy 100.33635 -255.014476) (xy 100.665292 -255.014476)
			(xy 100.669252 -254.965422) (xy 100.681029 -254.917638) (xy 100.70032 -254.872362) (xy 100.726623 -254.830766)
			(xy 100.759258 -254.793929) (xy 100.797379 -254.762804) (xy 100.84 -254.738197) (xy 100.886016 -254.720745)
			(xy 100.934235 -254.710901) (xy 100.98341 -254.70892) (xy 101.032265 -254.714852) (xy 101.079536 -254.728544)
			(xy 101.123998 -254.749642) (xy 101.164501 -254.777598) (xy 101.199994 -254.81169) (xy 101.229559 -254.851034)
			(xy 101.25243 -254.894611) (xy 101.268014 -254.941292) (xy 101.275909 -254.989869) (xy 101.276404 -255.014476)
			(xy 101.605346 -255.014476) (xy 101.609306 -254.965422) (xy 101.621083 -254.917638) (xy 101.640374 -254.872362)
			(xy 101.666677 -254.830766) (xy 101.699312 -254.793929) (xy 101.737433 -254.762804) (xy 101.780054 -254.738197)
			(xy 101.82607 -254.720745) (xy 101.874289 -254.710901) (xy 101.923464 -254.70892) (xy 101.972319 -254.714852)
			(xy 102.01959 -254.728544) (xy 102.064052 -254.749642) (xy 102.104555 -254.777598) (xy 102.140048 -254.81169)
			(xy 102.169613 -254.851034) (xy 102.192484 -254.894611) (xy 102.208068 -254.941292) (xy 102.215963 -254.989869)
			(xy 102.216458 -255.014476) (xy 102.215963 -255.039083) (xy 102.208068 -255.08766) (xy 102.192484 -255.134341)
			(xy 102.169613 -255.177918) (xy 102.140048 -255.217262) (xy 102.104555 -255.251354) (xy 102.064052 -255.27931)
			(xy 102.01959 -255.300408) (xy 101.972319 -255.3141) (xy 101.923464 -255.320032) (xy 101.874289 -255.318051)
			(xy 101.82607 -255.308207) (xy 101.780054 -255.290755) (xy 101.737433 -255.266148) (xy 101.699312 -255.235023)
			(xy 101.666677 -255.198186) (xy 101.640374 -255.15659) (xy 101.621083 -255.111314) (xy 101.609306 -255.06353)
			(xy 101.605346 -255.014476) (xy 101.276404 -255.014476) (xy 101.275909 -255.039083) (xy 101.268014 -255.08766)
			(xy 101.25243 -255.134341) (xy 101.229559 -255.177918) (xy 101.199994 -255.217262) (xy 101.164501 -255.251354)
			(xy 101.123998 -255.27931) (xy 101.079536 -255.300408) (xy 101.032265 -255.3141) (xy 100.98341 -255.320032)
			(xy 100.934235 -255.318051) (xy 100.886016 -255.308207) (xy 100.84 -255.290755) (xy 100.797379 -255.266148)
			(xy 100.759258 -255.235023) (xy 100.726623 -255.198186) (xy 100.70032 -255.15659) (xy 100.681029 -255.111314)
			(xy 100.669252 -255.06353) (xy 100.665292 -255.014476) (xy 100.33635 -255.014476) (xy 100.335855 -255.039083)
			(xy 100.32796 -255.08766) (xy 100.312376 -255.134341) (xy 100.289505 -255.177918) (xy 100.25994 -255.217262)
			(xy 100.224447 -255.251354) (xy 100.183944 -255.27931) (xy 100.139482 -255.300408) (xy 100.092211 -255.3141)
			(xy 100.043356 -255.320032) (xy 99.994181 -255.318051) (xy 99.945962 -255.308207) (xy 99.899946 -255.290755)
			(xy 99.857325 -255.266148) (xy 99.819204 -255.235023) (xy 99.786569 -255.198186) (xy 99.760266 -255.15659)
			(xy 99.740975 -255.111314) (xy 99.729198 -255.06353) (xy 99.725238 -255.014476) (xy 98.456242 -255.014476)
			(xy 98.455747 -255.039083) (xy 98.447852 -255.08766) (xy 98.432268 -255.134341) (xy 98.409397 -255.177918)
			(xy 98.379832 -255.217262) (xy 98.344339 -255.251354) (xy 98.303836 -255.27931) (xy 98.259374 -255.300408)
			(xy 98.212103 -255.3141) (xy 98.163248 -255.320032) (xy 98.114073 -255.318051) (xy 98.065854 -255.308207)
			(xy 98.019838 -255.290755) (xy 97.977217 -255.266148) (xy 97.939096 -255.235023) (xy 97.906461 -255.198186)
			(xy 97.880158 -255.15659) (xy 97.860867 -255.111314) (xy 97.84909 -255.06353) (xy 97.84513 -255.014476)
			(xy 96.575937 -255.014476) (xy 96.575938 -255.038669) (xy 96.568323 -255.086425) (xy 96.553282 -255.132385)
			(xy 96.53119 -255.175404) (xy 96.502599 -255.214406) (xy 96.468222 -255.248418) (xy 96.428917 -255.276592)
			(xy 96.407478 -255.28778) (xy 96.39427 -255.29413) (xy 96.379284 -255.318514) (xy 96.379284 -255.951482)
			(xy 96.379722 -255.961546) (xy 96.387455 -255.98013) (xy 96.39427 -255.98755) (xy 96.491298 -256.084578)
			(xy 96.498695 -256.091427) (xy 96.517294 -256.099166) (xy 96.527366 -256.099564) (xy 97.31502 -256.099564)
			(xy 97.323585 -256.099188) (xy 97.339738 -256.093472) (xy 97.353126 -256.082777) (xy 97.357946 -256.075688)
			(xy 97.409762 -255.993646) (xy 97.411032 -255.967738) (xy 97.405444 -255.9558) (xy 97.396069 -255.935191)
			(xy 97.382827 -255.891896) (xy 97.376126 -255.847119) (xy 97.375726 -255.824482) (xy 97.376248 -255.799227)
			(xy 97.384561 -255.749405) (xy 97.400962 -255.701631) (xy 97.425003 -255.657208) (xy 97.456027 -255.617348)
			(xy 97.493189 -255.583138) (xy 97.535475 -255.555512) (xy 97.581731 -255.535222) (xy 97.630696 -255.522822)
			(xy 97.681034 -255.518651) (xy 97.731372 -255.522822) (xy 97.780337 -255.535222) (xy 97.826593 -255.555512)
			(xy 97.868879 -255.583138) (xy 97.906041 -255.617348) (xy 97.937065 -255.657208) (xy 97.961106 -255.701631)
			(xy 97.977507 -255.749405) (xy 97.98582 -255.799227) (xy 97.986342 -255.824482) (xy 97.985931 -255.847119)
			(xy 97.979239 -255.891896) (xy 97.966001 -255.935192) (xy 97.956624 -255.9558) (xy 97.951036 -255.967738)
			(xy 97.952306 -255.993646) (xy 98.004122 -256.075688) (xy 98.008932 -256.082796) (xy 98.022299 -256.093541)
			(xy 98.038473 -256.099245) (xy 98.047048 -256.099564) (xy 99.195128 -256.099564) (xy 99.203693 -256.099187)
			(xy 99.219844 -256.093469) (xy 99.23323 -256.082774) (xy 99.238054 -256.075688) (xy 99.28987 -255.993646)
			(xy 99.29114 -255.967738) (xy 99.285552 -255.9558) (xy 99.276177 -255.935191) (xy 99.262934 -255.891896)
			(xy 99.256233 -255.847119) (xy 99.255834 -255.824482) (xy 99.256356 -255.799227) (xy 99.264669 -255.749405)
			(xy 99.28107 -255.701631) (xy 99.305111 -255.657208) (xy 99.336135 -255.617348) (xy 99.373297 -255.583138)
			(xy 99.415583 -255.555512) (xy 99.461839 -255.535222) (xy 99.510804 -255.522822) (xy 99.561142 -255.518651)
			(xy 99.61148 -255.522822) (xy 99.660445 -255.535222) (xy 99.706701 -255.555512) (xy 99.748987 -255.583138)
			(xy 99.786149 -255.617348) (xy 99.817173 -255.657208) (xy 99.841214 -255.701631) (xy 99.857615 -255.749405)
			(xy 99.865928 -255.799227) (xy 99.86645 -255.824482) (xy 99.866039 -255.847119) (xy 99.859347 -255.891897)
			(xy 99.84611 -255.935192) (xy 99.836732 -255.9558) (xy 99.831144 -255.967738) (xy 99.832414 -255.993646)
			(xy 99.88423 -256.075688) (xy 99.88904 -256.082795) (xy 99.902408 -256.093538) (xy 99.918582 -256.099239)
			(xy 99.927156 -256.099564) (xy 100.134928 -256.099564) (xy 100.143493 -256.099187) (xy 100.159644 -256.093469)
			(xy 100.17303 -256.082774) (xy 100.177854 -256.075688) (xy 100.22967 -255.993646) (xy 100.23094 -255.967738)
			(xy 100.225352 -255.9558) (xy 100.215977 -255.935191) (xy 100.202734 -255.891896) (xy 100.196033 -255.847119)
			(xy 100.195634 -255.824482) (xy 100.196156 -255.799227) (xy 100.204469 -255.749405) (xy 100.22087 -255.701631)
			(xy 100.244911 -255.657208) (xy 100.275935 -255.617348) (xy 100.313097 -255.583138) (xy 100.355383 -255.555512)
			(xy 100.401639 -255.535222) (xy 100.450604 -255.522822) (xy 100.500942 -255.518651) (xy 100.55128 -255.522822)
			(xy 100.600245 -255.535222) (xy 100.646501 -255.555512) (xy 100.688787 -255.583138) (xy 100.725949 -255.617348)
			(xy 100.756973 -255.657208) (xy 100.781014 -255.701631) (xy 100.797415 -255.749405) (xy 100.805728 -255.799227)
			(xy 100.80625 -255.824482) (xy 101.135192 -255.824482) (xy 101.139152 -255.775428) (xy 101.150929 -255.727644)
			(xy 101.17022 -255.682368) (xy 101.196523 -255.640772) (xy 101.229158 -255.603935) (xy 101.267279 -255.57281)
			(xy 101.3099 -255.548203) (xy 101.355916 -255.530751) (xy 101.404135 -255.520907) (xy 101.45331 -255.518926)
			(xy 101.502165 -255.524858) (xy 101.549436 -255.53855) (xy 101.593898 -255.559648) (xy 101.634401 -255.587604)
			(xy 101.669894 -255.621696) (xy 101.699459 -255.66104) (xy 101.72233 -255.704617) (xy 101.737914 -255.751298)
			(xy 101.745809 -255.799875) (xy 101.746304 -255.824482) (xy 102.075246 -255.824482) (xy 102.079206 -255.775428)
			(xy 102.090983 -255.727644) (xy 102.110274 -255.682368) (xy 102.136577 -255.640772) (xy 102.169212 -255.603935)
			(xy 102.207333 -255.57281) (xy 102.249954 -255.548203) (xy 102.29597 -255.530751) (xy 102.344189 -255.520907)
			(xy 102.393364 -255.518926) (xy 102.442219 -255.524858) (xy 102.48949 -255.53855) (xy 102.533952 -255.559648)
			(xy 102.574455 -255.587604) (xy 102.609948 -255.621696) (xy 102.639513 -255.66104) (xy 102.662384 -255.704617)
			(xy 102.677968 -255.751298) (xy 102.685863 -255.799875) (xy 102.686317 -255.82245) (xy 103.011998 -255.82245)
			(xy 103.015958 -255.773396) (xy 103.027735 -255.725612) (xy 103.047026 -255.680336) (xy 103.073329 -255.63874)
			(xy 103.105964 -255.601903) (xy 103.144085 -255.570778) (xy 103.186706 -255.546171) (xy 103.232722 -255.528719)
			(xy 103.280941 -255.518875) (xy 103.330116 -255.516894) (xy 103.378971 -255.522826) (xy 103.426242 -255.536518)
			(xy 103.470704 -255.557616) (xy 103.511207 -255.585572) (xy 103.5467 -255.619664) (xy 103.576265 -255.659008)
			(xy 103.599136 -255.702585) (xy 103.61472 -255.749266) (xy 103.622615 -255.797843) (xy 103.62311 -255.82245)
			(xy 103.952052 -255.82245) (xy 103.956012 -255.773396) (xy 103.967789 -255.725612) (xy 103.98708 -255.680336)
			(xy 104.013383 -255.63874) (xy 104.046018 -255.601903) (xy 104.084139 -255.570778) (xy 104.12676 -255.546171)
			(xy 104.172776 -255.528719) (xy 104.220995 -255.518875) (xy 104.27017 -255.516894) (xy 104.319025 -255.522826)
			(xy 104.366296 -255.536518) (xy 104.410758 -255.557616) (xy 104.451261 -255.585572) (xy 104.486754 -255.619664)
			(xy 104.516319 -255.659008) (xy 104.53919 -255.702585) (xy 104.554774 -255.749266) (xy 104.562669 -255.797843)
			(xy 104.563164 -255.82245) (xy 104.562669 -255.847057) (xy 104.554774 -255.895634) (xy 104.53919 -255.942315)
			(xy 104.516319 -255.985892) (xy 104.486754 -256.025236) (xy 104.451261 -256.059328) (xy 104.410758 -256.087284)
			(xy 104.366296 -256.108382) (xy 104.319025 -256.122074) (xy 104.27017 -256.128006) (xy 104.220995 -256.126025)
			(xy 104.172776 -256.116181) (xy 104.12676 -256.098729) (xy 104.084139 -256.074122) (xy 104.046018 -256.042997)
			(xy 104.013383 -256.00616) (xy 103.98708 -255.964564) (xy 103.967789 -255.919288) (xy 103.956012 -255.871504)
			(xy 103.952052 -255.82245) (xy 103.62311 -255.82245) (xy 103.622615 -255.847057) (xy 103.61472 -255.895634)
			(xy 103.599136 -255.942315) (xy 103.576265 -255.985892) (xy 103.5467 -256.025236) (xy 103.511207 -256.059328)
			(xy 103.470704 -256.087284) (xy 103.426242 -256.108382) (xy 103.378971 -256.122074) (xy 103.330116 -256.128006)
			(xy 103.280941 -256.126025) (xy 103.232722 -256.116181) (xy 103.186706 -256.098729) (xy 103.144085 -256.074122)
			(xy 103.105964 -256.042997) (xy 103.073329 -256.00616) (xy 103.047026 -255.964564) (xy 103.027735 -255.919288)
			(xy 103.015958 -255.871504) (xy 103.011998 -255.82245) (xy 102.686317 -255.82245) (xy 102.686358 -255.824482)
			(xy 102.685863 -255.849089) (xy 102.677968 -255.897666) (xy 102.662384 -255.944347) (xy 102.639513 -255.987924)
			(xy 102.609948 -256.027268) (xy 102.574455 -256.06136) (xy 102.533952 -256.089316) (xy 102.48949 -256.110414)
			(xy 102.442219 -256.124106) (xy 102.393364 -256.130038) (xy 102.344189 -256.128057) (xy 102.29597 -256.118213)
			(xy 102.249954 -256.100761) (xy 102.207333 -256.076154) (xy 102.169212 -256.045029) (xy 102.136577 -256.008192)
			(xy 102.110274 -255.966596) (xy 102.090983 -255.92132) (xy 102.079206 -255.873536) (xy 102.075246 -255.824482)
			(xy 101.746304 -255.824482) (xy 101.745809 -255.849089) (xy 101.737914 -255.897666) (xy 101.72233 -255.944347)
			(xy 101.699459 -255.987924) (xy 101.669894 -256.027268) (xy 101.634401 -256.06136) (xy 101.593898 -256.089316)
			(xy 101.549436 -256.110414) (xy 101.502165 -256.124106) (xy 101.45331 -256.130038) (xy 101.404135 -256.128057)
			(xy 101.355916 -256.118213) (xy 101.3099 -256.100761) (xy 101.267279 -256.076154) (xy 101.229158 -256.045029)
			(xy 101.196523 -256.008192) (xy 101.17022 -255.966596) (xy 101.150929 -255.92132) (xy 101.139152 -255.873536)
			(xy 101.135192 -255.824482) (xy 100.80625 -255.824482) (xy 100.80625 -255.825244) (xy 100.80612 -255.83762)
			(xy 100.804085 -255.862289) (xy 100.802186 -255.87452) (xy 100.79731 -255.900452) (xy 100.779846 -255.95024)
			(xy 100.754091 -255.996289) (xy 100.720811 -256.037232) (xy 100.680995 -256.071851) (xy 100.635826 -256.099119)
			(xy 100.586645 -256.118225) (xy 100.560886 -256.123948) (xy 100.54717 -256.126742) (xy 100.526596 -256.145538)
			(xy 100.497132 -256.242312) (xy 100.49484 -256.251226) (xy 100.496037 -256.269579) (xy 100.503594 -256.286346)
			(xy 100.509832 -256.293112) (xy 100.624386 -256.407666) (xy 100.631609 -256.414317) (xy 100.64964 -256.422039)
			(xy 100.659438 -256.422652) (xy 100.738178 -256.424176) (xy 100.756212 -256.417318) (xy 100.763578 -256.41046)
			(xy 100.78062 -256.395273) (xy 100.818365 -256.369606) (xy 100.859509 -256.349838) (xy 100.903135 -256.33641)
			(xy 100.948273 -256.32962) (xy 100.971096 -256.32918) (xy 100.99491 -256.329636) (xy 101.041961 -256.337032)
			(xy 101.087293 -256.351643) (xy 101.129806 -256.373117) (xy 101.168469 -256.400931) (xy 101.202344 -256.434412)
			(xy 101.230609 -256.472747) (xy 101.252578 -256.515006) (xy 101.267719 -256.560164) (xy 101.275664 -256.607125)
			(xy 101.276404 -256.630932) (xy 101.276404 -256.634742) (xy 101.275936 -256.658972) (xy 101.268274 -256.706823)
			(xy 101.261164 -256.729992) (xy 101.257354 -256.741676) (xy 101.26091 -256.765298) (xy 101.315266 -256.840482)
			(xy 101.322881 -256.849857) (xy 101.344356 -256.860838) (xy 101.356414 -256.861564) (xy 101.525832 -256.861564)
			(xy 101.537903 -256.860897) (xy 101.559387 -256.84989) (xy 101.56698 -256.840482) (xy 101.621336 -256.765298)
			(xy 101.624892 -256.741676) (xy 101.621082 -256.729738) (xy 101.613966 -256.706571) (xy 101.606314 -256.658718)
			(xy 101.605842 -256.634488) (xy 101.606364 -256.609233) (xy 101.614677 -256.559411) (xy 101.631078 -256.511637)
			(xy 101.655119 -256.467214) (xy 101.686143 -256.427354) (xy 101.723305 -256.393144) (xy 101.765591 -256.365518)
			(xy 101.811847 -256.345228) (xy 101.860812 -256.332828) (xy 101.91115 -256.328657) (xy 101.961488 -256.332828)
			(xy 102.010453 -256.345228) (xy 102.056709 -256.365518) (xy 102.098995 -256.393144) (xy 102.136157 -256.427354)
			(xy 102.167181 -256.467214) (xy 102.191222 -256.511637) (xy 102.207623 -256.559411) (xy 102.215936 -256.609233)
			(xy 102.216458 -256.634488) (xy 102.215994 -256.658719) (xy 102.208339 -256.706572) (xy 102.201218 -256.729738)
			(xy 102.197408 -256.741676) (xy 102.200964 -256.765298) (xy 102.25532 -256.840482) (xy 102.262932 -256.849865)
			(xy 102.284406 -256.860865) (xy 102.296468 -256.861564) (xy 102.465632 -256.861564) (xy 102.477703 -256.860897)
			(xy 102.499187 -256.84989) (xy 102.50678 -256.840482) (xy 102.560882 -256.765298) (xy 102.564692 -256.741168)
			(xy 102.560882 -256.729484) (xy 102.553566 -256.706026) (xy 102.545661 -256.657531) (xy 102.545134 -256.632964)
			(xy 102.545656 -256.607709) (xy 102.553969 -256.557887) (xy 102.57037 -256.510113) (xy 102.594411 -256.46569)
			(xy 102.625435 -256.42583) (xy 102.662597 -256.39162) (xy 102.704883 -256.363994) (xy 102.751139 -256.343704)
			(xy 102.800104 -256.331304) (xy 102.850442 -256.327133) (xy 102.90078 -256.331304) (xy 102.949745 -256.343704)
			(xy 102.996001 -256.363994) (xy 103.038287 -256.39162) (xy 103.075449 -256.42583) (xy 103.106473 -256.46569)
			(xy 103.130514 -256.510113) (xy 103.146915 -256.557887) (xy 103.155228 -256.607709) (xy 103.15575 -256.632964)
			(xy 103.155236 -256.657532) (xy 103.147321 -256.706026) (xy 103.140002 -256.729484) (xy 103.136192 -256.741168)
			(xy 103.140002 -256.765298) (xy 103.194104 -256.840482) (xy 103.201715 -256.849868) (xy 103.223189 -256.860875)
			(xy 103.235252 -256.861564) (xy 106.05897 -256.861564) (xy 106.068558 -256.861154) (xy 106.086404 -256.854136)
			(xy 106.100461 -256.841091) (xy 106.104944 -256.832608) (xy 106.150664 -256.736596) (xy 106.147362 -256.70764)
			(xy 106.137964 -256.69621) (xy 106.120116 -256.673099) (xy 106.091662 -256.622114) (xy 106.072231 -256.567055)
			(xy 106.062382 -256.509504) (xy 106.061764 -256.48031) (xy 106.062244 -256.454611) (xy 106.069905 -256.403787)
			(xy 106.085054 -256.354673) (xy 106.107355 -256.308365) (xy 106.136308 -256.265898) (xy 106.171268 -256.228221)
			(xy 106.211452 -256.196175) (xy 106.255964 -256.170476) (xy 106.303809 -256.151699) (xy 106.353918 -256.140261)
			(xy 106.405172 -256.136421) (xy 106.456426 -256.140261) (xy 106.506535 -256.151699) (xy 106.55438 -256.170476)
			(xy 106.598892 -256.196175) (xy 106.639076 -256.228221) (xy 106.674036 -256.265898) (xy 106.702989 -256.308365)
			(xy 106.72529 -256.354673) (xy 106.740439 -256.403787) (xy 106.7481 -256.454611) (xy 106.74858 -256.48031)
			(xy 106.748151 -256.504702) (xy 106.741241 -256.552993) (xy 106.727563 -256.59982) (xy 106.707391 -256.644237)
			(xy 106.681132 -256.68535) (xy 106.649316 -256.722331) (xy 106.612583 -256.754433) (xy 106.59237 -256.768092)
			(xy 106.581448 -256.775204) (xy 106.569256 -256.79781) (xy 106.569256 -256.810764) (xy 106.569737 -256.82078)
			(xy 106.577389 -256.839291) (xy 106.591541 -256.853466) (xy 106.610041 -256.861147) (xy 106.620056 -256.861564)
			(xy 106.637582 -256.861564) (xy 106.647644 -256.862004) (xy 106.666221 -256.869746) (xy 106.67365 -256.87655)
			(xy 107.54233 -257.74523) (xy 108.488229 -257.74523) (xy 108.492259 -257.692732) (xy 108.504256 -257.641464)
			(xy 108.523939 -257.592629) (xy 108.550845 -257.54737) (xy 108.584345 -257.506749) (xy 108.623653 -257.471718)
			(xy 108.667848 -257.443098) (xy 108.715893 -257.421559) (xy 108.766664 -257.407607) (xy 108.818969 -257.401569)
			(xy 108.871583 -257.403586) (xy 108.923273 -257.41361) (xy 108.972826 -257.431408) (xy 109.019082 -257.456561)
			(xy 109.060956 -257.48848) (xy 109.097468 -257.526418) (xy 109.12776 -257.569484) (xy 109.151123 -257.616669)
			(xy 109.167009 -257.666868) (xy 109.175046 -257.718904) (xy 109.17555 -257.74523) (xy 109.175046 -257.771556)
			(xy 109.167009 -257.823592) (xy 109.151123 -257.873791) (xy 109.12776 -257.920976) (xy 109.097468 -257.964042)
			(xy 109.060956 -258.00198) (xy 109.019082 -258.033899) (xy 108.972826 -258.059052) (xy 108.923273 -258.07685)
			(xy 108.871583 -258.086874) (xy 108.818969 -258.088891) (xy 108.766664 -258.082853) (xy 108.715893 -258.068901)
			(xy 108.667848 -258.047362) (xy 108.623653 -258.018742) (xy 108.584345 -257.983711) (xy 108.550845 -257.94309)
			(xy 108.523939 -257.897831) (xy 108.504256 -257.848996) (xy 108.492259 -257.797728) (xy 108.488229 -257.74523)
			(xy 107.54233 -257.74523) (xy 107.998514 -258.201414) (xy 108.005909 -258.208268) (xy 108.024508 -258.21601)
			(xy 108.034582 -258.2164)
		)
		(stroke
			(width 0)
			(type solid)
		)
		(fill yes)
		(layer "In6.Cu")
		(net "PVDD18_S5_P1")
	)
	(gr_poly
		(pts
			(xy 284.066488 -440.515248) (xy 284.076558 -440.514826) (xy 284.095161 -440.507108) (xy 284.102556 -440.500262)
			(xy 286.437578 -438.16524) (xy 286.444417 -438.157839) (xy 286.452133 -438.139241) (xy 286.452564 -438.129172)
			(xy 286.452564 -429.161702) (xy 286.452264 -429.153595) (xy 286.447214 -429.138188) (xy 286.442658 -429.131476)
			(xy 286.426943 -429.10947) (xy 286.401215 -429.061911) (xy 286.38246 -429.011194) (xy 286.371054 -428.958337)
			(xy 286.367227 -428.9044) (xy 286.371054 -428.850463) (xy 286.38246 -428.797606) (xy 286.401215 -428.746889)
			(xy 286.426943 -428.69933) (xy 286.442658 -428.677324) (xy 286.447248 -428.670628) (xy 286.452309 -428.655212)
			(xy 286.452564 -428.647098) (xy 286.452564 -424.5737) (xy 286.45214 -424.563631) (xy 286.444422 -424.545029)
			(xy 286.437578 -424.537632) (xy 285.810706 -423.91076) (xy 285.803311 -423.903906) (xy 285.784712 -423.89616)
			(xy 285.774638 -423.895774) (xy 281.1526 -423.895774) (xy 281.14253 -423.89535) (xy 281.123928 -423.887633)
			(xy 281.116532 -423.880788) (xy 281.115008 -423.879264) (xy 266.027408 -423.879264) (xy 266.017339 -423.879687)
			(xy 265.998738 -423.887407) (xy 265.99134 -423.89425) (xy 265.545062 -424.340528) (xy 265.538213 -424.347925)
			(xy 265.530479 -424.366524) (xy 265.530076 -424.376596) (xy 265.530076 -424.974469) (xy 274.98776 -424.974469)
			(xy 274.98776 -424.910547) (xy 274.995771 -424.847129) (xy 275.011668 -424.785215) (xy 275.0352 -424.725782)
			(xy 275.065994 -424.669767) (xy 275.103567 -424.618052) (xy 275.147324 -424.571455) (xy 275.196577 -424.53071)
			(xy 275.250548 -424.496459) (xy 275.308387 -424.469242) (xy 275.36918 -424.449489) (xy 275.43197 -424.437511)
			(xy 275.495766 -424.433498) (xy 275.559562 -424.437511) (xy 275.57977 -424.441366) (xy 283.081982 -424.441366)
			(xy 283.086053 -424.385744) (xy 283.098179 -424.331307) (xy 283.118102 -424.279216) (xy 283.145398 -424.230581)
			(xy 283.179484 -424.186438) (xy 283.219633 -424.147729) (xy 283.264991 -424.115278) (xy 283.314591 -424.089777)
			(xy 283.367375 -424.07177) (xy 283.422218 -424.06164) (xy 283.477952 -424.059603) (xy 283.533389 -424.065703)
			(xy 283.587346 -424.079809) (xy 283.638675 -424.101621) (xy 283.686281 -424.130675) (xy 283.729149 -424.16635)
			(xy 283.766366 -424.207887) (xy 283.797139 -424.2544) (xy 283.820811 -424.304897) (xy 283.836879 -424.358304)
			(xy 283.844999 -424.41348) (xy 283.845508 -424.441366) (xy 283.844999 -424.469252) (xy 283.836879 -424.524428)
			(xy 283.820811 -424.577835) (xy 283.797139 -424.628332) (xy 283.766366 -424.674845) (xy 283.729149 -424.716382)
			(xy 283.686281 -424.752057) (xy 283.638675 -424.781111) (xy 283.587346 -424.802923) (xy 283.533389 -424.817029)
			(xy 283.477952 -424.823129) (xy 283.422218 -424.821092) (xy 283.367375 -424.810962) (xy 283.314591 -424.792955)
			(xy 283.264991 -424.767454) (xy 283.219633 -424.735003) (xy 283.179484 -424.696294) (xy 283.145398 -424.652151)
			(xy 283.118102 -424.603516) (xy 283.098179 -424.551425) (xy 283.086053 -424.496988) (xy 283.081982 -424.441366)
			(xy 275.57977 -424.441366) (xy 275.622352 -424.449489) (xy 275.683145 -424.469242) (xy 275.740984 -424.496459)
			(xy 275.794955 -424.53071) (xy 275.844208 -424.571455) (xy 275.887965 -424.618052) (xy 275.925538 -424.669767)
			(xy 275.956332 -424.725782) (xy 275.979864 -424.785215) (xy 275.995761 -424.847129) (xy 276.003772 -424.910547)
			(xy 276.004274 -424.942508) (xy 276.003772 -424.974469) (xy 275.995761 -425.037887) (xy 275.979864 -425.099801)
			(xy 275.956332 -425.159234) (xy 275.925538 -425.215249) (xy 275.887965 -425.266964) (xy 275.844208 -425.313561)
			(xy 275.794955 -425.354306) (xy 275.740984 -425.388557) (xy 275.683145 -425.415774) (xy 275.622352 -425.435527)
			(xy 275.559562 -425.447505) (xy 275.495766 -425.451519) (xy 275.43197 -425.447505) (xy 275.36918 -425.435527)
			(xy 275.308387 -425.415774) (xy 275.250548 -425.388557) (xy 275.196577 -425.354306) (xy 275.147324 -425.313561)
			(xy 275.103567 -425.266964) (xy 275.065994 -425.215249) (xy 275.0352 -425.159234) (xy 275.011668 -425.099801)
			(xy 274.995771 -425.037887) (xy 274.98776 -424.974469) (xy 265.530076 -424.974469) (xy 265.530076 -425.910205)
			(xy 273.093682 -425.910205) (xy 273.093682 -425.846283) (xy 273.101693 -425.782865) (xy 273.11759 -425.720951)
			(xy 273.141122 -425.661518) (xy 273.171916 -425.605503) (xy 273.209489 -425.553788) (xy 273.253246 -425.507191)
			(xy 273.302499 -425.466446) (xy 273.35647 -425.432195) (xy 273.414309 -425.404978) (xy 273.475102 -425.385225)
			(xy 273.537892 -425.373247) (xy 273.601688 -425.369234) (xy 273.665484 -425.373247) (xy 273.728274 -425.385225)
			(xy 273.789067 -425.404978) (xy 273.846906 -425.432195) (xy 273.900877 -425.466446) (xy 273.95013 -425.507191)
			(xy 273.993887 -425.553788) (xy 274.03146 -425.605503) (xy 274.062254 -425.661518) (xy 274.085786 -425.720951)
			(xy 274.101683 -425.782865) (xy 274.109694 -425.846283) (xy 274.110196 -425.878244) (xy 274.109694 -425.910205)
			(xy 274.101683 -425.973623) (xy 274.085786 -426.035537) (xy 274.062254 -426.09497) (xy 274.03146 -426.150985)
			(xy 273.993887 -426.2027) (xy 273.960865 -426.237865) (xy 284.634934 -426.237865) (xy 284.634934 -426.173943)
			(xy 284.642945 -426.110525) (xy 284.658842 -426.048611) (xy 284.682374 -425.989178) (xy 284.713168 -425.933163)
			(xy 284.750741 -425.881448) (xy 284.794498 -425.834851) (xy 284.843751 -425.794106) (xy 284.897722 -425.759855)
			(xy 284.955561 -425.732638) (xy 285.016354 -425.712885) (xy 285.079144 -425.700907) (xy 285.14294 -425.696894)
			(xy 285.206736 -425.700907) (xy 285.269526 -425.712885) (xy 285.330319 -425.732638) (xy 285.388158 -425.759855)
			(xy 285.442129 -425.794106) (xy 285.491382 -425.834851) (xy 285.535139 -425.881448) (xy 285.572712 -425.933163)
			(xy 285.603506 -425.989178) (xy 285.627038 -426.048611) (xy 285.642935 -426.110525) (xy 285.650946 -426.173943)
			(xy 285.651448 -426.205904) (xy 285.650946 -426.237865) (xy 285.642935 -426.301283) (xy 285.627038 -426.363197)
			(xy 285.603506 -426.42263) (xy 285.572712 -426.478645) (xy 285.535139 -426.53036) (xy 285.491382 -426.576957)
			(xy 285.442129 -426.617702) (xy 285.388158 -426.651953) (xy 285.330319 -426.67917) (xy 285.269526 -426.698923)
			(xy 285.206736 -426.710901) (xy 285.14294 -426.714915) (xy 285.079144 -426.710901) (xy 285.016354 -426.698923)
			(xy 284.955561 -426.67917) (xy 284.897722 -426.651953) (xy 284.843751 -426.617702) (xy 284.794498 -426.576957)
			(xy 284.750741 -426.53036) (xy 284.713168 -426.478645) (xy 284.682374 -426.42263) (xy 284.658842 -426.363197)
			(xy 284.642945 -426.301283) (xy 284.634934 -426.237865) (xy 273.960865 -426.237865) (xy 273.95013 -426.249297)
			(xy 273.900877 -426.290042) (xy 273.846906 -426.324293) (xy 273.789067 -426.35151) (xy 273.728274 -426.371263)
			(xy 273.665484 -426.383241) (xy 273.601688 -426.387255) (xy 273.537892 -426.383241) (xy 273.475102 -426.371263)
			(xy 273.414309 -426.35151) (xy 273.35647 -426.324293) (xy 273.302499 -426.290042) (xy 273.253246 -426.249297)
			(xy 273.209489 -426.2027) (xy 273.171916 -426.150985) (xy 273.141122 -426.09497) (xy 273.11759 -426.035537)
			(xy 273.101693 -425.973623) (xy 273.093682 -425.910205) (xy 265.530076 -425.910205) (xy 265.530076 -427.261528)
			(xy 280.287982 -427.261528) (xy 280.292053 -427.205906) (xy 280.304179 -427.151469) (xy 280.324102 -427.099378)
			(xy 280.351398 -427.050743) (xy 280.385484 -427.0066) (xy 280.425633 -426.967891) (xy 280.470991 -426.93544)
			(xy 280.520591 -426.909939) (xy 280.573375 -426.891932) (xy 280.628218 -426.881802) (xy 280.683952 -426.879765)
			(xy 280.739389 -426.885865) (xy 280.793346 -426.899971) (xy 280.844675 -426.921783) (xy 280.892281 -426.950837)
			(xy 280.935149 -426.986512) (xy 280.972366 -427.028049) (xy 281.003139 -427.074562) (xy 281.026811 -427.125059)
			(xy 281.042879 -427.178466) (xy 281.050999 -427.233642) (xy 281.051151 -427.24197) (xy 284.174944 -427.24197)
			(xy 284.179015 -427.186348) (xy 284.191141 -427.131911) (xy 284.211064 -427.07982) (xy 284.23836 -427.031185)
			(xy 284.272446 -426.987042) (xy 284.312595 -426.948333) (xy 284.357953 -426.915882) (xy 284.407553 -426.890381)
			(xy 284.460337 -426.872374) (xy 284.51518 -426.862244) (xy 284.570914 -426.860207) (xy 284.626351 -426.866307)
			(xy 284.680308 -426.880413) (xy 284.731637 -426.902225) (xy 284.779243 -426.931279) (xy 284.822111 -426.966954)
			(xy 284.859328 -427.008491) (xy 284.890101 -427.055004) (xy 284.913773 -427.105501) (xy 284.929841 -427.158908)
			(xy 284.937961 -427.214084) (xy 284.93847 -427.24197) (xy 284.937961 -427.269856) (xy 284.929841 -427.325032)
			(xy 284.913773 -427.378439) (xy 284.890101 -427.428936) (xy 284.859328 -427.475449) (xy 284.822111 -427.516986)
			(xy 284.779243 -427.552661) (xy 284.731637 -427.581715) (xy 284.680308 -427.603527) (xy 284.626351 -427.617633)
			(xy 284.570914 -427.623733) (xy 284.51518 -427.621696) (xy 284.460337 -427.611566) (xy 284.407553 -427.593559)
			(xy 284.357953 -427.568058) (xy 284.312595 -427.535607) (xy 284.272446 -427.496898) (xy 284.23836 -427.452755)
			(xy 284.211064 -427.40412) (xy 284.191141 -427.352029) (xy 284.179015 -427.297592) (xy 284.174944 -427.24197)
			(xy 281.051151 -427.24197) (xy 281.051508 -427.261528) (xy 281.050999 -427.289414) (xy 281.042879 -427.34459)
			(xy 281.026811 -427.397997) (xy 281.003139 -427.448494) (xy 280.972366 -427.495007) (xy 280.935149 -427.536544)
			(xy 280.892281 -427.572219) (xy 280.844675 -427.601273) (xy 280.793346 -427.623085) (xy 280.739389 -427.637191)
			(xy 280.683952 -427.643291) (xy 280.628218 -427.641254) (xy 280.573375 -427.631124) (xy 280.520591 -427.613117)
			(xy 280.470991 -427.587616) (xy 280.425633 -427.555165) (xy 280.385484 -427.516456) (xy 280.351398 -427.472313)
			(xy 280.324102 -427.423678) (xy 280.304179 -427.371587) (xy 280.292053 -427.31715) (xy 280.287982 -427.261528)
			(xy 265.530076 -427.261528) (xy 265.530076 -427.763643) (xy 285.011108 -427.763643) (xy 285.011108 -427.699721)
			(xy 285.019119 -427.636303) (xy 285.035016 -427.574389) (xy 285.058548 -427.514956) (xy 285.089342 -427.458941)
			(xy 285.126915 -427.407226) (xy 285.170672 -427.360629) (xy 285.219925 -427.319884) (xy 285.273896 -427.285633)
			(xy 285.331735 -427.258416) (xy 285.392528 -427.238663) (xy 285.455318 -427.226685) (xy 285.519114 -427.222672)
			(xy 285.58291 -427.226685) (xy 285.6457 -427.238663) (xy 285.706493 -427.258416) (xy 285.764332 -427.285633)
			(xy 285.818303 -427.319884) (xy 285.867556 -427.360629) (xy 285.911313 -427.407226) (xy 285.948886 -427.458941)
			(xy 285.97968 -427.514956) (xy 286.003212 -427.574389) (xy 286.019109 -427.636303) (xy 286.02712 -427.699721)
			(xy 286.027622 -427.731682) (xy 286.02712 -427.763643) (xy 286.019109 -427.827061) (xy 286.003212 -427.888975)
			(xy 285.97968 -427.948408) (xy 285.948886 -428.004423) (xy 285.911313 -428.056138) (xy 285.867556 -428.102735)
			(xy 285.818303 -428.14348) (xy 285.764332 -428.177731) (xy 285.706493 -428.204948) (xy 285.6457 -428.224701)
			(xy 285.58291 -428.236679) (xy 285.519114 -428.240693) (xy 285.455318 -428.236679) (xy 285.392528 -428.224701)
			(xy 285.331735 -428.204948) (xy 285.273896 -428.177731) (xy 285.219925 -428.14348) (xy 285.170672 -428.102735)
			(xy 285.126915 -428.056138) (xy 285.089342 -428.004423) (xy 285.058548 -427.948408) (xy 285.035016 -427.888975)
			(xy 285.019119 -427.827061) (xy 285.011108 -427.763643) (xy 265.530076 -427.763643) (xy 265.530076 -428.984156)
			(xy 275.625306 -428.984156) (xy 275.625808 -428.952195) (xy 275.633819 -428.888777) (xy 275.649716 -428.826863)
			(xy 275.673248 -428.76743) (xy 275.704042 -428.711415) (xy 275.741615 -428.6597) (xy 275.785372 -428.613103)
			(xy 275.834625 -428.572358) (xy 275.888596 -428.538107) (xy 275.946435 -428.51089) (xy 276.007228 -428.491137)
			(xy 276.070018 -428.479159) (xy 276.133814 -428.475146) (xy 276.19761 -428.479159) (xy 276.2604 -428.491137)
			(xy 276.321193 -428.51089) (xy 276.379032 -428.538107) (xy 276.433003 -428.572358) (xy 276.482256 -428.613103)
			(xy 276.526013 -428.6597) (xy 276.563586 -428.711415) (xy 276.59438 -428.76743) (xy 276.617912 -428.826863)
			(xy 276.633809 -428.888777) (xy 276.64182 -428.952195) (xy 276.642322 -428.984156) (xy 276.642009 -429.00928)
			(xy 276.637048 -429.059283) (xy 276.632416 -429.083978) (xy 276.630384 -429.09363) (xy 276.63394 -429.11268)
			(xy 276.681946 -429.188626) (xy 276.697694 -429.199802) (xy 276.707092 -429.202342) (xy 276.734191 -429.209639)
			(xy 276.786003 -429.231208) (xy 276.834095 -429.260136) (xy 276.87743 -429.295799) (xy 276.91507 -429.337426)
			(xy 276.946205 -429.38412) (xy 276.970161 -429.434872) (xy 276.986422 -429.488587) (xy 276.994636 -429.544105)
			(xy 276.995128 -429.572166) (xy 276.994613 -429.599417) (xy 276.993936 -429.604127) (xy 278.665426 -429.604127)
			(xy 278.665426 -429.540205) (xy 278.673437 -429.476787) (xy 278.689334 -429.414873) (xy 278.712866 -429.35544)
			(xy 278.74366 -429.299425) (xy 278.781233 -429.24771) (xy 278.82499 -429.201113) (xy 278.874243 -429.160368)
			(xy 278.928214 -429.126117) (xy 278.986053 -429.0989) (xy 279.046846 -429.079147) (xy 279.109636 -429.067169)
			(xy 279.173432 -429.063156) (xy 279.237228 -429.067169) (xy 279.300018 -429.079147) (xy 279.360811 -429.0989)
			(xy 279.41865 -429.126117) (xy 279.472621 -429.160368) (xy 279.521874 -429.201113) (xy 279.565631 -429.24771)
			(xy 279.603204 -429.299425) (xy 279.633998 -429.35544) (xy 279.65753 -429.414873) (xy 279.673427 -429.476787)
			(xy 279.681438 -429.540205) (xy 279.68194 -429.572166) (xy 279.681438 -429.604127) (xy 279.673427 -429.667545)
			(xy 279.65753 -429.729459) (xy 279.633998 -429.788892) (xy 279.603204 -429.844907) (xy 279.565631 -429.896622)
			(xy 279.521874 -429.943219) (xy 279.472621 -429.983964) (xy 279.41865 -430.018215) (xy 279.360811 -430.045432)
			(xy 279.300018 -430.065185) (xy 279.237228 -430.077163) (xy 279.173432 -430.081177) (xy 279.109636 -430.077163)
			(xy 279.046846 -430.065185) (xy 278.986053 -430.045432) (xy 278.928214 -430.018215) (xy 278.874243 -429.983964)
			(xy 278.82499 -429.943219) (xy 278.781233 -429.896622) (xy 278.74366 -429.844907) (xy 278.712866 -429.788892)
			(xy 278.689334 -429.729459) (xy 278.673437 -429.667545) (xy 278.665426 -429.604127) (xy 276.993936 -429.604127)
			(xy 276.986861 -429.653365) (xy 276.971511 -429.705661) (xy 276.948874 -429.755239) (xy 276.919411 -429.801092)
			(xy 276.883723 -429.842284) (xy 276.842535 -429.877979) (xy 276.796687 -429.907448) (xy 276.747111 -429.930092)
			(xy 276.694818 -429.94545) (xy 276.640871 -429.953209) (xy 276.61362 -429.953674) (xy 276.587172 -429.953223)
			(xy 276.534786 -429.945892) (xy 276.483915 -429.931396) (xy 276.435533 -429.910012) (xy 276.390569 -429.882151)
			(xy 276.349884 -429.848346) (xy 276.314258 -429.809246) (xy 276.284374 -429.7656) (xy 276.260805 -429.718245)
			(xy 276.244003 -429.668088) (xy 276.234289 -429.616091) (xy 276.23262 -429.589692) (xy 276.232112 -429.579786)
			(xy 276.223984 -429.562006) (xy 276.159214 -429.50003) (xy 276.141434 -429.492664) (xy 276.131528 -429.492664)
			(xy 276.098331 -429.492002) (xy 276.032535 -429.483065) (xy 275.968462 -429.46564) (xy 275.907202 -429.440023)
			(xy 275.849798 -429.40665) (xy 275.797226 -429.366089) (xy 275.750382 -429.319031) (xy 275.710061 -429.266275)
			(xy 275.67695 -429.208719) (xy 275.651612 -429.147344) (xy 275.634479 -429.083192) (xy 275.625841 -429.017356)
			(xy 275.625306 -428.984156) (xy 265.530076 -428.984156) (xy 265.530076 -433.130706) (xy 266.885409 -433.130706)
			(xy 266.885409 -432.953414) (xy 266.893363 -432.7763) (xy 266.909256 -432.599721) (xy 266.933054 -432.424033)
			(xy 266.964711 -432.24959) (xy 267.004162 -432.076743) (xy 267.051329 -431.90584) (xy 267.106115 -431.737225)
			(xy 267.168411 -431.571237) (xy 267.238091 -431.408212) (xy 267.315016 -431.248477) (xy 267.399029 -431.092354)
			(xy 267.489962 -430.940158) (xy 267.587632 -430.792194) (xy 267.691842 -430.648762) (xy 267.802382 -430.510149)
			(xy 267.919029 -430.376635) (xy 268.041549 -430.248489) (xy 268.169695 -430.125969) (xy 268.303209 -430.009322)
			(xy 268.441822 -429.898782) (xy 268.585254 -429.794572) (xy 268.733218 -429.696902) (xy 268.885414 -429.605969)
			(xy 269.041537 -429.521956) (xy 269.201272 -429.445031) (xy 269.364297 -429.375351) (xy 269.530285 -429.313055)
			(xy 269.6989 -429.258269) (xy 269.869803 -429.211102) (xy 270.04265 -429.171651) (xy 270.217093 -429.139994)
			(xy 270.392781 -429.116196) (xy 270.56936 -429.100303) (xy 270.746474 -429.092349) (xy 270.923766 -429.092349)
			(xy 271.10088 -429.100303) (xy 271.277459 -429.116196) (xy 271.453147 -429.139994) (xy 271.62759 -429.171651)
			(xy 271.800437 -429.211102) (xy 271.97134 -429.258269) (xy 272.139955 -429.313055) (xy 272.305943 -429.375351)
			(xy 272.468968 -429.445031) (xy 272.628703 -429.521956) (xy 272.784826 -429.605969) (xy 272.937022 -429.696902)
			(xy 273.084986 -429.794572) (xy 273.228418 -429.898782) (xy 273.367031 -430.009322) (xy 273.500545 -430.125969)
			(xy 273.628691 -430.248489) (xy 273.751211 -430.376635) (xy 273.867858 -430.510149) (xy 273.978398 -430.648762)
			(xy 274.082006 -430.791366) (xy 277.234902 -430.791366) (xy 277.238973 -430.735744) (xy 277.251099 -430.681307)
			(xy 277.271022 -430.629216) (xy 277.298318 -430.580581) (xy 277.332404 -430.536438) (xy 277.372553 -430.497729)
			(xy 277.417911 -430.465278) (xy 277.467511 -430.439777) (xy 277.520295 -430.42177) (xy 277.575138 -430.41164)
			(xy 277.630872 -430.409603) (xy 277.686309 -430.415703) (xy 277.740266 -430.429809) (xy 277.791595 -430.451621)
			(xy 277.839201 -430.480675) (xy 277.882069 -430.51635) (xy 277.919286 -430.557887) (xy 277.950059 -430.6044)
			(xy 277.973731 -430.654897) (xy 277.989799 -430.708304) (xy 277.997919 -430.76348) (xy 277.998428 -430.791366)
			(xy 277.997919 -430.819252) (xy 277.989799 -430.874428) (xy 277.973731 -430.927835) (xy 277.950059 -430.978332)
			(xy 277.919286 -431.024845) (xy 277.882069 -431.066382) (xy 277.839201 -431.102057) (xy 277.791595 -431.131111)
			(xy 277.740266 -431.152923) (xy 277.686309 -431.167029) (xy 277.630872 -431.173129) (xy 277.575138 -431.171092)
			(xy 277.520295 -431.160962) (xy 277.467511 -431.142955) (xy 277.417911 -431.117454) (xy 277.372553 -431.085003)
			(xy 277.332404 -431.046294) (xy 277.298318 -431.002151) (xy 277.271022 -430.953516) (xy 277.251099 -430.901425)
			(xy 277.238973 -430.846988) (xy 277.234902 -430.791366) (xy 274.082006 -430.791366) (xy 274.082608 -430.792194)
			(xy 274.180278 -430.940158) (xy 274.271211 -431.092354) (xy 274.355224 -431.248477) (xy 274.432149 -431.408212)
			(xy 274.501829 -431.571237) (xy 274.564125 -431.737225) (xy 274.618911 -431.90584) (xy 274.666078 -432.076743)
			(xy 274.705529 -432.24959) (xy 274.737186 -432.424033) (xy 274.760984 -432.599721) (xy 274.776877 -432.7763)
			(xy 274.784831 -432.953414) (xy 274.785328 -433.04206) (xy 274.784831 -433.130706) (xy 274.776877 -433.30782)
			(xy 274.760984 -433.484399) (xy 274.737186 -433.660087) (xy 274.705529 -433.83453) (xy 274.676018 -433.963826)
			(xy 277.872188 -433.963826) (xy 277.876259 -433.908204) (xy 277.888385 -433.853767) (xy 277.908308 -433.801676)
			(xy 277.935604 -433.753041) (xy 277.96969 -433.708898) (xy 278.009839 -433.670189) (xy 278.055197 -433.637738)
			(xy 278.104797 -433.612237) (xy 278.157581 -433.59423) (xy 278.212424 -433.5841) (xy 278.268158 -433.582063)
			(xy 278.323595 -433.588163) (xy 278.377552 -433.602269) (xy 278.428881 -433.624081) (xy 278.476487 -433.653135)
			(xy 278.519355 -433.68881) (xy 278.556572 -433.730347) (xy 278.587345 -433.77686) (xy 278.611017 -433.827357)
			(xy 278.627085 -433.880764) (xy 278.635205 -433.93594) (xy 278.635714 -433.963826) (xy 278.635205 -433.991712)
			(xy 278.627085 -434.046888) (xy 278.611017 -434.100295) (xy 278.587345 -434.150792) (xy 278.556572 -434.197305)
			(xy 278.519355 -434.238842) (xy 278.476487 -434.274517) (xy 278.428881 -434.303571) (xy 278.377552 -434.325383)
			(xy 278.323595 -434.339489) (xy 278.268158 -434.345589) (xy 278.212424 -434.343552) (xy 278.157581 -434.333422)
			(xy 278.104797 -434.315415) (xy 278.055197 -434.289914) (xy 278.009839 -434.257463) (xy 277.96969 -434.218754)
			(xy 277.935604 -434.174611) (xy 277.908308 -434.125976) (xy 277.888385 -434.073885) (xy 277.876259 -434.019448)
			(xy 277.872188 -433.963826) (xy 274.676018 -433.963826) (xy 274.666078 -434.007377) (xy 274.618911 -434.17828)
			(xy 274.564125 -434.346895) (xy 274.501829 -434.512883) (xy 274.440668 -434.655976) (xy 282.434284 -434.655976)
			(xy 282.434786 -434.624015) (xy 282.442797 -434.560597) (xy 282.458694 -434.498683) (xy 282.482226 -434.43925)
			(xy 282.51302 -434.383235) (xy 282.550593 -434.33152) (xy 282.59435 -434.284923) (xy 282.643603 -434.244178)
			(xy 282.697574 -434.209927) (xy 282.755413 -434.18271) (xy 282.816206 -434.162957) (xy 282.878996 -434.150979)
			(xy 282.942792 -434.146966) (xy 283.006588 -434.150979) (xy 283.069378 -434.162957) (xy 283.130171 -434.18271)
			(xy 283.18801 -434.209927) (xy 283.241981 -434.244178) (xy 283.291234 -434.284923) (xy 283.334991 -434.33152)
			(xy 283.372564 -434.383235) (xy 283.403358 -434.43925) (xy 283.42689 -434.498683) (xy 283.442787 -434.560597)
			(xy 283.450798 -434.624015) (xy 283.4513 -434.655976) (xy 283.450818 -434.688126) (xy 283.442721 -434.751915)
			(xy 283.42664 -434.814173) (xy 283.402834 -434.873904) (xy 283.371681 -434.930154) (xy 283.33368 -434.982025)
			(xy 283.289439 -435.028686) (xy 283.264864 -435.049422) (xy 283.257244 -435.055772) (xy 283.247846 -435.07279)
			(xy 283.236924 -435.162452) (xy 283.242004 -435.180994) (xy 283.2481 -435.189122) (xy 283.266003 -435.21406)
			(xy 283.294466 -435.268448) (xy 283.31386 -435.326689) (xy 283.323685 -435.387283) (xy 283.3243 -435.417976)
			(xy 283.323814 -435.445227) (xy 283.316058 -435.499175) (xy 283.300703 -435.55147) (xy 283.278061 -435.601047)
			(xy 283.248595 -435.646897) (xy 283.212904 -435.688088) (xy 283.171713 -435.723779) (xy 283.125863 -435.753245)
			(xy 283.076286 -435.775887) (xy 283.023991 -435.791242) (xy 282.970043 -435.798998) (xy 282.915541 -435.798998)
			(xy 282.861593 -435.791242) (xy 282.809298 -435.775887) (xy 282.759721 -435.753245) (xy 282.713871 -435.723779)
			(xy 282.67268 -435.688088) (xy 282.636989 -435.646897) (xy 282.607523 -435.601047) (xy 282.584881 -435.55147)
			(xy 282.569526 -435.499175) (xy 282.56177 -435.445227) (xy 282.561284 -435.417976) (xy 282.561895 -435.387283)
			(xy 282.57172 -435.326688) (xy 282.591114 -435.268446) (xy 282.619576 -435.214057) (xy 282.637484 -435.189122)
			(xy 282.64358 -435.180994) (xy 282.64866 -435.162452) (xy 282.637738 -435.07279) (xy 282.62834 -435.055772)
			(xy 282.62072 -435.049422) (xy 282.596158 -435.028674) (xy 282.551932 -434.982004) (xy 282.513943 -434.930131)
			(xy 282.482795 -434.873883) (xy 282.458986 -434.814157) (xy 282.442896 -434.751906) (xy 282.434781 -434.688124)
			(xy 282.434284 -434.655976) (xy 274.440668 -434.655976) (xy 274.432149 -434.675908) (xy 274.355224 -434.835643)
			(xy 274.271211 -434.991766) (xy 274.180278 -435.143962) (xy 274.082608 -435.291926) (xy 273.978398 -435.435358)
			(xy 273.867858 -435.573971) (xy 273.751211 -435.707485) (xy 273.628691 -435.835631) (xy 273.500545 -435.958151)
			(xy 273.367031 -436.074798) (xy 273.228418 -436.185338) (xy 273.084986 -436.289548) (xy 273.037243 -436.321063)
			(xy 276.104713 -436.321063) (xy 276.109924 -436.258198) (xy 276.122871 -436.19646) (xy 276.143356 -436.136798)
			(xy 276.171062 -436.080128) (xy 276.205566 -436.027321) (xy 276.246337 -435.979187) (xy 276.292748 -435.936465)
			(xy 276.344088 -435.899812) (xy 276.399566 -435.869792) (xy 276.458333 -435.846864) (xy 276.519483 -435.831381)
			(xy 276.58208 -435.82358) (xy 276.61362 -435.823106) (xy 276.643941 -435.823541) (xy 276.704153 -435.830737)
			(xy 276.763084 -435.845037) (xy 276.819899 -435.866237) (xy 276.847046 -435.879748) (xy 276.860035 -435.885953)
			(xy 276.88826 -435.891548) (xy 276.916925 -435.889045) (xy 276.943753 -435.878643) (xy 276.966614 -435.861169)
			(xy 276.983691 -435.838011) (xy 276.993629 -435.811007) (xy 276.995128 -435.79669) (xy 276.997674 -435.768169)
			(xy 277.010192 -435.712296) (xy 277.030921 -435.658921) (xy 277.059397 -435.609245) (xy 277.094978 -435.564384)
			(xy 277.136866 -435.525346) (xy 277.184119 -435.493009) (xy 277.235675 -435.468098) (xy 277.290375 -435.451174)
			(xy 277.346991 -435.442618) (xy 277.37562 -435.442106) (xy 277.402871 -435.442565) (xy 277.456819 -435.450324)
			(xy 277.509113 -435.465682) (xy 277.55869 -435.488325) (xy 277.604539 -435.517793) (xy 277.645729 -435.553486)
			(xy 277.681419 -435.594677) (xy 277.710885 -435.640528) (xy 277.733525 -435.690106) (xy 277.74888 -435.742401)
			(xy 277.756636 -435.796349) (xy 277.756636 -435.850851) (xy 277.74888 -435.904799) (xy 277.733525 -435.957094)
			(xy 277.710885 -436.006672) (xy 277.681419 -436.052523) (xy 277.645729 -436.093714) (xy 277.604539 -436.129407)
			(xy 277.55869 -436.158875) (xy 277.509113 -436.181518) (xy 277.456819 -436.196876) (xy 277.402871 -436.204635)
			(xy 277.37562 -436.205122) (xy 277.344647 -436.204558) (xy 277.283508 -436.194598) (xy 277.253954 -436.18531)
			(xy 277.240167 -436.181197) (xy 277.211436 -436.179973) (xy 277.183505 -436.186814) (xy 277.158592 -436.201178)
			(xy 277.138677 -436.221923) (xy 277.125342 -436.247401) (xy 277.119646 -436.275588) (xy 277.12035 -436.289958)
			(xy 277.122128 -436.331614) (xy 277.121617 -436.363154) (xy 277.113813 -436.42575) (xy 277.098326 -436.4869)
			(xy 277.075394 -436.545664) (xy 277.04537 -436.601141) (xy 277.029252 -436.623714) (xy 282.066236 -436.623714)
			(xy 282.070307 -436.568092) (xy 282.082433 -436.513655) (xy 282.102356 -436.461564) (xy 282.129652 -436.412929)
			(xy 282.163738 -436.368786) (xy 282.203887 -436.330077) (xy 282.249245 -436.297626) (xy 282.298845 -436.272125)
			(xy 282.351629 -436.254118) (xy 282.406472 -436.243988) (xy 282.462206 -436.241951) (xy 282.517643 -436.248051)
			(xy 282.5716 -436.262157) (xy 282.622929 -436.283969) (xy 282.670535 -436.313023) (xy 282.713403 -436.348698)
			(xy 282.75062 -436.390235) (xy 282.781393 -436.436748) (xy 282.805065 -436.487245) (xy 282.821133 -436.540652)
			(xy 282.829253 -436.595828) (xy 282.829762 -436.623714) (xy 282.829253 -436.6516) (xy 282.821133 -436.706776)
			(xy 282.805065 -436.760183) (xy 282.781393 -436.81068) (xy 282.75062 -436.857193) (xy 282.713403 -436.89873)
			(xy 282.670535 -436.934405) (xy 282.622929 -436.963459) (xy 282.5716 -436.985271) (xy 282.517643 -436.999377)
			(xy 282.462206 -437.005477) (xy 282.406472 -437.00344) (xy 282.351629 -436.99331) (xy 282.298845 -436.975303)
			(xy 282.249245 -436.949802) (xy 282.203887 -436.917351) (xy 282.163738 -436.878642) (xy 282.129652 -436.834499)
			(xy 282.102356 -436.785864) (xy 282.082433 -436.733773) (xy 282.070307 -436.679336) (xy 282.066236 -436.623714)
			(xy 277.029252 -436.623714) (xy 277.008713 -436.652478) (xy 276.965989 -436.698887) (xy 276.917852 -436.739654)
			(xy 276.865042 -436.774154) (xy 276.80837 -436.801857) (xy 276.748707 -436.822338) (xy 276.686969 -436.835281)
			(xy 276.624103 -436.840488) (xy 276.561077 -436.837879) (xy 276.498857 -436.827495) (xy 276.4384 -436.809494)
			(xy 276.380633 -436.784153) (xy 276.326444 -436.751861) (xy 276.276666 -436.713114) (xy 276.232063 -436.668508)
			(xy 276.19332 -436.618727) (xy 276.161032 -436.564537) (xy 276.135695 -436.506769) (xy 276.117698 -436.44631)
			(xy 276.107317 -436.384089) (xy 276.104713 -436.321063) (xy 273.037243 -436.321063) (xy 272.937022 -436.387218)
			(xy 272.784826 -436.478151) (xy 272.628703 -436.562164) (xy 272.468968 -436.639089) (xy 272.305943 -436.708769)
			(xy 272.139955 -436.771065) (xy 271.97134 -436.825851) (xy 271.800437 -436.873018) (xy 271.62759 -436.912469)
			(xy 271.453147 -436.944126) (xy 271.277459 -436.967924) (xy 271.10088 -436.983817) (xy 270.923766 -436.991771)
			(xy 270.746474 -436.991771) (xy 270.56936 -436.983817) (xy 270.392781 -436.967924) (xy 270.217093 -436.944126)
			(xy 270.04265 -436.912469) (xy 269.869803 -436.873018) (xy 269.6989 -436.825851) (xy 269.530285 -436.771065)
			(xy 269.364297 -436.708769) (xy 269.201272 -436.639089) (xy 269.041537 -436.562164) (xy 268.885414 -436.478151)
			(xy 268.733218 -436.387218) (xy 268.585254 -436.289548) (xy 268.441822 -436.185338) (xy 268.303209 -436.074798)
			(xy 268.169695 -435.958151) (xy 268.041549 -435.835631) (xy 267.919029 -435.707485) (xy 267.802382 -435.573971)
			(xy 267.691842 -435.435358) (xy 267.587632 -435.291926) (xy 267.489962 -435.143962) (xy 267.399029 -434.991766)
			(xy 267.315016 -434.835643) (xy 267.238091 -434.675908) (xy 267.168411 -434.512883) (xy 267.106115 -434.346895)
			(xy 267.051329 -434.17828) (xy 267.004162 -434.007377) (xy 266.964711 -433.83453) (xy 266.933054 -433.660087)
			(xy 266.909256 -433.484399) (xy 266.893363 -433.30782) (xy 266.885409 -433.130706) (xy 265.530076 -433.130706)
			(xy 265.530076 -436.22468) (xy 265.529638 -436.234743) (xy 265.5219 -436.253324) (xy 265.51509 -436.260748)
			(xy 264.691368 -437.08447) (xy 264.683969 -437.091315) (xy 264.665371 -437.099042) (xy 264.6553 -437.099456)
			(xy 229.231698 -437.099456) (xy 229.212902 -437.107076) (xy 229.206044 -437.114188) (xy 207.181958 -437.114188)
			(xy 207.163162 -437.106314) (xy 207.156304 -437.099456) (xy 199.533002 -437.099456) (xy 199.522933 -437.099032)
			(xy 199.504332 -437.091313) (xy 199.496934 -437.08447) (xy 198.613268 -436.200804) (xy 198.61022 -436.198518)
			(xy 198.536696 -436.142527) (xy 198.394359 -436.024618) (xy 198.257693 -435.900181) (xy 198.126996 -435.769488)
			(xy 198.002555 -435.632826) (xy 197.884643 -435.490492) (xy 197.828662 -435.41696) (xy 197.826376 -435.413912)
			(xy 196.91604 -434.503576) (xy 196.909193 -434.496178) (xy 196.901461 -434.47758) (xy 196.901054 -434.467508)
			(xy 196.901054 -424.081702) (xy 196.90063 -424.071633) (xy 196.892911 -424.053032) (xy 196.886068 -424.045634)
			(xy 195.322698 -422.482264) (xy 195.315858 -422.474863) (xy 195.308137 -422.456265) (xy 195.307712 -422.446196)
			(xy 195.307712 -420.829486) (xy 195.307287 -420.819417) (xy 195.29957 -420.800815) (xy 195.292726 -420.793418)
			(xy 194.140074 -419.640766) (xy 194.132677 -419.633917) (xy 194.114078 -419.626181) (xy 194.104006 -419.62578)
			(xy 190.829184 -419.62578) (xy 190.819115 -419.626205) (xy 190.800512 -419.633922) (xy 190.793116 -419.640766)
			(xy 190.527432 -419.90645) (xy 190.52059 -419.91385) (xy 190.512869 -419.932448) (xy 190.512446 -419.942518)
			(xy 190.512446 -421.027098) (xy 190.512845 -421.036329) (xy 190.519393 -421.053591) (xy 190.531639 -421.067407)
			(xy 190.539624 -421.072056) (xy 190.631572 -421.12057) (xy 190.659512 -421.119046) (xy 190.671196 -421.110918)
			(xy 190.695098 -421.095239) (xy 190.746602 -421.070444) (xy 190.801227 -421.053606) (xy 190.857753 -421.045102)
			(xy 190.886334 -421.044624) (xy 190.913581 -421.045113) (xy 190.967521 -421.052872) (xy 191.019807 -421.068229)
			(xy 191.069376 -421.09087) (xy 191.115218 -421.120335) (xy 191.156401 -421.156023) (xy 191.192085 -421.197209)
			(xy 191.221546 -421.243054) (xy 191.244183 -421.292625) (xy 191.259535 -421.344912) (xy 191.26729 -421.398853)
			(xy 191.26729 -421.453347) (xy 191.259535 -421.507288) (xy 191.244183 -421.559575) (xy 191.221546 -421.609146)
			(xy 191.192085 -421.654991) (xy 191.156401 -421.696177) (xy 191.115218 -421.731865) (xy 191.069376 -421.76133)
			(xy 191.019807 -421.783971) (xy 190.967521 -421.799328) (xy 190.913581 -421.807087) (xy 190.886334 -421.80764)
			(xy 190.857754 -421.807148) (xy 190.801229 -421.798651) (xy 190.746605 -421.781813) (xy 190.695106 -421.757011)
			(xy 190.671196 -421.741346) (xy 190.659512 -421.733218) (xy 190.631572 -421.731694) (xy 190.539624 -421.780208)
			(xy 190.531642 -421.784857) (xy 190.519408 -421.798679) (xy 190.512862 -421.815937) (xy 190.512446 -421.825166)
			(xy 190.512446 -423.360088) (xy 190.51311 -423.372116) (xy 190.523971 -423.393583) (xy 190.533274 -423.401236)
			(xy 190.609728 -423.456862) (xy 190.63335 -423.460672) (xy 190.645034 -423.456862) (xy 190.673425 -423.448338)
			(xy 190.731983 -423.439146) (xy 190.76162 -423.438574) (xy 190.790084 -423.439101) (xy 190.846381 -423.447556)
			(xy 190.900798 -423.464276) (xy 190.95213 -423.48889) (xy 190.999238 -423.520853) (xy 191.041078 -423.559455)
			(xy 191.059308 -423.581322) (xy 191.065658 -423.58945) (xy 191.083438 -423.599102) (xy 191.175386 -423.608754)
			(xy 191.19469 -423.603166) (xy 191.202564 -423.596562) (xy 191.229906 -423.5751) (xy 191.289307 -423.539004)
			(xy 191.353069 -423.511328) (xy 191.420003 -423.492588) (xy 191.488866 -423.483131) (xy 191.52362 -423.482516)
			(xy 191.554351 -423.482963) (xy 191.615364 -423.490374) (xy 191.675039 -423.505085) (xy 191.732506 -423.526882)
			(xy 191.786926 -423.555447) (xy 191.837507 -423.590363) (xy 191.88351 -423.631122) (xy 191.924264 -423.677128)
			(xy 191.959176 -423.727711) (xy 191.987736 -423.782134) (xy 192.002126 -423.820082) (xy 193.173602 -423.820082)
			(xy 193.177673 -423.76446) (xy 193.189799 -423.710023) (xy 193.209722 -423.657932) (xy 193.237018 -423.609297)
			(xy 193.271104 -423.565154) (xy 193.311253 -423.526445) (xy 193.356611 -423.493994) (xy 193.406211 -423.468493)
			(xy 193.458995 -423.450486) (xy 193.513838 -423.440356) (xy 193.569572 -423.438319) (xy 193.625009 -423.444419)
			(xy 193.678966 -423.458525) (xy 193.730295 -423.480337) (xy 193.777901 -423.509391) (xy 193.820769 -423.545066)
			(xy 193.857986 -423.586603) (xy 193.888759 -423.633116) (xy 193.912431 -423.683613) (xy 193.928499 -423.73702)
			(xy 193.936619 -423.792196) (xy 193.937128 -423.820082) (xy 193.936619 -423.847968) (xy 193.928499 -423.903144)
			(xy 193.912431 -423.956551) (xy 193.888759 -424.007048) (xy 193.857986 -424.053561) (xy 193.820769 -424.095098)
			(xy 193.777901 -424.130773) (xy 193.730295 -424.159827) (xy 193.678966 -424.181639) (xy 193.625009 -424.195745)
			(xy 193.569572 -424.201845) (xy 193.513838 -424.199808) (xy 193.458995 -424.189678) (xy 193.406211 -424.171671)
			(xy 193.356611 -424.14617) (xy 193.311253 -424.113719) (xy 193.271104 -424.07501) (xy 193.237018 -424.030867)
			(xy 193.209722 -423.982232) (xy 193.189799 -423.930141) (xy 193.177673 -423.875704) (xy 193.173602 -423.820082)
			(xy 192.002126 -423.820082) (xy 192.009528 -423.839603) (xy 192.024234 -423.899279) (xy 192.03164 -423.960293)
			(xy 192.032128 -423.991024) (xy 192.031706 -424.020828) (xy 192.024741 -424.080028) (xy 192.010899 -424.138007)
			(xy 191.99037 -424.193969) (xy 191.963435 -424.247145) (xy 191.947292 -424.272202) (xy 191.940688 -424.282108)
			(xy 191.93764 -424.305222) (xy 191.970914 -424.404028) (xy 191.987424 -424.420538) (xy 191.9986 -424.424348)
			(xy 192.023237 -424.433353) (xy 192.069976 -424.457168) (xy 192.113011 -424.487161) (xy 192.151531 -424.522768)
			(xy 192.184809 -424.563316) (xy 192.212219 -424.608041) (xy 192.233242 -424.6561) (xy 192.247484 -424.706585)
			(xy 192.254674 -424.758546) (xy 192.25514 -424.784774) (xy 192.254654 -424.812025) (xy 192.246898 -424.865973)
			(xy 192.231543 -424.918268) (xy 192.208901 -424.967845) (xy 192.179435 -425.013695) (xy 192.143744 -425.054886)
			(xy 192.102553 -425.090577) (xy 192.056703 -425.120043) (xy 192.007126 -425.142685) (xy 191.954831 -425.15804)
			(xy 191.900883 -425.165796) (xy 191.846381 -425.165796) (xy 191.792433 -425.15804) (xy 191.740138 -425.142685)
			(xy 191.690561 -425.120043) (xy 191.644711 -425.090577) (xy 191.60352 -425.054886) (xy 191.567829 -425.013695)
			(xy 191.538363 -424.967845) (xy 191.515721 -424.918268) (xy 191.500366 -424.865973) (xy 191.49261 -424.812025)
			(xy 191.492124 -424.784774) (xy 191.492536 -424.758914) (xy 191.499484 -424.707665) (xy 191.513292 -424.657824)
			(xy 191.523112 -424.633898) (xy 191.527938 -424.622976) (xy 191.526668 -424.599862) (xy 191.476376 -424.508676)
			(xy 191.457326 -424.495214) (xy 191.445388 -424.493436) (xy 191.414985 -424.488242) (xy 191.355635 -424.471447)
			(xy 191.298751 -424.447599) (xy 191.245168 -424.417048) (xy 191.195672 -424.380243) (xy 191.15099 -424.337722)
			(xy 191.111777 -424.290111) (xy 191.078608 -424.238108) (xy 191.064896 -424.21048) (xy 191.060578 -424.201336)
			(xy 191.045592 -424.187874) (xy 190.957962 -424.157394) (xy 190.937896 -424.158664) (xy 190.928752 -424.162982)
			(xy 190.902586 -424.175143) (xy 190.847506 -424.192329) (xy 190.790469 -424.201045) (xy 190.76162 -424.20159)
			(xy 190.731981 -424.201031) (xy 190.67342 -424.191845) (xy 190.645034 -424.183302) (xy 190.63335 -424.179492)
			(xy 190.609728 -424.183302) (xy 190.533274 -424.238928) (xy 190.523922 -424.246546) (xy 190.513035 -424.26803)
			(xy 190.512446 -424.280076) (xy 190.512446 -425.155106) (xy 190.512594 -425.160688) (xy 190.515032 -425.171581)
			(xy 190.517272 -425.176696) (xy 190.530257 -425.205666) (xy 190.549743 -425.266089) (xy 190.561555 -425.328467)
			(xy 190.565511 -425.391831) (xy 190.561548 -425.455194) (xy 190.549728 -425.517571) (xy 190.530235 -425.577991)
			(xy 190.517272 -425.606972) (xy 190.515034 -425.612087) (xy 190.512602 -425.622981) (xy 190.512446 -425.628562)
			(xy 190.512446 -425.854876) (xy 194.532756 -425.854876) (xy 194.536827 -425.799254) (xy 194.548953 -425.744817)
			(xy 194.568876 -425.692726) (xy 194.596172 -425.644091) (xy 194.630258 -425.599948) (xy 194.670407 -425.561239)
			(xy 194.715765 -425.528788) (xy 194.765365 -425.503287) (xy 194.818149 -425.48528) (xy 194.872992 -425.47515)
			(xy 194.928726 -425.473113) (xy 194.984163 -425.479213) (xy 195.03812 -425.493319) (xy 195.089449 -425.515131)
			(xy 195.137055 -425.544185) (xy 195.179923 -425.57986) (xy 195.21714 -425.621397) (xy 195.247913 -425.66791)
			(xy 195.271585 -425.718407) (xy 195.287653 -425.771814) (xy 195.295773 -425.82699) (xy 195.296282 -425.854876)
			(xy 195.295773 -425.882762) (xy 195.287653 -425.937938) (xy 195.271585 -425.991345) (xy 195.247913 -426.041842)
			(xy 195.21714 -426.088355) (xy 195.179923 -426.129892) (xy 195.137055 -426.165567) (xy 195.089449 -426.194621)
			(xy 195.03812 -426.216433) (xy 194.984163 -426.230539) (xy 194.928726 -426.236639) (xy 194.872992 -426.234602)
			(xy 194.818149 -426.224472) (xy 194.765365 -426.206465) (xy 194.715765 -426.180964) (xy 194.670407 -426.148513)
			(xy 194.630258 -426.109804) (xy 194.596172 -426.065661) (xy 194.568876 -426.017026) (xy 194.548953 -425.964935)
			(xy 194.536827 -425.910498) (xy 194.532756 -425.854876) (xy 190.512446 -425.854876) (xy 190.512446 -426.250354)
			(xy 190.512674 -426.25783) (xy 190.516936 -426.27216) (xy 190.520828 -426.278548) (xy 190.536908 -426.303576)
			(xy 190.563758 -426.356662) (xy 190.584223 -426.412522) (xy 190.598023 -426.470389) (xy 190.60497 -426.529473)
			(xy 190.60541 -426.559218) (xy 190.604971 -426.588962) (xy 190.598 -426.648041) (xy 190.584192 -426.705905)
			(xy 190.563735 -426.761765) (xy 190.536906 -426.81486) (xy 190.520828 -426.839888) (xy 190.51693 -426.846274)
			(xy 190.512658 -426.860604) (xy 190.512446 -426.868082) (xy 190.512446 -427.290738) (xy 190.512877 -427.300804)
			(xy 190.520607 -427.319394) (xy 190.527432 -427.326806) (xy 191.049402 -427.848776) (xy 192.03746 -427.848776)
			(xy 192.041531 -427.793154) (xy 192.053657 -427.738717) (xy 192.07358 -427.686626) (xy 192.100876 -427.637991)
			(xy 192.134962 -427.593848) (xy 192.175111 -427.555139) (xy 192.220469 -427.522688) (xy 192.270069 -427.497187)
			(xy 192.322853 -427.47918) (xy 192.377696 -427.46905) (xy 192.43343 -427.467013) (xy 192.488867 -427.473113)
			(xy 192.542824 -427.487219) (xy 192.594153 -427.509031) (xy 192.641759 -427.538085) (xy 192.684627 -427.57376)
			(xy 192.721844 -427.615297) (xy 192.752617 -427.66181) (xy 192.776289 -427.712307) (xy 192.792357 -427.765714)
			(xy 192.800477 -427.82089) (xy 192.800986 -427.848776) (xy 192.800477 -427.876662) (xy 192.792357 -427.931838)
			(xy 192.776289 -427.985245) (xy 192.752617 -428.035742) (xy 192.721844 -428.082255) (xy 192.684627 -428.123792)
			(xy 192.641759 -428.159467) (xy 192.594153 -428.188521) (xy 192.542824 -428.210333) (xy 192.488867 -428.224439)
			(xy 192.43343 -428.230539) (xy 192.377696 -428.228502) (xy 192.322853 -428.218372) (xy 192.270069 -428.200365)
			(xy 192.220469 -428.174864) (xy 192.175111 -428.142413) (xy 192.134962 -428.103704) (xy 192.100876 -428.059561)
			(xy 192.07358 -428.010926) (xy 192.053657 -427.958835) (xy 192.041531 -427.904398) (xy 192.03746 -427.848776)
			(xy 191.049402 -427.848776) (xy 191.925913 -428.725287) (xy 194.681596 -428.725287) (xy 194.681596 -428.661365)
			(xy 194.689607 -428.597947) (xy 194.705504 -428.536033) (xy 194.729036 -428.4766) (xy 194.75983 -428.420585)
			(xy 194.797403 -428.36887) (xy 194.84116 -428.322273) (xy 194.890413 -428.281528) (xy 194.944384 -428.247277)
			(xy 195.002223 -428.22006) (xy 195.063016 -428.200307) (xy 195.125806 -428.188329) (xy 195.189602 -428.184316)
			(xy 195.253398 -428.188329) (xy 195.316188 -428.200307) (xy 195.376981 -428.22006) (xy 195.43482 -428.247277)
			(xy 195.488791 -428.281528) (xy 195.538044 -428.322273) (xy 195.581801 -428.36887) (xy 195.619374 -428.420585)
			(xy 195.650168 -428.4766) (xy 195.6737 -428.536033) (xy 195.689597 -428.597947) (xy 195.697608 -428.661365)
			(xy 195.69811 -428.693326) (xy 195.697608 -428.725287) (xy 195.689597 -428.788705) (xy 195.6737 -428.850619)
			(xy 195.650168 -428.910052) (xy 195.619374 -428.966067) (xy 195.581801 -429.017782) (xy 195.538044 -429.064379)
			(xy 195.488791 -429.105124) (xy 195.43482 -429.139375) (xy 195.376981 -429.166592) (xy 195.316188 -429.186345)
			(xy 195.253398 -429.198323) (xy 195.189602 -429.202337) (xy 195.125806 -429.198323) (xy 195.063016 -429.186345)
			(xy 195.002223 -429.166592) (xy 194.944384 -429.139375) (xy 194.890413 -429.105124) (xy 194.84116 -429.064379)
			(xy 194.797403 -429.017782) (xy 194.75983 -428.966067) (xy 194.729036 -428.910052) (xy 194.705504 -428.850619)
			(xy 194.689607 -428.788705) (xy 194.681596 -428.725287) (xy 191.925913 -428.725287) (xy 193.09207 -429.891444)
			(xy 193.098913 -429.898844) (xy 193.106636 -429.917442) (xy 193.107056 -429.927512) (xy 193.107056 -430.431151)
			(xy 194.750176 -430.431151) (xy 194.750176 -430.367229) (xy 194.758187 -430.303811) (xy 194.774084 -430.241897)
			(xy 194.797616 -430.182464) (xy 194.82841 -430.126449) (xy 194.865983 -430.074734) (xy 194.90974 -430.028137)
			(xy 194.958993 -429.987392) (xy 195.012964 -429.953141) (xy 195.070803 -429.925924) (xy 195.131596 -429.906171)
			(xy 195.194386 -429.894193) (xy 195.258182 -429.89018) (xy 195.321978 -429.894193) (xy 195.384768 -429.906171)
			(xy 195.445561 -429.925924) (xy 195.5034 -429.953141) (xy 195.557371 -429.987392) (xy 195.606624 -430.028137)
			(xy 195.650381 -430.074734) (xy 195.687954 -430.126449) (xy 195.718748 -430.182464) (xy 195.74228 -430.241897)
			(xy 195.758177 -430.303811) (xy 195.766188 -430.367229) (xy 195.76669 -430.39919) (xy 195.766188 -430.431151)
			(xy 195.758177 -430.494569) (xy 195.74228 -430.556483) (xy 195.718748 -430.615916) (xy 195.687954 -430.671931)
			(xy 195.650381 -430.723646) (xy 195.606624 -430.770243) (xy 195.557371 -430.810988) (xy 195.5034 -430.845239)
			(xy 195.445561 -430.872456) (xy 195.384768 -430.892209) (xy 195.321978 -430.904187) (xy 195.258182 -430.908201)
			(xy 195.194386 -430.904187) (xy 195.131596 -430.892209) (xy 195.070803 -430.872456) (xy 195.012964 -430.845239)
			(xy 194.958993 -430.810988) (xy 194.90974 -430.770243) (xy 194.865983 -430.723646) (xy 194.82841 -430.671931)
			(xy 194.797616 -430.615916) (xy 194.774084 -430.556483) (xy 194.758187 -430.494569) (xy 194.750176 -430.431151)
			(xy 193.107056 -430.431151) (xy 193.107056 -432.0413) (xy 193.107241 -432.04774) (xy 193.110445 -432.060216)
			(xy 193.113406 -432.065938) (xy 193.133191 -432.102534) (xy 193.166728 -432.178674) (xy 193.193112 -432.257578)
			(xy 193.21212 -432.338576) (xy 193.22359 -432.42098) (xy 193.227425 -432.50409) (xy 193.223592 -432.5872)
			(xy 193.212124 -432.669604) (xy 193.193118 -432.750602) (xy 193.166735 -432.829507) (xy 193.1332 -432.905647)
			(xy 193.113406 -432.942238) (xy 193.11044 -432.94796) (xy 193.10721 -432.960433) (xy 193.107056 -432.966876)
			(xy 193.107056 -434.356764) (xy 193.107431 -434.365599) (xy 193.113398 -434.382231) (xy 193.11874 -434.389276)
			(xy 193.146609 -434.423801) (xy 193.196963 -434.496864) (xy 193.240841 -434.573991) (xy 193.277916 -434.654608)
			(xy 193.307914 -434.738118) (xy 193.330613 -434.8239) (xy 193.345842 -434.911317) (xy 193.35349 -434.999721)
			(xy 193.353944 -435.044088) (xy 193.353442 -435.089605) (xy 193.345403 -435.180282) (xy 193.329388 -435.269895)
			(xy 193.30552 -435.357744) (xy 193.273988 -435.443141) (xy 193.235036 -435.52542) (xy 193.18897 -435.603937)
			(xy 193.13615 -435.67808) (xy 193.076988 -435.747267) (xy 193.011947 -435.810959) (xy 192.941535 -435.868658)
			(xy 192.866302 -435.919913) (xy 192.786837 -435.964323) (xy 192.70376 -436.001542) (xy 192.61772 -436.031278)
			(xy 192.529391 -436.053299) (xy 192.484502 -436.06085) (xy 192.476628 -436.06212) (xy 192.462404 -436.069232)
			(xy 192.432432 -436.099204) (xy 192.42503 -436.106039) (xy 192.406432 -436.113748) (xy 192.396364 -436.11419)
			(xy 191.77889 -436.11419) (xy 191.768933 -436.11472) (xy 191.750544 -436.122375) (xy 191.736423 -436.136423)
			(xy 191.732154 -436.145432) (xy 191.726058 -436.15991) (xy 191.732154 -436.189882) (xy 192.10782 -436.565802)
			(xy 192.131442 -436.573168) (xy 192.143888 -436.570882) (xy 192.188724 -436.563388) (xy 192.279281 -436.55538)
			(xy 192.324736 -436.55488) (xy 192.370499 -436.555381) (xy 192.461664 -436.563511) (xy 192.551747 -436.579704)
			(xy 192.640036 -436.603832) (xy 192.725833 -436.635705) (xy 192.808462 -436.67507) (xy 192.887269 -436.721617)
			(xy 192.961631 -436.774977) (xy 193.030962 -436.83473) (xy 193.094713 -436.900403) (xy 193.15238 -436.971477)
			(xy 193.203509 -437.047391) (xy 193.247695 -437.127545) (xy 193.284589 -437.211307) (xy 193.313899 -437.298013)
			(xy 193.335395 -437.386979) (xy 193.348906 -437.477503) (xy 193.354326 -437.568869) (xy 193.353667 -437.591063)
			(xy 276.104713 -437.591063) (xy 276.109924 -437.528198) (xy 276.122871 -437.46646) (xy 276.143356 -437.406798)
			(xy 276.171062 -437.350128) (xy 276.205566 -437.297321) (xy 276.246337 -437.249187) (xy 276.292748 -437.206465)
			(xy 276.344088 -437.169812) (xy 276.399566 -437.139792) (xy 276.458333 -437.116864) (xy 276.519483 -437.101381)
			(xy 276.58208 -437.09358) (xy 276.61362 -437.093106) (xy 276.643941 -437.093541) (xy 276.704153 -437.100737)
			(xy 276.763084 -437.115037) (xy 276.819899 -437.136237) (xy 276.847046 -437.149748) (xy 276.860035 -437.155953)
			(xy 276.88826 -437.161548) (xy 276.916925 -437.159045) (xy 276.943753 -437.148643) (xy 276.966614 -437.131169)
			(xy 276.983691 -437.108011) (xy 276.993629 -437.081007) (xy 276.995128 -437.06669) (xy 276.997674 -437.038169)
			(xy 277.010192 -436.982296) (xy 277.030921 -436.928921) (xy 277.059397 -436.879245) (xy 277.094978 -436.834384)
			(xy 277.136866 -436.795346) (xy 277.184119 -436.763009) (xy 277.235675 -436.738098) (xy 277.290375 -436.721174)
			(xy 277.346991 -436.712618) (xy 277.37562 -436.712106) (xy 277.402871 -436.712565) (xy 277.456819 -436.720324)
			(xy 277.509113 -436.735682) (xy 277.55869 -436.758325) (xy 277.604539 -436.787793) (xy 277.645729 -436.823486)
			(xy 277.681419 -436.864677) (xy 277.710885 -436.910528) (xy 277.733525 -436.960106) (xy 277.74888 -437.012401)
			(xy 277.756636 -437.066349) (xy 277.756636 -437.120851) (xy 277.74888 -437.174799) (xy 277.733525 -437.227094)
			(xy 277.710885 -437.276672) (xy 277.681419 -437.322523) (xy 277.645729 -437.363714) (xy 277.604539 -437.399407)
			(xy 277.55869 -437.428875) (xy 277.509113 -437.451518) (xy 277.456819 -437.466876) (xy 277.402871 -437.474635)
			(xy 277.37562 -437.475122) (xy 277.344647 -437.474558) (xy 277.283508 -437.464598) (xy 277.253954 -437.45531)
			(xy 277.240167 -437.451197) (xy 277.211436 -437.449973) (xy 277.183505 -437.456814) (xy 277.158592 -437.471178)
			(xy 277.138677 -437.491923) (xy 277.125342 -437.517401) (xy 277.119646 -437.545588) (xy 277.12035 -437.559958)
			(xy 277.122128 -437.601614) (xy 277.121617 -437.633154) (xy 277.113813 -437.69575) (xy 277.098326 -437.7569)
			(xy 277.075394 -437.815664) (xy 277.04537 -437.871141) (xy 277.008713 -437.922478) (xy 277.007601 -437.923686)
			(xy 281.436316 -437.923686) (xy 281.440387 -437.868064) (xy 281.452513 -437.813627) (xy 281.472436 -437.761536)
			(xy 281.499732 -437.712901) (xy 281.533818 -437.668758) (xy 281.573967 -437.630049) (xy 281.619325 -437.597598)
			(xy 281.668925 -437.572097) (xy 281.721709 -437.55409) (xy 281.776552 -437.54396) (xy 281.832286 -437.541923)
			(xy 281.887723 -437.548023) (xy 281.94168 -437.562129) (xy 281.993009 -437.583941) (xy 282.040615 -437.612995)
			(xy 282.083483 -437.64867) (xy 282.1207 -437.690207) (xy 282.151473 -437.73672) (xy 282.175145 -437.787217)
			(xy 282.191213 -437.840624) (xy 282.199333 -437.8958) (xy 282.199842 -437.923686) (xy 282.199333 -437.951572)
			(xy 282.191213 -438.006748) (xy 282.175145 -438.060155) (xy 282.151473 -438.110652) (xy 282.1207 -438.157165)
			(xy 282.083483 -438.198702) (xy 282.040615 -438.234377) (xy 281.993009 -438.263431) (xy 281.94168 -438.285243)
			(xy 281.887723 -438.299349) (xy 281.832286 -438.305449) (xy 281.776552 -438.303412) (xy 281.721709 -438.293282)
			(xy 281.668925 -438.275275) (xy 281.619325 -438.249774) (xy 281.573967 -438.217323) (xy 281.533818 -438.178614)
			(xy 281.499732 -438.134471) (xy 281.472436 -438.085836) (xy 281.452513 -438.033745) (xy 281.440387 -437.979308)
			(xy 281.436316 -437.923686) (xy 277.007601 -437.923686) (xy 276.965989 -437.968887) (xy 276.917852 -438.009654)
			(xy 276.865042 -438.044154) (xy 276.80837 -438.071857) (xy 276.748707 -438.092338) (xy 276.686969 -438.105281)
			(xy 276.624103 -438.110488) (xy 276.561077 -438.107879) (xy 276.498857 -438.097495) (xy 276.4384 -438.079494)
			(xy 276.380633 -438.054153) (xy 276.326444 -438.021861) (xy 276.276666 -437.983114) (xy 276.232063 -437.938508)
			(xy 276.19332 -437.888727) (xy 276.161032 -437.834537) (xy 276.135695 -437.776769) (xy 276.117698 -437.71631)
			(xy 276.107317 -437.654089) (xy 276.104713 -437.591063) (xy 193.353667 -437.591063) (xy 193.351611 -437.660355)
			(xy 193.340784 -437.751239) (xy 193.321929 -437.840803) (xy 193.295196 -437.928338) (xy 193.260795 -438.013154)
			(xy 193.218999 -438.09458) (xy 193.170139 -438.171973) (xy 193.114599 -438.244722) (xy 193.052818 -438.312252)
			(xy 192.985285 -438.374029) (xy 192.949019 -438.401714) (xy 276.993602 -438.401714) (xy 276.997673 -438.346092)
			(xy 277.009799 -438.291655) (xy 277.029722 -438.239564) (xy 277.057018 -438.190929) (xy 277.091104 -438.146786)
			(xy 277.131253 -438.108077) (xy 277.176611 -438.075626) (xy 277.226211 -438.050125) (xy 277.278995 -438.032118)
			(xy 277.333838 -438.021988) (xy 277.389572 -438.019951) (xy 277.445009 -438.026051) (xy 277.498966 -438.040157)
			(xy 277.550295 -438.061969) (xy 277.597901 -438.091023) (xy 277.640769 -438.126698) (xy 277.677986 -438.168235)
			(xy 277.708759 -438.214748) (xy 277.732431 -438.265245) (xy 277.748499 -438.318652) (xy 277.756619 -438.373828)
			(xy 277.757128 -438.401714) (xy 277.756619 -438.4296) (xy 277.748499 -438.484776) (xy 277.732431 -438.538183)
			(xy 277.708759 -438.58868) (xy 277.677986 -438.635193) (xy 277.640769 -438.67673) (xy 277.597901 -438.712405)
			(xy 277.550295 -438.741459) (xy 277.498966 -438.763271) (xy 277.445009 -438.777377) (xy 277.389572 -438.783477)
			(xy 277.333838 -438.78144) (xy 277.278995 -438.77131) (xy 277.226211 -438.753303) (xy 277.176611 -438.727802)
			(xy 277.131253 -438.695351) (xy 277.091104 -438.656642) (xy 277.057018 -438.612499) (xy 277.029722 -438.563864)
			(xy 277.009799 -438.511773) (xy 276.997673 -438.457336) (xy 276.993602 -438.401714) (xy 192.949019 -438.401714)
			(xy 192.912534 -438.429566) (xy 192.835138 -438.478423) (xy 192.75371 -438.520215) (xy 192.668893 -438.554612)
			(xy 192.581356 -438.581341) (xy 192.491792 -438.600191) (xy 192.400907 -438.611015) (xy 192.309421 -438.613725)
			(xy 192.218055 -438.608301) (xy 192.127532 -438.594786) (xy 192.038567 -438.573286) (xy 191.951862 -438.543971)
			(xy 191.868102 -438.507073) (xy 191.78795 -438.462884) (xy 191.712038 -438.411752) (xy 191.640967 -438.354081)
			(xy 191.575297 -438.290327) (xy 191.515547 -438.220993) (xy 191.46219 -438.146629) (xy 191.415647 -438.06782)
			(xy 191.376286 -437.985189) (xy 191.344418 -437.89939) (xy 191.320293 -437.8111) (xy 191.304104 -437.721016)
			(xy 191.295978 -437.629851) (xy 191.295528 -437.584088) (xy 191.296026 -437.538633) (xy 191.304034 -437.448076)
			(xy 191.31153 -437.40324) (xy 191.313816 -437.390794) (xy 191.30645 -437.367172) (xy 190.22441 -436.285386)
			(xy 190.217069 -436.278565) (xy 190.198606 -436.270815) (xy 190.188596 -436.2704) (xy 189.303914 -436.2704)
			(xy 189.269547 -436.26991) (xy 189.201314 -436.261627) (xy 189.134582 -436.245156) (xy 189.070331 -436.220738)
			(xy 189.009503 -436.188733) (xy 188.95299 -436.149609) (xy 188.926978 -436.127144) (xy 188.919784 -436.121279)
			(xy 188.902467 -436.11464) (xy 188.893196 -436.11419) (xy 186.42457 -436.11419) (xy 186.414566 -436.114683)
			(xy 186.396082 -436.122348) (xy 186.381937 -436.136499) (xy 186.374279 -436.154985) (xy 186.37377 -436.16499)
			(xy 186.37377 -440.083702) (xy 186.374193 -440.093773) (xy 186.381904 -440.112379) (xy 186.388756 -440.11977)
			(xy 186.62142 -440.352434) (xy 186.628816 -440.359284) (xy 186.647415 -440.367022) (xy 186.657488 -440.36742)
			(xy 193.545714 -440.36742) (xy 193.555784 -440.366995) (xy 193.574386 -440.359279) (xy 193.581782 -440.352434)
			(xy 194.684904 -439.249312) (xy 194.692302 -439.242465) (xy 194.7109 -439.23473) (xy 194.720972 -439.234326)
			(xy 278.072342 -439.234326) (xy 278.082408 -439.234757) (xy 278.100999 -439.242485) (xy 278.10841 -439.249312)
			(xy 279.35936 -440.500262) (xy 279.36676 -440.507103) (xy 279.385359 -440.514822) (xy 279.395428 -440.515248)
		)
		(stroke
			(width 0)
			(type solid)
		)
		(fill yes)
		(layer "In6.Cu")
		(net "P3V3_AUX")
	)
	(gr_poly
		(pts
			(xy 95.5294 -228.08946) (xy 95.540058 -228.089) (xy 95.559521 -228.080312) (xy 95.566992 -228.072696)
			(xy 95.585092 -228.053523) (xy 95.626503 -228.020892) (xy 95.672758 -227.995591) (xy 95.722574 -227.978325)
			(xy 95.774565 -227.969572) (xy 95.800926 -227.969064) (xy 95.827292 -227.969566) (xy 95.879298 -227.978281)
			(xy 95.929128 -227.99553) (xy 95.975391 -228.020833) (xy 96.016798 -228.053483) (xy 96.03486 -228.072696)
			(xy 96.042404 -228.080207) (xy 96.061823 -228.088876) (xy 96.072452 -228.08946) (xy 96.473264 -228.08946)
			(xy 96.479614 -228.088952) (xy 96.488504 -228.087174) (xy 96.493076 -228.085396) (xy 96.519238 -228.07422)
			(xy 96.526096 -228.067362) (xy 96.543375 -228.050928) (xy 96.582084 -228.023081) (xy 96.624647 -228.001583)
			(xy 96.670032 -227.986954) (xy 96.717138 -227.97955) (xy 96.764822 -227.97955) (xy 96.811928 -227.986954)
			(xy 96.857313 -228.001583) (xy 96.899876 -228.023081) (xy 96.938585 -228.050928) (xy 96.955864 -228.067362)
			(xy 96.962722 -228.07422) (xy 96.988884 -228.085396) (xy 96.993456 -228.087174) (xy 97.002346 -228.088952)
			(xy 97.008696 -228.08946) (xy 97.362518 -228.08946) (xy 97.372396 -228.089001) (xy 97.3907 -228.081565)
			(xy 97.398078 -228.074982) (xy 97.398332 -228.074728) (xy 97.757488 -227.715572) (xy 97.761507 -227.711285)
			(xy 97.767661 -227.701279) (xy 97.76968 -227.69576) (xy 97.77349 -227.68433) (xy 97.766226 -227.635882)
			(xy 97.75796 -227.538255) (xy 97.756876 -227.440285) (xy 97.762978 -227.3425) (xy 97.776235 -227.245425)
			(xy 97.796575 -227.149584) (xy 97.809812 -227.102416) (xy 97.811418 -227.096385) (xy 97.811933 -227.08392)
			(xy 97.810828 -227.077778) (xy 97.808288 -227.066094) (xy 97.743518 -226.986338) (xy 97.733612 -226.978972)
			(xy 97.728024 -226.976686) (xy 97.716342 -226.978276) (xy 97.692823 -226.97993) (xy 97.681034 -226.979988)
			(xy 97.656239 -226.979529) (xy 97.607259 -226.971777) (xy 97.560095 -226.956457) (xy 97.515909 -226.933947)
			(xy 97.475788 -226.904801) (xy 97.440721 -226.869738) (xy 97.411571 -226.82962) (xy 97.389056 -226.785436)
			(xy 97.373731 -226.738274) (xy 97.365973 -226.689295) (xy 97.365973 -226.639705) (xy 97.373731 -226.590726)
			(xy 97.389056 -226.543564) (xy 97.411571 -226.49938) (xy 97.440721 -226.459262) (xy 97.475788 -226.424199)
			(xy 97.515909 -226.395053) (xy 97.560095 -226.372543) (xy 97.607259 -226.357223) (xy 97.656239 -226.349471)
			(xy 97.681034 -226.349052) (xy 97.706886 -226.349567) (xy 97.757898 -226.357993) (xy 97.806851 -226.37463)
			(xy 97.829878 -226.38639) (xy 97.841562 -226.392486) (xy 97.866962 -226.392232) (xy 97.898458 -226.37496)
			(xy 97.90176 -226.372928) (xy 97.911945 -226.36541) (xy 97.923937 -226.343151) (xy 97.92462 -226.33051)
			(xy 97.92462 -226.3267) (xy 97.99066 -226.26066) (xy 97.99193 -226.25939) (xy 97.998808 -226.251186)
			(xy 98.005778 -226.230971) (xy 98.005392 -226.220274) (xy 97.998534 -226.143058) (xy 97.997994 -226.138375)
			(xy 97.995431 -226.129304) (xy 97.993454 -226.125024) (xy 97.990152 -226.118166) (xy 97.982024 -226.109022)
			(xy 97.97669 -226.105212) (xy 97.956834 -226.090812) (xy 97.921556 -226.056737) (xy 97.89218 -226.01746)
			(xy 97.869459 -225.973993) (xy 97.853979 -225.927453) (xy 97.846136 -225.879037) (xy 97.845626 -225.854514)
			(xy 97.846071 -225.830521) (xy 97.853576 -225.783126) (xy 97.868404 -225.737489) (xy 97.890189 -225.694733)
			(xy 97.918395 -225.655912) (xy 97.952327 -225.621982) (xy 97.99115 -225.593779) (xy 98.033907 -225.571996)
			(xy 98.079545 -225.557172) (xy 98.126941 -225.54967) (xy 98.150934 -225.549206) (xy 98.175457 -225.549697)
			(xy 98.223873 -225.557544) (xy 98.270411 -225.573031) (xy 98.313874 -225.595758) (xy 98.353145 -225.625142)
			(xy 98.387212 -225.660427) (xy 98.401632 -225.68027) (xy 98.405188 -225.68535) (xy 98.414078 -225.693224)
			(xy 98.419666 -225.696272) (xy 98.42425 -225.69861) (xy 98.434109 -225.701548) (xy 98.439224 -225.702114)
			(xy 98.516694 -225.708972) (xy 98.527407 -225.709464) (xy 98.547668 -225.702491) (xy 98.55581 -225.69551)
			(xy 98.556572 -225.694748) (xy 98.737928 -225.513392) (xy 98.744278 -225.50247) (xy 98.746056 -225.495866)
			(xy 98.75012 -225.48215) (xy 98.751136 -225.478594) (xy 98.752152 -225.470974) (xy 98.753166 -225.460539)
			(xy 98.74765 -225.440337) (xy 98.741484 -225.431858) (xy 98.681286 -225.35769) (xy 98.658172 -225.347784)
			(xy 98.645726 -225.3488) (xy 98.621088 -225.349816) (xy 98.595833 -225.349293) (xy 98.546011 -225.340978)
			(xy 98.498238 -225.324576) (xy 98.453816 -225.300534) (xy 98.413956 -225.269509) (xy 98.379747 -225.232346)
			(xy 98.352121 -225.19006) (xy 98.331831 -225.143803) (xy 98.319432 -225.094838) (xy 98.315261 -225.0445)
			(xy 98.319432 -224.994162) (xy 98.331831 -224.945197) (xy 98.352121 -224.89894) (xy 98.379747 -224.856654)
			(xy 98.413956 -224.819491) (xy 98.453816 -224.788466) (xy 98.498238 -224.764424) (xy 98.546011 -224.748022)
			(xy 98.595833 -224.739707) (xy 98.621088 -224.7392) (xy 98.645602 -224.739694) (xy 98.693999 -224.747538)
			(xy 98.740522 -224.763011) (xy 98.783977 -224.785716) (xy 98.823248 -224.81507) (xy 98.857326 -224.850318)
			(xy 98.885337 -224.890558) (xy 98.896424 -224.912428) (xy 98.901758 -224.923858) (xy 98.922078 -224.938844)
			(xy 99.009454 -224.952052) (xy 99.016554 -224.95292) (xy 99.030736 -224.95111) (xy 99.037394 -224.948496)
			(xy 99.061524 -224.938082) (xy 99.068636 -224.930716) (xy 99.093221 -224.905467) (xy 99.144684 -224.857309)
			(xy 99.171506 -224.83445) (xy 99.177985 -224.828502) (xy 99.186814 -224.813305) (xy 99.188778 -224.804732)
			(xy 99.194075 -224.776563) (xy 99.206779 -224.720664) (xy 99.214178 -224.692972) (xy 99.221036 -224.668588)
			(xy 99.224592 -224.656396) (xy 99.219766 -224.632266) (xy 99.151186 -224.54743) (xy 99.128326 -224.537778)
			(xy 99.115626 -224.538794) (xy 99.090988 -224.53981) (xy 99.065733 -224.539287) (xy 99.015913 -224.530972)
			(xy 98.96814 -224.51457) (xy 98.923719 -224.490529) (xy 98.88386 -224.459504) (xy 98.849652 -224.422343)
			(xy 98.822026 -224.380057) (xy 98.801737 -224.333801) (xy 98.789338 -224.284837) (xy 98.785167 -224.2345)
			(xy 98.789338 -224.184163) (xy 98.801737 -224.135199) (xy 98.822026 -224.088943) (xy 98.849652 -224.046657)
			(xy 98.88386 -224.009496) (xy 98.923719 -223.978471) (xy 98.96814 -223.95443) (xy 99.015913 -223.938028)
			(xy 99.065733 -223.929713) (xy 99.090988 -223.929194) (xy 99.103751 -223.92933) (xy 99.129186 -223.931489)
			(xy 99.141788 -223.933512) (xy 99.141788 -223.933258) (xy 99.165715 -223.937772) (xy 99.211835 -223.953379)
			(xy 99.254896 -223.976104) (xy 99.293806 -224.005372) (xy 99.327582 -224.040441) (xy 99.355368 -224.080423)
			(xy 99.366324 -224.102168) (xy 99.371912 -224.113852) (xy 99.391724 -224.128584) (xy 99.49942 -224.145094)
			(xy 99.522788 -224.136966) (xy 99.531424 -224.127822) (xy 99.556104 -224.102051) (xy 99.607822 -224.052877)
			(xy 99.634802 -224.029524) (xy 99.64166 -224.023682) (xy 99.658932 -223.994218) (xy 99.660456 -223.985582)
			(xy 99.666778 -223.953517) (xy 99.682152 -223.889989) (xy 99.69119 -223.858582) (xy 99.694746 -223.84639)
			(xy 99.68992 -223.82226) (xy 99.62134 -223.737424) (xy 99.59848 -223.727772) (xy 99.58578 -223.728788)
			(xy 99.561142 -223.729804) (xy 99.535882 -223.729315) (xy 99.486051 -223.721006) (xy 99.438267 -223.704607)
			(xy 99.393835 -223.680567) (xy 99.353966 -223.649541) (xy 99.319748 -223.612375) (xy 99.292114 -223.570083)
			(xy 99.271819 -223.52382) (xy 99.259416 -223.474847) (xy 99.255244 -223.4245) (xy 99.259416 -223.374153)
			(xy 99.271819 -223.32518) (xy 99.292114 -223.278917) (xy 99.319748 -223.236625) (xy 99.353966 -223.199459)
			(xy 99.393835 -223.168433) (xy 99.438267 -223.144393) (xy 99.486051 -223.127994) (xy 99.535882 -223.119685)
			(xy 99.561142 -223.119188) (xy 99.585658 -223.119678) (xy 99.634061 -223.127516) (xy 99.68059 -223.142984)
			(xy 99.724051 -223.165685) (xy 99.763328 -223.195037) (xy 99.797414 -223.230285) (xy 99.825432 -223.270524)
			(xy 99.836478 -223.292416) (xy 99.841812 -223.303846) (xy 99.862132 -223.318832) (xy 99.969574 -223.335342)
			(xy 99.993196 -223.327214) (xy 100.001832 -223.31807) (xy 100.027958 -223.290812) (xy 100.082856 -223.238966)
			(xy 100.11156 -223.214438) (xy 100.11791 -223.20885) (xy 100.126546 -223.19488) (xy 100.128324 -223.186752)
			(xy 100.128578 -223.185228) (xy 100.129086 -223.183704) (xy 100.139751 -223.128633) (xy 100.169146 -223.020371)
			(xy 100.207536 -222.914963) (xy 100.25465 -222.813154) (xy 100.310155 -222.715666) (xy 100.34143 -222.6691)
			(xy 100.345748 -222.662496) (xy 100.35032 -222.648272) (xy 100.35032 -222.098108) (xy 100.349705 -222.085689)
			(xy 100.338128 -222.063713) (xy 100.328222 -222.056198) (xy 100.308147 -222.041841) (xy 100.272483 -222.00773)
			(xy 100.242766 -221.968329) (xy 100.219771 -221.924662) (xy 100.204095 -221.877867) (xy 100.196147 -221.829159)
			(xy 100.195634 -221.804484) (xy 100.195634 -221.799658) (xy 100.196473 -221.775797) (xy 100.204649 -221.728761)
			(xy 100.220044 -221.683569) (xy 100.242284 -221.641323) (xy 100.270827 -221.603053) (xy 100.287582 -221.586044)
			(xy 100.294694 -221.579186) (xy 100.30714 -221.550992) (xy 100.31095 -221.541086) (xy 100.31095 -213.727792)
			(xy 100.311376 -213.717724) (xy 100.319098 -213.699126) (xy 100.325936 -213.691724) (xy 111.785654 -202.232006)
			(xy 111.786162 -202.231498) (xy 111.792736 -202.224114) (xy 111.800167 -202.205815) (xy 111.80064 -202.195938)
			(xy 111.80064 -191.407542) (xy 111.79302 -191.388746) (xy 111.785654 -191.381634) (xy 110.139226 -189.735206)
			(xy 110.131824 -189.728371) (xy 110.113225 -189.720662) (xy 110.103158 -189.72022) (xy 105.334562 -189.72022)
			(xy 105.315766 -189.72784) (xy 105.308654 -189.735206) (xy 101.200966 -193.842894) (xy 101.193566 -193.849736)
			(xy 101.174968 -193.857459) (xy 101.164898 -193.85788) (xy 78.585822 -193.85788) (xy 78.575759 -193.857442)
			(xy 78.557177 -193.849706) (xy 78.549754 -193.842894) (xy 76.725526 -192.018666) (xy 76.718682 -192.011267)
			(xy 76.710956 -191.992669) (xy 76.71054 -191.982598) (xy 76.71054 -189.33668) (xy 76.710049 -189.326672)
			(xy 76.702387 -189.30818) (xy 76.688237 -189.294024) (xy 76.669748 -189.286355) (xy 76.65974 -189.28588)
			(xy 71.138542 -189.28588) (xy 71.119746 -189.2935) (xy 71.112634 -189.300866) (xy 70.969886 -189.443614)
			(xy 70.963032 -189.451009) (xy 70.95529 -189.469608) (xy 70.9549 -189.479682) (xy 70.9549 -193.199258)
			(xy 70.955367 -193.209132) (xy 70.962821 -193.22742) (xy 70.969378 -193.234818) (xy 70.969632 -193.235072)
			(xy 79.067914 -201.333354) (xy 79.068422 -201.333862) (xy 79.075802 -201.340448) (xy 79.094101 -201.347908)
			(xy 79.103982 -201.34834) (xy 97.342198 -201.34834) (xy 97.352267 -201.348764) (xy 97.370869 -201.356482)
			(xy 97.378266 -201.363326) (xy 98.999294 -202.984354) (xy 99.006133 -202.991755) (xy 99.013848 -203.010353)
			(xy 99.01428 -203.020422) (xy 99.01428 -208.533238) (xy 99.013849 -208.543305) (xy 99.006123 -208.561897)
			(xy 98.999294 -208.569306) (xy 96.352614 -211.215986) (xy 96.3458 -211.22333) (xy 96.33806 -211.241792)
			(xy 96.337628 -211.2518) (xy 96.337628 -214.192866) (xy 96.337628 -214.411814) (xy 96.337089 -214.421801)
			(xy 96.329375 -214.440232) (xy 96.322642 -214.447628) (xy 96.178624 -214.5919) (xy 96.178116 -214.592154)
			(xy 96.167956 -214.602568) (xy 95.98914 -214.781384) (xy 95.983338 -214.788598) (xy 95.976835 -214.805916)
			(xy 95.97644 -214.815166) (xy 95.97644 -218.418918) (xy 95.976012 -218.428985) (xy 95.968286 -218.447579)
			(xy 95.961454 -218.454986) (xy 92.611956 -221.804484) (xy 93.615268 -221.804484) (xy 93.619228 -221.75543)
			(xy 93.631005 -221.707646) (xy 93.650296 -221.66237) (xy 93.676599 -221.620774) (xy 93.709234 -221.583937)
			(xy 93.747355 -221.552812) (xy 93.789976 -221.528205) (xy 93.835992 -221.510753) (xy 93.884211 -221.500909)
			(xy 93.933386 -221.498928) (xy 93.982241 -221.50486) (xy 94.029512 -221.518552) (xy 94.073974 -221.53965)
			(xy 94.114477 -221.567606) (xy 94.14997 -221.601698) (xy 94.179535 -221.641042) (xy 94.202406 -221.684619)
			(xy 94.21799 -221.7313) (xy 94.225885 -221.779877) (xy 94.22638 -221.804484) (xy 94.555322 -221.804484)
			(xy 94.559282 -221.75543) (xy 94.571059 -221.707646) (xy 94.59035 -221.66237) (xy 94.616653 -221.620774)
			(xy 94.649288 -221.583937) (xy 94.687409 -221.552812) (xy 94.73003 -221.528205) (xy 94.776046 -221.510753)
			(xy 94.824265 -221.500909) (xy 94.87344 -221.498928) (xy 94.922295 -221.50486) (xy 94.969566 -221.518552)
			(xy 95.014028 -221.53965) (xy 95.054531 -221.567606) (xy 95.090024 -221.601698) (xy 95.119589 -221.641042)
			(xy 95.14246 -221.684619) (xy 95.158044 -221.7313) (xy 95.165939 -221.779877) (xy 95.166434 -221.804484)
			(xy 95.495122 -221.804484) (xy 95.499082 -221.75543) (xy 95.510859 -221.707646) (xy 95.53015 -221.66237)
			(xy 95.556453 -221.620774) (xy 95.589088 -221.583937) (xy 95.627209 -221.552812) (xy 95.66983 -221.528205)
			(xy 95.715846 -221.510753) (xy 95.764065 -221.500909) (xy 95.81324 -221.498928) (xy 95.862095 -221.50486)
			(xy 95.909366 -221.518552) (xy 95.953828 -221.53965) (xy 95.994331 -221.567606) (xy 96.029824 -221.601698)
			(xy 96.059389 -221.641042) (xy 96.08226 -221.684619) (xy 96.097844 -221.7313) (xy 96.105739 -221.779877)
			(xy 96.106234 -221.804484) (xy 96.435176 -221.804484) (xy 96.439136 -221.75543) (xy 96.450913 -221.707646)
			(xy 96.470204 -221.66237) (xy 96.496507 -221.620774) (xy 96.529142 -221.583937) (xy 96.567263 -221.552812)
			(xy 96.609884 -221.528205) (xy 96.6559 -221.510753) (xy 96.704119 -221.500909) (xy 96.753294 -221.498928)
			(xy 96.802149 -221.50486) (xy 96.84942 -221.518552) (xy 96.893882 -221.53965) (xy 96.934385 -221.567606)
			(xy 96.969878 -221.601698) (xy 96.999443 -221.641042) (xy 97.022314 -221.684619) (xy 97.037898 -221.7313)
			(xy 97.045793 -221.779877) (xy 97.046288 -221.804484) (xy 97.37523 -221.804484) (xy 97.37919 -221.75543)
			(xy 97.390967 -221.707646) (xy 97.410258 -221.66237) (xy 97.436561 -221.620774) (xy 97.469196 -221.583937)
			(xy 97.507317 -221.552812) (xy 97.549938 -221.528205) (xy 97.595954 -221.510753) (xy 97.644173 -221.500909)
			(xy 97.693348 -221.498928) (xy 97.742203 -221.50486) (xy 97.789474 -221.518552) (xy 97.833936 -221.53965)
			(xy 97.874439 -221.567606) (xy 97.909932 -221.601698) (xy 97.939497 -221.641042) (xy 97.962368 -221.684619)
			(xy 97.977952 -221.7313) (xy 97.985847 -221.779877) (xy 97.986342 -221.804484) (xy 99.255338 -221.804484)
			(xy 99.259298 -221.75543) (xy 99.271075 -221.707646) (xy 99.290366 -221.66237) (xy 99.316669 -221.620774)
			(xy 99.349304 -221.583937) (xy 99.387425 -221.552812) (xy 99.430046 -221.528205) (xy 99.476062 -221.510753)
			(xy 99.524281 -221.500909) (xy 99.573456 -221.498928) (xy 99.622311 -221.50486) (xy 99.669582 -221.518552)
			(xy 99.714044 -221.53965) (xy 99.754547 -221.567606) (xy 99.79004 -221.601698) (xy 99.819605 -221.641042)
			(xy 99.842476 -221.684619) (xy 99.85806 -221.7313) (xy 99.865955 -221.779877) (xy 99.86645 -221.804484)
			(xy 99.865955 -221.829091) (xy 99.85806 -221.877668) (xy 99.842476 -221.924349) (xy 99.819605 -221.967926)
			(xy 99.79004 -222.00727) (xy 99.754547 -222.041362) (xy 99.714044 -222.069318) (xy 99.669582 -222.090416)
			(xy 99.622311 -222.104108) (xy 99.573456 -222.11004) (xy 99.524281 -222.108059) (xy 99.476062 -222.098215)
			(xy 99.430046 -222.080763) (xy 99.387425 -222.056156) (xy 99.349304 -222.025031) (xy 99.316669 -221.988194)
			(xy 99.290366 -221.946598) (xy 99.271075 -221.901322) (xy 99.259298 -221.853538) (xy 99.255338 -221.804484)
			(xy 97.986342 -221.804484) (xy 97.985847 -221.829091) (xy 97.977952 -221.877668) (xy 97.962368 -221.924349)
			(xy 97.939497 -221.967926) (xy 97.909932 -222.00727) (xy 97.874439 -222.041362) (xy 97.833936 -222.069318)
			(xy 97.789474 -222.090416) (xy 97.742203 -222.104108) (xy 97.693348 -222.11004) (xy 97.644173 -222.108059)
			(xy 97.595954 -222.098215) (xy 97.549938 -222.080763) (xy 97.507317 -222.056156) (xy 97.469196 -222.025031)
			(xy 97.436561 -221.988194) (xy 97.410258 -221.946598) (xy 97.390967 -221.901322) (xy 97.37919 -221.853538)
			(xy 97.37523 -221.804484) (xy 97.046288 -221.804484) (xy 97.045793 -221.829091) (xy 97.037898 -221.877668)
			(xy 97.022314 -221.924349) (xy 96.999443 -221.967926) (xy 96.969878 -222.00727) (xy 96.934385 -222.041362)
			(xy 96.893882 -222.069318) (xy 96.84942 -222.090416) (xy 96.802149 -222.104108) (xy 96.753294 -222.11004)
			(xy 96.704119 -222.108059) (xy 96.6559 -222.098215) (xy 96.609884 -222.080763) (xy 96.567263 -222.056156)
			(xy 96.529142 -222.025031) (xy 96.496507 -221.988194) (xy 96.470204 -221.946598) (xy 96.450913 -221.901322)
			(xy 96.439136 -221.853538) (xy 96.435176 -221.804484) (xy 96.106234 -221.804484) (xy 96.105739 -221.829091)
			(xy 96.097844 -221.877668) (xy 96.08226 -221.924349) (xy 96.059389 -221.967926) (xy 96.029824 -222.00727)
			(xy 95.994331 -222.041362) (xy 95.953828 -222.069318) (xy 95.909366 -222.090416) (xy 95.862095 -222.104108)
			(xy 95.81324 -222.11004) (xy 95.764065 -222.108059) (xy 95.715846 -222.098215) (xy 95.66983 -222.080763)
			(xy 95.627209 -222.056156) (xy 95.589088 -222.025031) (xy 95.556453 -221.988194) (xy 95.53015 -221.946598)
			(xy 95.510859 -221.901322) (xy 95.499082 -221.853538) (xy 95.495122 -221.804484) (xy 95.166434 -221.804484)
			(xy 95.165939 -221.829091) (xy 95.158044 -221.877668) (xy 95.14246 -221.924349) (xy 95.119589 -221.967926)
			(xy 95.090024 -222.00727) (xy 95.054531 -222.041362) (xy 95.014028 -222.069318) (xy 94.969566 -222.090416)
			(xy 94.922295 -222.104108) (xy 94.87344 -222.11004) (xy 94.824265 -222.108059) (xy 94.776046 -222.098215)
			(xy 94.73003 -222.080763) (xy 94.687409 -222.056156) (xy 94.649288 -222.025031) (xy 94.616653 -221.988194)
			(xy 94.59035 -221.946598) (xy 94.571059 -221.901322) (xy 94.559282 -221.853538) (xy 94.555322 -221.804484)
			(xy 94.22638 -221.804484) (xy 94.225885 -221.829091) (xy 94.21799 -221.877668) (xy 94.202406 -221.924349)
			(xy 94.179535 -221.967926) (xy 94.14997 -222.00727) (xy 94.114477 -222.041362) (xy 94.073974 -222.069318)
			(xy 94.029512 -222.090416) (xy 93.982241 -222.104108) (xy 93.933386 -222.11004) (xy 93.884211 -222.108059)
			(xy 93.835992 -222.098215) (xy 93.789976 -222.080763) (xy 93.747355 -222.056156) (xy 93.709234 -222.025031)
			(xy 93.676599 -221.988194) (xy 93.650296 -221.946598) (xy 93.631005 -221.901322) (xy 93.619228 -221.853538)
			(xy 93.615268 -221.804484) (xy 92.611956 -221.804484) (xy 92.041726 -222.374714) (xy 92.034879 -222.382112)
			(xy 92.027146 -222.40071) (xy 92.02674 -222.410782) (xy 92.02674 -222.61449) (xy 92.205314 -222.61449)
			(xy 92.209274 -222.565436) (xy 92.221051 -222.517652) (xy 92.240342 -222.472376) (xy 92.266645 -222.43078)
			(xy 92.29928 -222.393943) (xy 92.337401 -222.362818) (xy 92.380022 -222.338211) (xy 92.426038 -222.320759)
			(xy 92.474257 -222.310915) (xy 92.523432 -222.308934) (xy 92.572287 -222.314866) (xy 92.619558 -222.328558)
			(xy 92.66402 -222.349656) (xy 92.704523 -222.377612) (xy 92.740016 -222.411704) (xy 92.769581 -222.451048)
			(xy 92.792452 -222.494625) (xy 92.808036 -222.541306) (xy 92.815931 -222.589883) (xy 92.816426 -222.61449)
			(xy 95.025222 -222.61449) (xy 95.029182 -222.565436) (xy 95.040959 -222.517652) (xy 95.06025 -222.472376)
			(xy 95.086553 -222.43078) (xy 95.119188 -222.393943) (xy 95.157309 -222.362818) (xy 95.19993 -222.338211)
			(xy 95.245946 -222.320759) (xy 95.294165 -222.310915) (xy 95.34334 -222.308934) (xy 95.392195 -222.314866)
			(xy 95.439466 -222.328558) (xy 95.483928 -222.349656) (xy 95.524431 -222.377612) (xy 95.559924 -222.411704)
			(xy 95.589489 -222.451048) (xy 95.61236 -222.494625) (xy 95.627944 -222.541306) (xy 95.635839 -222.589883)
			(xy 95.636334 -222.61449) (xy 97.84513 -222.61449) (xy 97.84909 -222.565436) (xy 97.860867 -222.517652)
			(xy 97.880158 -222.472376) (xy 97.906461 -222.43078) (xy 97.939096 -222.393943) (xy 97.977217 -222.362818)
			(xy 98.019838 -222.338211) (xy 98.065854 -222.320759) (xy 98.114073 -222.310915) (xy 98.163248 -222.308934)
			(xy 98.212103 -222.314866) (xy 98.259374 -222.328558) (xy 98.303836 -222.349656) (xy 98.344339 -222.377612)
			(xy 98.379832 -222.411704) (xy 98.409397 -222.451048) (xy 98.432268 -222.494625) (xy 98.447852 -222.541306)
			(xy 98.455747 -222.589883) (xy 98.456242 -222.61449) (xy 98.455747 -222.639097) (xy 98.447852 -222.687674)
			(xy 98.432268 -222.734355) (xy 98.409397 -222.777932) (xy 98.379832 -222.817276) (xy 98.344339 -222.851368)
			(xy 98.303836 -222.879324) (xy 98.259374 -222.900422) (xy 98.212103 -222.914114) (xy 98.163248 -222.920046)
			(xy 98.114073 -222.918065) (xy 98.065854 -222.908221) (xy 98.019838 -222.890769) (xy 97.977217 -222.866162)
			(xy 97.939096 -222.835037) (xy 97.906461 -222.7982) (xy 97.880158 -222.756604) (xy 97.860867 -222.711328)
			(xy 97.84909 -222.663544) (xy 97.84513 -222.61449) (xy 95.636334 -222.61449) (xy 95.635839 -222.639097)
			(xy 95.627944 -222.687674) (xy 95.61236 -222.734355) (xy 95.589489 -222.777932) (xy 95.559924 -222.817276)
			(xy 95.524431 -222.851368) (xy 95.483928 -222.879324) (xy 95.439466 -222.900422) (xy 95.392195 -222.914114)
			(xy 95.34334 -222.920046) (xy 95.294165 -222.918065) (xy 95.245946 -222.908221) (xy 95.19993 -222.890769)
			(xy 95.157309 -222.866162) (xy 95.119188 -222.835037) (xy 95.086553 -222.7982) (xy 95.06025 -222.756604)
			(xy 95.040959 -222.711328) (xy 95.029182 -222.663544) (xy 95.025222 -222.61449) (xy 92.816426 -222.61449)
			(xy 92.815931 -222.639097) (xy 92.808036 -222.687674) (xy 92.792452 -222.734355) (xy 92.769581 -222.777932)
			(xy 92.740016 -222.817276) (xy 92.704523 -222.851368) (xy 92.66402 -222.879324) (xy 92.619558 -222.900422)
			(xy 92.572287 -222.914114) (xy 92.523432 -222.920046) (xy 92.474257 -222.918065) (xy 92.426038 -222.908221)
			(xy 92.380022 -222.890769) (xy 92.337401 -222.866162) (xy 92.29928 -222.835037) (xy 92.266645 -222.7982)
			(xy 92.240342 -222.756604) (xy 92.221051 -222.711328) (xy 92.209274 -222.663544) (xy 92.205314 -222.61449)
			(xy 92.02674 -222.61449) (xy 92.02674 -223.424496) (xy 93.615268 -223.424496) (xy 93.619228 -223.375442)
			(xy 93.631005 -223.327658) (xy 93.650296 -223.282382) (xy 93.676599 -223.240786) (xy 93.709234 -223.203949)
			(xy 93.747355 -223.172824) (xy 93.789976 -223.148217) (xy 93.835992 -223.130765) (xy 93.884211 -223.120921)
			(xy 93.933386 -223.11894) (xy 93.982241 -223.124872) (xy 94.029512 -223.138564) (xy 94.073974 -223.159662)
			(xy 94.114477 -223.187618) (xy 94.14997 -223.22171) (xy 94.179535 -223.261054) (xy 94.202406 -223.304631)
			(xy 94.21799 -223.351312) (xy 94.225885 -223.399889) (xy 94.22638 -223.424496) (xy 94.555322 -223.424496)
			(xy 94.559282 -223.375442) (xy 94.571059 -223.327658) (xy 94.59035 -223.282382) (xy 94.616653 -223.240786)
			(xy 94.649288 -223.203949) (xy 94.687409 -223.172824) (xy 94.73003 -223.148217) (xy 94.776046 -223.130765)
			(xy 94.824265 -223.120921) (xy 94.87344 -223.11894) (xy 94.922295 -223.124872) (xy 94.969566 -223.138564)
			(xy 95.014028 -223.159662) (xy 95.054531 -223.187618) (xy 95.090024 -223.22171) (xy 95.119589 -223.261054)
			(xy 95.14246 -223.304631) (xy 95.158044 -223.351312) (xy 95.165939 -223.399889) (xy 95.166434 -223.424496)
			(xy 95.495122 -223.424496) (xy 95.499082 -223.375442) (xy 95.510859 -223.327658) (xy 95.53015 -223.282382)
			(xy 95.556453 -223.240786) (xy 95.589088 -223.203949) (xy 95.627209 -223.172824) (xy 95.66983 -223.148217)
			(xy 95.715846 -223.130765) (xy 95.764065 -223.120921) (xy 95.81324 -223.11894) (xy 95.862095 -223.124872)
			(xy 95.909366 -223.138564) (xy 95.953828 -223.159662) (xy 95.994331 -223.187618) (xy 96.029824 -223.22171)
			(xy 96.059389 -223.261054) (xy 96.08226 -223.304631) (xy 96.097844 -223.351312) (xy 96.105739 -223.399889)
			(xy 96.106234 -223.424496) (xy 96.435176 -223.424496) (xy 96.439136 -223.375442) (xy 96.450913 -223.327658)
			(xy 96.470204 -223.282382) (xy 96.496507 -223.240786) (xy 96.529142 -223.203949) (xy 96.567263 -223.172824)
			(xy 96.609884 -223.148217) (xy 96.6559 -223.130765) (xy 96.704119 -223.120921) (xy 96.753294 -223.11894)
			(xy 96.802149 -223.124872) (xy 96.84942 -223.138564) (xy 96.893882 -223.159662) (xy 96.934385 -223.187618)
			(xy 96.969878 -223.22171) (xy 96.999443 -223.261054) (xy 97.022314 -223.304631) (xy 97.037898 -223.351312)
			(xy 97.045793 -223.399889) (xy 97.046288 -223.424496) (xy 97.37523 -223.424496) (xy 97.37919 -223.375442)
			(xy 97.390967 -223.327658) (xy 97.410258 -223.282382) (xy 97.436561 -223.240786) (xy 97.469196 -223.203949)
			(xy 97.507317 -223.172824) (xy 97.549938 -223.148217) (xy 97.595954 -223.130765) (xy 97.644173 -223.120921)
			(xy 97.693348 -223.11894) (xy 97.742203 -223.124872) (xy 97.789474 -223.138564) (xy 97.833936 -223.159662)
			(xy 97.874439 -223.187618) (xy 97.909932 -223.22171) (xy 97.939497 -223.261054) (xy 97.962368 -223.304631)
			(xy 97.977952 -223.351312) (xy 97.985847 -223.399889) (xy 97.986342 -223.424496) (xy 98.315284 -223.424496)
			(xy 98.319244 -223.375442) (xy 98.331021 -223.327658) (xy 98.350312 -223.282382) (xy 98.376615 -223.240786)
			(xy 98.40925 -223.203949) (xy 98.447371 -223.172824) (xy 98.489992 -223.148217) (xy 98.536008 -223.130765)
			(xy 98.584227 -223.120921) (xy 98.633402 -223.11894) (xy 98.682257 -223.124872) (xy 98.729528 -223.138564)
			(xy 98.77399 -223.159662) (xy 98.814493 -223.187618) (xy 98.849986 -223.22171) (xy 98.879551 -223.261054)
			(xy 98.902422 -223.304631) (xy 98.918006 -223.351312) (xy 98.925901 -223.399889) (xy 98.926396 -223.424496)
			(xy 98.925901 -223.449103) (xy 98.918006 -223.49768) (xy 98.902422 -223.544361) (xy 98.879551 -223.587938)
			(xy 98.849986 -223.627282) (xy 98.814493 -223.661374) (xy 98.77399 -223.68933) (xy 98.729528 -223.710428)
			(xy 98.682257 -223.72412) (xy 98.633402 -223.730052) (xy 98.584227 -223.728071) (xy 98.536008 -223.718227)
			(xy 98.489992 -223.700775) (xy 98.447371 -223.676168) (xy 98.40925 -223.645043) (xy 98.376615 -223.608206)
			(xy 98.350312 -223.56661) (xy 98.331021 -223.521334) (xy 98.319244 -223.47355) (xy 98.315284 -223.424496)
			(xy 97.986342 -223.424496) (xy 97.985847 -223.449103) (xy 97.977952 -223.49768) (xy 97.962368 -223.544361)
			(xy 97.939497 -223.587938) (xy 97.909932 -223.627282) (xy 97.874439 -223.661374) (xy 97.833936 -223.68933)
			(xy 97.789474 -223.710428) (xy 97.742203 -223.72412) (xy 97.693348 -223.730052) (xy 97.644173 -223.728071)
			(xy 97.595954 -223.718227) (xy 97.549938 -223.700775) (xy 97.507317 -223.676168) (xy 97.469196 -223.645043)
			(xy 97.436561 -223.608206) (xy 97.410258 -223.56661) (xy 97.390967 -223.521334) (xy 97.37919 -223.47355)
			(xy 97.37523 -223.424496) (xy 97.046288 -223.424496) (xy 97.045793 -223.449103) (xy 97.037898 -223.49768)
			(xy 97.022314 -223.544361) (xy 96.999443 -223.587938) (xy 96.969878 -223.627282) (xy 96.934385 -223.661374)
			(xy 96.893882 -223.68933) (xy 96.84942 -223.710428) (xy 96.802149 -223.72412) (xy 96.753294 -223.730052)
			(xy 96.704119 -223.728071) (xy 96.6559 -223.718227) (xy 96.609884 -223.700775) (xy 96.567263 -223.676168)
			(xy 96.529142 -223.645043) (xy 96.496507 -223.608206) (xy 96.470204 -223.56661) (xy 96.450913 -223.521334)
			(xy 96.439136 -223.47355) (xy 96.435176 -223.424496) (xy 96.106234 -223.424496) (xy 96.105739 -223.449103)
			(xy 96.097844 -223.49768) (xy 96.08226 -223.544361) (xy 96.059389 -223.587938) (xy 96.029824 -223.627282)
			(xy 95.994331 -223.661374) (xy 95.953828 -223.68933) (xy 95.909366 -223.710428) (xy 95.862095 -223.72412)
			(xy 95.81324 -223.730052) (xy 95.764065 -223.728071) (xy 95.715846 -223.718227) (xy 95.66983 -223.700775)
			(xy 95.627209 -223.676168) (xy 95.589088 -223.645043) (xy 95.556453 -223.608206) (xy 95.53015 -223.56661)
			(xy 95.510859 -223.521334) (xy 95.499082 -223.47355) (xy 95.495122 -223.424496) (xy 95.166434 -223.424496)
			(xy 95.165939 -223.449103) (xy 95.158044 -223.49768) (xy 95.14246 -223.544361) (xy 95.119589 -223.587938)
			(xy 95.090024 -223.627282) (xy 95.054531 -223.661374) (xy 95.014028 -223.68933) (xy 94.969566 -223.710428)
			(xy 94.922295 -223.72412) (xy 94.87344 -223.730052) (xy 94.824265 -223.728071) (xy 94.776046 -223.718227)
			(xy 94.73003 -223.700775) (xy 94.687409 -223.676168) (xy 94.649288 -223.645043) (xy 94.616653 -223.608206)
			(xy 94.59035 -223.56661) (xy 94.571059 -223.521334) (xy 94.559282 -223.47355) (xy 94.555322 -223.424496)
			(xy 94.22638 -223.424496) (xy 94.225885 -223.449103) (xy 94.21799 -223.49768) (xy 94.202406 -223.544361)
			(xy 94.179535 -223.587938) (xy 94.14997 -223.627282) (xy 94.114477 -223.661374) (xy 94.073974 -223.68933)
			(xy 94.029512 -223.710428) (xy 93.982241 -223.72412) (xy 93.933386 -223.730052) (xy 93.884211 -223.728071)
			(xy 93.835992 -223.718227) (xy 93.789976 -223.700775) (xy 93.747355 -223.676168) (xy 93.709234 -223.645043)
			(xy 93.676599 -223.608206) (xy 93.650296 -223.56661) (xy 93.631005 -223.521334) (xy 93.619228 -223.47355)
			(xy 93.615268 -223.424496) (xy 92.02674 -223.424496) (xy 92.02674 -224.234502) (xy 93.145114 -224.234502)
			(xy 93.149074 -224.185448) (xy 93.160851 -224.137664) (xy 93.180142 -224.092388) (xy 93.206445 -224.050792)
			(xy 93.23908 -224.013955) (xy 93.277201 -223.98283) (xy 93.319822 -223.958223) (xy 93.365838 -223.940771)
			(xy 93.414057 -223.930927) (xy 93.463232 -223.928946) (xy 93.512087 -223.934878) (xy 93.559358 -223.94857)
			(xy 93.60382 -223.969668) (xy 93.644323 -223.997624) (xy 93.679816 -224.031716) (xy 93.709381 -224.07106)
			(xy 93.732252 -224.114637) (xy 93.747836 -224.161318) (xy 93.755731 -224.209895) (xy 93.756226 -224.234502)
			(xy 95.965276 -224.234502) (xy 95.969236 -224.185448) (xy 95.981013 -224.137664) (xy 96.000304 -224.092388)
			(xy 96.026607 -224.050792) (xy 96.059242 -224.013955) (xy 96.097363 -223.98283) (xy 96.139984 -223.958223)
			(xy 96.186 -223.940771) (xy 96.234219 -223.930927) (xy 96.283394 -223.928946) (xy 96.332249 -223.934878)
			(xy 96.37952 -223.94857) (xy 96.423982 -223.969668) (xy 96.464485 -223.997624) (xy 96.499978 -224.031716)
			(xy 96.529543 -224.07106) (xy 96.552414 -224.114637) (xy 96.567998 -224.161318) (xy 96.575893 -224.209895)
			(xy 96.576388 -224.234502) (xy 96.90533 -224.234502) (xy 96.90929 -224.185448) (xy 96.921067 -224.137664)
			(xy 96.940358 -224.092388) (xy 96.966661 -224.050792) (xy 96.999296 -224.013955) (xy 97.037417 -223.98283)
			(xy 97.080038 -223.958223) (xy 97.126054 -223.940771) (xy 97.174273 -223.930927) (xy 97.223448 -223.928946)
			(xy 97.272303 -223.934878) (xy 97.319574 -223.94857) (xy 97.364036 -223.969668) (xy 97.404539 -223.997624)
			(xy 97.440032 -224.031716) (xy 97.469597 -224.07106) (xy 97.492468 -224.114637) (xy 97.508052 -224.161318)
			(xy 97.515947 -224.209895) (xy 97.516442 -224.234502) (xy 97.84513 -224.234502) (xy 97.84909 -224.185448)
			(xy 97.860867 -224.137664) (xy 97.880158 -224.092388) (xy 97.906461 -224.050792) (xy 97.939096 -224.013955)
			(xy 97.977217 -223.98283) (xy 98.019838 -223.958223) (xy 98.065854 -223.940771) (xy 98.114073 -223.930927)
			(xy 98.163248 -223.928946) (xy 98.212103 -223.934878) (xy 98.259374 -223.94857) (xy 98.303836 -223.969668)
			(xy 98.344339 -223.997624) (xy 98.379832 -224.031716) (xy 98.409397 -224.07106) (xy 98.432268 -224.114637)
			(xy 98.447852 -224.161318) (xy 98.455747 -224.209895) (xy 98.456242 -224.234502) (xy 98.455747 -224.259109)
			(xy 98.447852 -224.307686) (xy 98.432268 -224.354367) (xy 98.409397 -224.397944) (xy 98.379832 -224.437288)
			(xy 98.344339 -224.47138) (xy 98.303836 -224.499336) (xy 98.259374 -224.520434) (xy 98.212103 -224.534126)
			(xy 98.163248 -224.540058) (xy 98.114073 -224.538077) (xy 98.065854 -224.528233) (xy 98.019838 -224.510781)
			(xy 97.977217 -224.486174) (xy 97.939096 -224.455049) (xy 97.906461 -224.418212) (xy 97.880158 -224.376616)
			(xy 97.860867 -224.33134) (xy 97.84909 -224.283556) (xy 97.84513 -224.234502) (xy 97.516442 -224.234502)
			(xy 97.515947 -224.259109) (xy 97.508052 -224.307686) (xy 97.492468 -224.354367) (xy 97.469597 -224.397944)
			(xy 97.440032 -224.437288) (xy 97.404539 -224.47138) (xy 97.364036 -224.499336) (xy 97.319574 -224.520434)
			(xy 97.272303 -224.534126) (xy 97.223448 -224.540058) (xy 97.174273 -224.538077) (xy 97.126054 -224.528233)
			(xy 97.080038 -224.510781) (xy 97.037417 -224.486174) (xy 96.999296 -224.455049) (xy 96.966661 -224.418212)
			(xy 96.940358 -224.376616) (xy 96.921067 -224.33134) (xy 96.90929 -224.283556) (xy 96.90533 -224.234502)
			(xy 96.576388 -224.234502) (xy 96.575893 -224.259109) (xy 96.567998 -224.307686) (xy 96.552414 -224.354367)
			(xy 96.529543 -224.397944) (xy 96.499978 -224.437288) (xy 96.464485 -224.47138) (xy 96.423982 -224.499336)
			(xy 96.37952 -224.520434) (xy 96.332249 -224.534126) (xy 96.283394 -224.540058) (xy 96.234219 -224.538077)
			(xy 96.186 -224.528233) (xy 96.139984 -224.510781) (xy 96.097363 -224.486174) (xy 96.059242 -224.455049)
			(xy 96.026607 -224.418212) (xy 96.000304 -224.376616) (xy 95.981013 -224.33134) (xy 95.969236 -224.283556)
			(xy 95.965276 -224.234502) (xy 93.756226 -224.234502) (xy 93.755731 -224.259109) (xy 93.747836 -224.307686)
			(xy 93.732252 -224.354367) (xy 93.709381 -224.397944) (xy 93.679816 -224.437288) (xy 93.644323 -224.47138)
			(xy 93.60382 -224.499336) (xy 93.559358 -224.520434) (xy 93.512087 -224.534126) (xy 93.463232 -224.540058)
			(xy 93.414057 -224.538077) (xy 93.365838 -224.528233) (xy 93.319822 -224.510781) (xy 93.277201 -224.486174)
			(xy 93.23908 -224.455049) (xy 93.206445 -224.418212) (xy 93.180142 -224.376616) (xy 93.160851 -224.33134)
			(xy 93.149074 -224.283556) (xy 93.145114 -224.234502) (xy 92.02674 -224.234502) (xy 92.02674 -224.709736)
			(xy 92.052648 -224.738692) (xy 92.072206 -224.740724) (xy 92.096952 -224.743763) (xy 92.14506 -224.756845)
			(xy 92.190403 -224.777569) (xy 92.231778 -224.805382) (xy 92.268086 -224.839547) (xy 92.298362 -224.879156)
			(xy 92.321802 -224.923157) (xy 92.337783 -224.970381) (xy 92.345881 -225.019573) (xy 92.345881 -225.044508)
			(xy 92.675214 -225.044508) (xy 92.679174 -224.995454) (xy 92.690951 -224.94767) (xy 92.710242 -224.902394)
			(xy 92.736545 -224.860798) (xy 92.76918 -224.823961) (xy 92.807301 -224.792836) (xy 92.849922 -224.768229)
			(xy 92.895938 -224.750777) (xy 92.944157 -224.740933) (xy 92.993332 -224.738952) (xy 93.042187 -224.744884)
			(xy 93.089458 -224.758576) (xy 93.13392 -224.779674) (xy 93.174423 -224.80763) (xy 93.209916 -224.841722)
			(xy 93.239481 -224.881066) (xy 93.262352 -224.924643) (xy 93.277936 -224.971324) (xy 93.285831 -225.019901)
			(xy 93.286326 -225.044508) (xy 93.604837 -225.044508) (xy 93.608932 -224.99378) (xy 93.621111 -224.944366)
			(xy 93.641059 -224.897546) (xy 93.66826 -224.854532) (xy 93.702008 -224.816438) (xy 93.74143 -224.784251)
			(xy 93.785504 -224.758805) (xy 93.83309 -224.740758) (xy 93.882954 -224.730578) (xy 93.933806 -224.728529)
			(xy 93.984327 -224.734663) (xy 94.033211 -224.748823) (xy 94.07919 -224.77064) (xy 94.121074 -224.79955)
			(xy 94.157778 -224.834805) (xy 94.188351 -224.875491) (xy 94.212002 -224.920554) (xy 94.228118 -224.968828)
			(xy 94.236282 -225.019062) (xy 94.236794 -225.044508) (xy 94.555322 -225.044508) (xy 94.559282 -224.995454)
			(xy 94.571059 -224.94767) (xy 94.59035 -224.902394) (xy 94.616653 -224.860798) (xy 94.649288 -224.823961)
			(xy 94.687409 -224.792836) (xy 94.73003 -224.768229) (xy 94.776046 -224.750777) (xy 94.824265 -224.740933)
			(xy 94.87344 -224.738952) (xy 94.922295 -224.744884) (xy 94.969566 -224.758576) (xy 95.014028 -224.779674)
			(xy 95.054531 -224.80763) (xy 95.090024 -224.841722) (xy 95.119589 -224.881066) (xy 95.14246 -224.924643)
			(xy 95.158044 -224.971324) (xy 95.165939 -225.019901) (xy 95.166434 -225.044508) (xy 95.495122 -225.044508)
			(xy 95.499082 -224.995454) (xy 95.510859 -224.94767) (xy 95.53015 -224.902394) (xy 95.556453 -224.860798)
			(xy 95.589088 -224.823961) (xy 95.627209 -224.792836) (xy 95.66983 -224.768229) (xy 95.715846 -224.750777)
			(xy 95.764065 -224.740933) (xy 95.81324 -224.738952) (xy 95.862095 -224.744884) (xy 95.909366 -224.758576)
			(xy 95.953828 -224.779674) (xy 95.994331 -224.80763) (xy 96.029824 -224.841722) (xy 96.059389 -224.881066)
			(xy 96.08226 -224.924643) (xy 96.097844 -224.971324) (xy 96.105739 -225.019901) (xy 96.106234 -225.044508)
			(xy 97.37523 -225.044508) (xy 97.37919 -224.995454) (xy 97.390967 -224.94767) (xy 97.410258 -224.902394)
			(xy 97.436561 -224.860798) (xy 97.469196 -224.823961) (xy 97.507317 -224.792836) (xy 97.549938 -224.768229)
			(xy 97.595954 -224.750777) (xy 97.644173 -224.740933) (xy 97.693348 -224.738952) (xy 97.742203 -224.744884)
			(xy 97.789474 -224.758576) (xy 97.833936 -224.779674) (xy 97.874439 -224.80763) (xy 97.909932 -224.841722)
			(xy 97.939497 -224.881066) (xy 97.962368 -224.924643) (xy 97.977952 -224.971324) (xy 97.985847 -225.019901)
			(xy 97.986342 -225.044508) (xy 97.985847 -225.069115) (xy 97.977952 -225.117692) (xy 97.962368 -225.164373)
			(xy 97.939497 -225.20795) (xy 97.909932 -225.247294) (xy 97.874439 -225.281386) (xy 97.833936 -225.309342)
			(xy 97.789474 -225.33044) (xy 97.742203 -225.344132) (xy 97.693348 -225.350064) (xy 97.644173 -225.348083)
			(xy 97.595954 -225.338239) (xy 97.549938 -225.320787) (xy 97.507317 -225.29618) (xy 97.469196 -225.265055)
			(xy 97.436561 -225.228218) (xy 97.410258 -225.186622) (xy 97.390967 -225.141346) (xy 97.37919 -225.093562)
			(xy 97.37523 -225.044508) (xy 96.106234 -225.044508) (xy 96.105739 -225.069115) (xy 96.097844 -225.117692)
			(xy 96.08226 -225.164373) (xy 96.059389 -225.20795) (xy 96.029824 -225.247294) (xy 95.994331 -225.281386)
			(xy 95.953828 -225.309342) (xy 95.909366 -225.33044) (xy 95.862095 -225.344132) (xy 95.81324 -225.350064)
			(xy 95.764065 -225.348083) (xy 95.715846 -225.338239) (xy 95.66983 -225.320787) (xy 95.627209 -225.29618)
			(xy 95.589088 -225.265055) (xy 95.556453 -225.228218) (xy 95.53015 -225.186622) (xy 95.510859 -225.141346)
			(xy 95.499082 -225.093562) (xy 95.495122 -225.044508) (xy 95.166434 -225.044508) (xy 95.165939 -225.069115)
			(xy 95.158044 -225.117692) (xy 95.14246 -225.164373) (xy 95.119589 -225.20795) (xy 95.090024 -225.247294)
			(xy 95.054531 -225.281386) (xy 95.014028 -225.309342) (xy 94.969566 -225.33044) (xy 94.922295 -225.344132)
			(xy 94.87344 -225.350064) (xy 94.824265 -225.348083) (xy 94.776046 -225.338239) (xy 94.73003 -225.320787)
			(xy 94.687409 -225.29618) (xy 94.649288 -225.265055) (xy 94.616653 -225.228218) (xy 94.59035 -225.186622)
			(xy 94.571059 -225.141346) (xy 94.559282 -225.093562) (xy 94.555322 -225.044508) (xy 94.236794 -225.044508)
			(xy 94.236282 -225.069954) (xy 94.228118 -225.120188) (xy 94.212002 -225.168462) (xy 94.188351 -225.213525)
			(xy 94.157778 -225.254211) (xy 94.121074 -225.289466) (xy 94.07919 -225.318376) (xy 94.033211 -225.340193)
			(xy 93.984327 -225.354353) (xy 93.933806 -225.360487) (xy 93.882954 -225.358438) (xy 93.83309 -225.348258)
			(xy 93.785504 -225.330211) (xy 93.74143 -225.304765) (xy 93.702008 -225.272578) (xy 93.66826 -225.234484)
			(xy 93.641059 -225.19147) (xy 93.621111 -225.14465) (xy 93.608932 -225.095236) (xy 93.604837 -225.044508)
			(xy 93.286326 -225.044508) (xy 93.285831 -225.069115) (xy 93.277936 -225.117692) (xy 93.262352 -225.164373)
			(xy 93.239481 -225.20795) (xy 93.209916 -225.247294) (xy 93.174423 -225.281386) (xy 93.13392 -225.309342)
			(xy 93.089458 -225.33044) (xy 93.042187 -225.344132) (xy 92.993332 -225.350064) (xy 92.944157 -225.348083)
			(xy 92.895938 -225.338239) (xy 92.849922 -225.320787) (xy 92.807301 -225.29618) (xy 92.76918 -225.265055)
			(xy 92.736545 -225.228218) (xy 92.710242 -225.186622) (xy 92.690951 -225.141346) (xy 92.679174 -225.093562)
			(xy 92.675214 -225.044508) (xy 92.345881 -225.044508) (xy 92.345881 -225.069428) (xy 92.337782 -225.118621)
			(xy 92.321801 -225.165844) (xy 92.298361 -225.209845) (xy 92.268085 -225.249454) (xy 92.231777 -225.283619)
			(xy 92.190402 -225.311432) (xy 92.145058 -225.332155) (xy 92.096951 -225.345238) (xy 92.072206 -225.348292)
			(xy 92.052648 -225.350324) (xy 92.02674 -225.37928) (xy 92.02674 -225.749358) (xy 92.027206 -225.759233)
			(xy 92.034653 -225.777527) (xy 92.041218 -225.784918) (xy 92.041472 -225.785172) (xy 92.050362 -225.794062)
			(xy 92.059655 -225.802522) (xy 92.083652 -225.809872) (xy 92.096082 -225.808032) (xy 92.096844 -225.807778)
			(xy 92.187522 -225.786696) (xy 92.20708 -225.768662) (xy 92.211398 -225.755962) (xy 92.219564 -225.732611)
			(xy 92.242128 -225.68859) (xy 92.271285 -225.648629) (xy 92.306321 -225.613708) (xy 92.346377 -225.584683)
			(xy 92.390472 -225.562265) (xy 92.437526 -225.547002) (xy 92.486385 -225.53927) (xy 92.511118 -225.538792)
			(xy 92.535926 -225.53928) (xy 92.584931 -225.547045) (xy 92.632119 -225.56238) (xy 92.676326 -225.584907)
			(xy 92.716465 -225.614073) (xy 92.751548 -225.649159) (xy 92.780709 -225.689301) (xy 92.803233 -225.733511)
			(xy 92.818563 -225.7807) (xy 92.826322 -225.829706) (xy 92.82684 -225.854514) (xy 93.145114 -225.854514)
			(xy 93.149074 -225.80546) (xy 93.160851 -225.757676) (xy 93.180142 -225.7124) (xy 93.206445 -225.670804)
			(xy 93.23908 -225.633967) (xy 93.277201 -225.602842) (xy 93.319822 -225.578235) (xy 93.365838 -225.560783)
			(xy 93.414057 -225.550939) (xy 93.463232 -225.548958) (xy 93.512087 -225.55489) (xy 93.559358 -225.568582)
			(xy 93.60382 -225.58968) (xy 93.644323 -225.617636) (xy 93.679816 -225.651728) (xy 93.709381 -225.691072)
			(xy 93.732252 -225.734649) (xy 93.747836 -225.78133) (xy 93.755731 -225.829907) (xy 93.756226 -225.854514)
			(xy 94.074737 -225.854514) (xy 94.078832 -225.803786) (xy 94.091011 -225.754372) (xy 94.110959 -225.707552)
			(xy 94.13816 -225.664538) (xy 94.171908 -225.626444) (xy 94.21133 -225.594257) (xy 94.255404 -225.568811)
			(xy 94.30299 -225.550764) (xy 94.352854 -225.540584) (xy 94.403706 -225.538535) (xy 94.454227 -225.544669)
			(xy 94.503111 -225.558829) (xy 94.54909 -225.580646) (xy 94.590974 -225.609556) (xy 94.627678 -225.644811)
			(xy 94.658251 -225.685497) (xy 94.681902 -225.73056) (xy 94.698018 -225.778834) (xy 94.706182 -225.829068)
			(xy 94.706694 -225.854514) (xy 95.014791 -225.854514) (xy 95.018886 -225.803786) (xy 95.031065 -225.754372)
			(xy 95.051013 -225.707552) (xy 95.078214 -225.664538) (xy 95.111962 -225.626444) (xy 95.151384 -225.594257)
			(xy 95.195458 -225.568811) (xy 95.243044 -225.550764) (xy 95.292908 -225.540584) (xy 95.34376 -225.538535)
			(xy 95.394281 -225.544669) (xy 95.443165 -225.558829) (xy 95.489144 -225.580646) (xy 95.531028 -225.609556)
			(xy 95.567732 -225.644811) (xy 95.598305 -225.685497) (xy 95.621956 -225.73056) (xy 95.638072 -225.778834)
			(xy 95.646236 -225.829068) (xy 95.646748 -225.854514) (xy 96.90533 -225.854514) (xy 96.90929 -225.80546)
			(xy 96.921067 -225.757676) (xy 96.940358 -225.7124) (xy 96.966661 -225.670804) (xy 96.999296 -225.633967)
			(xy 97.037417 -225.602842) (xy 97.080038 -225.578235) (xy 97.126054 -225.560783) (xy 97.174273 -225.550939)
			(xy 97.223448 -225.548958) (xy 97.272303 -225.55489) (xy 97.319574 -225.568582) (xy 97.364036 -225.58968)
			(xy 97.404539 -225.617636) (xy 97.440032 -225.651728) (xy 97.469597 -225.691072) (xy 97.492468 -225.734649)
			(xy 97.508052 -225.78133) (xy 97.515947 -225.829907) (xy 97.516442 -225.854514) (xy 97.515947 -225.879121)
			(xy 97.508052 -225.927698) (xy 97.492468 -225.974379) (xy 97.469597 -226.017956) (xy 97.440032 -226.0573)
			(xy 97.404539 -226.091392) (xy 97.364036 -226.119348) (xy 97.319574 -226.140446) (xy 97.272303 -226.154138)
			(xy 97.223448 -226.16007) (xy 97.174273 -226.158089) (xy 97.126054 -226.148245) (xy 97.080038 -226.130793)
			(xy 97.037417 -226.106186) (xy 96.999296 -226.075061) (xy 96.966661 -226.038224) (xy 96.940358 -225.996628)
			(xy 96.921067 -225.951352) (xy 96.90929 -225.903568) (xy 96.90533 -225.854514) (xy 95.646748 -225.854514)
			(xy 95.646236 -225.87996) (xy 95.638072 -225.930194) (xy 95.621956 -225.978468) (xy 95.598305 -226.023531)
			(xy 95.567732 -226.064217) (xy 95.531028 -226.099472) (xy 95.489144 -226.128382) (xy 95.443165 -226.150199)
			(xy 95.394281 -226.164359) (xy 95.34376 -226.170493) (xy 95.292908 -226.168444) (xy 95.243044 -226.158264)
			(xy 95.195458 -226.140217) (xy 95.151384 -226.114771) (xy 95.111962 -226.082584) (xy 95.078214 -226.04449)
			(xy 95.051013 -226.001476) (xy 95.031065 -225.954656) (xy 95.018886 -225.905242) (xy 95.014791 -225.854514)
			(xy 94.706694 -225.854514) (xy 94.706182 -225.87996) (xy 94.698018 -225.930194) (xy 94.681902 -225.978468)
			(xy 94.658251 -226.023531) (xy 94.627678 -226.064217) (xy 94.590974 -226.099472) (xy 94.54909 -226.128382)
			(xy 94.503111 -226.150199) (xy 94.454227 -226.164359) (xy 94.403706 -226.170493) (xy 94.352854 -226.168444)
			(xy 94.30299 -226.158264) (xy 94.255404 -226.140217) (xy 94.21133 -226.114771) (xy 94.171908 -226.082584)
			(xy 94.13816 -226.04449) (xy 94.110959 -226.001476) (xy 94.091011 -225.954656) (xy 94.078832 -225.905242)
			(xy 94.074737 -225.854514) (xy 93.756226 -225.854514) (xy 93.755731 -225.879121) (xy 93.747836 -225.927698)
			(xy 93.732252 -225.974379) (xy 93.709381 -226.017956) (xy 93.679816 -226.0573) (xy 93.644323 -226.091392)
			(xy 93.60382 -226.119348) (xy 93.559358 -226.140446) (xy 93.512087 -226.154138) (xy 93.463232 -226.16007)
			(xy 93.414057 -226.158089) (xy 93.365838 -226.148245) (xy 93.319822 -226.130793) (xy 93.277201 -226.106186)
			(xy 93.23908 -226.075061) (xy 93.206445 -226.038224) (xy 93.180142 -225.996628) (xy 93.160851 -225.951352)
			(xy 93.149074 -225.903568) (xy 93.145114 -225.854514) (xy 92.82684 -225.854514) (xy 92.826323 -225.880333)
			(xy 92.81791 -225.931282) (xy 92.801311 -225.98018) (xy 92.776969 -226.025722) (xy 92.745534 -226.066691)
			(xy 92.707846 -226.101992) (xy 92.664912 -226.130684) (xy 92.617878 -226.152) (xy 92.568 -226.16537)
			(xy 92.54236 -226.168458) (xy 92.533216 -226.169474) (xy 92.517722 -226.17684) (xy 92.511372 -226.18319)
			(xy 92.50454 -226.190556) (xy 92.496812 -226.209084) (xy 92.496821 -226.229159) (xy 92.504565 -226.24768)
			(xy 92.511372 -226.255072) (xy 92.568014 -226.311714) (xy 92.568522 -226.312222) (xy 92.5759 -226.318812)
			(xy 92.594199 -226.326279) (xy 92.604082 -226.3267) (xy 93.676978 -226.3267) (xy 93.687042 -226.327138)
			(xy 93.705626 -226.334872) (xy 93.713046 -226.341686) (xy 93.747844 -226.376484) (xy 93.778832 -226.382326)
			(xy 93.79331 -226.375976) (xy 93.81352 -226.367456) (xy 93.855704 -226.355453) (xy 93.899143 -226.349405)
			(xy 93.921072 -226.349052) (xy 93.945864 -226.349511) (xy 93.994839 -226.357264) (xy 94.041998 -226.372584)
			(xy 94.08618 -226.395093) (xy 94.126295 -226.424237) (xy 94.161358 -226.459299) (xy 94.190503 -226.499414)
			(xy 94.213013 -226.543594) (xy 94.228334 -226.590753) (xy 94.236088 -226.639728) (xy 94.23654 -226.66452)
			(xy 94.555322 -226.66452) (xy 94.559282 -226.615466) (xy 94.571059 -226.567682) (xy 94.59035 -226.522406)
			(xy 94.616653 -226.48081) (xy 94.649288 -226.443973) (xy 94.687409 -226.412848) (xy 94.73003 -226.388241)
			(xy 94.776046 -226.370789) (xy 94.824265 -226.360945) (xy 94.87344 -226.358964) (xy 94.922295 -226.364896)
			(xy 94.969566 -226.378588) (xy 95.014028 -226.399686) (xy 95.054531 -226.427642) (xy 95.090024 -226.461734)
			(xy 95.119589 -226.501078) (xy 95.14246 -226.544655) (xy 95.158044 -226.591336) (xy 95.165939 -226.639913)
			(xy 95.166434 -226.66452) (xy 95.484691 -226.66452) (xy 95.488786 -226.613792) (xy 95.500965 -226.564378)
			(xy 95.520913 -226.517558) (xy 95.548114 -226.474544) (xy 95.581862 -226.43645) (xy 95.621284 -226.404263)
			(xy 95.665358 -226.378817) (xy 95.712944 -226.36077) (xy 95.762808 -226.35059) (xy 95.81366 -226.348541)
			(xy 95.864181 -226.354675) (xy 95.913065 -226.368835) (xy 95.959044 -226.390652) (xy 96.000928 -226.419562)
			(xy 96.037632 -226.454817) (xy 96.068205 -226.495503) (xy 96.091856 -226.540566) (xy 96.107972 -226.58884)
			(xy 96.116136 -226.639074) (xy 96.116648 -226.66452) (xy 96.435176 -226.66452) (xy 96.439136 -226.615466)
			(xy 96.450913 -226.567682) (xy 96.470204 -226.522406) (xy 96.496507 -226.48081) (xy 96.529142 -226.443973)
			(xy 96.567263 -226.412848) (xy 96.609884 -226.388241) (xy 96.6559 -226.370789) (xy 96.704119 -226.360945)
			(xy 96.753294 -226.358964) (xy 96.802149 -226.364896) (xy 96.84942 -226.378588) (xy 96.893882 -226.399686)
			(xy 96.934385 -226.427642) (xy 96.969878 -226.461734) (xy 96.999443 -226.501078) (xy 97.022314 -226.544655)
			(xy 97.037898 -226.591336) (xy 97.045793 -226.639913) (xy 97.046288 -226.66452) (xy 97.045793 -226.689127)
			(xy 97.037898 -226.737704) (xy 97.022314 -226.784385) (xy 96.999443 -226.827962) (xy 96.969878 -226.867306)
			(xy 96.934385 -226.901398) (xy 96.893882 -226.929354) (xy 96.84942 -226.950452) (xy 96.802149 -226.964144)
			(xy 96.753294 -226.970076) (xy 96.704119 -226.968095) (xy 96.6559 -226.958251) (xy 96.609884 -226.940799)
			(xy 96.567263 -226.916192) (xy 96.529142 -226.885067) (xy 96.496507 -226.84823) (xy 96.470204 -226.806634)
			(xy 96.450913 -226.761358) (xy 96.439136 -226.713574) (xy 96.435176 -226.66452) (xy 96.116648 -226.66452)
			(xy 96.116136 -226.689966) (xy 96.107972 -226.7402) (xy 96.091856 -226.788474) (xy 96.068205 -226.833537)
			(xy 96.037632 -226.874223) (xy 96.000928 -226.909478) (xy 95.959044 -226.938388) (xy 95.913065 -226.960205)
			(xy 95.864181 -226.974365) (xy 95.81366 -226.980499) (xy 95.762808 -226.97845) (xy 95.712944 -226.96827)
			(xy 95.665358 -226.950223) (xy 95.621284 -226.924777) (xy 95.581862 -226.89259) (xy 95.548114 -226.854496)
			(xy 95.520913 -226.811482) (xy 95.500965 -226.764662) (xy 95.488786 -226.715248) (xy 95.484691 -226.66452)
			(xy 95.166434 -226.66452) (xy 95.165939 -226.689127) (xy 95.158044 -226.737704) (xy 95.14246 -226.784385)
			(xy 95.119589 -226.827962) (xy 95.090024 -226.867306) (xy 95.054531 -226.901398) (xy 95.014028 -226.929354)
			(xy 94.969566 -226.950452) (xy 94.922295 -226.964144) (xy 94.87344 -226.970076) (xy 94.824265 -226.968095)
			(xy 94.776046 -226.958251) (xy 94.73003 -226.940799) (xy 94.687409 -226.916192) (xy 94.649288 -226.885067)
			(xy 94.616653 -226.84823) (xy 94.59035 -226.806634) (xy 94.571059 -226.761358) (xy 94.559282 -226.713574)
			(xy 94.555322 -226.66452) (xy 94.23654 -226.66452) (xy 94.236182 -226.68645) (xy 94.230143 -226.72989)
			(xy 94.218142 -226.772075) (xy 94.209616 -226.792282) (xy 94.203266 -226.80676) (xy 94.209108 -226.837748)
			(xy 94.853252 -227.481892) (xy 94.860087 -227.488284) (xy 94.877146 -227.495944) (xy 94.895821 -227.496923)
			(xy 94.904814 -227.494338) (xy 94.998286 -227.464112) (xy 95.016828 -227.442268) (xy 95.01886 -227.42779)
			(xy 95.023026 -227.40318) (xy 95.038095 -227.355597) (xy 95.060461 -227.310977) (xy 95.089567 -227.27043)
			(xy 95.124688 -227.234965) (xy 95.16495 -227.205466) (xy 95.20935 -227.182667) (xy 95.256784 -227.167136)
			(xy 95.30607 -227.159258) (xy 95.331026 -227.158804) (xy 95.355833 -227.159293) (xy 95.404837 -227.167058)
			(xy 95.452022 -227.182394) (xy 95.496228 -227.204922) (xy 95.536365 -227.234089) (xy 95.571445 -227.269175)
			(xy 95.600605 -227.309317) (xy 95.623126 -227.353526) (xy 95.638454 -227.400714) (xy 95.646211 -227.449718)
			(xy 95.646748 -227.474526) (xy 95.965276 -227.474526) (xy 95.969236 -227.425472) (xy 95.981013 -227.377688)
			(xy 96.000304 -227.332412) (xy 96.026607 -227.290816) (xy 96.059242 -227.253979) (xy 96.097363 -227.222854)
			(xy 96.139984 -227.198247) (xy 96.186 -227.180795) (xy 96.234219 -227.170951) (xy 96.283394 -227.16897)
			(xy 96.332249 -227.174902) (xy 96.37952 -227.188594) (xy 96.423982 -227.209692) (xy 96.464485 -227.237648)
			(xy 96.499978 -227.27174) (xy 96.529543 -227.311084) (xy 96.552414 -227.354661) (xy 96.567998 -227.401342)
			(xy 96.575893 -227.449919) (xy 96.576388 -227.474526) (xy 96.575893 -227.499133) (xy 96.567998 -227.54771)
			(xy 96.552414 -227.594391) (xy 96.529543 -227.637968) (xy 96.499978 -227.677312) (xy 96.464485 -227.711404)
			(xy 96.423982 -227.73936) (xy 96.37952 -227.760458) (xy 96.332249 -227.77415) (xy 96.283394 -227.780082)
			(xy 96.234219 -227.778101) (xy 96.186 -227.768257) (xy 96.139984 -227.750805) (xy 96.097363 -227.726198)
			(xy 96.059242 -227.695073) (xy 96.026607 -227.658236) (xy 96.000304 -227.61664) (xy 95.981013 -227.571364)
			(xy 95.969236 -227.52358) (xy 95.965276 -227.474526) (xy 95.646748 -227.474526) (xy 95.64628 -227.499485)
			(xy 95.638432 -227.548783) (xy 95.622921 -227.59623) (xy 95.600132 -227.640643) (xy 95.570635 -227.680914)
			(xy 95.535166 -227.716039) (xy 95.494608 -227.745141) (xy 95.449975 -227.767495) (xy 95.402378 -227.782542)
			(xy 95.377762 -227.786692) (xy 95.363284 -227.788724) (xy 95.34144 -227.807266) (xy 95.311214 -227.900738)
			(xy 95.308766 -227.909748) (xy 95.30978 -227.928375) (xy 95.317345 -227.945427) (xy 95.32366 -227.9523)
			(xy 95.445834 -228.074474) (xy 95.446342 -228.074982) (xy 95.453724 -228.081563) (xy 95.472023 -228.089013)
			(xy 95.481902 -228.08946)
		)
		(stroke
			(width 0)
			(type solid)
		)
		(fill yes)
		(layer "In6.Cu")
		(net "PVDDCR_CPU0_P1")
	)
	(gr_poly
		(pts
			(xy 122.259598 -105.25252) (xy 122.269477 -105.252064) (xy 122.287783 -105.244628) (xy 122.295158 -105.238042)
			(xy 122.295412 -105.237788) (xy 136.672574 -90.860626) (xy 136.673082 -90.860118) (xy 136.679657 -90.852734)
			(xy 136.687092 -90.834435) (xy 136.68756 -90.824558) (xy 136.68756 -79.754222) (xy 136.687999 -79.744159)
			(xy 136.69574 -79.725581) (xy 136.702546 -79.718154) (xy 139.852654 -76.568046) (xy 139.853162 -76.567538)
			(xy 139.859742 -76.560156) (xy 139.867188 -76.541857) (xy 139.86764 -76.531978) (xy 139.86764 -71.557134)
			(xy 139.867203 -71.54707) (xy 139.859465 -71.528489) (xy 139.852654 -71.521066) (xy 139.319762 -70.988174)
			(xy 139.31265 -70.980808) (xy 139.293854 -70.973188) (xy 137.607294 -70.973188) (xy 137.595356 -70.974712)
			(xy 137.578084 -70.978776) (xy 137.573004 -70.981316) (xy 137.521348 -71.006704) (xy 137.414809 -71.050291)
			(xy 137.305193 -71.085429) (xy 137.193168 -71.111904) (xy 137.136378 -71.12127) (xy 137.080159 -71.12947)
			(xy 136.966875 -71.138243) (xy 136.910064 -71.138796) (xy 136.858738 -71.13835) (xy 136.756334 -71.131204)
			(xy 136.654676 -71.116949) (xy 136.554256 -71.095655) (xy 136.455561 -71.067424) (xy 136.359071 -71.032394)
			(xy 136.265252 -70.990733) (xy 136.219692 -70.967092) (xy 136.214358 -70.964298) (xy 136.196324 -70.959726)
			(xy 136.183878 -70.958202) (xy 133.491224 -70.958202) (xy 133.479602 -70.958774) (xy 133.458706 -70.96896)
			(xy 133.451092 -70.97776) (xy 133.39445 -71.050404) (xy 133.389624 -71.073518) (xy 133.392672 -71.084948)
			(xy 133.401159 -71.119961) (xy 133.413124 -71.19101) (xy 133.419308 -71.262793) (xy 133.41985 -71.298816)
			(xy 133.41985 -71.306182) (xy 133.419237 -71.347191) (xy 133.411403 -71.428839) (xy 133.396084 -71.509418)
			(xy 133.373412 -71.588244) (xy 133.343578 -71.664649) (xy 133.306837 -71.737982) (xy 133.2635 -71.80762)
			(xy 133.213935 -71.872973) (xy 133.158564 -71.933486) (xy 133.097857 -71.988643) (xy 133.032329 -72.037976)
			(xy 132.962538 -72.081067) (xy 132.889076 -72.117549) (xy 132.812566 -72.147113) (xy 132.73366 -72.169507)
			(xy 132.653028 -72.184541) (xy 132.571353 -72.192088) (xy 132.530342 -72.192642) (xy 132.491649 -72.192228)
			(xy 132.414555 -72.185507) (xy 132.338338 -72.172104) (xy 132.263577 -72.15212) (xy 132.227066 -72.139302)
			(xy 132.218565 -72.136646) (xy 132.200769 -72.136646) (xy 132.192268 -72.139302) (xy 132.155751 -72.152098)
			(xy 132.080987 -72.17206) (xy 132.004773 -72.185461) (xy 131.927683 -72.192199) (xy 131.888992 -72.192642)
			(xy 131.850299 -72.192226) (xy 131.773206 -72.185501) (xy 131.696991 -72.172094) (xy 131.622231 -72.152106)
			(xy 131.585716 -72.139302) (xy 131.577215 -72.136646) (xy 131.559419 -72.136646) (xy 131.550918 -72.139302)
			(xy 131.514401 -72.1521) (xy 131.439638 -72.172066) (xy 131.363423 -72.185471) (xy 131.286334 -72.192214)
			(xy 131.247642 -72.192642) (xy 131.206627 -72.192173) (xy 131.124946 -72.184625) (xy 131.044307 -72.169588)
			(xy 130.965394 -72.147191) (xy 130.888879 -72.117624) (xy 130.815411 -72.081138) (xy 130.745614 -72.038042)
			(xy 130.680081 -71.988704) (xy 130.619369 -71.933541) (xy 130.563994 -71.873024) (xy 130.514425 -71.807665)
			(xy 130.471085 -71.738019) (xy 130.434341 -71.66468) (xy 130.404505 -71.588269) (xy 130.381831 -71.509436)
			(xy 130.366511 -71.428849) (xy 130.358676 -71.347195) (xy 130.358134 -71.306182) (xy 130.358134 -71.30288)
			(xy 130.35852 -71.266178) (xy 130.36459 -71.193024) (xy 130.37667 -71.12062) (xy 130.385312 -71.084948)
			(xy 130.38836 -71.073518) (xy 130.383534 -71.050404) (xy 130.326892 -70.97776) (xy 130.319304 -70.968924)
			(xy 130.298395 -70.95872) (xy 130.28676 -70.958202) (xy 129.632964 -70.958202) (xy 129.624071 -70.958533)
			(xy 129.607359 -70.964615) (xy 129.593748 -70.976062) (xy 129.589022 -70.983602) (xy 129.54508 -71.059802)
			(xy 129.541913 -71.065797) (xy 129.538569 -71.07893) (xy 129.538476 -71.08571) (xy 129.538476 -71.099172)
			(xy 129.545334 -71.11111) (xy 129.557644 -71.133059) (xy 129.577026 -71.1795) (xy 129.590141 -71.228085)
			(xy 129.596759 -71.277972) (xy 129.59715 -71.303134) (xy 129.59715 -71.311008) (xy 129.596063 -71.339173)
			(xy 129.586623 -71.394741) (xy 129.569113 -71.448315) (xy 129.543912 -71.498731) (xy 129.511569 -71.544891)
			(xy 129.472787 -71.585791) (xy 129.428412 -71.620542) (xy 129.379407 -71.648388) (xy 129.326839 -71.668721)
			(xy 129.271852 -71.681101) (xy 129.215642 -71.685258) (xy 129.159432 -71.681101) (xy 129.104445 -71.668721)
			(xy 129.051877 -71.648388) (xy 129.002872 -71.620542) (xy 128.958497 -71.585791) (xy 128.919715 -71.544891)
			(xy 128.887372 -71.498731) (xy 128.862171 -71.448315) (xy 128.844661 -71.394741) (xy 128.835221 -71.339173)
			(xy 128.834134 -71.311008) (xy 128.834134 -71.303134) (xy 128.834534 -71.277972) (xy 128.841143 -71.228084)
			(xy 128.854252 -71.179497) (xy 128.873631 -71.133054) (xy 128.88595 -71.11111) (xy 128.886204 -71.110856)
			(xy 128.8893 -71.105039) (xy 128.892644 -71.092298) (xy 128.892808 -71.08571) (xy 128.893062 -71.07174)
			(xy 128.842262 -70.983602) (xy 128.837484 -70.976107) (xy 128.82388 -70.96469) (xy 128.807199 -70.958595)
			(xy 128.79832 -70.958202) (xy 115.129056 -70.958202) (xy 115.124709 -70.958308) (xy 115.116149 -70.959833)
			(xy 115.112038 -70.96125) (xy 112.32899 -71.962772) (xy 113.62639 -71.962772) (xy 113.630461 -71.90715)
			(xy 113.642587 -71.852713) (xy 113.66251 -71.800622) (xy 113.689806 -71.751987) (xy 113.723892 -71.707844)
			(xy 113.764041 -71.669135) (xy 113.809399 -71.636684) (xy 113.858999 -71.611183) (xy 113.911783 -71.593176)
			(xy 113.966626 -71.583046) (xy 114.02236 -71.581009) (xy 114.077797 -71.587109) (xy 114.131754 -71.601215)
			(xy 114.183083 -71.623027) (xy 114.230689 -71.652081) (xy 114.273557 -71.687756) (xy 114.310774 -71.729293)
			(xy 114.341547 -71.775806) (xy 114.365219 -71.826303) (xy 114.37742 -71.866856) (xy 117.906437 -71.866856)
			(xy 117.906437 -71.812344) (xy 117.914196 -71.758386) (xy 117.929555 -71.706082) (xy 117.952202 -71.656497)
			(xy 117.981675 -71.610639) (xy 118.017376 -71.569443) (xy 118.058576 -71.533748) (xy 118.104437 -71.50428)
			(xy 118.154025 -71.481639) (xy 118.206331 -71.466286) (xy 118.26029 -71.458534) (xy 118.287546 -71.458074)
			(xy 118.314692 -71.458614) (xy 118.368436 -71.466304) (xy 118.420547 -71.481537) (xy 118.469971 -71.504004)
			(xy 118.515711 -71.533251) (xy 118.556842 -71.568689) (xy 118.592533 -71.6096) (xy 118.622063 -71.655158)
			(xy 118.644835 -71.704443) (xy 118.660389 -71.756458) (xy 118.668411 -71.810154) (xy 118.669054 -71.837296)
			(xy 118.669054 -71.852536) (xy 118.685564 -71.877428) (xy 118.798848 -71.926704) (xy 118.828058 -71.921878)
			(xy 118.839488 -71.911464) (xy 118.870218 -71.883781) (xy 118.936023 -71.833664) (xy 119.006197 -71.789874)
			(xy 119.080134 -71.75279) (xy 119.157195 -71.72273) (xy 119.236714 -71.699956) (xy 119.318005 -71.684663)
			(xy 119.400364 -71.676985) (xy 119.441722 -71.676514) (xy 119.482825 -71.676946) (xy 119.564682 -71.684533)
			(xy 119.645489 -71.69964) (xy 119.724557 -71.722139) (xy 119.801212 -71.751838) (xy 119.8748 -71.788482)
			(xy 119.944692 -71.831761) (xy 120.010294 -71.881303) (xy 120.071044 -71.936687) (xy 120.126425 -71.99744)
			(xy 120.175964 -72.063044) (xy 120.219239 -72.132939) (xy 120.25588 -72.206528) (xy 120.285575 -72.283185)
			(xy 120.30807 -72.362254) (xy 120.323173 -72.443062) (xy 120.330756 -72.524918) (xy 120.33123 -72.566022)
			(xy 120.330715 -72.608489) (xy 120.322618 -72.693035) (xy 120.3065 -72.776425) (xy 120.282508 -72.857899)
			(xy 120.25086 -72.936715) (xy 120.211843 -73.012157) (xy 120.189244 -73.048114) (xy 120.180354 -73.062084)
			(xy 120.181878 -73.094088) (xy 120.261634 -73.195434) (xy 120.292622 -73.204578) (xy 120.308116 -73.199244)
			(xy 120.3435 -73.187295) (xy 120.415827 -73.168653) (xy 120.489462 -73.156143) (xy 120.563887 -73.149855)
			(xy 120.601232 -73.14946) (xy 120.643156 -73.150009) (xy 120.726631 -73.157903) (xy 120.808993 -73.173617)
			(xy 120.88951 -73.197013) (xy 120.967469 -73.227882) (xy 121.042176 -73.265951) (xy 121.11297 -73.310881)
			(xy 121.17922 -73.362274) (xy 121.240341 -73.419674) (xy 121.295788 -73.482571) (xy 121.34507 -73.550407)
			(xy 121.387749 -73.62258) (xy 121.423447 -73.698449) (xy 121.451847 -73.77734) (xy 121.472696 -73.858555)
			(xy 121.4824 -73.919842) (xy 121.620534 -73.919842) (xy 121.621103 -73.891532) (xy 121.629472 -73.835535)
			(xy 121.64602 -73.781388) (xy 121.670382 -73.730278) (xy 121.702025 -73.683326) (xy 121.740255 -73.641562)
			(xy 121.784233 -73.605901) (xy 121.832995 -73.577126) (xy 121.85904 -73.56602) (xy 121.866803 -73.562622)
			(xy 121.87965 -73.551588) (xy 121.884186 -73.54443) (xy 121.908381 -73.503671) (xy 121.964154 -73.427026)
			(xy 122.027767 -73.356752) (xy 122.098496 -73.293645) (xy 122.136662 -73.265538) (xy 122.14479 -73.259442)
			(xy 122.155458 -73.242678) (xy 122.170952 -73.152508) (xy 122.166634 -73.133204) (xy 122.160792 -73.124822)
			(xy 122.135538 -73.087494) (xy 122.091829 -73.008674) (xy 122.056311 -72.925839) (xy 122.029348 -72.839839)
			(xy 122.011217 -72.751553) (xy 122.002104 -72.661886) (xy 122.001534 -72.616822) (xy 122.002038 -72.574474)
			(xy 122.010089 -72.49016) (xy 122.026118 -72.406994) (xy 122.049979 -72.325727) (xy 122.081458 -72.247097)
			(xy 122.120269 -72.171816) (xy 122.166059 -72.100564) (xy 122.218415 -72.033988) (xy 122.276863 -71.97269)
			(xy 122.340873 -71.917225) (xy 122.409865 -71.868096) (xy 122.483215 -71.825747) (xy 122.560258 -71.790563)
			(xy 122.640297 -71.762861) (xy 122.722606 -71.742893) (xy 122.806441 -71.73084) (xy 122.891042 -71.72681)
			(xy 122.975643 -71.73084) (xy 123.059478 -71.742893) (xy 123.141787 -71.762861) (xy 123.221826 -71.790563)
			(xy 123.298869 -71.825747) (xy 123.372219 -71.868096) (xy 123.441211 -71.917225) (xy 123.505221 -71.97269)
			(xy 123.563669 -72.033988) (xy 123.616025 -72.100564) (xy 123.661815 -72.171816) (xy 123.700626 -72.247097)
			(xy 123.732105 -72.325727) (xy 123.755966 -72.406994) (xy 123.771995 -72.49016) (xy 123.780046 -72.574474)
			(xy 123.78055 -72.616822) (xy 123.780134 -72.655042) (xy 123.773572 -72.7312) (xy 123.76049 -72.806513)
			(xy 123.740985 -72.880423) (xy 123.72848 -72.916542) (xy 123.725634 -72.925866) (xy 123.726409 -72.945327)
			(xy 123.730004 -72.954388) (xy 123.74245 -72.982328) (xy 123.746833 -72.99099) (xy 123.760804 -73.004445)
			(xy 123.769628 -73.00849) (xy 123.810113 -73.02549) (xy 123.887784 -73.066457) (xy 123.961042 -73.114877)
			(xy 124.029174 -73.170278) (xy 124.091517 -73.232121) (xy 124.147464 -73.299805) (xy 124.196471 -73.372672)
			(xy 124.233835 -73.442152) (xy 128.574268 -73.442152) (xy 128.574268 -73.387648) (xy 128.582024 -73.3337)
			(xy 128.597379 -73.281404) (xy 128.620021 -73.231826) (xy 128.649487 -73.185975) (xy 128.685178 -73.144784)
			(xy 128.726369 -73.109092) (xy 128.772219 -73.079624) (xy 128.821797 -73.056982) (xy 128.874092 -73.041626)
			(xy 128.92804 -73.033868) (xy 128.955292 -73.033382) (xy 128.983 -73.033909) (xy 129.037833 -73.04193)
			(xy 129.090927 -73.057804) (xy 129.141164 -73.081198) (xy 129.187485 -73.111617) (xy 129.20853 -73.129648)
			(xy 129.215642 -73.135744) (xy 129.232914 -73.142348) (xy 129.31902 -73.142348) (xy 129.336292 -73.135744)
			(xy 129.343404 -73.129648) (xy 129.36443 -73.111593) (xy 129.410753 -73.081167) (xy 129.460994 -73.05777)
			(xy 129.514093 -73.041895) (xy 129.568931 -73.033876) (xy 129.596642 -73.033382) (xy 129.626466 -73.033932)
			(xy 129.685392 -73.043188) (xy 129.742161 -73.061498) (xy 129.795389 -73.088418) (xy 129.843781 -73.123292)
			(xy 129.865374 -73.143872) (xy 129.874518 -73.153016) (xy 129.89941 -73.160382) (xy 130.008122 -73.136252)
			(xy 130.02768 -73.119234) (xy 130.031998 -73.107042) (xy 130.046864 -73.068121) (xy 130.082891 -72.992991)
			(xy 130.125785 -72.921558) (xy 130.17517 -72.85445) (xy 130.230614 -72.792253) (xy 130.291631 -72.735513)
			(xy 130.357686 -72.684727) (xy 130.428201 -72.64034) (xy 130.502557 -72.602741) (xy 130.580103 -72.57226)
			(xy 130.660159 -72.549163) (xy 130.742024 -72.533653) (xy 130.824981 -72.525866) (xy 130.866642 -72.525382)
			(xy 130.905334 -72.525815) (xy 130.982423 -72.532557) (xy 131.058637 -72.545961) (xy 131.133401 -72.565925)
			(xy 131.169918 -72.578722) (xy 131.178419 -72.581378) (xy 131.196215 -72.581378) (xy 131.204716 -72.578722)
			(xy 131.24123 -72.565915) (xy 131.315991 -72.545929) (xy 131.392206 -72.532522) (xy 131.469299 -72.525798)
			(xy 131.507992 -72.525382) (xy 131.546683 -72.525829) (xy 131.623772 -72.532567) (xy 131.699986 -72.545967)
			(xy 131.774751 -72.565928) (xy 131.811268 -72.578722) (xy 131.819769 -72.581378) (xy 131.837565 -72.581378)
			(xy 131.846066 -72.578722) (xy 131.882576 -72.565901) (xy 131.957338 -72.545918) (xy 132.033555 -72.532516)
			(xy 132.110649 -72.525796) (xy 132.149342 -72.525382) (xy 132.188034 -72.525815) (xy 132.265123 -72.532557)
			(xy 132.341337 -72.545961) (xy 132.416101 -72.565925) (xy 132.452618 -72.578722) (xy 132.461119 -72.581378)
			(xy 132.478915 -72.581378) (xy 132.487416 -72.578722) (xy 132.52393 -72.565915) (xy 132.598691 -72.545929)
			(xy 132.674906 -72.532522) (xy 132.751999 -72.525798) (xy 132.790692 -72.525382) (xy 132.833041 -72.52589)
			(xy 132.917356 -72.53394) (xy 133.000523 -72.549969) (xy 133.08179 -72.57383) (xy 133.160422 -72.605309)
			(xy 133.235704 -72.644119) (xy 133.306957 -72.68991) (xy 133.373535 -72.742266) (xy 133.434834 -72.800714)
			(xy 133.490299 -72.864725) (xy 133.539429 -72.933717) (xy 133.581778 -73.007068) (xy 133.616963 -73.084112)
			(xy 133.644666 -73.164152) (xy 133.664634 -73.246462) (xy 133.676688 -73.330298) (xy 133.680718 -73.4149)
			(xy 133.676688 -73.499502) (xy 133.664634 -73.583338) (xy 133.644666 -73.665648) (xy 133.616963 -73.745688)
			(xy 133.581778 -73.822732) (xy 133.539429 -73.896083) (xy 133.490299 -73.965075) (xy 133.434834 -74.029086)
			(xy 133.373535 -74.087534) (xy 133.306957 -74.13989) (xy 133.235704 -74.185681) (xy 133.160422 -74.224491)
			(xy 133.08179 -74.25597) (xy 133.000523 -74.279831) (xy 132.917356 -74.29586) (xy 132.833041 -74.30391)
			(xy 132.790692 -74.304398) (xy 132.752001 -74.303956) (xy 132.674911 -74.297217) (xy 132.598697 -74.283816)
			(xy 132.523933 -74.263853) (xy 132.487416 -74.251058) (xy 132.478931 -74.248301) (xy 132.461103 -74.248301)
			(xy 132.452618 -74.251058) (xy 132.41611 -74.263883) (xy 132.341347 -74.283865) (xy 132.26513 -74.297266)
			(xy 132.188035 -74.303985) (xy 132.149342 -74.304398) (xy 132.11065 -74.303971) (xy 132.033561 -74.297228)
			(xy 131.957347 -74.283822) (xy 131.882583 -74.263855) (xy 131.846066 -74.251058) (xy 131.837581 -74.248301)
			(xy 131.819753 -74.248301) (xy 131.811268 -74.251058) (xy 131.774755 -74.263869) (xy 131.699994 -74.283854)
			(xy 131.623778 -74.297259) (xy 131.546685 -74.303983) (xy 131.507992 -74.304398) (xy 131.469301 -74.303956)
			(xy 131.392211 -74.297217) (xy 131.315997 -74.283816) (xy 131.241233 -74.263853) (xy 131.204716 -74.251058)
			(xy 131.196231 -74.248301) (xy 131.178403 -74.248301) (xy 131.169918 -74.251058) (xy 131.13341 -74.263883)
			(xy 131.058647 -74.283865) (xy 130.98243 -74.297266) (xy 130.905335 -74.303985) (xy 130.866642 -74.304398)
			(xy 130.824984 -74.303897) (xy 130.742033 -74.296095) (xy 130.660175 -74.280573) (xy 130.580126 -74.257468)
			(xy 130.502587 -74.226981) (xy 130.428238 -74.18938) (xy 130.357728 -74.144994) (xy 130.291676 -74.094212)
			(xy 130.23066 -74.037479) (xy 130.175214 -73.97529) (xy 130.125824 -73.908191) (xy 130.082921 -73.836769)
			(xy 130.046883 -73.761649) (xy 130.031998 -73.722738) (xy 130.02768 -73.710546) (xy 130.008122 -73.693528)
			(xy 129.89941 -73.669398) (xy 129.874518 -73.676764) (xy 129.865374 -73.685908) (xy 129.84378 -73.706487)
			(xy 129.795392 -73.741367) (xy 129.742164 -73.768289) (xy 129.685394 -73.786596) (xy 129.626467 -73.795842)
			(xy 129.596642 -73.796398) (xy 129.568932 -73.795915) (xy 129.514097 -73.787884) (xy 129.461002 -73.772)
			(xy 129.410766 -73.748596) (xy 129.364447 -73.718167) (xy 129.343404 -73.700132) (xy 129.336292 -73.694036)
			(xy 129.31902 -73.687432) (xy 129.232914 -73.687432) (xy 129.215642 -73.694036) (xy 129.20853 -73.700132)
			(xy 129.187488 -73.718168) (xy 129.141169 -73.748597) (xy 129.090933 -73.771998) (xy 129.037837 -73.787878)
			(xy 128.983002 -73.795901) (xy 128.955292 -73.796398) (xy 128.92804 -73.795932) (xy 128.874092 -73.788174)
			(xy 128.821797 -73.772818) (xy 128.772219 -73.750176) (xy 128.726369 -73.720708) (xy 128.685178 -73.685016)
			(xy 128.649487 -73.643825) (xy 128.620021 -73.597974) (xy 128.597379 -73.548396) (xy 128.582024 -73.4961)
			(xy 128.574268 -73.442152) (xy 124.233835 -73.442152) (xy 124.238061 -73.450011) (xy 124.27183 -73.531072)
			(xy 124.29745 -73.615065) (xy 124.31467 -73.701173) (xy 124.323325 -73.788559) (xy 124.323856 -73.832466)
			(xy 124.323301 -73.873567) (xy 124.31572 -73.955417) (xy 124.300618 -74.036219) (xy 124.278126 -74.115283)
			(xy 124.248435 -74.191935) (xy 124.211798 -74.265519) (xy 124.168528 -74.33541) (xy 124.118994 -74.40101)
			(xy 124.063618 -74.46176) (xy 124.002873 -74.517141) (xy 123.937278 -74.566682) (xy 123.867391 -74.609958)
			(xy 123.79381 -74.646602) (xy 123.717161 -74.6763) (xy 123.638099 -74.6988) (xy 123.557298 -74.713908)
			(xy 123.475448 -74.721497) (xy 123.434348 -74.721974) (xy 123.39891 -74.721613) (xy 123.328262 -74.715934)
			(xy 123.25829 -74.704649) (xy 123.223782 -74.696574) (xy 123.212796 -74.69454) (xy 123.190931 -74.699034)
			(xy 123.181618 -74.70521) (xy 123.148887 -74.728685) (xy 123.079927 -74.770318) (xy 123.007486 -74.805545)
			(xy 122.932157 -74.834081) (xy 122.854557 -74.85569) (xy 122.775321 -74.870195) (xy 122.740485 -74.873358)
			(xy 136.414 -74.873358) (xy 136.418071 -74.817736) (xy 136.430197 -74.763299) (xy 136.45012 -74.711208)
			(xy 136.477416 -74.662573) (xy 136.511502 -74.61843) (xy 136.551651 -74.579721) (xy 136.597009 -74.54727)
			(xy 136.646609 -74.521769) (xy 136.699393 -74.503762) (xy 136.754236 -74.493632) (xy 136.80997 -74.491595)
			(xy 136.865407 -74.497695) (xy 136.919364 -74.511801) (xy 136.970693 -74.533613) (xy 137.018299 -74.562667)
			(xy 137.061167 -74.598342) (xy 137.098384 -74.639879) (xy 137.129157 -74.686392) (xy 137.152829 -74.736889)
			(xy 137.168897 -74.790296) (xy 137.177017 -74.845472) (xy 137.177526 -74.873358) (xy 137.177017 -74.901244)
			(xy 137.168897 -74.95642) (xy 137.152829 -75.009827) (xy 137.129157 -75.060324) (xy 137.098384 -75.106837)
			(xy 137.061167 -75.148374) (xy 137.018299 -75.184049) (xy 136.970693 -75.213103) (xy 136.919364 -75.234915)
			(xy 136.865407 -75.249021) (xy 136.80997 -75.255121) (xy 136.754236 -75.253084) (xy 136.699393 -75.242954)
			(xy 136.646609 -75.224947) (xy 136.597009 -75.199446) (xy 136.551651 -75.166995) (xy 136.511502 -75.128286)
			(xy 136.477416 -75.084143) (xy 136.45012 -75.035508) (xy 136.430197 -74.983417) (xy 136.418071 -74.92898)
			(xy 136.414 -74.873358) (xy 122.740485 -74.873358) (xy 122.695098 -74.877479) (xy 122.654822 -74.87793)
			(xy 122.611789 -74.877384) (xy 122.526126 -74.869058) (xy 122.441667 -74.8525) (xy 122.359201 -74.827865)
			(xy 122.279498 -74.795384) (xy 122.203304 -74.75536) (xy 122.13133 -74.708167) (xy 122.064248 -74.654245)
			(xy 122.002685 -74.594099) (xy 121.947217 -74.528291) (xy 121.898361 -74.457435) (xy 121.856574 -74.382193)
			(xy 121.822247 -74.303268) (xy 121.808494 -74.262488) (xy 121.80556 -74.254582) (xy 121.795453 -74.241098)
			(xy 121.788682 -74.236072) (xy 121.76683 -74.220822) (xy 121.727229 -74.185168) (xy 121.692976 -74.144349)
			(xy 121.664738 -74.099159) (xy 121.643067 -74.050478) (xy 121.628383 -73.999255) (xy 121.620974 -73.946485)
			(xy 121.620534 -73.919842) (xy 121.4824 -73.919842) (xy 121.485809 -73.94137) (xy 121.491071 -74.025053)
			(xy 121.488434 -74.108859) (xy 121.477923 -74.192045) (xy 121.459629 -74.273873) (xy 121.433716 -74.353616)
			(xy 121.400413 -74.430566) (xy 121.360016 -74.504041) (xy 121.312885 -74.573388) (xy 121.259436 -74.637992)
			(xy 121.200144 -74.697279) (xy 121.135537 -74.750723) (xy 121.066186 -74.79785) (xy 120.992709 -74.838241)
			(xy 120.915756 -74.871538) (xy 120.836011 -74.897446) (xy 120.754182 -74.915734) (xy 120.670995 -74.926239)
			(xy 120.587189 -74.92887) (xy 120.503507 -74.923602) (xy 120.420692 -74.910483) (xy 120.339479 -74.889628)
			(xy 120.26059 -74.861223) (xy 120.184723 -74.825519) (xy 120.112554 -74.782835) (xy 120.044721 -74.733548)
			(xy 119.981828 -74.678096) (xy 119.924433 -74.616972) (xy 119.873044 -74.550717) (xy 119.828119 -74.479921)
			(xy 119.790056 -74.405211) (xy 119.759192 -74.32725) (xy 119.735802 -74.246731) (xy 119.720094 -74.164368)
			(xy 119.712206 -74.080892) (xy 119.711724 -74.038968) (xy 119.712241 -73.996502) (xy 119.720339 -73.911955)
			(xy 119.736457 -73.828566) (xy 119.760449 -73.747092) (xy 119.792096 -73.668275) (xy 119.831111 -73.592834)
			(xy 119.85371 -73.556876) (xy 119.8626 -73.542906) (xy 119.861076 -73.510902) (xy 119.78132 -73.409556)
			(xy 119.750332 -73.400412) (xy 119.734838 -73.405746) (xy 119.699458 -73.417707) (xy 119.62713 -73.436347)
			(xy 119.553493 -73.448853) (xy 119.479067 -73.455137) (xy 119.441722 -73.45553) (xy 119.400621 -73.455012)
			(xy 119.318768 -73.44743) (xy 119.237964 -73.432327) (xy 119.158899 -73.409833) (xy 119.082246 -73.38014)
			(xy 119.00866 -73.343501) (xy 118.938769 -73.300228) (xy 118.873168 -73.250691) (xy 118.812418 -73.195313)
			(xy 118.757037 -73.134566) (xy 118.707497 -73.068968) (xy 118.664221 -72.999078) (xy 118.627578 -72.925494)
			(xy 118.597881 -72.848843) (xy 118.575383 -72.769778) (xy 118.560276 -72.688976) (xy 118.55269 -72.607123)
			(xy 118.552214 -72.566022) (xy 118.552763 -72.522063) (xy 118.56145 -72.434576) (xy 118.578732 -72.348374)
			(xy 118.591076 -72.30618) (xy 118.595394 -72.291448) (xy 118.587266 -72.262746) (xy 118.493794 -72.181974)
			(xy 118.46433 -72.17791) (xy 118.450614 -72.184514) (xy 118.424992 -72.196048) (xy 118.37122 -72.212347)
			(xy 118.31564 -72.220589) (xy 118.287546 -72.22109) (xy 118.26029 -72.220666) (xy 118.206331 -72.212914)
			(xy 118.154025 -72.197561) (xy 118.104437 -72.17492) (xy 118.058576 -72.145452) (xy 118.017376 -72.109757)
			(xy 117.981675 -72.068561) (xy 117.952202 -72.022703) (xy 117.929555 -71.973118) (xy 117.914196 -71.920814)
			(xy 117.906437 -71.866856) (xy 114.37742 -71.866856) (xy 114.381287 -71.87971) (xy 114.389407 -71.934886)
			(xy 114.389916 -71.962772) (xy 114.389407 -71.990658) (xy 114.381287 -72.045834) (xy 114.365219 -72.099241)
			(xy 114.341547 -72.149738) (xy 114.310774 -72.196251) (xy 114.273557 -72.237788) (xy 114.230689 -72.273463)
			(xy 114.183083 -72.302517) (xy 114.131754 -72.324329) (xy 114.077797 -72.338435) (xy 114.02236 -72.344535)
			(xy 113.966626 -72.342498) (xy 113.911783 -72.332368) (xy 113.858999 -72.314361) (xy 113.809399 -72.28886)
			(xy 113.764041 -72.256409) (xy 113.723892 -72.2177) (xy 113.689806 -72.173557) (xy 113.66251 -72.124922)
			(xy 113.642587 -72.072831) (xy 113.630461 -72.018394) (xy 113.62639 -71.962772) (xy 112.32899 -71.962772)
			(xy 111.646462 -72.20839) (xy 111.64062 -72.212454) (xy 110.663736 -72.896476) (xy 110.658656 -72.900032)
			(xy 106.86923 -77.242924) (xy 106.861751 -77.252611) (xy 106.856028 -77.276368) (xy 106.858308 -77.28839)
			(xy 106.880914 -77.381354) (xy 106.896916 -77.399642) (xy 106.9086 -77.404468) (xy 106.946498 -77.419882)
			(xy 107.019562 -77.456711) (xy 107.088934 -77.500097) (xy 107.154026 -77.549673) (xy 107.214288 -77.605019)
			(xy 107.26921 -77.665667) (xy 107.318329 -77.731105) (xy 107.361228 -77.800778) (xy 107.397544 -77.874098)
			(xy 107.426971 -77.950445) (xy 107.449259 -78.029172) (xy 107.464221 -78.109613) (xy 107.471729 -78.191089)
			(xy 107.472226 -78.232) (xy 107.471751 -78.273103) (xy 107.464166 -78.354958) (xy 107.449061 -78.435764)
			(xy 107.426565 -78.514831) (xy 107.396869 -78.591486) (xy 107.360228 -78.665073) (xy 107.316952 -78.734966)
			(xy 107.267413 -78.800568) (xy 107.212032 -78.861319) (xy 107.151282 -78.916702) (xy 107.085681 -78.966242)
			(xy 107.015789 -79.009519) (xy 106.942202 -79.046162) (xy 106.865548 -79.075859) (xy 106.786481 -79.098357)
			(xy 106.705676 -79.113464) (xy 106.623821 -79.121051) (xy 106.582718 -79.121508) (xy 106.539867 -79.120997)
			(xy 106.454563 -79.112755) (xy 106.370447 -79.096346) (xy 106.288299 -79.071921) (xy 106.208882 -79.039709)
			(xy 106.132931 -79.000006) (xy 106.061152 -78.953182) (xy 105.99421 -78.899671) (xy 105.932725 -78.839968)
			(xy 105.877268 -78.774629) (xy 105.828353 -78.704257) (xy 105.807002 -78.667102) (xy 105.800652 -78.65618)
			(xy 105.780332 -78.642718) (xy 105.685336 -78.632812) (xy 105.673055 -78.632245) (xy 105.650236 -78.641284)
			(xy 105.641648 -78.650084) (xy 104.195864 -80.30718) (xy 111.205772 -80.30718) (xy 111.206385 -80.260785)
			(xy 111.216021 -80.168498) (xy 111.235209 -80.077714) (xy 111.263738 -79.98942) (xy 111.281972 -79.946754)
			(xy 111.285801 -79.936817) (xy 111.285793 -79.915547) (xy 111.281972 -79.905606) (xy 111.263719 -79.862947)
			(xy 111.235178 -79.774653) (xy 111.215987 -79.683867) (xy 111.206356 -79.591576) (xy 111.205772 -79.54518)
			(xy 111.206286 -79.501835) (xy 111.214733 -79.415557) (xy 111.231535 -79.33051) (xy 111.256533 -79.247502)
			(xy 111.289488 -79.167319) (xy 111.33009 -79.090725) (xy 111.377952 -79.018444) (xy 111.432619 -78.951163)
			(xy 111.493574 -78.889521) (xy 111.526574 -78.861412) (xy 111.53521 -78.854046) (xy 111.544862 -78.833726)
			(xy 111.544862 -78.732634) (xy 111.53521 -78.712314) (xy 111.526574 -78.704948) (xy 111.493575 -78.67684)
			(xy 111.432634 -78.615189) (xy 111.377977 -78.547903) (xy 111.330124 -78.47562) (xy 111.289527 -78.399025)
			(xy 111.256572 -78.318845) (xy 111.231572 -78.235841) (xy 111.214763 -78.150798) (xy 111.206305 -78.064524)
			(xy 111.205772 -78.02118) (xy 111.206286 -77.977835) (xy 111.214733 -77.891557) (xy 111.231535 -77.80651)
			(xy 111.256533 -77.723502) (xy 111.289488 -77.643319) (xy 111.33009 -77.566725) (xy 111.377952 -77.494444)
			(xy 111.432619 -77.427163) (xy 111.493574 -77.365521) (xy 111.526574 -77.337412) (xy 111.53521 -77.330046)
			(xy 111.544862 -77.309726) (xy 111.544862 -77.208634) (xy 111.53521 -77.188314) (xy 111.526574 -77.180948)
			(xy 111.493575 -77.15284) (xy 111.432634 -77.091189) (xy 111.377977 -77.023903) (xy 111.330124 -76.95162)
			(xy 111.289527 -76.875025) (xy 111.256572 -76.794845) (xy 111.231572 -76.711841) (xy 111.214763 -76.626798)
			(xy 111.206305 -76.540524) (xy 111.205772 -76.49718) (xy 111.206286 -76.453835) (xy 111.214733 -76.367557)
			(xy 111.231535 -76.28251) (xy 111.256533 -76.199502) (xy 111.289488 -76.119319) (xy 111.33009 -76.042725)
			(xy 111.377952 -75.970444) (xy 111.432619 -75.903163) (xy 111.493574 -75.841521) (xy 111.526574 -75.813412)
			(xy 111.53521 -75.806046) (xy 111.544862 -75.785726) (xy 111.544862 -75.684634) (xy 111.53521 -75.664314)
			(xy 111.526574 -75.656948) (xy 111.493575 -75.62884) (xy 111.432634 -75.567189) (xy 111.377977 -75.499903)
			(xy 111.330124 -75.42762) (xy 111.289527 -75.351025) (xy 111.256572 -75.270845) (xy 111.231572 -75.187841)
			(xy 111.214763 -75.102798) (xy 111.206305 -75.016524) (xy 111.205772 -74.97318) (xy 111.206276 -74.930832)
			(xy 111.214327 -74.846518) (xy 111.230356 -74.763352) (xy 111.254217 -74.682085) (xy 111.285696 -74.603455)
			(xy 111.324507 -74.528174) (xy 111.370297 -74.456922) (xy 111.422653 -74.390346) (xy 111.481101 -74.329048)
			(xy 111.545111 -74.273583) (xy 111.614103 -74.224454) (xy 111.687453 -74.182105) (xy 111.764496 -74.146921)
			(xy 111.844535 -74.119219) (xy 111.926844 -74.099251) (xy 112.010679 -74.087198) (xy 112.09528 -74.083168)
			(xy 112.179881 -74.087198) (xy 112.263716 -74.099251) (xy 112.346025 -74.119219) (xy 112.426064 -74.146921)
			(xy 112.503107 -74.182105) (xy 112.576457 -74.224454) (xy 112.645449 -74.273583) (xy 112.709459 -74.329048)
			(xy 112.767907 -74.390346) (xy 112.820263 -74.456922) (xy 112.866053 -74.528174) (xy 112.904864 -74.603455)
			(xy 112.936343 -74.682085) (xy 112.960204 -74.763352) (xy 112.976233 -74.846518) (xy 112.984284 -74.930832)
			(xy 112.984788 -74.97318) (xy 112.984259 -75.016525) (xy 112.975815 -75.102803) (xy 112.959016 -75.18785)
			(xy 112.934021 -75.270858) (xy 112.901067 -75.351041) (xy 112.860468 -75.427636) (xy 112.820396 -75.488154)
			(xy 128.574238 -75.488154) (xy 128.574238 -75.433646) (xy 128.581995 -75.379694) (xy 128.597351 -75.327394)
			(xy 128.619994 -75.277812) (xy 128.649463 -75.231957) (xy 128.685157 -75.190763) (xy 128.726351 -75.155068)
			(xy 128.772205 -75.125598) (xy 128.821786 -75.102954) (xy 128.874086 -75.087597) (xy 128.928038 -75.079838)
			(xy 128.955292 -75.079352) (xy 128.983 -75.079886) (xy 129.037832 -75.087907) (xy 129.090926 -75.10378)
			(xy 129.141163 -75.127171) (xy 129.187485 -75.157588) (xy 129.20853 -75.175618) (xy 129.215642 -75.181714)
			(xy 129.232914 -75.188318) (xy 129.31902 -75.188318) (xy 129.336292 -75.181714) (xy 129.343404 -75.175618)
			(xy 129.36444 -75.157574) (xy 129.410759 -75.127144) (xy 129.460997 -75.103744) (xy 129.514095 -75.087867)
			(xy 129.568932 -75.079846) (xy 129.596642 -75.079352) (xy 129.623888 -75.079921) (xy 129.677826 -75.087682)
			(xy 129.73011 -75.103039) (xy 129.779677 -75.12568) (xy 129.825517 -75.155144) (xy 129.866698 -75.190832)
			(xy 129.902381 -75.232017) (xy 129.93184 -75.27786) (xy 129.954476 -75.327429) (xy 129.969827 -75.379715)
			(xy 129.977582 -75.433654) (xy 129.977582 -75.488146) (xy 129.969827 -75.542085) (xy 129.954476 -75.594371)
			(xy 129.93184 -75.64394) (xy 129.902381 -75.689783) (xy 129.866698 -75.730968) (xy 129.825517 -75.766656)
			(xy 129.779677 -75.79612) (xy 129.73011 -75.818761) (xy 129.677826 -75.834118) (xy 129.623888 -75.841879)
			(xy 129.596642 -75.842368) (xy 129.568933 -75.841868) (xy 129.514099 -75.833838) (xy 129.461005 -75.817957)
			(xy 129.410769 -75.794558) (xy 129.364449 -75.764135) (xy 129.343404 -75.746102) (xy 129.336292 -75.740006)
			(xy 129.31902 -75.733402) (xy 129.232914 -75.733402) (xy 129.215642 -75.740006) (xy 129.20853 -75.746102)
			(xy 129.187484 -75.764134) (xy 129.141167 -75.794564) (xy 129.090932 -75.817966) (xy 129.037837 -75.833847)
			(xy 128.983002 -75.841871) (xy 128.955292 -75.842368) (xy 128.928038 -75.841962) (xy 128.874086 -75.834203)
			(xy 128.821786 -75.818846) (xy 128.772205 -75.796202) (xy 128.726351 -75.766732) (xy 128.685157 -75.731037)
			(xy 128.649463 -75.689843) (xy 128.619994 -75.643988) (xy 128.597351 -75.594406) (xy 128.581995 -75.542106)
			(xy 128.574238 -75.488154) (xy 112.820396 -75.488154) (xy 112.812607 -75.499917) (xy 112.75794 -75.567197)
			(xy 112.696985 -75.628839) (xy 112.663986 -75.656948) (xy 112.65535 -75.664314) (xy 112.645698 -75.684634)
			(xy 112.645698 -75.785726) (xy 112.65535 -75.806046) (xy 112.663986 -75.813412) (xy 112.696978 -75.841527)
			(xy 112.757918 -75.903179) (xy 112.812574 -75.970465) (xy 112.860427 -76.042747) (xy 112.901023 -76.119341)
			(xy 112.933979 -76.199519) (xy 112.958981 -76.282522) (xy 112.975792 -76.367564) (xy 112.984253 -76.453837)
			(xy 112.984788 -76.49718) (xy 112.984259 -76.540525) (xy 112.975815 -76.626803) (xy 112.959016 -76.71185)
			(xy 112.934021 -76.794858) (xy 112.901067 -76.875041) (xy 112.860468 -76.951636) (xy 112.812607 -77.023917)
			(xy 112.75794 -77.091197) (xy 112.696985 -77.152839) (xy 112.663986 -77.180948) (xy 112.65535 -77.188314)
			(xy 112.645698 -77.208634) (xy 112.645698 -77.309726) (xy 112.65535 -77.330046) (xy 112.663986 -77.337412)
			(xy 112.696978 -77.365527) (xy 112.757918 -77.427179) (xy 112.812574 -77.494465) (xy 112.860427 -77.566747)
			(xy 112.901023 -77.643341) (xy 112.933979 -77.723519) (xy 112.958981 -77.806522) (xy 112.975792 -77.891564)
			(xy 112.984253 -77.977837) (xy 112.984788 -78.02118) (xy 112.984259 -78.064525) (xy 112.975815 -78.150803)
			(xy 112.959016 -78.23585) (xy 112.934021 -78.318858) (xy 112.901067 -78.399041) (xy 112.860468 -78.475636)
			(xy 112.812607 -78.547917) (xy 112.75794 -78.615197) (xy 112.696985 -78.676839) (xy 112.663986 -78.704948)
			(xy 112.65535 -78.712314) (xy 112.645698 -78.732634) (xy 112.645698 -78.81115) (xy 115.395497 -78.81115)
			(xy 115.395497 -78.75665) (xy 115.403253 -78.702705) (xy 115.418608 -78.650413) (xy 115.441248 -78.600838)
			(xy 115.470713 -78.55499) (xy 115.506403 -78.513801) (xy 115.547591 -78.478112) (xy 115.59344 -78.448647)
			(xy 115.643015 -78.426007) (xy 115.695307 -78.410653) (xy 115.749252 -78.402897) (xy 115.776502 -78.402434)
			(xy 115.806236 -78.402955) (xy 115.864982 -78.412189) (xy 115.921582 -78.430434) (xy 115.974663 -78.457246)
			(xy 116.022935 -78.491976) (xy 116.06523 -78.53378) (xy 116.083334 -78.557374) (xy 116.090971 -78.566569)
			(xy 116.112293 -78.577302) (xy 116.124228 -78.577948) (xy 116.206016 -78.577948) (xy 116.217957 -78.577308)
			(xy 116.239294 -78.566591) (xy 116.24691 -78.557374) (xy 116.265057 -78.533818) (xy 116.307348 -78.492023)
			(xy 116.355615 -78.457301) (xy 116.408687 -78.430492) (xy 116.465277 -78.412247) (xy 116.524013 -78.403008)
			(xy 116.553742 -78.402434) (xy 116.580841 -78.402917) (xy 116.634494 -78.410592) (xy 116.686521 -78.425782)
			(xy 116.735874 -78.448182) (xy 116.781561 -78.47734) (xy 116.822663 -78.51267) (xy 116.858351 -78.55346)
			(xy 116.873528 -78.575916) (xy 116.880894 -78.587092) (xy 116.9035 -78.599284) (xy 117.016276 -78.597506)
			(xy 117.038628 -78.584552) (xy 117.045486 -78.573122) (xy 117.060416 -78.549494) (xy 117.096108 -78.506482)
			(xy 117.13769 -78.469135) (xy 117.184275 -78.438253) (xy 117.234866 -78.414495) (xy 117.288381 -78.398369)
			(xy 117.343676 -78.39022) (xy 117.371622 -78.389734) (xy 117.401354 -78.390313) (xy 117.460097 -78.399535)
			(xy 117.516696 -78.417768) (xy 117.569777 -78.44457) (xy 117.618051 -78.479289) (xy 117.660349 -78.521084)
			(xy 117.678454 -78.544674) (xy 117.686081 -78.553878) (xy 117.707411 -78.564606) (xy 117.719348 -78.565248)
			(xy 117.801136 -78.565248) (xy 117.813078 -78.564619) (xy 117.834415 -78.553894) (xy 117.84203 -78.544674)
			(xy 117.860165 -78.521108) (xy 117.902459 -78.479314) (xy 117.950728 -78.444593) (xy 118.003802 -78.417786)
			(xy 118.060394 -78.399543) (xy 118.119132 -78.390307) (xy 118.148862 -78.389734) (xy 118.178377 -78.39028)
			(xy 118.2367 -78.399386) (xy 118.292918 -78.417386) (xy 118.31955 -78.43012) (xy 118.330726 -78.435708)
			(xy 118.355364 -78.4352) (xy 118.450614 -78.383892) (xy 118.46433 -78.363318) (xy 118.465854 -78.350872)
			(xy 118.469375 -78.324785) (xy 118.482666 -78.273851) (xy 118.502828 -78.225226) (xy 118.52948 -78.179832)
			(xy 118.562115 -78.13853) (xy 118.600115 -78.102104) (xy 118.642759 -78.071243) (xy 118.689239 -78.046534)
			(xy 118.738672 -78.028444) (xy 118.764304 -78.02245) (xy 118.774464 -78.020164) (xy 118.791482 -78.007972)
			(xy 118.840504 -77.926692) (xy 118.843298 -77.905864) (xy 118.840504 -77.895958) (xy 118.833972 -77.870808)
			(xy 118.826959 -77.819323) (xy 118.826534 -77.793342) (xy 118.826995 -77.766088) (xy 118.834747 -77.712135)
			(xy 118.8501 -77.659835) (xy 118.87274 -77.610252) (xy 118.902208 -77.564396) (xy 118.937902 -77.523202)
			(xy 118.979096 -77.487508) (xy 119.024952 -77.45804) (xy 119.074535 -77.4354) (xy 119.126835 -77.420047)
			(xy 119.180788 -77.412295) (xy 119.208042 -77.411834) (xy 119.237343 -77.412348) (xy 119.29526 -77.421285)
			(xy 119.323358 -77.429614) (xy 119.333518 -77.432916) (xy 119.354346 -77.430884) (xy 119.437404 -77.384402)
			(xy 119.450104 -77.367892) (xy 119.452644 -77.357478) (xy 119.460004 -77.330364) (xy 119.48155 -77.278479)
			(xy 119.510469 -77.230312) (xy 119.546136 -77.186906) (xy 119.587781 -77.149197) (xy 119.634505 -77.118)
			(xy 119.685297 -77.09399) (xy 119.739059 -77.077686) (xy 119.794632 -77.069438) (xy 119.822722 -77.068934)
			(xy 119.851447 -77.069499) (xy 119.908248 -77.078116) (xy 119.963115 -77.095153) (xy 120.014807 -77.120223)
			(xy 120.062156 -77.15276) (xy 120.104091 -77.192029) (xy 120.139664 -77.237142) (xy 120.168071 -77.287078)
			(xy 120.18867 -77.340709) (xy 120.19534 -77.368654) (xy 120.198134 -77.3811) (xy 120.21439 -77.40015)
			(xy 120.31726 -77.440282) (xy 120.342152 -77.437488) (xy 120.35282 -77.429868) (xy 120.377 -77.413627)
			(xy 120.42926 -77.387908) (xy 120.48482 -77.370425) (xy 120.542391 -77.361581) (xy 120.571514 -77.361034)
			(xy 120.598769 -77.361442) (xy 120.652724 -77.369202) (xy 120.705026 -77.384562) (xy 120.754609 -77.407209)
			(xy 120.800464 -77.436683) (xy 120.841658 -77.472382) (xy 120.877351 -77.513581) (xy 120.906818 -77.55944)
			(xy 120.929458 -77.609027) (xy 120.94481 -77.661331) (xy 120.952562 -77.715287) (xy 120.953022 -77.742542)
			(xy 120.952472 -77.771491) (xy 120.943704 -77.828723) (xy 120.926392 -77.883974) (xy 120.900931 -77.935975)
			(xy 120.867908 -77.983533) (xy 120.836284 -78.0169) (xy 121.226234 -78.0169) (xy 121.230265 -77.932291)
			(xy 121.24232 -77.848449) (xy 121.26229 -77.766132) (xy 121.289995 -77.686086) (xy 121.325184 -77.609037)
			(xy 121.367537 -77.535681) (xy 121.416672 -77.466684) (xy 121.472143 -77.402669) (xy 121.533448 -77.344218)
			(xy 121.600032 -77.291859) (xy 121.671291 -77.246066) (xy 121.746581 -77.207255) (xy 121.825219 -77.175776)
			(xy 121.906494 -77.151915) (xy 121.989668 -77.135888) (xy 122.07399 -77.12784) (xy 122.116342 -77.127354)
			(xy 122.135353 -77.127471) (xy 122.173339 -77.129125) (xy 122.192288 -77.130656) (xy 122.200938 -77.131019)
			(xy 122.21769 -77.126703) (xy 122.232054 -77.117064) (xy 122.2375 -77.110336) (xy 122.26261 -77.077292)
			(xy 122.318007 -77.015489) (xy 122.378923 -76.959118) (xy 122.444827 -76.90867) (xy 122.515147 -76.864583)
			(xy 122.589269 -76.827242) (xy 122.666549 -76.796972) (xy 122.746313 -76.774035) (xy 122.827868 -76.758632)
			(xy 122.910504 -76.750897) (xy 122.952002 -76.750418) (xy 122.994352 -76.75087) (xy 123.078667 -76.758921)
			(xy 123.161836 -76.774951) (xy 123.243105 -76.798813) (xy 123.321737 -76.830293) (xy 123.39702 -76.869105)
			(xy 123.468274 -76.914897) (xy 123.534852 -76.967254) (xy 123.596152 -77.025704) (xy 123.651618 -77.089715)
			(xy 123.700748 -77.158709) (xy 123.743098 -77.232061) (xy 123.778283 -77.309107) (xy 123.805986 -77.389148)
			(xy 123.825954 -77.471459) (xy 123.834953 -77.534049) (xy 128.574308 -77.534049) (xy 128.574308 -77.479551)
			(xy 128.582064 -77.425609) (xy 128.597417 -77.373319) (xy 128.620056 -77.323746) (xy 128.649519 -77.2779)
			(xy 128.685207 -77.236713) (xy 128.726393 -77.201024) (xy 128.772239 -77.17156) (xy 128.821811 -77.14892)
			(xy 128.874101 -77.133566) (xy 128.928043 -77.125809) (xy 128.955292 -77.125322) (xy 128.983001 -77.125839)
			(xy 129.037834 -77.133861) (xy 129.090929 -77.149737) (xy 129.141166 -77.173133) (xy 129.187486 -77.203555)
			(xy 129.20853 -77.221588) (xy 129.215642 -77.227684) (xy 129.232914 -77.234288) (xy 129.31902 -77.234288)
			(xy 129.336292 -77.227684) (xy 129.343404 -77.221588) (xy 129.364436 -77.203539) (xy 129.410757 -77.173111)
			(xy 129.460996 -77.149713) (xy 129.514094 -77.133836) (xy 129.568931 -77.125816) (xy 129.596642 -77.125322)
			(xy 129.626466 -77.125889) (xy 129.68539 -77.135143) (xy 129.742157 -77.153451) (xy 129.795386 -77.180367)
			(xy 129.843779 -77.215235) (xy 129.865374 -77.235812) (xy 129.874518 -77.244956) (xy 129.89941 -77.252322)
			(xy 130.008122 -77.228192) (xy 130.02768 -77.211174) (xy 130.031998 -77.198982) (xy 130.046887 -77.16007)
			(xy 130.082911 -77.084939) (xy 130.125802 -77.013506) (xy 130.175184 -76.946396) (xy 130.230626 -76.884199)
			(xy 130.291641 -76.827458) (xy 130.357694 -76.776671) (xy 130.428207 -76.732283) (xy 130.502561 -76.694683)
			(xy 130.580106 -76.664201) (xy 130.660161 -76.641104) (xy 130.742026 -76.625593) (xy 130.824982 -76.617806)
			(xy 130.866642 -76.617322) (xy 130.905334 -76.617752) (xy 130.982423 -76.624495) (xy 131.058637 -76.637899)
			(xy 131.133401 -76.657865) (xy 131.169918 -76.670662) (xy 131.178419 -76.673318) (xy 131.196215 -76.673318)
			(xy 131.204716 -76.670662) (xy 131.241231 -76.657857) (xy 131.315991 -76.63787) (xy 131.392206 -76.624463)
			(xy 131.469299 -76.617738) (xy 131.507992 -76.617322) (xy 131.546683 -76.617767) (xy 131.623773 -76.624505)
			(xy 131.699987 -76.637906) (xy 131.774751 -76.657867) (xy 131.811268 -76.670662) (xy 131.819769 -76.673318)
			(xy 131.837565 -76.673318) (xy 131.846066 -76.670662) (xy 131.882576 -76.657842) (xy 131.957338 -76.637859)
			(xy 132.033555 -76.624456) (xy 132.110649 -76.617736) (xy 132.149342 -76.617322) (xy 132.191691 -76.617768)
			(xy 132.276004 -76.625822) (xy 132.35917 -76.641855) (xy 132.440436 -76.66572) (xy 132.519065 -76.697202)
			(xy 132.594346 -76.736015) (xy 132.665596 -76.781808) (xy 132.732171 -76.834166) (xy 132.793468 -76.892615)
			(xy 132.848932 -76.956626) (xy 132.89806 -77.02562) (xy 132.940407 -77.09897) (xy 132.975591 -77.176014)
			(xy 133.003292 -77.256053) (xy 133.023259 -77.338363) (xy 133.035313 -77.422199) (xy 133.039343 -77.5068)
			(xy 133.035313 -77.591401) (xy 133.023259 -77.675237) (xy 133.003292 -77.757547) (xy 132.975591 -77.837586)
			(xy 132.940407 -77.91463) (xy 132.89806 -77.98798) (xy 132.848932 -78.056974) (xy 132.793468 -78.120985)
			(xy 132.732171 -78.179434) (xy 132.665596 -78.231792) (xy 132.594346 -78.277585) (xy 132.519065 -78.316398)
			(xy 132.440436 -78.34788) (xy 132.35917 -78.371745) (xy 132.276004 -78.387778) (xy 132.191691 -78.395832)
			(xy 132.149342 -78.396338) (xy 132.11065 -78.395915) (xy 132.03356 -78.389171) (xy 131.957346 -78.375764)
			(xy 131.882583 -78.355796) (xy 131.846066 -78.342998) (xy 131.837581 -78.340241) (xy 131.819753 -78.340241)
			(xy 131.811268 -78.342998) (xy 131.774754 -78.355806) (xy 131.699994 -78.375793) (xy 131.623778 -78.389199)
			(xy 131.546685 -78.395923) (xy 131.507992 -78.396338) (xy 131.4693 -78.3959) (xy 131.392211 -78.38916)
			(xy 131.315997 -78.375758) (xy 131.241233 -78.355794) (xy 131.204716 -78.342998) (xy 131.196231 -78.340241)
			(xy 131.178403 -78.340241) (xy 131.169918 -78.342998) (xy 131.133409 -78.35582) (xy 131.058647 -78.375803)
			(xy 130.98243 -78.389205) (xy 130.905335 -78.395925) (xy 130.866642 -78.396338) (xy 130.824982 -78.395877)
			(xy 130.742029 -78.388073) (xy 130.660169 -78.37255) (xy 130.580118 -78.349443) (xy 130.502578 -78.318954)
			(xy 130.428227 -78.28135) (xy 130.357717 -78.236961) (xy 130.291665 -78.186175) (xy 130.230649 -78.129438)
			(xy 130.175204 -78.067245) (xy 130.125816 -78.000141) (xy 130.082916 -77.928715) (xy 130.046881 -77.853591)
			(xy 130.031998 -77.814678) (xy 130.02768 -77.802486) (xy 130.008122 -77.785468) (xy 129.89941 -77.761338)
			(xy 129.874518 -77.768704) (xy 129.865374 -77.777848) (xy 129.84377 -77.798417) (xy 129.795386 -77.8333)
			(xy 129.742161 -77.860225) (xy 129.685393 -77.878534) (xy 129.626466 -77.887781) (xy 129.596642 -77.888338)
			(xy 129.568933 -77.887845) (xy 129.514098 -77.879815) (xy 129.461004 -77.863932) (xy 129.410768 -77.840532)
			(xy 129.364448 -77.810106) (xy 129.343404 -77.792072) (xy 129.336292 -77.785976) (xy 129.31902 -77.779372)
			(xy 129.232914 -77.779372) (xy 129.215642 -77.785976) (xy 129.20853 -77.792072) (xy 129.18748 -77.810098)
			(xy 129.141164 -77.840531) (xy 129.09093 -77.863934) (xy 129.037836 -77.879816) (xy 128.983001 -77.887841)
			(xy 128.955292 -77.888338) (xy 128.928043 -77.887791) (xy 128.874101 -77.880034) (xy 128.821811 -77.86468)
			(xy 128.772239 -77.84204) (xy 128.726393 -77.812576) (xy 128.685207 -77.776887) (xy 128.649519 -77.7357)
			(xy 128.620056 -77.689854) (xy 128.597417 -77.640281) (xy 128.582064 -77.587991) (xy 128.574308 -77.534049)
			(xy 123.834953 -77.534049) (xy 123.838008 -77.555297) (xy 123.842039 -77.6399) (xy 123.838008 -77.724503)
			(xy 123.825954 -77.808341) (xy 123.805986 -77.890652) (xy 123.778283 -77.970693) (xy 123.743098 -78.047739)
			(xy 123.700748 -78.121091) (xy 123.651618 -78.190085) (xy 123.596152 -78.254096) (xy 123.534852 -78.312546)
			(xy 123.468274 -78.364903) (xy 123.39702 -78.410695) (xy 123.321737 -78.449507) (xy 123.243105 -78.480987)
			(xy 123.161836 -78.504849) (xy 123.078667 -78.520879) (xy 122.994352 -78.52893) (xy 122.952002 -78.529434)
			(xy 122.932991 -78.529314) (xy 122.895005 -78.527663) (xy 122.876056 -78.526132) (xy 122.867406 -78.525733)
			(xy 122.850652 -78.530066) (xy 122.836288 -78.539718) (xy 122.830844 -78.546452) (xy 122.805765 -78.57952)
			(xy 122.750365 -78.641323) (xy 122.689445 -78.697693) (xy 122.623537 -78.74814) (xy 122.553214 -78.792225)
			(xy 122.479088 -78.829564) (xy 122.401805 -78.859831) (xy 122.322037 -78.882764) (xy 122.24048 -78.898163)
			(xy 122.157841 -78.905893) (xy 122.116342 -78.90637) (xy 122.07399 -78.90596) (xy 121.989668 -78.897912)
			(xy 121.906494 -78.881885) (xy 121.825219 -78.858024) (xy 121.746581 -78.826545) (xy 121.671291 -78.787734)
			(xy 121.600032 -78.741941) (xy 121.533448 -78.689582) (xy 121.472143 -78.631131) (xy 121.416672 -78.567116)
			(xy 121.367537 -78.498119) (xy 121.325184 -78.424763) (xy 121.289995 -78.347714) (xy 121.26229 -78.267668)
			(xy 121.24232 -78.185351) (xy 121.230265 -78.101509) (xy 121.226234 -78.0169) (xy 120.836284 -78.0169)
			(xy 120.828079 -78.025557) (xy 120.78236 -78.061082) (xy 120.731798 -78.089293) (xy 120.704864 -78.09992)
			(xy 120.694704 -78.10373) (xy 120.679464 -78.118716) (xy 120.643396 -78.208378) (xy 120.644158 -78.229714)
			(xy 120.64873 -78.239366) (xy 120.660746 -78.265393) (xy 120.677725 -78.320144) (xy 120.686312 -78.37682)
			(xy 120.68683 -78.405482) (xy 120.686305 -78.432732) (xy 120.678552 -78.486677) (xy 120.6632 -78.53897)
			(xy 120.640562 -78.588545) (xy 120.6111 -78.634395) (xy 120.575413 -78.675584) (xy 120.534227 -78.711276)
			(xy 120.48838 -78.740743) (xy 120.438807 -78.763386) (xy 120.386516 -78.778743) (xy 120.332572 -78.786502)
			(xy 120.305322 -78.78699) (xy 120.279862 -78.786605) (xy 120.229393 -78.779833) (xy 120.180275 -78.766406)
			(xy 120.133379 -78.746563) (xy 120.089541 -78.720656) (xy 120.04954 -78.689147) (xy 120.03151 -78.671166)
			(xy 120.024398 -78.6638) (xy 120.005856 -78.655926) (xy 119.913908 -78.654402) (xy 119.895112 -78.662022)
			(xy 119.887746 -78.669134) (xy 119.87149 -78.683866) (xy 119.862854 -78.691486) (xy 119.85371 -78.71206)
			(xy 119.855488 -78.812644) (xy 119.865394 -78.832964) (xy 119.874284 -78.840076) (xy 119.896044 -78.85829)
			(xy 119.934448 -78.900063) (xy 119.96624 -78.947065) (xy 119.990719 -78.998258) (xy 120.007345 -79.052512)
			(xy 120.01575 -79.10863) (xy 120.01627 -79.137002) (xy 120.015846 -79.164257) (xy 120.008088 -79.218211)
			(xy 119.99273 -79.270512) (xy 119.970084 -79.320095) (xy 119.940613 -79.365949) (xy 119.904915 -79.407143)
			(xy 119.863717 -79.442837) (xy 119.817859 -79.472304) (xy 119.768274 -79.494944) (xy 119.715972 -79.510297)
			(xy 119.662017 -79.518049) (xy 119.634762 -79.51851) (xy 119.605031 -79.517925) (xy 119.546288 -79.508701)
			(xy 119.48969 -79.490468) (xy 119.43661 -79.463668) (xy 119.388335 -79.428951) (xy 119.346037 -79.387158)
			(xy 119.32793 -79.36357) (xy 119.320301 -79.354366) (xy 119.298973 -79.343637) (xy 119.287036 -79.342996)
			(xy 119.205248 -79.342996) (xy 119.193302 -79.343599) (xy 119.171964 -79.354341) (xy 119.164354 -79.36357)
			(xy 119.14624 -79.387153) (xy 119.103941 -79.428944) (xy 119.055667 -79.463662) (xy 119.002589 -79.490465)
			(xy 118.945993 -79.508705) (xy 118.887253 -79.517939) (xy 118.857522 -79.51851) (xy 118.829894 -79.518011)
			(xy 118.775214 -79.510069) (xy 118.722251 -79.49432) (xy 118.672116 -79.471093) (xy 118.625857 -79.440874)
			(xy 118.584443 -79.404295) (xy 118.548741 -79.362124) (xy 118.519498 -79.315242) (xy 118.497327 -79.26463)
			(xy 118.482692 -79.211349) (xy 118.478808 -79.183992) (xy 118.477284 -79.171292) (xy 118.463314 -79.150972)
			(xy 118.365778 -79.10068) (xy 118.34114 -79.100934) (xy 118.329964 -79.10703) (xy 118.301968 -79.121414)
			(xy 118.242417 -79.141787) (xy 118.180331 -79.152109) (xy 118.148862 -79.15275) (xy 118.119132 -79.152149)
			(xy 118.060391 -79.142926) (xy 118.003794 -79.124695) (xy 117.950714 -79.097898) (xy 117.902438 -79.063184)
			(xy 117.860138 -79.021396) (xy 117.84203 -78.99781) (xy 117.834413 -78.988596) (xy 117.813075 -78.977874)
			(xy 117.801136 -78.977236) (xy 117.719348 -78.977236) (xy 117.707399 -78.977824) (xy 117.686061 -78.988575)
			(xy 117.678454 -78.99781) (xy 117.660351 -79.021401) (xy 117.618048 -79.06319) (xy 117.569771 -79.097906)
			(xy 117.516692 -79.124708) (xy 117.460095 -79.142946) (xy 117.401353 -79.152179) (xy 117.371622 -79.15275)
			(xy 117.344521 -79.152302) (xy 117.290867 -79.144621) (xy 117.238839 -79.129426) (xy 117.189485 -79.10702)
			(xy 117.143798 -79.077857) (xy 117.102698 -79.042522) (xy 117.067011 -79.001726) (xy 117.051836 -78.979268)
			(xy 117.04447 -78.968092) (xy 117.021864 -78.9559) (xy 116.909088 -78.957678) (xy 116.886736 -78.970632)
			(xy 116.879878 -78.982062) (xy 116.864966 -79.005703) (xy 116.829273 -79.048715) (xy 116.787687 -79.086062)
			(xy 116.741099 -79.116943) (xy 116.690505 -79.140699) (xy 116.636986 -79.156822) (xy 116.581689 -79.164966)
			(xy 116.553742 -79.16545) (xy 116.524011 -79.164864) (xy 116.465269 -79.155638) (xy 116.408672 -79.137404)
			(xy 116.355592 -79.110604) (xy 116.307317 -79.075888) (xy 116.265018 -79.034097) (xy 116.24691 -79.01051)
			(xy 116.239302 -79.001287) (xy 116.217958 -78.99057) (xy 116.206016 -78.989936) (xy 116.124228 -78.989936)
			(xy 116.112278 -78.990513) (xy 116.090939 -79.001271) (xy 116.083334 -79.01051) (xy 116.065243 -79.034111)
			(xy 116.022937 -79.075899) (xy 115.974658 -79.110613) (xy 115.921576 -79.137414) (xy 115.864977 -79.15565)
			(xy 115.806234 -79.16488) (xy 115.776502 -79.16545) (xy 115.749252 -79.164903) (xy 115.695307 -79.157147)
			(xy 115.643015 -79.141793) (xy 115.59344 -79.119153) (xy 115.547591 -79.089688) (xy 115.506403 -79.053999)
			(xy 115.470713 -79.01281) (xy 115.441248 -78.966962) (xy 115.418608 -78.917387) (xy 115.403253 -78.865095)
			(xy 115.395497 -78.81115) (xy 112.645698 -78.81115) (xy 112.645698 -78.833726) (xy 112.65535 -78.854046)
			(xy 112.663986 -78.861412) (xy 112.696978 -78.889527) (xy 112.757918 -78.951179) (xy 112.812574 -79.018465)
			(xy 112.860427 -79.090747) (xy 112.901023 -79.167341) (xy 112.933979 -79.247519) (xy 112.958981 -79.330522)
			(xy 112.975792 -79.415564) (xy 112.984253 -79.501837) (xy 112.984788 -79.54518) (xy 112.9842 -79.591575)
			(xy 112.974557 -79.683864) (xy 112.955362 -79.774648) (xy 112.926825 -79.862941) (xy 112.908588 -79.905606)
			(xy 112.904779 -79.915549) (xy 112.904772 -79.936815) (xy 112.908588 -79.946754) (xy 112.926825 -79.989419)
			(xy 112.955371 -80.077711) (xy 112.968013 -80.1375) (xy 120.813595 -80.1375) (xy 120.817625 -80.0529)
			(xy 120.829679 -79.969066) (xy 120.849647 -79.886758) (xy 120.877348 -79.806721) (xy 120.912531 -79.729678)
			(xy 120.954879 -79.65633) (xy 121.004007 -79.587338) (xy 121.059471 -79.523329) (xy 121.120768 -79.464882)
			(xy 121.187343 -79.412527) (xy 121.258593 -79.366736) (xy 121.333873 -79.327926) (xy 121.412502 -79.296447)
			(xy 121.493767 -79.272585) (xy 121.576932 -79.256555) (xy 121.661244 -79.248504) (xy 121.703592 -79.248)
			(xy 121.745627 -79.248524) (xy 121.829321 -79.256458) (xy 121.911893 -79.272255) (xy 121.992605 -79.295774)
			(xy 122.070737 -79.326807) (xy 122.145592 -79.365074) (xy 122.216501 -79.410236) (xy 122.282831 -79.461888)
			(xy 122.34399 -79.51957) (xy 122.399432 -79.582767) (xy 122.424444 -79.616554) (xy 122.432619 -79.62728)
			(xy 122.453563 -79.644262) (xy 122.478223 -79.655167) (xy 122.504878 -79.659231) (xy 122.531668 -79.656173)
			(xy 122.556721 -79.646206) (xy 122.578289 -79.630024) (xy 122.594867 -79.608759) (xy 122.600466 -79.596488)
			(xy 122.611732 -79.570905) (xy 122.640765 -79.523135) (xy 122.676456 -79.48011) (xy 122.71804 -79.442752)
			(xy 122.764629 -79.411858) (xy 122.815226 -79.388091) (xy 122.868748 -79.371958) (xy 122.924051 -79.363804)
			(xy 122.952002 -79.363316) (xy 122.979255 -79.363754) (xy 123.033206 -79.371511) (xy 123.085504 -79.386867)
			(xy 123.135084 -79.40951) (xy 123.180937 -79.438978) (xy 123.222129 -79.474672) (xy 123.257823 -79.515865)
			(xy 123.287291 -79.561718) (xy 123.309933 -79.611298) (xy 123.325289 -79.663596) (xy 123.333046 -79.717547)
			(xy 123.333046 -79.772053) (xy 123.326907 -79.81475) (xy 128.671574 -79.81475) (xy 128.671574 -79.76025)
			(xy 128.67933 -79.706304) (xy 128.694684 -79.65401) (xy 128.717323 -79.604434) (xy 128.746787 -79.558585)
			(xy 128.782476 -79.517395) (xy 128.823664 -79.481703) (xy 128.869512 -79.452236) (xy 128.919086 -79.429593)
			(xy 128.971378 -79.414235) (xy 129.025324 -79.406476) (xy 129.052574 -79.405988) (xy 129.080284 -79.406465)
			(xy 129.135119 -79.414498) (xy 129.188214 -79.430384) (xy 129.23845 -79.453788) (xy 129.284769 -79.484218)
			(xy 129.305812 -79.502254) (xy 129.312924 -79.50835) (xy 129.330196 -79.514954) (xy 129.416302 -79.514954)
			(xy 129.433574 -79.50835) (xy 129.440686 -79.502254) (xy 129.46172 -79.484208) (xy 129.508041 -79.453781)
			(xy 129.55828 -79.430382) (xy 129.611377 -79.414505) (xy 129.666214 -79.406483) (xy 129.693924 -79.405988)
			(xy 129.721505 -79.406482) (xy 129.776091 -79.414427) (xy 129.828964 -79.43015) (xy 129.854198 -79.441294)
			(xy 129.864866 -79.44612) (xy 129.887726 -79.445866) (xy 129.979674 -79.399638) (xy 129.993644 -79.38135)
			(xy 129.996184 -79.36992) (xy 130.005589 -79.327619) (xy 130.031564 -79.24494) (xy 130.065457 -79.16518)
			(xy 130.106948 -79.089094) (xy 130.155642 -79.017405) (xy 130.211078 -78.950793) (xy 130.272731 -78.889887)
			(xy 130.340015 -78.835268) (xy 130.412292 -78.787451) (xy 130.488878 -78.746892) (xy 130.569045 -78.713973)
			(xy 130.652034 -78.689009) (xy 130.737058 -78.672234) (xy 130.823311 -78.663809) (xy 130.866642 -78.663292)
			(xy 130.905334 -78.663724) (xy 130.982423 -78.670466) (xy 131.058637 -78.68387) (xy 131.133401 -78.703835)
			(xy 131.169918 -78.716632) (xy 131.178419 -78.719288) (xy 131.196215 -78.719288) (xy 131.204716 -78.716632)
			(xy 131.24123 -78.703825) (xy 131.315991 -78.683839) (xy 131.392206 -78.670432) (xy 131.469299 -78.663708)
			(xy 131.507992 -78.663292) (xy 131.546683 -78.663739) (xy 131.623772 -78.670477) (xy 131.699987 -78.683877)
			(xy 131.774751 -78.703837) (xy 131.811268 -78.716632) (xy 131.819769 -78.719288) (xy 131.837565 -78.719288)
			(xy 131.846066 -78.716632) (xy 131.882576 -78.703811) (xy 131.957338 -78.683828) (xy 132.033555 -78.670426)
			(xy 132.110649 -78.663706) (xy 132.149342 -78.663292) (xy 132.191689 -78.663798) (xy 132.276 -78.671852)
			(xy 132.359163 -78.687884) (xy 132.440426 -78.711748) (xy 132.519052 -78.743229) (xy 132.594331 -78.782041)
			(xy 132.665579 -78.827832) (xy 132.732152 -78.880188) (xy 132.793446 -78.938636) (xy 132.848908 -79.002645)
			(xy 132.898034 -79.071636) (xy 132.94038 -79.144984) (xy 132.975563 -79.222025) (xy 133.003263 -79.302062)
			(xy 133.02323 -79.384369) (xy 133.035283 -79.468201) (xy 133.039313 -79.5528) (xy 133.035283 -79.637399)
			(xy 133.02323 -79.721231) (xy 133.003263 -79.803538) (xy 132.975563 -79.883575) (xy 132.94038 -79.960616)
			(xy 132.898034 -80.033964) (xy 132.848908 -80.102955) (xy 132.793446 -80.166964) (xy 132.732152 -80.225412)
			(xy 132.665579 -80.277768) (xy 132.594331 -80.323559) (xy 132.519052 -80.362371) (xy 132.440426 -80.393852)
			(xy 132.359163 -80.417716) (xy 132.276 -80.433748) (xy 132.191689 -80.441802) (xy 132.149342 -80.442308)
			(xy 132.11065 -80.441881) (xy 132.033561 -80.435137) (xy 131.957347 -80.421732) (xy 131.882583 -80.401765)
			(xy 131.846066 -80.388968) (xy 131.837581 -80.386211) (xy 131.819753 -80.386211) (xy 131.811268 -80.388968)
			(xy 131.774755 -80.401779) (xy 131.699994 -80.421764) (xy 131.623778 -80.43517) (xy 131.546685 -80.441893)
			(xy 131.507992 -80.442308) (xy 131.469301 -80.441866) (xy 131.392211 -80.435126) (xy 131.315997 -80.421725)
			(xy 131.241233 -80.401763) (xy 131.204716 -80.388968) (xy 131.196231 -80.386211) (xy 131.178403 -80.386211)
			(xy 131.169918 -80.388968) (xy 131.13341 -80.401793) (xy 131.058647 -80.421775) (xy 130.98243 -80.435176)
			(xy 130.905335 -80.441895) (xy 130.866642 -80.442308) (xy 130.823556 -80.441779) (xy 130.737786 -80.433459)
			(xy 130.653223 -80.416881) (xy 130.57066 -80.392203) (xy 130.490871 -80.359655) (xy 130.414603 -80.319542)
			(xy 130.342573 -80.272241) (xy 130.275456 -80.218195) (xy 130.213881 -80.157911) (xy 130.158424 -80.091954)
			(xy 130.133598 -80.056736) (xy 130.126994 -80.04683) (xy 130.106928 -80.035654) (xy 130.004312 -80.028288)
			(xy 129.982976 -80.03667) (xy 129.975102 -80.04556) (xy 129.956951 -80.064665) (xy 129.916309 -80.098209)
			(xy 129.871434 -80.125836) (xy 129.823183 -80.147021) (xy 129.772473 -80.161359) (xy 129.720273 -80.168578)
			(xy 129.693924 -80.169004) (xy 129.666214 -80.16853) (xy 129.611378 -80.160497) (xy 129.558284 -80.14461)
			(xy 129.508048 -80.121205) (xy 129.461729 -80.090774) (xy 129.440686 -80.072738) (xy 129.433574 -80.066642)
			(xy 129.416302 -80.060038) (xy 129.330196 -80.060038) (xy 129.312924 -80.066642) (xy 129.305812 -80.072738)
			(xy 129.284778 -80.090784) (xy 129.238457 -80.121211) (xy 129.188218 -80.14461) (xy 129.135121 -80.160487)
			(xy 129.080284 -80.168509) (xy 129.052574 -80.169004) (xy 129.025324 -80.168524) (xy 128.971378 -80.160765)
			(xy 128.919086 -80.145407) (xy 128.869512 -80.122764) (xy 128.823664 -80.093297) (xy 128.782476 -80.057605)
			(xy 128.746787 -80.016415) (xy 128.717323 -79.970566) (xy 128.694684 -79.92099) (xy 128.67933 -79.868696)
			(xy 128.671574 -79.81475) (xy 123.326907 -79.81475) (xy 123.325289 -79.826004) (xy 123.309933 -79.878302)
			(xy 123.287291 -79.927882) (xy 123.257823 -79.973735) (xy 123.222129 -80.014928) (xy 123.180937 -80.050622)
			(xy 123.135084 -80.08009) (xy 123.085504 -80.102733) (xy 123.033206 -80.118089) (xy 122.979255 -80.125846)
			(xy 122.952002 -80.126332) (xy 122.925202 -80.125856) (xy 122.872129 -80.11835) (xy 122.820631 -80.103485)
			(xy 122.771722 -80.081555) (xy 122.748802 -80.067658) (xy 122.737226 -80.060748) (xy 122.711464 -80.052817)
			(xy 122.684524 -80.051912) (xy 122.658288 -80.058097) (xy 122.634589 -80.070938) (xy 122.615081 -80.08954)
			(xy 122.601129 -80.112603) (xy 122.593705 -80.138516) (xy 122.5931 -80.151986) (xy 122.591868 -80.195193)
			(xy 122.582066 -80.281077) (xy 122.56398 -80.365606) (xy 122.537782 -80.447983) (xy 122.503718 -80.52743)
			(xy 122.462109 -80.603199) (xy 122.413348 -80.674576) (xy 122.357895 -80.740887) (xy 122.296272 -80.801507)
			(xy 122.22906 -80.855865) (xy 122.156893 -80.903449) (xy 122.080452 -80.943809) (xy 122.000456 -80.976565)
			(xy 121.917661 -81.001409) (xy 121.832847 -81.018106) (xy 121.746813 -81.026498) (xy 121.703592 -81.027016)
			(xy 121.661244 -81.026496) (xy 121.576932 -81.018445) (xy 121.493767 -81.002415) (xy 121.412502 -80.978553)
			(xy 121.333873 -80.947074) (xy 121.258593 -80.908264) (xy 121.187343 -80.862473) (xy 121.120768 -80.810118)
			(xy 121.059471 -80.751671) (xy 121.004007 -80.687662) (xy 120.954879 -80.61867) (xy 120.912531 -80.545322)
			(xy 120.877348 -80.468279) (xy 120.849647 -80.388242) (xy 120.829679 -80.305934) (xy 120.817625 -80.2221)
			(xy 120.813595 -80.1375) (xy 112.968013 -80.1375) (xy 112.974567 -80.168495) (xy 112.984202 -80.260784)
			(xy 112.984788 -80.30718) (xy 112.984284 -80.349528) (xy 112.976233 -80.433842) (xy 112.960204 -80.517008)
			(xy 112.936343 -80.598275) (xy 112.904864 -80.676905) (xy 112.866053 -80.752186) (xy 112.820263 -80.823438)
			(xy 112.767907 -80.890014) (xy 112.709459 -80.951312) (xy 112.645449 -81.006777) (xy 112.576457 -81.055906)
			(xy 112.503107 -81.098255) (xy 112.426064 -81.133439) (xy 112.346025 -81.161141) (xy 112.263716 -81.181109)
			(xy 112.179881 -81.193162) (xy 112.09528 -81.197193) (xy 112.010679 -81.193162) (xy 111.926844 -81.181109)
			(xy 111.844535 -81.161141) (xy 111.764496 -81.133439) (xy 111.687453 -81.098255) (xy 111.614103 -81.055906)
			(xy 111.545111 -81.006777) (xy 111.481101 -80.951312) (xy 111.422653 -80.890014) (xy 111.370297 -80.823438)
			(xy 111.324507 -80.752186) (xy 111.285696 -80.676905) (xy 111.254217 -80.598275) (xy 111.230356 -80.517008)
			(xy 111.214327 -80.433842) (xy 111.206276 -80.349528) (xy 111.205772 -80.30718) (xy 104.195864 -80.30718)
			(xy 103.144164 -81.512594) (xy 107.555534 -81.512594) (xy 107.555534 -81.427898) (xy 107.563585 -81.343584)
			(xy 107.579614 -81.260418) (xy 107.603475 -81.179151) (xy 107.634954 -81.100521) (xy 107.673765 -81.02524)
			(xy 107.719555 -80.953988) (xy 107.771911 -80.887412) (xy 107.830359 -80.826114) (xy 107.894369 -80.770649)
			(xy 107.963361 -80.72152) (xy 108.036711 -80.679171) (xy 108.113754 -80.643987) (xy 108.193793 -80.616285)
			(xy 108.276102 -80.596317) (xy 108.359937 -80.584264) (xy 108.444538 -80.580234) (xy 108.529139 -80.584264)
			(xy 108.612974 -80.596317) (xy 108.695283 -80.616285) (xy 108.775322 -80.643987) (xy 108.852365 -80.679171)
			(xy 108.925715 -80.72152) (xy 108.994707 -80.770649) (xy 109.058717 -80.826114) (xy 109.117165 -80.887412)
			(xy 109.169521 -80.953988) (xy 109.215311 -81.02524) (xy 109.254122 -81.100521) (xy 109.285601 -81.179151)
			(xy 109.309462 -81.260418) (xy 109.325491 -81.343584) (xy 109.333542 -81.427898) (xy 109.334046 -81.470246)
			(xy 109.333542 -81.512594) (xy 109.325491 -81.596908) (xy 109.309462 -81.680074) (xy 109.285601 -81.761341)
			(xy 109.254122 -81.839971) (xy 109.215311 -81.915252) (xy 109.169521 -81.986504) (xy 109.117165 -82.05308)
			(xy 109.058717 -82.114378) (xy 108.994707 -82.169843) (xy 108.925715 -82.218972) (xy 108.852365 -82.261321)
			(xy 108.775322 -82.296505) (xy 108.695283 -82.324207) (xy 108.612974 -82.344175) (xy 108.529139 -82.356228)
			(xy 108.444538 -82.360259) (xy 108.359937 -82.356228) (xy 108.276102 -82.344175) (xy 108.193793 -82.324207)
			(xy 108.113754 -82.296505) (xy 108.036711 -82.261321) (xy 107.963361 -82.218972) (xy 107.894369 -82.169843)
			(xy 107.830359 -82.114378) (xy 107.771911 -82.05308) (xy 107.719555 -81.986504) (xy 107.673765 -81.915252)
			(xy 107.634954 -81.839971) (xy 107.603475 -81.761341) (xy 107.579614 -81.680074) (xy 107.563585 -81.596908)
			(xy 107.555534 -81.512594) (xy 103.144164 -81.512594) (xy 99.850153 -85.28805) (xy 130.053838 -85.28805)
			(xy 130.053838 -85.203354) (xy 130.061889 -85.11904) (xy 130.077918 -85.035874) (xy 130.101779 -84.954607)
			(xy 130.133258 -84.875977) (xy 130.172069 -84.800696) (xy 130.217859 -84.729444) (xy 130.270215 -84.662868)
			(xy 130.328663 -84.60157) (xy 130.392673 -84.546105) (xy 130.461665 -84.496976) (xy 130.535015 -84.454627)
			(xy 130.612058 -84.419443) (xy 130.692097 -84.391741) (xy 130.774406 -84.371773) (xy 130.858241 -84.35972)
			(xy 130.942842 -84.35569) (xy 131.027443 -84.35972) (xy 131.111278 -84.371773) (xy 131.193587 -84.391741)
			(xy 131.273626 -84.419443) (xy 131.350669 -84.454627) (xy 131.424019 -84.496976) (xy 131.493011 -84.546105)
			(xy 131.557021 -84.60157) (xy 131.615469 -84.662868) (xy 131.667825 -84.729444) (xy 131.713615 -84.800696)
			(xy 131.752426 -84.875977) (xy 131.783905 -84.954607) (xy 131.807766 -85.035874) (xy 131.823795 -85.11904)
			(xy 131.831846 -85.203354) (xy 131.83235 -85.245702) (xy 131.831846 -85.28805) (xy 131.823795 -85.372364)
			(xy 131.807766 -85.45553) (xy 131.783905 -85.536797) (xy 131.752426 -85.615427) (xy 131.713615 -85.690708)
			(xy 131.667825 -85.76196) (xy 131.615469 -85.828536) (xy 131.557021 -85.889834) (xy 131.493011 -85.945299)
			(xy 131.424019 -85.994428) (xy 131.350669 -86.036777) (xy 131.273626 -86.071961) (xy 131.193587 -86.099663)
			(xy 131.111278 -86.119631) (xy 131.027443 -86.131684) (xy 130.942842 -86.135715) (xy 130.858241 -86.131684)
			(xy 130.774406 -86.119631) (xy 130.692097 -86.099663) (xy 130.612058 -86.071961) (xy 130.535015 -86.036777)
			(xy 130.461665 -85.994428) (xy 130.392673 -85.945299) (xy 130.328663 -85.889834) (xy 130.270215 -85.828536)
			(xy 130.217859 -85.76196) (xy 130.172069 -85.690708) (xy 130.133258 -85.615427) (xy 130.101779 -85.536797)
			(xy 130.077918 -85.45553) (xy 130.061889 -85.372364) (xy 130.053838 -85.28805) (xy 99.850153 -85.28805)
			(xy 95.177667 -90.643456) (xy 117.866922 -90.643456) (xy 117.867449 -90.601793) (xy 117.875254 -90.518833)
			(xy 117.890783 -90.436966) (xy 117.913898 -90.356911) (xy 117.944399 -90.279367) (xy 117.982016 -90.205015)
			(xy 118.026421 -90.134507) (xy 118.077225 -90.068459) (xy 118.133982 -90.007452) (xy 118.196196 -89.952019)
			(xy 118.26332 -89.902647) (xy 118.334766 -89.859768) (xy 118.372128 -89.841324) (xy 118.381061 -89.83659)
			(xy 118.394509 -89.821516) (xy 118.401067 -89.802409) (xy 118.40083 -89.792302) (xy 118.400068 -89.767918)
			(xy 118.400554 -89.740667) (xy 118.40831 -89.686719) (xy 118.423665 -89.634424) (xy 118.446307 -89.584847)
			(xy 118.475773 -89.538997) (xy 118.511464 -89.497806) (xy 118.552655 -89.462115) (xy 118.598505 -89.432649)
			(xy 118.648082 -89.410007) (xy 118.700377 -89.394652) (xy 118.754325 -89.386896) (xy 118.808827 -89.386896)
			(xy 118.862775 -89.394652) (xy 118.91507 -89.410007) (xy 118.964647 -89.432649) (xy 119.010497 -89.462115)
			(xy 119.051688 -89.497806) (xy 119.087379 -89.538997) (xy 119.116845 -89.584847) (xy 119.139487 -89.634424)
			(xy 119.154842 -89.686719) (xy 119.162598 -89.740667) (xy 119.163084 -89.767918) (xy 119.162997 -89.779504)
			(xy 119.161598 -89.802634) (xy 119.16029 -89.814146) (xy 119.159488 -89.824212) (xy 119.165029 -89.843619)
			(xy 119.17758 -89.859425) (xy 119.186198 -89.864692) (xy 119.223736 -89.88594) (xy 119.273857 -89.920318)
			(xy 123.01855 -89.920318) (xy 123.019118 -89.876932) (xy 123.027566 -89.790572) (xy 123.044383 -89.705445)
			(xy 123.06941 -89.622361) (xy 123.102408 -89.542108) (xy 123.143064 -89.46545) (xy 123.190991 -89.393115)
			(xy 123.245735 -89.325791) (xy 123.306774 -89.264117) (xy 123.373528 -89.208681) (xy 123.445364 -89.160008)
			(xy 123.521598 -89.118561) (xy 123.561348 -89.101168) (xy 123.571202 -89.096476) (xy 123.585991 -89.080455)
			(xy 123.592781 -89.059736) (xy 123.592082 -89.048844) (xy 123.590999 -89.038337) (xy 123.589855 -89.017243)
			(xy 123.589796 -89.00668) (xy 123.590282 -88.979429) (xy 123.598038 -88.925481) (xy 123.613393 -88.873186)
			(xy 123.636035 -88.823609) (xy 123.665501 -88.777759) (xy 123.701192 -88.736568) (xy 123.742383 -88.700877)
			(xy 123.788233 -88.671411) (xy 123.83781 -88.648769) (xy 123.890105 -88.633414) (xy 123.944053 -88.625658)
			(xy 123.998555 -88.625658) (xy 124.052503 -88.633414) (xy 124.104798 -88.648769) (xy 124.154375 -88.671411)
			(xy 124.200225 -88.700877) (xy 124.241416 -88.736568) (xy 124.277107 -88.777759) (xy 124.306573 -88.823609)
			(xy 124.329215 -88.873186) (xy 124.34457 -88.925481) (xy 124.352326 -88.979429) (xy 124.352812 -89.00668)
			(xy 124.352475 -89.030426) (xy 124.346613 -89.077554) (xy 124.341128 -89.10066) (xy 124.338934 -89.111353)
			(xy 124.342756 -89.132819) (xy 124.355147 -89.15076) (xy 124.361839 -89.1552) (xy 134.54659 -89.1552)
			(xy 134.54659 -89.070504) (xy 134.554641 -88.98619) (xy 134.57067 -88.903024) (xy 134.594531 -88.821757)
			(xy 134.62601 -88.743127) (xy 134.664821 -88.667846) (xy 134.710611 -88.596594) (xy 134.762967 -88.530018)
			(xy 134.821415 -88.46872) (xy 134.885425 -88.413255) (xy 134.954417 -88.364126) (xy 135.027767 -88.321777)
			(xy 135.10481 -88.286593) (xy 135.184849 -88.258891) (xy 135.267158 -88.238923) (xy 135.350993 -88.22687)
			(xy 135.435594 -88.22284) (xy 135.520195 -88.22687) (xy 135.60403 -88.238923) (xy 135.686339 -88.258891)
			(xy 135.766378 -88.286593) (xy 135.843421 -88.321777) (xy 135.916771 -88.364126) (xy 135.985763 -88.413255)
			(xy 136.049773 -88.46872) (xy 136.108221 -88.530018) (xy 136.160577 -88.596594) (xy 136.206367 -88.667846)
			(xy 136.245178 -88.743127) (xy 136.276657 -88.821757) (xy 136.300518 -88.903024) (xy 136.316547 -88.98619)
			(xy 136.324598 -89.070504) (xy 136.325102 -89.112852) (xy 136.324598 -89.1552) (xy 136.316547 -89.239514)
			(xy 136.300518 -89.32268) (xy 136.276657 -89.403947) (xy 136.245178 -89.482577) (xy 136.206367 -89.557858)
			(xy 136.160577 -89.62911) (xy 136.108221 -89.695686) (xy 136.049773 -89.756984) (xy 135.985763 -89.812449)
			(xy 135.916771 -89.861578) (xy 135.843421 -89.903927) (xy 135.766378 -89.939111) (xy 135.686339 -89.966813)
			(xy 135.60403 -89.986781) (xy 135.520195 -89.998834) (xy 135.435594 -90.002865) (xy 135.350993 -89.998834)
			(xy 135.267158 -89.986781) (xy 135.184849 -89.966813) (xy 135.10481 -89.939111) (xy 135.027767 -89.903927)
			(xy 134.954417 -89.861578) (xy 134.885425 -89.812449) (xy 134.821415 -89.756984) (xy 134.762967 -89.695686)
			(xy 134.710611 -89.62911) (xy 134.664821 -89.557858) (xy 134.62601 -89.482577) (xy 134.594531 -89.403947)
			(xy 134.57067 -89.32268) (xy 134.554641 -89.239514) (xy 134.54659 -89.1552) (xy 124.361839 -89.1552)
			(xy 124.364242 -89.156794) (xy 124.399807 -89.178651) (xy 124.467153 -89.227984) (xy 124.52958 -89.283411)
			(xy 124.586538 -89.344444) (xy 124.637526 -89.410546) (xy 124.682096 -89.481135) (xy 124.719854 -89.55559)
			(xy 124.750469 -89.633256) (xy 124.773671 -89.713449) (xy 124.789256 -89.795463) (xy 124.797087 -89.878577)
			(xy 124.797566 -89.920318) (xy 124.797062 -89.962666) (xy 124.789011 -90.04698) (xy 124.772982 -90.130146)
			(xy 124.749121 -90.211413) (xy 124.717642 -90.290043) (xy 124.678831 -90.365324) (xy 124.633041 -90.436576)
			(xy 124.580685 -90.503152) (xy 124.522237 -90.56445) (xy 124.458227 -90.619915) (xy 124.389235 -90.669044)
			(xy 124.315885 -90.711393) (xy 124.238842 -90.746577) (xy 124.158803 -90.774279) (xy 124.076494 -90.794247)
			(xy 123.992659 -90.8063) (xy 123.908058 -90.810331) (xy 123.823457 -90.8063) (xy 123.739622 -90.794247)
			(xy 123.657313 -90.774279) (xy 123.577274 -90.746577) (xy 123.500231 -90.711393) (xy 123.426881 -90.669044)
			(xy 123.357889 -90.619915) (xy 123.293879 -90.56445) (xy 123.235431 -90.503152) (xy 123.183075 -90.436576)
			(xy 123.137285 -90.365324) (xy 123.098474 -90.290043) (xy 123.066995 -90.211413) (xy 123.043134 -90.130146)
			(xy 123.027105 -90.04698) (xy 123.019054 -89.962666) (xy 123.01855 -89.920318) (xy 119.273857 -89.920318)
			(xy 119.294874 -89.934734) (xy 119.360954 -89.990185) (xy 119.421355 -90.051773) (xy 119.47551 -90.11892)
			(xy 119.522909 -90.190994) (xy 119.563109 -90.267319) (xy 119.59573 -90.347177) (xy 119.620466 -90.429818)
			(xy 119.637085 -90.514465) (xy 119.645431 -90.600324) (xy 119.645938 -90.643456) (xy 119.645434 -90.685804)
			(xy 119.637383 -90.770118) (xy 119.621354 -90.853284) (xy 119.597493 -90.934551) (xy 119.566014 -91.013181)
			(xy 119.527203 -91.088462) (xy 119.481413 -91.159714) (xy 119.429057 -91.22629) (xy 119.370609 -91.287588)
			(xy 119.306599 -91.343053) (xy 119.237607 -91.392182) (xy 119.164257 -91.434531) (xy 119.087214 -91.469715)
			(xy 119.007175 -91.497417) (xy 118.924866 -91.517385) (xy 118.841031 -91.529438) (xy 118.75643 -91.533469)
			(xy 118.671829 -91.529438) (xy 118.587994 -91.517385) (xy 118.505685 -91.497417) (xy 118.425646 -91.469715)
			(xy 118.348603 -91.434531) (xy 118.275253 -91.392182) (xy 118.206261 -91.343053) (xy 118.142251 -91.287588)
			(xy 118.083803 -91.22629) (xy 118.031447 -91.159714) (xy 117.985657 -91.088462) (xy 117.946846 -91.013181)
			(xy 117.915367 -90.934551) (xy 117.891506 -90.853284) (xy 117.875477 -90.770118) (xy 117.867426 -90.685804)
			(xy 117.866922 -90.643456) (xy 95.177667 -90.643456) (xy 93.971948 -92.0254) (xy 123.677422 -92.0254)
			(xy 123.677422 -91.940704) (xy 123.685473 -91.85639) (xy 123.701502 -91.773224) (xy 123.725363 -91.691957)
			(xy 123.756842 -91.613327) (xy 123.795653 -91.538046) (xy 123.841443 -91.466794) (xy 123.893799 -91.400218)
			(xy 123.952247 -91.33892) (xy 124.016257 -91.283455) (xy 124.085249 -91.234326) (xy 124.158599 -91.191977)
			(xy 124.235642 -91.156793) (xy 124.315681 -91.129091) (xy 124.39799 -91.109123) (xy 124.481825 -91.09707)
			(xy 124.566426 -91.09304) (xy 124.651027 -91.09707) (xy 124.734862 -91.109123) (xy 124.817171 -91.129091)
			(xy 124.89721 -91.156793) (xy 124.974253 -91.191977) (xy 125.047603 -91.234326) (xy 125.116595 -91.283455)
			(xy 125.180605 -91.33892) (xy 125.239053 -91.400218) (xy 125.291409 -91.466794) (xy 125.337199 -91.538046)
			(xy 125.37601 -91.613327) (xy 125.407489 -91.691957) (xy 125.43135 -91.773224) (xy 125.447379 -91.85639)
			(xy 125.45543 -91.940704) (xy 125.455934 -91.983052) (xy 125.45543 -92.0254) (xy 125.447379 -92.109714)
			(xy 125.43135 -92.19288) (xy 125.407489 -92.274147) (xy 125.37601 -92.352777) (xy 125.337199 -92.428058)
			(xy 125.291409 -92.49931) (xy 125.239053 -92.565886) (xy 125.180605 -92.627184) (xy 125.116595 -92.682649)
			(xy 125.047603 -92.731778) (xy 124.974253 -92.774127) (xy 124.89721 -92.809311) (xy 124.817171 -92.837013)
			(xy 124.734862 -92.856981) (xy 124.651027 -92.869034) (xy 124.566426 -92.873065) (xy 124.481825 -92.869034)
			(xy 124.39799 -92.856981) (xy 124.315681 -92.837013) (xy 124.235642 -92.809311) (xy 124.158599 -92.774127)
			(xy 124.085249 -92.731778) (xy 124.016257 -92.682649) (xy 123.952247 -92.627184) (xy 123.893799 -92.565886)
			(xy 123.841443 -92.49931) (xy 123.795653 -92.428058) (xy 123.756842 -92.352777) (xy 123.725363 -92.274147)
			(xy 123.701502 -92.19288) (xy 123.685473 -92.109714) (xy 123.677422 -92.0254) (xy 93.971948 -92.0254)
			(xy 90.404188 -96.114616) (xy 90.40241 -96.117156) (xy 86.496144 -101.695758) (xy 86.491983 -101.70227)
			(xy 86.48732 -101.716994) (xy 86.487 -101.724714) (xy 86.487 -104.324658) (xy 86.487467 -104.334532)
			(xy 86.494921 -104.35282) (xy 86.501478 -104.360218) (xy 86.501732 -104.360472) (xy 87.378794 -105.237534)
			(xy 87.379302 -105.238042) (xy 87.386685 -105.244618) (xy 87.404985 -105.252052) (xy 87.414862 -105.25252)
		)
		(stroke
			(width 0)
			(type solid)
		)
		(fill yes)
		(layer "In6.Cu")
		(net "P12V_AUX")
	)
	(gr_poly
		(pts
			(xy 455.091038 -82.242406) (xy 455.098194 -82.240695) (xy 455.111211 -82.233853) (xy 455.116692 -82.228944)
			(xy 466.667342 -70.678294) (xy 466.672329 -70.672794) (xy 466.679172 -70.659628) (xy 466.680804 -70.652386)
			(xy 466.68182 -70.642734) (xy 466.68182 -54.22519) (xy 466.68182 -54.22265) (xy 466.680683 -54.211495)
			(xy 466.670179 -54.191716) (xy 466.652277 -54.178259) (xy 466.641434 -54.175406) (xy 466.640418 -54.175152)
			(xy 466.63864 -54.174898) (xy 466.562233 -54.167738) (xy 466.410251 -54.14634) (xy 466.259616 -54.116921)
			(xy 466.110751 -54.079564) (xy 465.964074 -54.034374) (xy 465.819997 -53.981477) (xy 465.678924 -53.921023)
			(xy 465.541252 -53.85318) (xy 465.407367 -53.778139) (xy 465.277645 -53.696112) (xy 465.15245 -53.607328)
			(xy 465.032134 -53.512037) (xy 464.917035 -53.410506) (xy 464.807476 -53.303021) (xy 464.703764 -53.189882)
			(xy 464.606192 -53.071409) (xy 464.515032 -52.947934) (xy 464.430541 -52.819802) (xy 464.352956 -52.687375)
			(xy 464.282495 -52.551025) (xy 464.219356 -52.411133) (xy 464.163716 -52.268092) (xy 464.115732 -52.122305)
			(xy 464.075537 -51.974181) (xy 464.043246 -51.824136) (xy 464.018948 -51.672591) (xy 464.002712 -51.519972)
			(xy 463.994583 -51.366706) (xy 463.993992 -51.289966) (xy 463.994468 -51.215253) (xy 464.002174 -51.066026)
			(xy 464.017565 -50.917395) (xy 464.040599 -50.769756) (xy 464.071215 -50.6235) (xy 464.109332 -50.479018)
			(xy 464.154848 -50.336693) (xy 464.207641 -50.196904) (xy 464.267573 -50.060024) (xy 464.334482 -49.926416)
			(xy 464.408192 -49.796435) (xy 464.488506 -49.670428) (xy 464.57521 -49.54873) (xy 464.668074 -49.431665)
			(xy 464.76685 -49.319543) (xy 464.871277 -49.212664) (xy 464.981075 -49.111311) (xy 465.095953 -49.015755)
			(xy 465.215606 -48.926249) (xy 465.339715 -48.843032) (xy 465.467949 -48.766325) (xy 465.53374 -48.730916)
			(xy 465.533994 -48.730916) (xy 465.539295 -48.727905) (xy 465.548419 -48.719826) (xy 465.552028 -48.714914)
			(xy 465.555076 -48.710596) (xy 465.55914 -48.699928) (xy 465.572094 -48.612806) (xy 465.573208 -48.600985)
			(xy 465.565804 -48.578457) (xy 465.55787 -48.569626) (xy 461.861408 -44.873164) (xy 461.850994 -44.869354)
			(xy 461.825247 -44.859394) (xy 461.776696 -44.833119) (xy 461.732439 -44.80012) (xy 461.693402 -44.761086)
			(xy 461.660399 -44.716832) (xy 461.63412 -44.668284) (xy 461.624172 -44.642532) (xy 461.620362 -44.632118)
			(xy 460.84363 -43.855386) (xy 460.839902 -43.851861) (xy 460.83133 -43.846225) (xy 460.826612 -43.84421)
			(xy 460.817976 -43.840654) (xy 443.24905 -43.840654) (xy 443.240362 -43.841009) (xy 443.224004 -43.846867)
			(xy 443.217046 -43.852084) (xy 443.213236 -43.855386) (xy 441.726828 -45.341794) (xy 441.719426 -45.34863)
			(xy 441.700828 -45.356339) (xy 441.69076 -45.35678) (xy 439.823606 -45.35678) (xy 439.814528 -45.357113)
			(xy 439.797487 -45.363372) (xy 439.790332 -45.368972) (xy 439.770552 -45.38923) (xy 439.726077 -45.424267)
			(xy 439.676914 -45.452348) (xy 439.624141 -45.472858) (xy 439.597186 -45.478954) (xy 450.958202 -45.478954)
			(xy 450.962273 -45.423332) (xy 450.974399 -45.368895) (xy 450.994322 -45.316804) (xy 451.021618 -45.268169)
			(xy 451.055704 -45.224026) (xy 451.095853 -45.185317) (xy 451.141211 -45.152866) (xy 451.190811 -45.127365)
			(xy 451.243595 -45.109358) (xy 451.298438 -45.099228) (xy 451.354172 -45.097191) (xy 451.409609 -45.103291)
			(xy 451.463566 -45.117397) (xy 451.514895 -45.139209) (xy 451.562501 -45.168263) (xy 451.605369 -45.203938)
			(xy 451.642586 -45.245475) (xy 451.673359 -45.291988) (xy 451.697031 -45.342485) (xy 451.713099 -45.395892)
			(xy 451.721219 -45.451068) (xy 451.721728 -45.478954) (xy 451.721219 -45.50684) (xy 451.713099 -45.562016)
			(xy 451.710808 -45.569632) (xy 451.974458 -45.569632) (xy 451.975199 -45.5367) (xy 451.986559 -45.47182)
			(xy 451.997064 -45.4406) (xy 452.000112 -45.432218) (xy 452.000112 -44.695618) (xy 452.000697 -44.667678)
			(xy 452.009452 -44.612487) (xy 452.02672 -44.55934) (xy 452.052075 -44.509543) (xy 452.084897 -44.464316)
			(xy 452.104252 -44.444158) (xy 452.32574 -44.22267) (xy 452.345922 -44.203289) (xy 452.39118 -44.170391)
			(xy 452.441022 -44.144968) (xy 452.494224 -44.127646) (xy 452.549479 -44.11885) (xy 452.577454 -44.118276)
			(xy 454.776078 -44.118276) (xy 454.804059 -44.118795) (xy 454.85933 -44.127568) (xy 454.912547 -44.144883)
			(xy 454.962397 -44.170316) (xy 455.007652 -44.203238) (xy 455.027792 -44.22267) (xy 455.689208 -44.884086)
			(xy 455.697336 -44.887896) (xy 455.720985 -44.899544) (xy 455.765133 -44.928353) (xy 455.804895 -44.962965)
			(xy 455.839513 -45.002722) (xy 455.848289 -45.016166) (xy 456.958698 -45.016166) (xy 456.962769 -44.960544)
			(xy 456.974895 -44.906107) (xy 456.994818 -44.854016) (xy 457.022114 -44.805381) (xy 457.0562 -44.761238)
			(xy 457.096349 -44.722529) (xy 457.141707 -44.690078) (xy 457.191307 -44.664577) (xy 457.244091 -44.64657)
			(xy 457.298934 -44.63644) (xy 457.354668 -44.634403) (xy 457.410105 -44.640503) (xy 457.464062 -44.654609)
			(xy 457.515391 -44.676421) (xy 457.562997 -44.705475) (xy 457.605865 -44.74115) (xy 457.643082 -44.782687)
			(xy 457.673855 -44.8292) (xy 457.697527 -44.879697) (xy 457.713595 -44.933104) (xy 457.721715 -44.98828)
			(xy 457.722224 -45.016166) (xy 457.721715 -45.044052) (xy 457.713595 -45.099228) (xy 457.697527 -45.152635)
			(xy 457.673855 -45.203132) (xy 457.643082 -45.249645) (xy 457.605865 -45.291182) (xy 457.562997 -45.326857)
			(xy 457.515391 -45.355911) (xy 457.464062 -45.377723) (xy 457.410105 -45.391829) (xy 457.354668 -45.397929)
			(xy 457.298934 -45.395892) (xy 457.244091 -45.385762) (xy 457.191307 -45.367755) (xy 457.141707 -45.342254)
			(xy 457.096349 -45.309803) (xy 457.0562 -45.271094) (xy 457.022114 -45.226951) (xy 456.994818 -45.178316)
			(xy 456.974895 -45.126225) (xy 456.962769 -45.071788) (xy 456.958698 -45.016166) (xy 455.848289 -45.016166)
			(xy 455.868328 -45.046866) (xy 455.879962 -45.070522) (xy 455.883772 -45.07865) (xy 456.799442 -45.994066)
			(xy 456.806838 -46.000912) (xy 456.82544 -46.008629) (xy 456.83551 -46.009052) (xy 461.105758 -46.009052)
			(xy 461.13319 -46.010068) (xy 461.144641 -46.010595) (xy 461.166069 -46.002515) (xy 461.174338 -45.994574)
			(xy 461.196436 -45.971206) (xy 461.203859 -45.962407) (xy 461.210856 -45.940513) (xy 461.209898 -45.929042)
			(xy 461.208238 -45.916152) (xy 461.206461 -45.890222) (xy 461.206342 -45.877226) (xy 461.206828 -45.849975)
			(xy 461.214584 -45.796027) (xy 461.229939 -45.743732) (xy 461.252581 -45.694155) (xy 461.282047 -45.648305)
			(xy 461.317738 -45.607114) (xy 461.358929 -45.571423) (xy 461.404779 -45.541957) (xy 461.454356 -45.519315)
			(xy 461.506651 -45.50396) (xy 461.560599 -45.496204) (xy 461.615101 -45.496204) (xy 461.669049 -45.50396)
			(xy 461.721344 -45.519315) (xy 461.770921 -45.541957) (xy 461.816771 -45.571423) (xy 461.857962 -45.607114)
			(xy 461.893653 -45.648305) (xy 461.923119 -45.694155) (xy 461.945761 -45.743732) (xy 461.961116 -45.796027)
			(xy 461.968872 -45.849975) (xy 461.969358 -45.877226) (xy 461.968869 -45.904319) (xy 461.961212 -45.957961)
			(xy 461.94604 -46.009979) (xy 461.923659 -46.059327) (xy 461.89452 -46.10501) (xy 461.859209 -46.146111)
			(xy 461.818437 -46.1818) (xy 461.773025 -46.21136) (xy 461.723887 -46.234197) (xy 461.698086 -46.242478)
			(xy 461.689805 -46.24537) (xy 461.675718 -46.255796) (xy 461.666 -46.270381) (xy 461.663542 -46.2788)
			(xy 461.642206 -46.363382) (xy 461.640435 -46.371968) (xy 461.642173 -46.389399) (xy 461.649706 -46.405215)
			(xy 461.655668 -46.411642) (xy 462.602326 -47.3583) (xy 462.621735 -47.378457) (xy 462.65463 -47.423721)
			(xy 462.680047 -47.473569) (xy 462.697362 -47.526777) (xy 462.706151 -47.582037) (xy 462.70672 -47.610014)
			(xy 462.70672 -53.591714) (xy 462.707133 -53.601785) (xy 462.714862 -53.620383) (xy 462.721706 -53.627782)
			(xy 463.445606 -54.351936) (xy 463.464981 -54.372124) (xy 463.497881 -54.417379) (xy 463.523305 -54.46722)
			(xy 463.540628 -54.520421) (xy 463.549426 -54.575675) (xy 463.55 -54.60365) (xy 463.55 -63.025274)
			(xy 463.549485 -63.053256) (xy 463.540713 -63.108527) (xy 463.523396 -63.161744) (xy 463.497963 -63.211594)
			(xy 463.465039 -63.256848) (xy 463.445606 -63.276988) (xy 459.47838 -67.244214) (xy 459.47457 -67.252342)
			(xy 459.462892 -67.276052) (xy 459.433959 -67.320282) (xy 459.416912 -67.34048) (xy 459.416658 -67.340734)
			(xy 459.411088 -67.347832) (xy 459.404832 -67.36474) (xy 459.404466 -67.373754) (xy 459.404466 -67.44081)
			(xy 459.404825 -67.449826) (xy 459.411072 -67.466743) (xy 459.416658 -67.47383) (xy 459.416912 -67.47383)
			(xy 459.416912 -67.474084) (xy 459.434533 -67.495032) (xy 459.464256 -67.540998) (xy 459.4871 -67.590742)
			(xy 459.502596 -67.643241) (xy 459.510425 -67.697417) (xy 459.510427 -67.752156) (xy 459.502602 -67.806332)
			(xy 459.48711 -67.858833) (xy 459.464269 -67.908578) (xy 459.43455 -67.954547) (xy 459.416912 -67.97548)
			(xy 459.416658 -67.975734) (xy 459.411088 -67.982832) (xy 459.404832 -67.99974) (xy 459.404466 -68.008754)
			(xy 459.404466 -68.07581) (xy 459.404825 -68.084826) (xy 459.411072 -68.101743) (xy 459.416658 -68.10883)
			(xy 459.416912 -68.10883) (xy 459.416912 -68.109084) (xy 459.434533 -68.130032) (xy 459.464256 -68.175998)
			(xy 459.4871 -68.225742) (xy 459.502596 -68.278241) (xy 459.510425 -68.332417) (xy 459.510427 -68.387156)
			(xy 459.502602 -68.441332) (xy 459.48711 -68.493833) (xy 459.464269 -68.543578) (xy 459.43455 -68.589547)
			(xy 459.416912 -68.61048) (xy 459.416658 -68.610734) (xy 459.411088 -68.617832) (xy 459.404832 -68.63474)
			(xy 459.404466 -68.643754) (xy 459.404466 -68.71081) (xy 459.404825 -68.719826) (xy 459.411072 -68.736743)
			(xy 459.416658 -68.74383) (xy 459.416912 -68.74383) (xy 459.416912 -68.744084) (xy 459.434559 -68.76501)
			(xy 459.464269 -68.810984) (xy 459.487103 -68.860734) (xy 459.502593 -68.913236) (xy 459.510419 -68.967412)
			(xy 459.510892 -68.994782) (xy 459.510406 -69.022033) (xy 459.50265 -69.075981) (xy 459.487295 -69.128276)
			(xy 459.464653 -69.177853) (xy 459.435187 -69.223703) (xy 459.399496 -69.264894) (xy 459.358305 -69.300585)
			(xy 459.312455 -69.330051) (xy 459.262878 -69.352693) (xy 459.210583 -69.368048) (xy 459.156635 -69.375804)
			(xy 459.102133 -69.375804) (xy 459.048185 -69.368048) (xy 458.99589 -69.352693) (xy 458.946313 -69.330051)
			(xy 458.900463 -69.300585) (xy 458.859272 -69.264894) (xy 458.823581 -69.223703) (xy 458.794115 -69.177853)
			(xy 458.771473 -69.128276) (xy 458.756118 -69.075981) (xy 458.748362 -69.022033) (xy 458.747876 -68.994782)
			(xy 458.748313 -68.967411) (xy 458.756135 -68.913229) (xy 458.77163 -68.860725) (xy 458.794479 -68.810979)
			(xy 458.824211 -68.765014) (xy 458.841856 -68.744084) (xy 458.84211 -68.74383) (xy 458.847691 -68.73674)
			(xy 458.853941 -68.719826) (xy 458.854302 -68.71081) (xy 458.854302 -68.643754) (xy 458.853918 -68.63474)
			(xy 458.847689 -68.617823) (xy 458.84211 -68.610734) (xy 458.841856 -68.610734) (xy 458.841856 -68.61048)
			(xy 458.824196 -68.589562) (xy 458.79447 -68.543592) (xy 458.771624 -68.493844) (xy 458.756128 -68.441339)
			(xy 458.7483 -68.387158) (xy 458.748302 -68.332415) (xy 458.756134 -68.278234) (xy 458.771634 -68.225731)
			(xy 458.794483 -68.175984) (xy 458.824213 -68.130016) (xy 458.841856 -68.109084) (xy 458.84211 -68.10883)
			(xy 458.847691 -68.10174) (xy 458.853941 -68.084826) (xy 458.854302 -68.07581) (xy 458.854302 -68.008754)
			(xy 458.853918 -67.99974) (xy 458.847689 -67.982823) (xy 458.84211 -67.975734) (xy 458.841856 -67.975734)
			(xy 458.841856 -67.97548) (xy 458.824196 -67.954562) (xy 458.79447 -67.908592) (xy 458.771624 -67.858844)
			(xy 458.756128 -67.806339) (xy 458.7483 -67.752158) (xy 458.748302 -67.697415) (xy 458.756134 -67.643234)
			(xy 458.771634 -67.590731) (xy 458.794483 -67.540984) (xy 458.824213 -67.495016) (xy 458.841856 -67.474084)
			(xy 458.84211 -67.47383) (xy 458.847691 -67.46674) (xy 458.853941 -67.449826) (xy 458.854302 -67.44081)
			(xy 458.854302 -67.373754) (xy 458.853918 -67.36474) (xy 458.847689 -67.347823) (xy 458.84211 -67.340734)
			(xy 458.841856 -67.340734) (xy 458.841856 -67.34048) (xy 458.824234 -67.319535) (xy 458.794521 -67.273565)
			(xy 458.771682 -67.223821) (xy 458.756187 -67.171323) (xy 458.748353 -67.11715) (xy 458.747876 -67.089782)
			(xy 458.748323 -67.062807) (xy 458.755913 -67.009394) (xy 458.770953 -66.957584) (xy 458.793144 -66.90841)
			(xy 458.822042 -66.862853) (xy 458.857071 -66.821822) (xy 458.897532 -66.786137) (xy 458.942618 -66.756508)
			(xy 458.966824 -66.744596) (xy 458.974952 -66.740786) (xy 462.822798 -62.892686) (xy 462.829636 -62.885285)
			(xy 462.837357 -62.866686) (xy 462.837784 -62.856618) (xy 462.837784 -54.772306) (xy 462.83736 -54.762237)
			(xy 462.829639 -54.743639) (xy 462.822798 -54.736238) (xy 462.098898 -54.012084) (xy 462.079485 -53.99193)
			(xy 462.04659 -53.946666) (xy 462.021173 -53.896817) (xy 462.003859 -53.843608) (xy 461.995072 -53.788347)
			(xy 461.994504 -53.76037) (xy 461.994504 -47.77867) (xy 461.99412 -47.768596) (xy 461.986373 -47.749997)
			(xy 461.979518 -47.742602) (xy 460.97317 -46.736254) (xy 460.96578 -46.729402) (xy 460.947173 -46.721691)
			(xy 460.937102 -46.721268) (xy 456.666854 -46.721268) (xy 456.638874 -46.720716) (xy 456.583605 -46.71195)
			(xy 456.530389 -46.694641) (xy 456.480539 -46.669216) (xy 456.435282 -46.636302) (xy 456.41514 -46.616874)
			(xy 455.380344 -45.582078) (xy 455.372216 -45.578268) (xy 455.34855 -45.566652) (xy 455.304404 -45.537835)
			(xy 455.264645 -45.503215) (xy 455.230031 -45.463451) (xy 455.201221 -45.419301) (xy 455.18959 -45.395642)
			(xy 455.18578 -45.387514) (xy 454.64349 -44.845478) (xy 454.63609 -44.838638) (xy 454.617491 -44.830919)
			(xy 454.607422 -44.830492) (xy 452.725028 -44.830492) (xy 452.719694 -44.835826) (xy 452.71182 -44.854368)
			(xy 452.71182 -45.432218) (xy 452.714868 -45.4406) (xy 452.725396 -45.471815) (xy 452.736761 -45.536697)
			(xy 452.737474 -45.569632) (xy 452.736988 -45.596883) (xy 452.729232 -45.650831) (xy 452.713877 -45.703126)
			(xy 452.691235 -45.752703) (xy 452.661769 -45.798553) (xy 452.626078 -45.839744) (xy 452.584887 -45.875435)
			(xy 452.539037 -45.904901) (xy 452.48946 -45.927543) (xy 452.437165 -45.942898) (xy 452.383217 -45.950654)
			(xy 452.328715 -45.950654) (xy 452.274767 -45.942898) (xy 452.222472 -45.927543) (xy 452.172895 -45.904901)
			(xy 452.127045 -45.875435) (xy 452.085854 -45.839744) (xy 452.050163 -45.798553) (xy 452.020697 -45.752703)
			(xy 451.998055 -45.703126) (xy 451.9827 -45.650831) (xy 451.974944 -45.596883) (xy 451.974458 -45.569632)
			(xy 451.710808 -45.569632) (xy 451.697031 -45.615423) (xy 451.673359 -45.66592) (xy 451.642586 -45.712433)
			(xy 451.605369 -45.75397) (xy 451.562501 -45.789645) (xy 451.514895 -45.818699) (xy 451.463566 -45.840511)
			(xy 451.409609 -45.854617) (xy 451.354172 -45.860717) (xy 451.298438 -45.85868) (xy 451.243595 -45.84855)
			(xy 451.190811 -45.830543) (xy 451.141211 -45.805042) (xy 451.095853 -45.772591) (xy 451.055704 -45.733882)
			(xy 451.021618 -45.689739) (xy 450.994322 -45.641104) (xy 450.974399 -45.589013) (xy 450.962273 -45.534576)
			(xy 450.958202 -45.478954) (xy 439.597186 -45.478954) (xy 439.568918 -45.485347) (xy 439.512456 -45.489541)
			(xy 439.455994 -45.485347) (xy 439.400771 -45.472858) (xy 439.347998 -45.452348) (xy 439.298835 -45.424267)
			(xy 439.25436 -45.38923) (xy 439.23458 -45.368972) (xy 439.227436 -45.36336) (xy 439.210385 -45.357127)
			(xy 439.201306 -45.35678) (xy 431.96383 -45.35678) (xy 431.955137 -45.357122) (xy 431.938764 -45.362962)
			(xy 431.931826 -45.36821) (xy 431.928016 -45.371512) (xy 430.273206 -47.026322) (xy 430.269684 -47.030052)
			(xy 430.264054 -47.038626) (xy 430.26203 -47.04334) (xy 430.258474 -47.051976) (xy 430.258474 -47.257462)
			(xy 452.986392 -47.257462) (xy 452.990463 -47.20184) (xy 453.002589 -47.147403) (xy 453.022512 -47.095312)
			(xy 453.049808 -47.046677) (xy 453.083894 -47.002534) (xy 453.124043 -46.963825) (xy 453.169401 -46.931374)
			(xy 453.219001 -46.905873) (xy 453.271785 -46.887866) (xy 453.326628 -46.877736) (xy 453.382362 -46.875699)
			(xy 453.437799 -46.881799) (xy 453.491756 -46.895905) (xy 453.543085 -46.917717) (xy 453.590691 -46.946771)
			(xy 453.633559 -46.982446) (xy 453.670776 -47.023983) (xy 453.701549 -47.070496) (xy 453.725221 -47.120993)
			(xy 453.741289 -47.1744) (xy 453.749409 -47.229576) (xy 453.749918 -47.257462) (xy 453.749409 -47.285348)
			(xy 453.741289 -47.340524) (xy 453.725221 -47.393931) (xy 453.701549 -47.444428) (xy 453.680726 -47.475902)
			(xy 457.470762 -47.475902) (xy 457.474833 -47.42028) (xy 457.486959 -47.365843) (xy 457.506882 -47.313752)
			(xy 457.534178 -47.265117) (xy 457.568264 -47.220974) (xy 457.608413 -47.182265) (xy 457.653771 -47.149814)
			(xy 457.703371 -47.124313) (xy 457.756155 -47.106306) (xy 457.810998 -47.096176) (xy 457.866732 -47.094139)
			(xy 457.922169 -47.100239) (xy 457.976126 -47.114345) (xy 458.027455 -47.136157) (xy 458.075061 -47.165211)
			(xy 458.117929 -47.200886) (xy 458.155146 -47.242423) (xy 458.185919 -47.288936) (xy 458.209591 -47.339433)
			(xy 458.225659 -47.39284) (xy 458.233779 -47.448016) (xy 458.23407 -47.463964) (xy 458.461362 -47.463964)
			(xy 458.465433 -47.408342) (xy 458.477559 -47.353905) (xy 458.497482 -47.301814) (xy 458.524778 -47.253179)
			(xy 458.558864 -47.209036) (xy 458.599013 -47.170327) (xy 458.644371 -47.137876) (xy 458.693971 -47.112375)
			(xy 458.746755 -47.094368) (xy 458.801598 -47.084238) (xy 458.857332 -47.082201) (xy 458.912769 -47.088301)
			(xy 458.966726 -47.102407) (xy 459.018055 -47.124219) (xy 459.065661 -47.153273) (xy 459.108529 -47.188948)
			(xy 459.145746 -47.230485) (xy 459.176519 -47.276998) (xy 459.200191 -47.327495) (xy 459.216259 -47.380902)
			(xy 459.224379 -47.436078) (xy 459.224888 -47.463964) (xy 459.224379 -47.49185) (xy 459.216259 -47.547026)
			(xy 459.200191 -47.600433) (xy 459.176519 -47.65093) (xy 459.145746 -47.697443) (xy 459.108529 -47.73898)
			(xy 459.065661 -47.774655) (xy 459.018055 -47.803709) (xy 458.966726 -47.825521) (xy 458.912769 -47.839627)
			(xy 458.857332 -47.845727) (xy 458.801598 -47.84369) (xy 458.746755 -47.83356) (xy 458.693971 -47.815553)
			(xy 458.644371 -47.790052) (xy 458.599013 -47.757601) (xy 458.558864 -47.718892) (xy 458.524778 -47.674749)
			(xy 458.497482 -47.626114) (xy 458.477559 -47.574023) (xy 458.465433 -47.519586) (xy 458.461362 -47.463964)
			(xy 458.23407 -47.463964) (xy 458.234288 -47.475902) (xy 458.233779 -47.503788) (xy 458.225659 -47.558964)
			(xy 458.209591 -47.612371) (xy 458.185919 -47.662868) (xy 458.155146 -47.709381) (xy 458.117929 -47.750918)
			(xy 458.075061 -47.786593) (xy 458.027455 -47.815647) (xy 457.976126 -47.837459) (xy 457.922169 -47.851565)
			(xy 457.866732 -47.857665) (xy 457.810998 -47.855628) (xy 457.756155 -47.845498) (xy 457.703371 -47.827491)
			(xy 457.653771 -47.80199) (xy 457.608413 -47.769539) (xy 457.568264 -47.73083) (xy 457.534178 -47.686687)
			(xy 457.506882 -47.638052) (xy 457.486959 -47.585961) (xy 457.474833 -47.531524) (xy 457.470762 -47.475902)
			(xy 453.680726 -47.475902) (xy 453.670776 -47.490941) (xy 453.633559 -47.532478) (xy 453.590691 -47.568153)
			(xy 453.543085 -47.597207) (xy 453.491756 -47.619019) (xy 453.437799 -47.633125) (xy 453.382362 -47.639225)
			(xy 453.326628 -47.637188) (xy 453.271785 -47.627058) (xy 453.219001 -47.609051) (xy 453.169401 -47.58355)
			(xy 453.124043 -47.551099) (xy 453.083894 -47.51239) (xy 453.049808 -47.468247) (xy 453.022512 -47.419612)
			(xy 453.002589 -47.367521) (xy 452.990463 -47.313084) (xy 452.986392 -47.257462) (xy 430.258474 -47.257462)
			(xy 430.258474 -49.333751) (xy 449.466958 -49.333751) (xy 449.466958 -49.279249) (xy 449.474714 -49.225301)
			(xy 449.490068 -49.173006) (xy 449.512708 -49.123428) (xy 449.542173 -49.077576) (xy 449.577864 -49.036385)
			(xy 449.619052 -49.000691) (xy 449.664901 -48.971223) (xy 449.714478 -48.948579) (xy 449.766771 -48.93322)
			(xy 449.820719 -48.92546) (xy 449.84797 -48.924972) (xy 449.87568 -48.925455) (xy 449.930515 -48.933487)
			(xy 449.983609 -48.949372) (xy 450.033845 -48.972775) (xy 450.080164 -49.003203) (xy 450.101208 -49.021238)
			(xy 450.10836 -49.027025) (xy 450.125545 -49.033545) (xy 450.134736 -49.033938) (xy 450.212206 -49.033938)
			(xy 450.229224 -49.027588) (xy 450.236336 -49.021238) (xy 450.257401 -49.003229) (xy 450.303712 -48.972794)
			(xy 450.353943 -48.949387) (xy 450.407034 -48.933501) (xy 450.461866 -48.925472) (xy 450.489574 -48.924972)
			(xy 450.516827 -48.925474) (xy 450.570778 -48.933227) (xy 450.623076 -48.94858) (xy 450.672657 -48.97122)
			(xy 450.718511 -49.000686) (xy 450.759704 -49.036377) (xy 450.763093 -49.040288) (xy 453.089262 -49.040288)
			(xy 453.093333 -48.984666) (xy 453.105459 -48.930229) (xy 453.125382 -48.878138) (xy 453.152678 -48.829503)
			(xy 453.186764 -48.78536) (xy 453.226913 -48.746651) (xy 453.272271 -48.7142) (xy 453.321871 -48.688699)
			(xy 453.374655 -48.670692) (xy 453.429498 -48.660562) (xy 453.485232 -48.658525) (xy 453.540669 -48.664625)
			(xy 453.594626 -48.678731) (xy 453.645955 -48.700543) (xy 453.693561 -48.729597) (xy 453.736429 -48.765272)
			(xy 453.773646 -48.806809) (xy 453.804419 -48.853322) (xy 453.828091 -48.903819) (xy 453.844159 -48.957226)
			(xy 453.852279 -49.012402) (xy 453.852788 -49.040288) (xy 453.852279 -49.068174) (xy 453.844159 -49.12335)
			(xy 453.828091 -49.176757) (xy 453.804419 -49.227254) (xy 453.773646 -49.273767) (xy 453.736429 -49.315304)
			(xy 453.693561 -49.350979) (xy 453.645955 -49.380033) (xy 453.594626 -49.401845) (xy 453.540669 -49.415951)
			(xy 453.485232 -49.422051) (xy 453.429498 -49.420014) (xy 453.374655 -49.409884) (xy 453.321871 -49.391877)
			(xy 453.272271 -49.366376) (xy 453.226913 -49.333925) (xy 453.186764 -49.295216) (xy 453.152678 -49.251073)
			(xy 453.125382 -49.202438) (xy 453.105459 -49.150347) (xy 453.093333 -49.09591) (xy 453.089262 -49.040288)
			(xy 450.763093 -49.040288) (xy 450.795399 -49.077569) (xy 450.824868 -49.123421) (xy 450.847511 -49.173)
			(xy 450.862867 -49.225297) (xy 450.870625 -49.279247) (xy 450.870625 -49.333753) (xy 450.862867 -49.387703)
			(xy 450.847511 -49.44) (xy 450.841324 -49.453546) (xy 460.176878 -49.453546) (xy 460.180949 -49.397924)
			(xy 460.193075 -49.343487) (xy 460.212998 -49.291396) (xy 460.240294 -49.242761) (xy 460.27438 -49.198618)
			(xy 460.314529 -49.159909) (xy 460.359887 -49.127458) (xy 460.409487 -49.101957) (xy 460.462271 -49.08395)
			(xy 460.517114 -49.07382) (xy 460.572848 -49.071783) (xy 460.628285 -49.077883) (xy 460.682242 -49.091989)
			(xy 460.733571 -49.113801) (xy 460.781177 -49.142855) (xy 460.824045 -49.17853) (xy 460.861262 -49.220067)
			(xy 460.892035 -49.26658) (xy 460.915707 -49.317077) (xy 460.931775 -49.370484) (xy 460.939895 -49.42566)
			(xy 460.940404 -49.453546) (xy 460.939895 -49.481432) (xy 460.931775 -49.536608) (xy 460.915707 -49.590015)
			(xy 460.892035 -49.640512) (xy 460.861262 -49.687025) (xy 460.824045 -49.728562) (xy 460.781177 -49.764237)
			(xy 460.733571 -49.793291) (xy 460.682242 -49.815103) (xy 460.628285 -49.829209) (xy 460.572848 -49.835309)
			(xy 460.517114 -49.833272) (xy 460.462271 -49.823142) (xy 460.409487 -49.805135) (xy 460.359887 -49.779634)
			(xy 460.314529 -49.747183) (xy 460.27438 -49.708474) (xy 460.240294 -49.664331) (xy 460.212998 -49.615696)
			(xy 460.193075 -49.563605) (xy 460.180949 -49.509168) (xy 460.176878 -49.453546) (xy 450.841324 -49.453546)
			(xy 450.824868 -49.489579) (xy 450.795399 -49.535431) (xy 450.759704 -49.576623) (xy 450.718511 -49.612314)
			(xy 450.672657 -49.64178) (xy 450.623076 -49.66442) (xy 450.570778 -49.679773) (xy 450.516827 -49.687526)
			(xy 450.489574 -49.687988) (xy 450.461865 -49.687489) (xy 450.40703 -49.679462) (xy 450.353935 -49.663582)
			(xy 450.303699 -49.640182) (xy 450.257379 -49.609756) (xy 450.236336 -49.591722) (xy 450.229196 -49.585918)
			(xy 450.212002 -49.579407) (xy 450.202808 -49.579022) (xy 450.125338 -49.579022) (xy 450.10832 -49.585372)
			(xy 450.101208 -49.591722) (xy 450.080173 -49.609767) (xy 450.033853 -49.640195) (xy 449.983614 -49.663594)
			(xy 449.930517 -49.679472) (xy 449.87568 -49.687493) (xy 449.84797 -49.687988) (xy 449.820719 -49.68754)
			(xy 449.766771 -49.67978) (xy 449.714478 -49.664421) (xy 449.664901 -49.641777) (xy 449.619052 -49.612309)
			(xy 449.577864 -49.576615) (xy 449.542173 -49.535424) (xy 449.512708 -49.489572) (xy 449.490068 -49.439994)
			(xy 449.474714 -49.387699) (xy 449.466958 -49.333751) (xy 430.258474 -49.333751) (xy 430.258474 -50.489796)
			(xy 431.237386 -50.489796) (xy 431.237386 -50.4051) (xy 431.245437 -50.320786) (xy 431.261466 -50.23762)
			(xy 431.285327 -50.156353) (xy 431.316806 -50.077723) (xy 431.355617 -50.002442) (xy 431.401407 -49.93119)
			(xy 431.453763 -49.864614) (xy 431.512211 -49.803316) (xy 431.576221 -49.747851) (xy 431.645213 -49.698722)
			(xy 431.718563 -49.656373) (xy 431.795606 -49.621189) (xy 431.875645 -49.593487) (xy 431.957954 -49.573519)
			(xy 432.041789 -49.561466) (xy 432.12639 -49.557436) (xy 432.210991 -49.561466) (xy 432.294826 -49.573519)
			(xy 432.377135 -49.593487) (xy 432.457174 -49.621189) (xy 432.534217 -49.656373) (xy 432.607567 -49.698722)
			(xy 432.676559 -49.747851) (xy 432.740569 -49.803316) (xy 432.799017 -49.864614) (xy 432.851373 -49.93119)
			(xy 432.897163 -50.002442) (xy 432.935974 -50.077723) (xy 432.967453 -50.156353) (xy 432.991314 -50.23762)
			(xy 433.007343 -50.320786) (xy 433.015394 -50.4051) (xy 433.015898 -50.447448) (xy 433.015394 -50.489796)
			(xy 438.952636 -50.489796) (xy 438.952636 -50.4051) (xy 438.960687 -50.320786) (xy 438.976716 -50.23762)
			(xy 439.000577 -50.156353) (xy 439.032056 -50.077723) (xy 439.070867 -50.002442) (xy 439.116657 -49.93119)
			(xy 439.169013 -49.864614) (xy 439.227461 -49.803316) (xy 439.291471 -49.747851) (xy 439.360463 -49.698722)
			(xy 439.433813 -49.656373) (xy 439.510856 -49.621189) (xy 439.590895 -49.593487) (xy 439.673204 -49.573519)
			(xy 439.757039 -49.561466) (xy 439.84164 -49.557436) (xy 439.926241 -49.561466) (xy 440.010076 -49.573519)
			(xy 440.092385 -49.593487) (xy 440.172424 -49.621189) (xy 440.249467 -49.656373) (xy 440.322817 -49.698722)
			(xy 440.391809 -49.747851) (xy 440.455819 -49.803316) (xy 440.514267 -49.864614) (xy 440.566623 -49.93119)
			(xy 440.612413 -50.002442) (xy 440.651224 -50.077723) (xy 440.682703 -50.156353) (xy 440.706564 -50.23762)
			(xy 440.721842 -50.316892) (xy 459.681578 -50.316892) (xy 459.685649 -50.26127) (xy 459.697775 -50.206833)
			(xy 459.717698 -50.154742) (xy 459.744994 -50.106107) (xy 459.77908 -50.061964) (xy 459.819229 -50.023255)
			(xy 459.864587 -49.990804) (xy 459.914187 -49.965303) (xy 459.966971 -49.947296) (xy 460.021814 -49.937166)
			(xy 460.077548 -49.935129) (xy 460.132985 -49.941229) (xy 460.186942 -49.955335) (xy 460.238271 -49.977147)
			(xy 460.285877 -50.006201) (xy 460.328745 -50.041876) (xy 460.365962 -50.083413) (xy 460.396735 -50.129926)
			(xy 460.420407 -50.180423) (xy 460.436475 -50.23383) (xy 460.444595 -50.289006) (xy 460.445104 -50.316892)
			(xy 460.444595 -50.344778) (xy 460.436475 -50.399954) (xy 460.420407 -50.453361) (xy 460.396735 -50.503858)
			(xy 460.365962 -50.550371) (xy 460.328745 -50.591908) (xy 460.285877 -50.627583) (xy 460.238271 -50.656637)
			(xy 460.186942 -50.678449) (xy 460.132985 -50.692555) (xy 460.077548 -50.698655) (xy 460.021814 -50.696618)
			(xy 459.966971 -50.686488) (xy 459.914187 -50.668481) (xy 459.864587 -50.64298) (xy 459.819229 -50.610529)
			(xy 459.77908 -50.57182) (xy 459.744994 -50.527677) (xy 459.717698 -50.479042) (xy 459.697775 -50.426951)
			(xy 459.685649 -50.372514) (xy 459.681578 -50.316892) (xy 440.721842 -50.316892) (xy 440.722593 -50.320786)
			(xy 440.730644 -50.4051) (xy 440.731148 -50.447448) (xy 440.730644 -50.489796) (xy 440.722593 -50.57411)
			(xy 440.706564 -50.657276) (xy 440.682703 -50.738543) (xy 440.651224 -50.817173) (xy 440.612413 -50.892454)
			(xy 440.566623 -50.963706) (xy 440.514267 -51.030282) (xy 440.455819 -51.09158) (xy 440.391809 -51.147045)
			(xy 440.322817 -51.196174) (xy 440.249467 -51.238523) (xy 440.172424 -51.273707) (xy 440.092385 -51.301409)
			(xy 440.010076 -51.321377) (xy 439.926241 -51.33343) (xy 439.84164 -51.337461) (xy 439.757039 -51.33343)
			(xy 439.673204 -51.321377) (xy 439.590895 -51.301409) (xy 439.510856 -51.273707) (xy 439.433813 -51.238523)
			(xy 439.360463 -51.196174) (xy 439.291471 -51.147045) (xy 439.227461 -51.09158) (xy 439.169013 -51.030282)
			(xy 439.116657 -50.963706) (xy 439.070867 -50.892454) (xy 439.032056 -50.817173) (xy 439.000577 -50.738543)
			(xy 438.976716 -50.657276) (xy 438.960687 -50.57411) (xy 438.952636 -50.489796) (xy 433.015394 -50.489796)
			(xy 433.007343 -50.57411) (xy 432.991314 -50.657276) (xy 432.967453 -50.738543) (xy 432.935974 -50.817173)
			(xy 432.897163 -50.892454) (xy 432.851373 -50.963706) (xy 432.799017 -51.030282) (xy 432.740569 -51.09158)
			(xy 432.676559 -51.147045) (xy 432.607567 -51.196174) (xy 432.534217 -51.238523) (xy 432.457174 -51.273707)
			(xy 432.377135 -51.301409) (xy 432.294826 -51.321377) (xy 432.210991 -51.33343) (xy 432.12639 -51.337461)
			(xy 432.041789 -51.33343) (xy 431.957954 -51.321377) (xy 431.875645 -51.301409) (xy 431.795606 -51.273707)
			(xy 431.718563 -51.238523) (xy 431.645213 -51.196174) (xy 431.576221 -51.147045) (xy 431.512211 -51.09158)
			(xy 431.453763 -51.030282) (xy 431.401407 -50.963706) (xy 431.355617 -50.892454) (xy 431.316806 -50.817173)
			(xy 431.285327 -50.738543) (xy 431.261466 -50.657276) (xy 431.245437 -50.57411) (xy 431.237386 -50.489796)
			(xy 430.258474 -50.489796) (xy 430.258474 -51.402053) (xy 445.516957 -51.402053) (xy 445.516957 -51.347547)
			(xy 445.524715 -51.293595) (xy 445.540071 -51.241296) (xy 445.562715 -51.191715) (xy 445.592184 -51.145861)
			(xy 445.62788 -51.104668) (xy 445.669074 -51.068975) (xy 445.714929 -51.039507) (xy 445.764511 -51.016866)
			(xy 445.81681 -51.001511) (xy 445.870763 -50.993756) (xy 445.898016 -50.993294) (xy 445.925725 -50.993804)
			(xy 445.980559 -51.001828) (xy 446.033653 -51.017707) (xy 446.08389 -51.041104) (xy 446.13021 -51.071527)
			(xy 446.151254 -51.08956) (xy 446.15839 -51.095369) (xy 446.175588 -51.101875) (xy 446.184782 -51.10226)
			(xy 446.262252 -51.10226) (xy 446.27927 -51.09591) (xy 446.286382 -51.08956) (xy 446.307418 -51.071517)
			(xy 446.353739 -51.041089) (xy 446.403977 -51.01769) (xy 446.457073 -51.001812) (xy 446.51191 -50.99379)
			(xy 446.53962 -50.993294) (xy 446.56687 -50.993777) (xy 446.620816 -51.001536) (xy 446.673109 -51.016893)
			(xy 446.722684 -51.039535) (xy 446.768532 -51.069002) (xy 446.80972 -51.104694) (xy 446.84541 -51.145884)
			(xy 446.874874 -51.191734) (xy 446.897514 -51.24131) (xy 446.912868 -51.293603) (xy 446.920624 -51.34755)
			(xy 446.920624 -51.40205) (xy 446.918324 -51.418049) (xy 447.310282 -51.418049) (xy 447.310282 -51.363551)
			(xy 447.318037 -51.309608) (xy 447.33339 -51.257317) (xy 447.356027 -51.207743) (xy 447.385489 -51.161895)
			(xy 447.421176 -51.120707) (xy 447.46236 -51.085016) (xy 447.508205 -51.055548) (xy 447.557776 -51.032905)
			(xy 447.610065 -51.017546) (xy 447.664007 -51.009785) (xy 447.691256 -51.009296) (xy 447.718966 -51.009781)
			(xy 447.773801 -51.017812) (xy 447.826895 -51.033696) (xy 447.877132 -51.057099) (xy 447.923451 -51.087527)
			(xy 447.944494 -51.105562) (xy 447.951648 -51.111346) (xy 447.968832 -51.117867) (xy 447.978022 -51.118262)
			(xy 448.055492 -51.118262) (xy 448.07251 -51.111912) (xy 448.079622 -51.105562) (xy 448.100643 -51.0875)
			(xy 448.146968 -51.057076) (xy 448.197209 -51.03368) (xy 448.25031 -51.017806) (xy 448.305149 -51.009789)
			(xy 448.33286 -51.009296) (xy 448.360115 -51.009749) (xy 448.414071 -51.017501) (xy 448.466374 -51.032854)
			(xy 448.51596 -51.055494) (xy 448.524452 -51.060951) (xy 449.047858 -51.060951) (xy 449.047858 -51.006449)
			(xy 449.055614 -50.952501) (xy 449.070968 -50.900206) (xy 449.093608 -50.850628) (xy 449.123073 -50.804776)
			(xy 449.158764 -50.763585) (xy 449.199952 -50.727891) (xy 449.245801 -50.698423) (xy 449.295378 -50.675779)
			(xy 449.347671 -50.66042) (xy 449.401619 -50.65266) (xy 449.42887 -50.652172) (xy 449.45658 -50.652655)
			(xy 449.511415 -50.660687) (xy 449.564509 -50.676572) (xy 449.614745 -50.699975) (xy 449.661064 -50.730403)
			(xy 449.682108 -50.748438) (xy 449.68926 -50.754225) (xy 449.706445 -50.760745) (xy 449.715636 -50.761138)
			(xy 449.793106 -50.761138) (xy 449.810124 -50.754788) (xy 449.817236 -50.748438) (xy 449.838301 -50.730429)
			(xy 449.884612 -50.699994) (xy 449.934843 -50.676587) (xy 449.987934 -50.660701) (xy 450.042766 -50.652672)
			(xy 450.070474 -50.652172) (xy 450.096709 -50.652656) (xy 450.148683 -50.659847) (xy 450.199181 -50.674097)
			(xy 450.247247 -50.695137) (xy 450.291975 -50.722569) (xy 450.332518 -50.755875) (xy 450.350636 -50.774854)
			(xy 450.357801 -50.781955) (xy 450.376138 -50.79033) (xy 450.386196 -50.79111) (xy 450.459094 -50.793142)
			(xy 450.469199 -50.793029) (xy 450.488061 -50.785822) (xy 450.49567 -50.779172) (xy 450.517104 -50.759388)
			(xy 450.564862 -50.725905) (xy 450.617157 -50.700074) (xy 450.672772 -50.682494) (xy 450.730413 -50.673576)
			(xy 450.759576 -50.673) (xy 450.787286 -50.673473) (xy 450.842122 -50.681506) (xy 450.895217 -50.697393)
			(xy 450.945453 -50.720799) (xy 450.991771 -50.75123) (xy 451.012814 -50.769266) (xy 451.019961 -50.775059)
			(xy 451.03715 -50.781574) (xy 451.046342 -50.781966) (xy 451.123812 -50.781966) (xy 451.14083 -50.775616)
			(xy 451.147942 -50.769266) (xy 451.168995 -50.751243) (xy 451.21531 -50.720812) (xy 451.265544 -50.697409)
			(xy 451.318637 -50.681526) (xy 451.373471 -50.673499) (xy 451.40118 -50.673) (xy 451.428434 -50.673446)
			(xy 451.482389 -50.681201) (xy 451.53469 -50.696555) (xy 451.584274 -50.719197) (xy 451.63013 -50.748665)
			(xy 451.671326 -50.78436) (xy 451.707023 -50.825554) (xy 451.736493 -50.871409) (xy 451.759138 -50.920991)
			(xy 451.774495 -50.973292) (xy 451.782253 -51.027246) (xy 451.782253 -51.081754) (xy 451.774495 -51.135708)
			(xy 451.759138 -51.188009) (xy 451.736493 -51.237591) (xy 451.707023 -51.283446) (xy 451.671326 -51.32464)
			(xy 451.63013 -51.360335) (xy 451.584274 -51.389803) (xy 451.53469 -51.412445) (xy 451.482389 -51.427799)
			(xy 451.428434 -51.435554) (xy 451.40118 -51.436016) (xy 451.373471 -51.435506) (xy 451.318637 -51.427481)
			(xy 451.265543 -51.411603) (xy 451.215307 -51.388206) (xy 451.168986 -51.357783) (xy 451.147942 -51.33975)
			(xy 451.140806 -51.33394) (xy 451.123608 -51.327435) (xy 451.114414 -51.32705) (xy 451.036944 -51.32705)
			(xy 451.019926 -51.3334) (xy 451.012814 -51.33975) (xy 450.99178 -51.357797) (xy 450.945459 -51.388223)
			(xy 450.895221 -51.411622) (xy 450.842123 -51.427499) (xy 450.787286 -51.435521) (xy 450.759576 -51.436016)
			(xy 450.73334 -51.435569) (xy 450.681364 -51.428371) (xy 450.630865 -51.414114) (xy 450.582799 -51.393067)
			(xy 450.538072 -51.365628) (xy 450.497531 -51.332316) (xy 450.479414 -51.313334) (xy 450.472233 -51.306252)
			(xy 450.453908 -51.297866) (xy 450.443854 -51.297078) (xy 450.370956 -51.295046) (xy 450.360849 -51.295135)
			(xy 450.341987 -51.302359) (xy 450.33438 -51.309016) (xy 450.312924 -51.328774) (xy 450.265171 -51.362261)
			(xy 450.212882 -51.388098) (xy 450.157272 -51.405683) (xy 450.099635 -51.414608) (xy 450.070474 -51.415188)
			(xy 450.042765 -51.414689) (xy 449.98793 -51.406662) (xy 449.934835 -51.390782) (xy 449.884599 -51.367382)
			(xy 449.838279 -51.336956) (xy 449.817236 -51.318922) (xy 449.810096 -51.313118) (xy 449.792902 -51.306607)
			(xy 449.783708 -51.306222) (xy 449.706238 -51.306222) (xy 449.68922 -51.312572) (xy 449.682108 -51.318922)
			(xy 449.661073 -51.336967) (xy 449.614753 -51.367395) (xy 449.564514 -51.390794) (xy 449.511417 -51.406672)
			(xy 449.45658 -51.414693) (xy 449.42887 -51.415188) (xy 449.401619 -51.41474) (xy 449.347671 -51.40698)
			(xy 449.295378 -51.391621) (xy 449.245801 -51.368977) (xy 449.199952 -51.339509) (xy 449.158764 -51.303815)
			(xy 449.123073 -51.262624) (xy 449.093608 -51.216772) (xy 449.070968 -51.167194) (xy 449.055614 -51.114899)
			(xy 449.047858 -51.060951) (xy 448.524452 -51.060951) (xy 448.561818 -51.084961) (xy 448.603016 -51.120655)
			(xy 448.638715 -51.16185) (xy 448.668187 -51.207705) (xy 448.690832 -51.257288) (xy 448.70619 -51.30959)
			(xy 448.713949 -51.363545) (xy 448.713949 -51.418055) (xy 448.70619 -51.47201) (xy 448.690832 -51.524312)
			(xy 448.668187 -51.573895) (xy 448.638715 -51.61975) (xy 448.603016 -51.660945) (xy 448.561818 -51.696639)
			(xy 448.51596 -51.726106) (xy 448.466374 -51.748746) (xy 448.414071 -51.764099) (xy 448.360115 -51.771851)
			(xy 448.33286 -51.772312) (xy 448.305151 -51.771815) (xy 448.250316 -51.763787) (xy 448.197222 -51.747906)
			(xy 448.146986 -51.724506) (xy 448.100666 -51.69408) (xy 448.079622 -51.676046) (xy 448.072493 -51.670227)
			(xy 448.05529 -51.663727) (xy 448.046094 -51.663346) (xy 447.968624 -51.663346) (xy 447.951606 -51.669696)
			(xy 447.944494 -51.676046) (xy 447.923468 -51.694101) (xy 447.877145 -51.724527) (xy 447.826904 -51.747924)
			(xy 447.773805 -51.763799) (xy 447.718967 -51.771818) (xy 447.691256 -51.772312) (xy 447.664007 -51.771815)
			(xy 447.610065 -51.764054) (xy 447.557776 -51.748695) (xy 447.508205 -51.726052) (xy 447.46236 -51.696584)
			(xy 447.421176 -51.660893) (xy 447.385489 -51.619705) (xy 447.356027 -51.573857) (xy 447.33339 -51.524283)
			(xy 447.318037 -51.471992) (xy 447.310282 -51.418049) (xy 446.918324 -51.418049) (xy 446.912868 -51.455997)
			(xy 446.897514 -51.50829) (xy 446.874874 -51.557866) (xy 446.84541 -51.603716) (xy 446.80972 -51.644906)
			(xy 446.768532 -51.680598) (xy 446.722684 -51.710065) (xy 446.673109 -51.732707) (xy 446.620816 -51.748064)
			(xy 446.56687 -51.755823) (xy 446.53962 -51.75631) (xy 446.51191 -51.755837) (xy 446.457074 -51.747803)
			(xy 446.40398 -51.731916) (xy 446.353744 -51.708511) (xy 446.307425 -51.67808) (xy 446.286382 -51.660044)
			(xy 446.279235 -51.65425) (xy 446.262046 -51.647735) (xy 446.252854 -51.647344) (xy 446.175384 -51.647344)
			(xy 446.158366 -51.653694) (xy 446.151254 -51.660044) (xy 446.130204 -51.678071) (xy 446.083888 -51.708501)
			(xy 446.033653 -51.731903) (xy 445.980559 -51.747785) (xy 445.925725 -51.755812) (xy 445.898016 -51.75631)
			(xy 445.870763 -51.755844) (xy 445.81681 -51.748089) (xy 445.764511 -51.732734) (xy 445.714929 -51.710093)
			(xy 445.669074 -51.680625) (xy 445.62788 -51.644932) (xy 445.592184 -51.603739) (xy 445.562715 -51.557885)
			(xy 445.540071 -51.508304) (xy 445.524715 -51.456005) (xy 445.516957 -51.402053) (xy 430.258474 -51.402053)
			(xy 430.258474 -53.04155) (xy 430.25949 -53.051456) (xy 430.260395 -53.055266) (xy 460.930242 -53.055266)
			(xy 460.934313 -52.999644) (xy 460.946439 -52.945207) (xy 460.966362 -52.893116) (xy 460.993658 -52.844481)
			(xy 461.027744 -52.800338) (xy 461.067893 -52.761629) (xy 461.113251 -52.729178) (xy 461.162851 -52.703677)
			(xy 461.215635 -52.68567) (xy 461.270478 -52.67554) (xy 461.326212 -52.673503) (xy 461.381649 -52.679603)
			(xy 461.435606 -52.693709) (xy 461.486935 -52.715521) (xy 461.534541 -52.744575) (xy 461.577409 -52.78025)
			(xy 461.614626 -52.821787) (xy 461.645399 -52.8683) (xy 461.669071 -52.918797) (xy 461.685139 -52.972204)
			(xy 461.693259 -53.02738) (xy 461.693768 -53.055266) (xy 461.693259 -53.083152) (xy 461.685139 -53.138328)
			(xy 461.669071 -53.191735) (xy 461.645399 -53.242232) (xy 461.614626 -53.288745) (xy 461.577409 -53.330282)
			(xy 461.534541 -53.365957) (xy 461.486935 -53.395011) (xy 461.435606 -53.416823) (xy 461.381649 -53.430929)
			(xy 461.326212 -53.437029) (xy 461.270478 -53.434992) (xy 461.215635 -53.424862) (xy 461.162851 -53.406855)
			(xy 461.113251 -53.381354) (xy 461.067893 -53.348903) (xy 461.027744 -53.310194) (xy 460.993658 -53.266051)
			(xy 460.966362 -53.217416) (xy 460.946439 -53.165325) (xy 460.934313 -53.110888) (xy 460.930242 -53.055266)
			(xy 430.260395 -53.055266) (xy 430.261191 -53.058617) (xy 430.268018 -53.071649) (xy 430.272952 -53.07711)
			(xy 438.496964 -61.301122) (xy 438.503811 -61.30852) (xy 438.511543 -61.327118) (xy 438.51195 -61.33719)
			(xy 438.51195 -68.527676) (xy 444.63208 -68.527676) (xy 444.632623 -68.49876) (xy 444.641342 -68.441588)
			(xy 444.658594 -68.386389) (xy 444.68398 -68.334426) (xy 444.716921 -68.286892) (xy 444.756661 -68.244876)
			(xy 444.779146 -68.226686) (xy 444.787957 -68.219083) (xy 444.798137 -68.198179) (xy 444.798704 -68.186554)
			(xy 444.798704 -68.106798) (xy 444.79815 -68.095168) (xy 444.787972 -68.074258) (xy 444.779146 -68.066666)
			(xy 444.756635 -68.048508) (xy 444.716904 -68.00648) (xy 444.68397 -67.958937) (xy 444.658587 -67.90697)
			(xy 444.641336 -67.851767) (xy 444.632612 -67.794594) (xy 444.63208 -67.765676) (xy 444.632555 -67.738425)
			(xy 444.640315 -67.684477) (xy 444.655672 -67.632183) (xy 444.678316 -67.582607) (xy 444.707783 -67.536757)
			(xy 444.743476 -67.495567) (xy 444.784666 -67.459876) (xy 444.830517 -67.43041) (xy 444.880094 -67.407768)
			(xy 444.932389 -67.392412) (xy 444.986337 -67.384655) (xy 445.013588 -67.384168) (xy 445.042506 -67.384669)
			(xy 445.099679 -67.393398) (xy 445.154879 -67.410658) (xy 445.206842 -67.436052) (xy 445.254375 -67.469)
			(xy 445.29639 -67.508746) (xy 445.314578 -67.531234) (xy 445.322199 -67.540027) (xy 445.343089 -67.550217)
			(xy 445.35471 -67.550792) (xy 445.434466 -67.550792) (xy 445.446094 -67.550222) (xy 445.467004 -67.540055)
			(xy 445.474598 -67.531234) (xy 445.491351 -67.510451) (xy 445.529705 -67.473321) (xy 445.572859 -67.441899)
			(xy 445.619973 -67.4168) (xy 445.670125 -67.398514) (xy 445.722336 -67.387397) (xy 445.775588 -67.383667)
			(xy 445.82884 -67.387397) (xy 445.881051 -67.398514) (xy 445.931203 -67.4168) (xy 445.978317 -67.441899)
			(xy 446.021471 -67.473321) (xy 446.059825 -67.510451) (xy 446.076578 -67.531234) (xy 446.084199 -67.540027)
			(xy 446.105089 -67.550217) (xy 446.11671 -67.550792) (xy 446.196466 -67.550792) (xy 446.208094 -67.550222)
			(xy 446.229004 -67.540055) (xy 446.236598 -67.531234) (xy 446.254799 -67.508759) (xy 446.296815 -67.469021)
			(xy 446.344348 -67.43608) (xy 446.396308 -67.41069) (xy 446.451504 -67.393433) (xy 446.508672 -67.384703)
			(xy 446.537588 -67.384168) (xy 446.564838 -67.384689) (xy 446.618783 -67.392444) (xy 446.671076 -67.407796)
			(xy 446.720651 -67.430434) (xy 446.7665 -67.459897) (xy 446.80769 -67.495584) (xy 446.843382 -67.536771)
			(xy 446.872849 -67.582617) (xy 446.895491 -67.632191) (xy 446.910849 -67.684482) (xy 446.918608 -67.738426)
			(xy 446.919096 -67.765676) (xy 446.918562 -67.794592) (xy 446.909836 -67.851763) (xy 446.892582 -67.906961)
			(xy 446.867193 -67.958923) (xy 446.834252 -68.006458) (xy 446.794514 -68.048475) (xy 446.77203 -68.066666)
			(xy 446.763237 -68.074286) (xy 446.753048 -68.095177) (xy 446.752472 -68.106798) (xy 446.752472 -68.186554)
			(xy 446.752969 -68.198192) (xy 446.763185 -68.219103) (xy 446.77203 -68.226686) (xy 446.794513 -68.244877)
			(xy 446.834247 -68.286898) (xy 446.867185 -68.334433) (xy 446.892573 -68.386394) (xy 446.90983 -68.441591)
			(xy 446.917662 -68.492878) (xy 447.058034 -68.492878) (xy 447.058596 -68.463963) (xy 447.067314 -68.406793)
			(xy 447.084562 -68.351594) (xy 447.109946 -68.299632) (xy 447.142883 -68.252097) (xy 447.182617 -68.210079)
			(xy 447.2051 -68.191888) (xy 447.213903 -68.184276) (xy 447.224089 -68.163379) (xy 447.224658 -68.151756)
			(xy 447.224658 -68.072) (xy 447.224119 -68.060368) (xy 447.213932 -68.039457) (xy 447.2051 -68.031868)
			(xy 447.182601 -68.013695) (xy 447.142867 -67.971672) (xy 447.10993 -67.924133) (xy 447.084544 -67.872168)
			(xy 447.067291 -67.816967) (xy 447.058567 -67.759795) (xy 447.058034 -67.730878) (xy 447.058435 -67.703623)
			(xy 447.066196 -67.649667) (xy 447.081557 -67.597366) (xy 447.104205 -67.547783) (xy 447.133679 -67.501927)
			(xy 447.169379 -67.460734) (xy 447.210579 -67.425041) (xy 447.256439 -67.395574) (xy 447.306026 -67.372934)
			(xy 447.35833 -67.357582) (xy 447.412287 -67.34983) (xy 447.439542 -67.34937) (xy 447.468459 -67.349904)
			(xy 447.52563 -67.358626) (xy 447.58083 -67.375879) (xy 447.632792 -67.401268) (xy 447.680326 -67.43421)
			(xy 447.722342 -67.473951) (xy 447.740532 -67.496436) (xy 447.748129 -67.505254) (xy 447.769038 -67.51543)
			(xy 447.780664 -67.515994) (xy 447.86042 -67.515994) (xy 447.872052 -67.515454) (xy 447.892961 -67.505266)
			(xy 447.900552 -67.496436) (xy 447.917305 -67.475653) (xy 447.955659 -67.438523) (xy 447.998813 -67.407101)
			(xy 448.045927 -67.382002) (xy 448.096079 -67.363716) (xy 448.14829 -67.352599) (xy 448.201542 -67.348869)
			(xy 448.254794 -67.352599) (xy 448.307005 -67.363716) (xy 448.357157 -67.382002) (xy 448.404271 -67.407101)
			(xy 448.447425 -67.438523) (xy 448.485779 -67.475653) (xy 448.502532 -67.496436) (xy 448.510129 -67.505254)
			(xy 448.531038 -67.51543) (xy 448.542664 -67.515994) (xy 448.62242 -67.515994) (xy 448.634052 -67.515454)
			(xy 448.654961 -67.505266) (xy 448.662552 -67.496436) (xy 448.680779 -67.473983) (xy 448.72279 -67.434244)
			(xy 448.770317 -67.401301) (xy 448.822272 -67.375907) (xy 448.877463 -67.358644) (xy 448.934628 -67.349908)
			(xy 448.963542 -67.34937) (xy 448.990793 -67.349839) (xy 449.04474 -67.3576) (xy 449.097034 -67.37296)
			(xy 449.14661 -67.395604) (xy 449.192459 -67.425073) (xy 449.233648 -67.460766) (xy 449.269339 -67.501957)
			(xy 449.298806 -67.547807) (xy 449.321447 -67.597385) (xy 449.336804 -67.649679) (xy 449.344563 -67.703627)
			(xy 449.34505 -67.730878) (xy 449.344535 -67.759795) (xy 449.335808 -67.816967) (xy 449.318551 -67.872167)
			(xy 449.293158 -67.924129) (xy 449.260213 -67.971663) (xy 449.220471 -68.013679) (xy 449.197984 -68.031868)
			(xy 449.189198 -68.039496) (xy 449.179003 -68.060381) (xy 449.178426 -68.072) (xy 449.178426 -68.151756)
			(xy 449.178938 -68.163392) (xy 449.189145 -68.184301) (xy 449.197984 -68.191888) (xy 449.220458 -68.21009)
			(xy 449.260195 -68.252107) (xy 449.293135 -68.299639) (xy 449.318526 -68.351599) (xy 449.335784 -68.406794)
			(xy 449.344514 -68.463963) (xy 449.34505 -68.492878) (xy 449.344501 -68.520127) (xy 449.336749 -68.57407)
			(xy 449.321399 -68.626361) (xy 449.298763 -68.675935) (xy 449.269303 -68.721784) (xy 449.233618 -68.762973)
			(xy 449.192435 -68.798665) (xy 449.146591 -68.828133) (xy 449.097021 -68.850776) (xy 449.044733 -68.866135)
			(xy 448.990791 -68.873897) (xy 448.963542 -68.874386) (xy 448.934626 -68.873843) (xy 448.877456 -68.86512)
			(xy 448.822257 -68.847867) (xy 448.770295 -68.82248) (xy 448.722761 -68.789541) (xy 448.680743 -68.749804)
			(xy 448.662552 -68.72732) (xy 448.65497 -68.718488) (xy 448.63405 -68.708321) (xy 448.62242 -68.707762)
			(xy 448.542664 -68.707762) (xy 448.531028 -68.708273) (xy 448.510118 -68.71848) (xy 448.502532 -68.72732)
			(xy 448.485779 -68.748103) (xy 448.447425 -68.785233) (xy 448.404271 -68.816655) (xy 448.357157 -68.841754)
			(xy 448.307005 -68.86004) (xy 448.254794 -68.871157) (xy 448.201542 -68.874887) (xy 448.14829 -68.871157)
			(xy 448.096079 -68.86004) (xy 448.045927 -68.841754) (xy 447.998813 -68.816655) (xy 447.955659 -68.785233)
			(xy 447.917305 -68.748103) (xy 447.900552 -68.72732) (xy 447.89297 -68.718488) (xy 447.87205 -68.708321)
			(xy 447.86042 -68.707762) (xy 447.780664 -68.707762) (xy 447.769028 -68.708273) (xy 447.748118 -68.71848)
			(xy 447.740532 -68.72732) (xy 447.722328 -68.749792) (xy 447.68031 -68.789527) (xy 447.632778 -68.822467)
			(xy 447.580819 -68.847857) (xy 447.525624 -68.865116) (xy 447.468457 -68.873849) (xy 447.439542 -68.874386)
			(xy 447.412289 -68.873906) (xy 447.358338 -68.866154) (xy 447.306039 -68.850802) (xy 447.256457 -68.828163)
			(xy 447.210603 -68.798697) (xy 447.169409 -68.763005) (xy 447.133715 -68.721813) (xy 447.104247 -68.67596)
			(xy 447.081605 -68.62638) (xy 447.066251 -68.574082) (xy 447.058496 -68.520131) (xy 447.058034 -68.492878)
			(xy 446.917662 -68.492878) (xy 446.91856 -68.49876) (xy 446.919096 -68.527676) (xy 446.918622 -68.554929)
			(xy 446.910868 -68.60888) (xy 446.895515 -68.661178) (xy 446.872874 -68.710759) (xy 446.843408 -68.756613)
			(xy 446.807715 -68.797806) (xy 446.766523 -68.8335) (xy 446.72067 -68.862968) (xy 446.67109 -68.885611)
			(xy 446.618792 -68.900966) (xy 446.564841 -68.908721) (xy 446.537588 -68.909184) (xy 446.508673 -68.908609)
			(xy 446.451504 -68.899892) (xy 446.396306 -68.882646) (xy 446.344344 -68.857265) (xy 446.296809 -68.824331)
			(xy 446.25479 -68.784599) (xy 446.236598 -68.762118) (xy 446.228996 -68.753306) (xy 446.208091 -68.743128)
			(xy 446.196466 -68.74256) (xy 446.11671 -68.74256) (xy 446.105077 -68.743098) (xy 446.084167 -68.753286)
			(xy 446.076578 -68.762118) (xy 446.059825 -68.782901) (xy 446.021471 -68.820031) (xy 445.978317 -68.851453)
			(xy 445.931203 -68.876552) (xy 445.881051 -68.894838) (xy 445.82884 -68.905955) (xy 445.775588 -68.909685)
			(xy 445.722336 -68.905955) (xy 445.670125 -68.894838) (xy 445.619973 -68.876552) (xy 445.572859 -68.851453)
			(xy 445.529705 -68.820031) (xy 445.491351 -68.782901) (xy 445.474598 -68.762118) (xy 445.466996 -68.753306)
			(xy 445.446091 -68.743128) (xy 445.434466 -68.74256) (xy 445.35471 -68.74256) (xy 445.343077 -68.743098)
			(xy 445.322167 -68.753286) (xy 445.314578 -68.762118) (xy 445.296404 -68.784616) (xy 445.25438 -68.824349)
			(xy 445.206842 -68.857286) (xy 445.154877 -68.882672) (xy 445.099677 -68.899925) (xy 445.042505 -68.908651)
			(xy 445.013588 -68.909184) (xy 444.986334 -68.908756) (xy 444.93238 -68.900997) (xy 444.88008 -68.885638)
			(xy 444.830498 -68.862993) (xy 444.784644 -68.833521) (xy 444.743451 -68.797824) (xy 444.707757 -68.756627)
			(xy 444.67829 -68.71077) (xy 444.655649 -68.661186) (xy 444.640295 -68.608885) (xy 444.632541 -68.55493)
			(xy 444.63208 -68.527676) (xy 438.51195 -68.527676) (xy 438.51195 -69.003164) (xy 450.629274 -69.003164)
			(xy 450.629701 -68.975792) (xy 450.637525 -68.921611) (xy 450.653023 -68.869106) (xy 450.675874 -68.81936)
			(xy 450.705608 -68.773396) (xy 450.723254 -68.752466) (xy 450.723508 -68.752212) (xy 450.729097 -68.745127)
			(xy 450.735342 -68.728209) (xy 450.7357 -68.719192) (xy 450.7357 -68.652136) (xy 450.735326 -68.643121)
			(xy 450.72909 -68.626204) (xy 450.723508 -68.619116) (xy 450.723254 -68.619116) (xy 450.723254 -68.618862)
			(xy 450.705577 -68.597958) (xy 450.675852 -68.551986) (xy 450.653007 -68.502235) (xy 450.637512 -68.449729)
			(xy 450.629686 -68.395546) (xy 450.62969 -68.3408) (xy 450.637524 -68.286618) (xy 450.653026 -68.234114)
			(xy 450.675878 -68.184366) (xy 450.70561 -68.138398) (xy 450.723254 -68.117466) (xy 450.723508 -68.117212)
			(xy 450.729097 -68.110127) (xy 450.735342 -68.093209) (xy 450.7357 -68.084192) (xy 450.7357 -68.017136)
			(xy 450.735326 -68.008121) (xy 450.72909 -67.991204) (xy 450.723508 -67.984116) (xy 450.723254 -67.984116)
			(xy 450.723254 -67.983862) (xy 450.705577 -67.962958) (xy 450.675852 -67.916986) (xy 450.653007 -67.867235)
			(xy 450.637512 -67.814729) (xy 450.629686 -67.760546) (xy 450.62969 -67.7058) (xy 450.637524 -67.651618)
			(xy 450.653026 -67.599114) (xy 450.675878 -67.549366) (xy 450.70561 -67.503398) (xy 450.723254 -67.482466)
			(xy 450.723508 -67.482212) (xy 450.729097 -67.475127) (xy 450.735342 -67.458209) (xy 450.7357 -67.449192)
			(xy 450.7357 -67.382136) (xy 450.735326 -67.373121) (xy 450.72909 -67.356204) (xy 450.723508 -67.349116)
			(xy 450.723254 -67.349116) (xy 450.723254 -67.348862) (xy 450.705577 -67.327958) (xy 450.675852 -67.281986)
			(xy 450.653007 -67.232235) (xy 450.637512 -67.179729) (xy 450.629686 -67.125546) (xy 450.62969 -67.0708)
			(xy 450.637524 -67.016618) (xy 450.653026 -66.964114) (xy 450.675878 -66.914366) (xy 450.70561 -66.868398)
			(xy 450.723254 -66.847466) (xy 450.723508 -66.847212) (xy 450.729097 -66.840127) (xy 450.735342 -66.823209)
			(xy 450.7357 -66.814192) (xy 450.7357 -66.747136) (xy 450.735326 -66.738121) (xy 450.72909 -66.721204)
			(xy 450.723508 -66.714116) (xy 450.723254 -66.714116) (xy 450.723254 -66.713862) (xy 450.705639 -66.69291)
			(xy 450.675922 -66.646944) (xy 450.65308 -66.597201) (xy 450.637584 -66.544705) (xy 450.62975 -66.490532)
			(xy 450.629274 -66.463164) (xy 450.629744 -66.435913) (xy 450.637505 -66.381965) (xy 450.652864 -66.329671)
			(xy 450.675508 -66.280095) (xy 450.704976 -66.234246) (xy 450.740669 -66.193057) (xy 450.78186 -66.157366)
			(xy 450.827711 -66.127899) (xy 450.877288 -66.105258) (xy 450.929583 -66.089901) (xy 450.983531 -66.082143)
			(xy 451.010782 -66.081656) (xy 451.037266 -66.082125) (xy 451.089726 -66.089444) (xy 451.140667 -66.103956)
			(xy 451.189108 -66.125383) (xy 451.234115 -66.153311) (xy 451.274821 -66.187202) (xy 451.310442 -66.226404)
			(xy 451.325742 -66.248026) (xy 451.325996 -66.24828) (xy 451.333593 -66.258166) (xy 451.355703 -66.269623)
			(xy 451.36816 -66.270124) (xy 451.465696 -66.269108) (xy 451.487794 -66.256916) (xy 451.494652 -66.246248)
			(xy 451.509819 -66.223831) (xy 451.545524 -66.183154) (xy 451.586616 -66.147929) (xy 451.632272 -66.118861)
			(xy 451.681577 -66.096533) (xy 451.733541 -66.081394) (xy 451.787122 -66.073747) (xy 451.814184 -66.073274)
			(xy 451.841434 -66.073793) (xy 451.89538 -66.081547) (xy 451.947673 -66.096899) (xy 451.997248 -66.119537)
			(xy 452.043098 -66.149) (xy 452.084288 -66.184688) (xy 452.11998 -66.225875) (xy 452.149447 -66.271722)
			(xy 452.172089 -66.321296) (xy 452.187446 -66.373587) (xy 452.195204 -66.427532) (xy 452.195692 -66.454782)
			(xy 452.195217 -66.482152) (xy 452.187402 -66.536331) (xy 452.171915 -66.588834) (xy 452.149075 -66.638581)
			(xy 452.119352 -66.684548) (xy 452.101712 -66.70548) (xy 452.101458 -66.705734) (xy 452.095888 -66.712832)
			(xy 452.089632 -66.72974) (xy 452.089266 -66.738754) (xy 452.089266 -66.80581) (xy 452.089625 -66.814826)
			(xy 452.095872 -66.831743) (xy 452.101458 -66.83883) (xy 452.101712 -66.83883) (xy 452.101712 -66.839084)
			(xy 452.119333 -66.860032) (xy 452.149056 -66.905998) (xy 452.1719 -66.955742) (xy 452.187396 -67.008241)
			(xy 452.195225 -67.062417) (xy 452.195227 -67.117156) (xy 452.187402 -67.171332) (xy 452.17191 -67.223833)
			(xy 452.149069 -67.273578) (xy 452.11935 -67.319547) (xy 452.101712 -67.34048) (xy 452.101458 -67.340734)
			(xy 452.095888 -67.347832) (xy 452.089632 -67.36474) (xy 452.089266 -67.373754) (xy 452.089266 -67.44081)
			(xy 452.089625 -67.449826) (xy 452.095872 -67.466743) (xy 452.101458 -67.47383) (xy 452.101712 -67.47383)
			(xy 452.101712 -67.474084) (xy 452.119333 -67.495032) (xy 452.149056 -67.540998) (xy 452.1719 -67.590742)
			(xy 452.187396 -67.643241) (xy 452.195225 -67.697417) (xy 452.195227 -67.752156) (xy 452.187402 -67.806332)
			(xy 452.17191 -67.858833) (xy 452.149069 -67.908578) (xy 452.11935 -67.954547) (xy 452.101712 -67.97548)
			(xy 452.101458 -67.975734) (xy 452.095888 -67.982832) (xy 452.089632 -67.99974) (xy 452.089266 -68.008754)
			(xy 452.089266 -68.07581) (xy 452.089625 -68.084826) (xy 452.095872 -68.101743) (xy 452.101458 -68.10883)
			(xy 452.101712 -68.10883) (xy 452.101712 -68.109084) (xy 452.119333 -68.130032) (xy 452.149056 -68.175998)
			(xy 452.1719 -68.225742) (xy 452.187396 -68.278241) (xy 452.195225 -68.332417) (xy 452.195227 -68.387156)
			(xy 452.187402 -68.441332) (xy 452.17191 -68.493833) (xy 452.149069 -68.543578) (xy 452.11935 -68.589547)
			(xy 452.101712 -68.61048) (xy 452.101458 -68.610734) (xy 452.095888 -68.617832) (xy 452.089632 -68.63474)
			(xy 452.089266 -68.643754) (xy 452.089266 -68.71081) (xy 452.089625 -68.719826) (xy 452.095872 -68.736743)
			(xy 452.101458 -68.74383) (xy 452.101712 -68.74383) (xy 452.101712 -68.744084) (xy 452.119359 -68.76501)
			(xy 452.149069 -68.810984) (xy 452.171903 -68.860734) (xy 452.187393 -68.913236) (xy 452.195219 -68.967412)
			(xy 452.195692 -68.994782) (xy 452.728076 -68.994782) (xy 452.728513 -68.967411) (xy 452.736335 -68.913229)
			(xy 452.75183 -68.860725) (xy 452.774679 -68.810979) (xy 452.804411 -68.765014) (xy 452.822056 -68.744084)
			(xy 452.82231 -68.74383) (xy 452.827891 -68.73674) (xy 452.834141 -68.719826) (xy 452.834502 -68.71081)
			(xy 452.834502 -68.643754) (xy 452.834118 -68.63474) (xy 452.827889 -68.617823) (xy 452.82231 -68.610734)
			(xy 452.822056 -68.610734) (xy 452.822056 -68.61048) (xy 452.804396 -68.589562) (xy 452.77467 -68.543592)
			(xy 452.751824 -68.493844) (xy 452.736328 -68.441339) (xy 452.7285 -68.387158) (xy 452.728502 -68.332415)
			(xy 452.736334 -68.278234) (xy 452.751834 -68.225731) (xy 452.774683 -68.175984) (xy 452.804413 -68.130016)
			(xy 452.822056 -68.109084) (xy 452.82231 -68.10883) (xy 452.827891 -68.10174) (xy 452.834141 -68.084826)
			(xy 452.834502 -68.07581) (xy 452.834502 -68.008754) (xy 452.834118 -67.99974) (xy 452.827889 -67.982823)
			(xy 452.82231 -67.975734) (xy 452.822056 -67.975734) (xy 452.822056 -67.97548) (xy 452.804434 -67.954535)
			(xy 452.774721 -67.908565) (xy 452.751882 -67.858821) (xy 452.736387 -67.806323) (xy 452.728553 -67.75215)
			(xy 452.728076 -67.724782) (xy 452.728562 -67.697531) (xy 452.736318 -67.643583) (xy 452.751673 -67.591288)
			(xy 452.774315 -67.541711) (xy 452.803781 -67.495861) (xy 452.839472 -67.45467) (xy 452.880663 -67.418979)
			(xy 452.926513 -67.389513) (xy 452.97609 -67.366871) (xy 453.028385 -67.351516) (xy 453.082333 -67.34376)
			(xy 453.136835 -67.34376) (xy 453.190783 -67.351516) (xy 453.243078 -67.366871) (xy 453.292655 -67.389513)
			(xy 453.338505 -67.418979) (xy 453.379696 -67.45467) (xy 453.415387 -67.495861) (xy 453.444853 -67.541711)
			(xy 453.467495 -67.591288) (xy 453.48285 -67.643583) (xy 453.490606 -67.697531) (xy 453.491092 -67.724782)
			(xy 453.490617 -67.752152) (xy 453.482802 -67.806331) (xy 453.467315 -67.858834) (xy 453.444475 -67.908581)
			(xy 453.414752 -67.954548) (xy 453.397112 -67.97548) (xy 453.396858 -67.975734) (xy 453.391288 -67.982832)
			(xy 453.385032 -67.99974) (xy 453.384666 -68.008754) (xy 453.384666 -68.07581) (xy 453.385025 -68.084826)
			(xy 453.391272 -68.101743) (xy 453.396858 -68.10883) (xy 453.397112 -68.10883) (xy 453.397112 -68.109084)
			(xy 453.414733 -68.130032) (xy 453.444456 -68.175998) (xy 453.4673 -68.225742) (xy 453.482796 -68.278241)
			(xy 453.490625 -68.332417) (xy 453.490627 -68.387156) (xy 453.482802 -68.441332) (xy 453.46731 -68.493833)
			(xy 453.444469 -68.543578) (xy 453.41475 -68.589547) (xy 453.397112 -68.61048) (xy 453.396858 -68.610734)
			(xy 453.391288 -68.617832) (xy 453.385032 -68.63474) (xy 453.384666 -68.643754) (xy 453.384666 -68.71081)
			(xy 453.385025 -68.719826) (xy 453.391272 -68.736743) (xy 453.396858 -68.74383) (xy 453.397112 -68.74383)
			(xy 453.397112 -68.744084) (xy 453.414759 -68.76501) (xy 453.444469 -68.810984) (xy 453.467303 -68.860734)
			(xy 453.482793 -68.913236) (xy 453.490619 -68.967412) (xy 453.491092 -68.994782) (xy 453.490606 -69.022033)
			(xy 453.48285 -69.075981) (xy 453.467495 -69.128276) (xy 453.444853 -69.177853) (xy 453.415387 -69.223703)
			(xy 453.379696 -69.264894) (xy 453.338505 -69.300585) (xy 453.292655 -69.330051) (xy 453.243078 -69.352693)
			(xy 453.190783 -69.368048) (xy 453.136835 -69.375804) (xy 453.082333 -69.375804) (xy 453.028385 -69.368048)
			(xy 452.97609 -69.352693) (xy 452.926513 -69.330051) (xy 452.880663 -69.300585) (xy 452.839472 -69.264894)
			(xy 452.803781 -69.223703) (xy 452.774315 -69.177853) (xy 452.751673 -69.128276) (xy 452.736318 -69.075981)
			(xy 452.728562 -69.022033) (xy 452.728076 -68.994782) (xy 452.195692 -68.994782) (xy 452.195228 -69.022035)
			(xy 452.187473 -69.075987) (xy 452.172118 -69.128286) (xy 452.149477 -69.177867) (xy 452.120009 -69.223721)
			(xy 452.084315 -69.264914) (xy 452.043122 -69.300608) (xy 451.997269 -69.330076) (xy 451.947688 -69.352718)
			(xy 451.895389 -69.368073) (xy 451.841437 -69.375828) (xy 451.814184 -69.37629) (xy 451.7877 -69.375826)
			(xy 451.735241 -69.368504) (xy 451.6843 -69.353989) (xy 451.63586 -69.332561) (xy 451.590853 -69.304633)
			(xy 451.550147 -69.270742) (xy 451.514525 -69.231541) (xy 451.499224 -69.20992) (xy 451.49897 -69.209666)
			(xy 451.491381 -69.199772) (xy 451.469266 -69.188317) (xy 451.456806 -69.187822) (xy 451.35927 -69.188838)
			(xy 451.337172 -69.20103) (xy 451.330314 -69.211698) (xy 451.315087 -69.234072) (xy 451.279394 -69.274752)
			(xy 451.238313 -69.309983) (xy 451.192667 -69.339057) (xy 451.143372 -69.361391) (xy 451.091416 -69.376538)
			(xy 451.037841 -69.384194) (xy 451.010782 -69.384672) (xy 450.983527 -69.384262) (xy 450.929572 -69.376501)
			(xy 450.877271 -69.361141) (xy 450.827689 -69.338494) (xy 450.781834 -69.309021) (xy 450.74064 -69.273321)
			(xy 450.704947 -69.232123) (xy 450.67548 -69.186264) (xy 450.65284 -69.136678) (xy 450.637487 -69.084375)
			(xy 450.629734 -69.030419) (xy 450.629274 -69.003164) (xy 438.51195 -69.003164) (xy 438.51195 -69.722746)
			(xy 454.449178 -69.722746) (xy 454.453249 -69.667124) (xy 454.465375 -69.612687) (xy 454.485298 -69.560596)
			(xy 454.512594 -69.511961) (xy 454.54668 -69.467818) (xy 454.586829 -69.429109) (xy 454.632187 -69.396658)
			(xy 454.681787 -69.371157) (xy 454.734571 -69.35315) (xy 454.789414 -69.34302) (xy 454.845148 -69.340983)
			(xy 454.900585 -69.347083) (xy 454.954542 -69.361189) (xy 455.005871 -69.383001) (xy 455.053477 -69.412055)
			(xy 455.096345 -69.44773) (xy 455.133562 -69.489267) (xy 455.164335 -69.53578) (xy 455.188007 -69.586277)
			(xy 455.204075 -69.639684) (xy 455.212195 -69.69486) (xy 455.212704 -69.722746) (xy 455.338178 -69.722746)
			(xy 455.342249 -69.667124) (xy 455.354375 -69.612687) (xy 455.374298 -69.560596) (xy 455.401594 -69.511961)
			(xy 455.43568 -69.467818) (xy 455.475829 -69.429109) (xy 455.521187 -69.396658) (xy 455.570787 -69.371157)
			(xy 455.623571 -69.35315) (xy 455.678414 -69.34302) (xy 455.734148 -69.340983) (xy 455.789585 -69.347083)
			(xy 455.843542 -69.361189) (xy 455.894871 -69.383001) (xy 455.942477 -69.412055) (xy 455.985345 -69.44773)
			(xy 456.022562 -69.489267) (xy 456.053335 -69.53578) (xy 456.077007 -69.586277) (xy 456.093075 -69.639684)
			(xy 456.101195 -69.69486) (xy 456.101704 -69.722746) (xy 456.227178 -69.722746) (xy 456.231249 -69.667124)
			(xy 456.243375 -69.612687) (xy 456.263298 -69.560596) (xy 456.290594 -69.511961) (xy 456.32468 -69.467818)
			(xy 456.364829 -69.429109) (xy 456.410187 -69.396658) (xy 456.459787 -69.371157) (xy 456.512571 -69.35315)
			(xy 456.567414 -69.34302) (xy 456.623148 -69.340983) (xy 456.678585 -69.347083) (xy 456.732542 -69.361189)
			(xy 456.783871 -69.383001) (xy 456.831477 -69.412055) (xy 456.874345 -69.44773) (xy 456.911562 -69.489267)
			(xy 456.942335 -69.53578) (xy 456.966007 -69.586277) (xy 456.982075 -69.639684) (xy 456.990195 -69.69486)
			(xy 456.990704 -69.722746) (xy 457.116178 -69.722746) (xy 457.120249 -69.667124) (xy 457.132375 -69.612687)
			(xy 457.152298 -69.560596) (xy 457.179594 -69.511961) (xy 457.21368 -69.467818) (xy 457.253829 -69.429109)
			(xy 457.299187 -69.396658) (xy 457.348787 -69.371157) (xy 457.401571 -69.35315) (xy 457.456414 -69.34302)
			(xy 457.512148 -69.340983) (xy 457.567585 -69.347083) (xy 457.621542 -69.361189) (xy 457.672871 -69.383001)
			(xy 457.720477 -69.412055) (xy 457.763345 -69.44773) (xy 457.800562 -69.489267) (xy 457.831335 -69.53578)
			(xy 457.855007 -69.586277) (xy 457.871075 -69.639684) (xy 457.879195 -69.69486) (xy 457.879704 -69.722746)
			(xy 457.879195 -69.750632) (xy 457.871075 -69.805808) (xy 457.855007 -69.859215) (xy 457.831335 -69.909712)
			(xy 457.800562 -69.956225) (xy 457.763345 -69.997762) (xy 457.720477 -70.033437) (xy 457.672871 -70.062491)
			(xy 457.621542 -70.084303) (xy 457.567585 -70.098409) (xy 457.512148 -70.104509) (xy 457.456414 -70.102472)
			(xy 457.401571 -70.092342) (xy 457.348787 -70.074335) (xy 457.299187 -70.048834) (xy 457.253829 -70.016383)
			(xy 457.21368 -69.977674) (xy 457.179594 -69.933531) (xy 457.152298 -69.884896) (xy 457.132375 -69.832805)
			(xy 457.120249 -69.778368) (xy 457.116178 -69.722746) (xy 456.990704 -69.722746) (xy 456.990195 -69.750632)
			(xy 456.982075 -69.805808) (xy 456.966007 -69.859215) (xy 456.942335 -69.909712) (xy 456.911562 -69.956225)
			(xy 456.874345 -69.997762) (xy 456.831477 -70.033437) (xy 456.783871 -70.062491) (xy 456.732542 -70.084303)
			(xy 456.678585 -70.098409) (xy 456.623148 -70.104509) (xy 456.567414 -70.102472) (xy 456.512571 -70.092342)
			(xy 456.459787 -70.074335) (xy 456.410187 -70.048834) (xy 456.364829 -70.016383) (xy 456.32468 -69.977674)
			(xy 456.290594 -69.933531) (xy 456.263298 -69.884896) (xy 456.243375 -69.832805) (xy 456.231249 -69.778368)
			(xy 456.227178 -69.722746) (xy 456.101704 -69.722746) (xy 456.101195 -69.750632) (xy 456.093075 -69.805808)
			(xy 456.077007 -69.859215) (xy 456.053335 -69.909712) (xy 456.022562 -69.956225) (xy 455.985345 -69.997762)
			(xy 455.942477 -70.033437) (xy 455.894871 -70.062491) (xy 455.843542 -70.084303) (xy 455.789585 -70.098409)
			(xy 455.734148 -70.104509) (xy 455.678414 -70.102472) (xy 455.623571 -70.092342) (xy 455.570787 -70.074335)
			(xy 455.521187 -70.048834) (xy 455.475829 -70.016383) (xy 455.43568 -69.977674) (xy 455.401594 -69.933531)
			(xy 455.374298 -69.884896) (xy 455.354375 -69.832805) (xy 455.342249 -69.778368) (xy 455.338178 -69.722746)
			(xy 455.212704 -69.722746) (xy 455.212195 -69.750632) (xy 455.204075 -69.805808) (xy 455.188007 -69.859215)
			(xy 455.164335 -69.909712) (xy 455.133562 -69.956225) (xy 455.096345 -69.997762) (xy 455.053477 -70.033437)
			(xy 455.005871 -70.062491) (xy 454.954542 -70.084303) (xy 454.900585 -70.098409) (xy 454.845148 -70.104509)
			(xy 454.789414 -70.102472) (xy 454.734571 -70.092342) (xy 454.681787 -70.074335) (xy 454.632187 -70.048834)
			(xy 454.586829 -70.016383) (xy 454.54668 -69.977674) (xy 454.512594 -69.933531) (xy 454.485298 -69.884896)
			(xy 454.465375 -69.832805) (xy 454.453249 -69.778368) (xy 454.449178 -69.722746) (xy 438.51195 -69.722746)
			(xy 438.51195 -71.592186) (xy 444.82258 -71.592186) (xy 444.82313 -71.56327) (xy 444.831848 -71.506099)
			(xy 444.849098 -71.450899) (xy 444.874483 -71.398937) (xy 444.907423 -71.351402) (xy 444.947162 -71.309386)
			(xy 444.969646 -71.291196) (xy 444.978453 -71.283589) (xy 444.988635 -71.262688) (xy 444.989204 -71.251064)
			(xy 444.989204 -71.171308) (xy 444.988645 -71.159679) (xy 444.97847 -71.138769) (xy 444.969646 -71.131176)
			(xy 444.94714 -71.113012) (xy 444.907408 -71.070985) (xy 444.874474 -71.023444) (xy 444.84909 -70.971478)
			(xy 444.831838 -70.916276) (xy 444.823113 -70.859103) (xy 444.82258 -70.830186) (xy 444.823065 -70.802935)
			(xy 444.830823 -70.748988) (xy 444.846179 -70.696694) (xy 444.868821 -70.647117) (xy 444.898288 -70.601268)
			(xy 444.933979 -70.560078) (xy 444.975169 -70.524386) (xy 445.021019 -70.49492) (xy 445.070596 -70.472278)
			(xy 445.12289 -70.456922) (xy 445.176837 -70.449165) (xy 445.204088 -70.448678) (xy 445.233006 -70.449175)
			(xy 445.29018 -70.457904) (xy 445.34538 -70.475165) (xy 445.397342 -70.50056) (xy 445.444876 -70.533509)
			(xy 445.48689 -70.573256) (xy 445.505078 -70.595744) (xy 445.512697 -70.604538) (xy 445.533589 -70.614727)
			(xy 445.54521 -70.615302) (xy 445.624966 -70.615302) (xy 445.636594 -70.614728) (xy 445.657503 -70.604564)
			(xy 445.665098 -70.595744) (xy 445.681851 -70.574961) (xy 445.720205 -70.537831) (xy 445.763359 -70.506409)
			(xy 445.810473 -70.48131) (xy 445.860625 -70.463024) (xy 445.912836 -70.451907) (xy 445.966088 -70.448177)
			(xy 446.01934 -70.451907) (xy 446.071551 -70.463024) (xy 446.121703 -70.48131) (xy 446.168817 -70.506409)
			(xy 446.211971 -70.537831) (xy 446.250325 -70.574961) (xy 446.267078 -70.595744) (xy 446.274697 -70.604538)
			(xy 446.295589 -70.614727) (xy 446.30721 -70.615302) (xy 446.386966 -70.615302) (xy 446.398594 -70.614728)
			(xy 446.419503 -70.604564) (xy 446.427098 -70.595744) (xy 446.443851 -70.574961) (xy 446.482205 -70.537831)
			(xy 446.525359 -70.506409) (xy 446.572473 -70.48131) (xy 446.622625 -70.463024) (xy 446.674836 -70.451907)
			(xy 446.728088 -70.448177) (xy 446.78134 -70.451907) (xy 446.833551 -70.463024) (xy 446.883703 -70.48131)
			(xy 446.930817 -70.506409) (xy 446.973971 -70.537831) (xy 447.012325 -70.574961) (xy 447.029078 -70.595744)
			(xy 447.036697 -70.604538) (xy 447.057589 -70.614727) (xy 447.06921 -70.615302) (xy 447.148966 -70.615302)
			(xy 447.160594 -70.614728) (xy 447.181503 -70.604564) (xy 447.189098 -70.595744) (xy 447.207301 -70.573271)
			(xy 447.249317 -70.533533) (xy 447.296849 -70.500591) (xy 447.348808 -70.475201) (xy 447.404004 -70.457943)
			(xy 447.461173 -70.449213) (xy 447.490088 -70.448678) (xy 447.517338 -70.449189) (xy 447.571284 -70.456944)
			(xy 447.623578 -70.472297) (xy 447.673154 -70.494935) (xy 447.719004 -70.524399) (xy 447.760194 -70.560088)
			(xy 447.795885 -70.601276) (xy 447.825352 -70.647123) (xy 447.847994 -70.696698) (xy 447.863351 -70.74899)
			(xy 447.871109 -70.802936) (xy 447.871596 -70.830186) (xy 447.871069 -70.859103) (xy 447.862342 -70.916273)
			(xy 447.845086 -70.971472) (xy 447.819696 -71.023434) (xy 447.786754 -71.070968) (xy 447.747015 -71.112985)
			(xy 447.72453 -71.131176) (xy 447.715732 -71.138791) (xy 447.705546 -71.159686) (xy 447.704972 -71.171308)
			(xy 447.704972 -71.251064) (xy 447.705463 -71.262703) (xy 447.715683 -71.283613) (xy 447.72453 -71.291196)
			(xy 447.747018 -71.309382) (xy 447.786751 -71.351403) (xy 447.819689 -71.39894) (xy 447.845076 -71.450902)
			(xy 447.862332 -71.5061) (xy 447.871061 -71.56327) (xy 447.871596 -71.592186) (xy 447.871132 -71.619439)
			(xy 447.863376 -71.673391) (xy 447.848021 -71.725689) (xy 447.82538 -71.77527) (xy 447.795912 -71.821124)
			(xy 447.760218 -71.862317) (xy 447.719025 -71.898011) (xy 447.673172 -71.927479) (xy 447.623591 -71.950121)
			(xy 447.571293 -71.965476) (xy 447.517341 -71.973231) (xy 447.490088 -71.973694) (xy 447.461173 -71.973115)
			(xy 447.404005 -71.964399) (xy 447.348807 -71.947153) (xy 447.296845 -71.921773) (xy 447.24931 -71.88884)
			(xy 447.20729 -71.849109) (xy 447.189098 -71.826628) (xy 447.181494 -71.817818) (xy 447.16059 -71.807639)
			(xy 447.148966 -71.80707) (xy 447.06921 -71.80707) (xy 447.057577 -71.807605) (xy 447.036666 -71.817794)
			(xy 447.029078 -71.826628) (xy 447.012325 -71.847411) (xy 446.973971 -71.884541) (xy 446.930817 -71.915963)
			(xy 446.883703 -71.941062) (xy 446.833551 -71.959348) (xy 446.78134 -71.970465) (xy 446.728088 -71.974195)
			(xy 446.674836 -71.970465) (xy 446.622625 -71.959348) (xy 446.572473 -71.941062) (xy 446.525359 -71.915963)
			(xy 446.482205 -71.884541) (xy 446.443851 -71.847411) (xy 446.427098 -71.826628) (xy 446.419494 -71.817818)
			(xy 446.39859 -71.807639) (xy 446.386966 -71.80707) (xy 446.30721 -71.80707) (xy 446.295577 -71.807605)
			(xy 446.274666 -71.817794) (xy 446.267078 -71.826628) (xy 446.250325 -71.847411) (xy 446.211971 -71.884541)
			(xy 446.168817 -71.915963) (xy 446.121703 -71.941062) (xy 446.071551 -71.959348) (xy 446.01934 -71.970465)
			(xy 445.966088 -71.974195) (xy 445.912836 -71.970465) (xy 445.860625 -71.959348) (xy 445.810473 -71.941062)
			(xy 445.763359 -71.915963) (xy 445.720205 -71.884541) (xy 445.681851 -71.847411) (xy 445.665098 -71.826628)
			(xy 445.657494 -71.817818) (xy 445.63659 -71.807639) (xy 445.624966 -71.80707) (xy 445.54521 -71.80707)
			(xy 445.533577 -71.807605) (xy 445.512666 -71.817794) (xy 445.505078 -71.826628) (xy 445.486906 -71.849128)
			(xy 445.444882 -71.888861) (xy 445.397343 -71.921797) (xy 445.345378 -71.947182) (xy 445.290177 -71.964435)
			(xy 445.233005 -71.973161) (xy 445.204088 -71.973694) (xy 445.176834 -71.973256) (xy 445.122882 -71.965497)
			(xy 445.070582 -71.950139) (xy 445.021001 -71.927494) (xy 444.975147 -71.898023) (xy 444.933954 -71.862327)
			(xy 444.898261 -71.821132) (xy 444.868793 -71.775276) (xy 444.846152 -71.725693) (xy 444.830797 -71.673393)
			(xy 444.823042 -71.61944) (xy 444.82258 -71.592186) (xy 438.51195 -71.592186) (xy 438.51195 -72.415584)
			(xy 448.803264 -72.415584) (xy 448.803264 -72.330888) (xy 448.811315 -72.246574) (xy 448.827344 -72.163408)
			(xy 448.851205 -72.082141) (xy 448.882684 -72.003511) (xy 448.921495 -71.92823) (xy 448.967285 -71.856978)
			(xy 449.019641 -71.790402) (xy 449.078089 -71.729104) (xy 449.142099 -71.673639) (xy 449.211091 -71.62451)
			(xy 449.284441 -71.582161) (xy 449.361484 -71.546977) (xy 449.441523 -71.519275) (xy 449.523832 -71.499307)
			(xy 449.607667 -71.487254) (xy 449.692268 -71.483224) (xy 449.776869 -71.487254) (xy 449.860704 -71.499307)
			(xy 449.943013 -71.519275) (xy 450.023052 -71.546977) (xy 450.100095 -71.582161) (xy 450.173445 -71.62451)
			(xy 450.242437 -71.673639) (xy 450.306447 -71.729104) (xy 450.364895 -71.790402) (xy 450.417251 -71.856978)
			(xy 450.463041 -71.92823) (xy 450.501852 -72.003511) (xy 450.533331 -72.082141) (xy 450.557192 -72.163408)
			(xy 450.573221 -72.246574) (xy 450.581272 -72.330888) (xy 450.581776 -72.373236) (xy 450.581272 -72.415584)
			(xy 456.311504 -72.415584) (xy 456.311504 -72.330888) (xy 456.319555 -72.246574) (xy 456.335584 -72.163408)
			(xy 456.359445 -72.082141) (xy 456.390924 -72.003511) (xy 456.429735 -71.92823) (xy 456.475525 -71.856978)
			(xy 456.527881 -71.790402) (xy 456.586329 -71.729104) (xy 456.650339 -71.673639) (xy 456.719331 -71.62451)
			(xy 456.792681 -71.582161) (xy 456.869724 -71.546977) (xy 456.949763 -71.519275) (xy 457.032072 -71.499307)
			(xy 457.115907 -71.487254) (xy 457.200508 -71.483224) (xy 457.285109 -71.487254) (xy 457.368944 -71.499307)
			(xy 457.451253 -71.519275) (xy 457.531292 -71.546977) (xy 457.608335 -71.582161) (xy 457.681685 -71.62451)
			(xy 457.750677 -71.673639) (xy 457.814687 -71.729104) (xy 457.873135 -71.790402) (xy 457.925491 -71.856978)
			(xy 457.971281 -71.92823) (xy 458.010092 -72.003511) (xy 458.041571 -72.082141) (xy 458.065432 -72.163408)
			(xy 458.081461 -72.246574) (xy 458.089512 -72.330888) (xy 458.090016 -72.373236) (xy 458.089512 -72.415584)
			(xy 458.081461 -72.499898) (xy 458.065432 -72.583064) (xy 458.041571 -72.664331) (xy 458.010092 -72.742961)
			(xy 457.971281 -72.818242) (xy 457.925491 -72.889494) (xy 457.873135 -72.95607) (xy 457.814687 -73.017368)
			(xy 457.750677 -73.072833) (xy 457.681685 -73.121962) (xy 457.608335 -73.164311) (xy 457.531292 -73.199495)
			(xy 457.451253 -73.227197) (xy 457.368944 -73.247165) (xy 457.285109 -73.259218) (xy 457.200508 -73.263249)
			(xy 457.115907 -73.259218) (xy 457.032072 -73.247165) (xy 456.949763 -73.227197) (xy 456.869724 -73.199495)
			(xy 456.792681 -73.164311) (xy 456.719331 -73.121962) (xy 456.650339 -73.072833) (xy 456.586329 -73.017368)
			(xy 456.527881 -72.95607) (xy 456.475525 -72.889494) (xy 456.429735 -72.818242) (xy 456.390924 -72.742961)
			(xy 456.359445 -72.664331) (xy 456.335584 -72.583064) (xy 456.319555 -72.499898) (xy 456.311504 -72.415584)
			(xy 450.581272 -72.415584) (xy 450.573221 -72.499898) (xy 450.557192 -72.583064) (xy 450.533331 -72.664331)
			(xy 450.501852 -72.742961) (xy 450.463041 -72.818242) (xy 450.417251 -72.889494) (xy 450.364895 -72.95607)
			(xy 450.306447 -73.017368) (xy 450.242437 -73.072833) (xy 450.173445 -73.121962) (xy 450.100095 -73.164311)
			(xy 450.023052 -73.199495) (xy 449.943013 -73.227197) (xy 449.860704 -73.247165) (xy 449.776869 -73.259218)
			(xy 449.692268 -73.263249) (xy 449.607667 -73.259218) (xy 449.523832 -73.247165) (xy 449.441523 -73.227197)
			(xy 449.361484 -73.199495) (xy 449.284441 -73.164311) (xy 449.211091 -73.121962) (xy 449.142099 -73.072833)
			(xy 449.078089 -73.017368) (xy 449.019641 -72.95607) (xy 448.967285 -72.889494) (xy 448.921495 -72.818242)
			(xy 448.882684 -72.742961) (xy 448.851205 -72.664331) (xy 448.827344 -72.583064) (xy 448.811315 -72.499898)
			(xy 448.803264 -72.415584) (xy 438.51195 -72.415584) (xy 438.51195 -73.29932) (xy 438.512441 -73.309329)
			(xy 438.520102 -73.327822) (xy 438.534253 -73.341981) (xy 438.552742 -73.349653) (xy 438.56275 -73.35012)
			(xy 440.809634 -73.35012) (xy 440.841694 -73.350664) (xy 440.905245 -73.359184) (xy 440.967113 -73.376029)
			(xy 441.026211 -73.400904) (xy 441.081503 -73.433373) (xy 441.132018 -73.472865) (xy 441.15482 -73.495408)
			(xy 441.16109 -73.501334) (xy 441.176532 -73.509006) (xy 441.185046 -73.510394) (xy 441.21451 -73.51395)
			(xy 441.222991 -73.514652) (xy 441.239602 -73.511005) (xy 441.247022 -73.506838) (xy 441.269439 -73.493772)
			(xy 441.317057 -73.473163) (xy 441.367031 -73.459206) (xy 441.418437 -73.452162) (xy 441.44438 -73.45172)
			(xy 441.444634 -73.45172) (xy 441.472003 -73.452194) (xy 441.526179 -73.460023) (xy 441.578679 -73.475514)
			(xy 441.628426 -73.49835) (xy 441.674399 -73.528062) (xy 441.695332 -73.5457) (xy 441.695586 -73.5457)
			(xy 441.695586 -73.545954) (xy 441.702671 -73.551545) (xy 441.719588 -73.557798) (xy 441.728606 -73.558146)
			(xy 441.795662 -73.558146) (xy 441.804682 -73.557794) (xy 441.821609 -73.551561) (xy 441.828682 -73.545954)
			(xy 441.828936 -73.5457) (xy 441.849869 -73.528059) (xy 441.895837 -73.498335) (xy 441.945583 -73.475489)
			(xy 441.998085 -73.459993) (xy 442.052263 -73.452164) (xy 442.107005 -73.452164) (xy 442.161183 -73.459993)
			(xy 442.213685 -73.475489) (xy 442.263431 -73.498335) (xy 442.309399 -73.528059) (xy 442.330332 -73.5457)
			(xy 442.330586 -73.5457) (xy 442.330586 -73.545954) (xy 442.337671 -73.551545) (xy 442.354588 -73.557798)
			(xy 442.363606 -73.558146) (xy 442.430662 -73.558146) (xy 442.439682 -73.557794) (xy 442.456609 -73.551561)
			(xy 442.463682 -73.545954) (xy 442.463936 -73.5457) (xy 442.484868 -73.52806) (xy 442.530835 -73.498338)
			(xy 442.580582 -73.4755) (xy 442.633086 -73.460015) (xy 442.687264 -73.452201) (xy 442.714634 -73.45172)
			(xy 442.74476 -73.452284) (xy 442.804264 -73.461747) (xy 442.86154 -73.480449) (xy 442.915162 -73.507924)
			(xy 442.963798 -73.543489) (xy 442.985398 -73.564496) (xy 442.992796 -73.571343) (xy 443.011394 -73.579079)
			(xy 443.021466 -73.579482) (xy 443.093602 -73.579482) (xy 443.103672 -73.579058) (xy 443.122274 -73.571341)
			(xy 443.12967 -73.564496) (xy 443.151296 -73.54352) (xy 443.199932 -73.507969) (xy 443.25355 -73.4805)
			(xy 443.310817 -73.461796) (xy 443.370312 -73.452321) (xy 443.400434 -73.45172) (xy 443.427683 -73.452209)
			(xy 443.481625 -73.459969) (xy 443.533914 -73.475328) (xy 443.583485 -73.497971) (xy 443.62933 -73.527439)
			(xy 443.670513 -73.56313) (xy 443.706199 -73.60432) (xy 443.735659 -73.650169) (xy 443.758294 -73.699744)
			(xy 443.773644 -73.752035) (xy 443.781396 -73.805979) (xy 443.781942 -73.833228) (xy 443.781406 -73.862143)
			(xy 443.772674 -73.919311) (xy 443.755415 -73.974506) (xy 443.730024 -74.026464) (xy 443.697083 -74.073995)
			(xy 443.657346 -74.116011) (xy 443.634876 -74.134218) (xy 443.626039 -74.141806) (xy 443.615836 -74.162715)
			(xy 443.615318 -74.17435) (xy 443.615318 -74.254106) (xy 443.615897 -74.265725) (xy 443.626092 -74.286609)
			(xy 443.634876 -74.294238) (xy 443.657363 -74.312427) (xy 443.697106 -74.354443) (xy 443.730051 -74.401976)
			(xy 443.755442 -74.453939) (xy 443.772699 -74.509138) (xy 443.774364 -74.520044) (xy 444.46139 -74.520044)
			(xy 444.465461 -74.464422) (xy 444.477587 -74.409985) (xy 444.49751 -74.357894) (xy 444.524806 -74.309259)
			(xy 444.558892 -74.265116) (xy 444.599041 -74.226407) (xy 444.644399 -74.193956) (xy 444.693999 -74.168455)
			(xy 444.746783 -74.150448) (xy 444.801626 -74.140318) (xy 444.85736 -74.138281) (xy 444.912797 -74.144381)
			(xy 444.966754 -74.158487) (xy 445.018083 -74.180299) (xy 445.065689 -74.209353) (xy 445.108557 -74.245028)
			(xy 445.145774 -74.286565) (xy 445.176547 -74.333078) (xy 445.200219 -74.383575) (xy 445.216287 -74.436982)
			(xy 445.224407 -74.492158) (xy 445.224916 -74.520044) (xy 445.224407 -74.54793) (xy 445.216287 -74.603106)
			(xy 445.200219 -74.656513) (xy 445.176547 -74.70701) (xy 445.145774 -74.753523) (xy 445.108557 -74.79506)
			(xy 445.065689 -74.830735) (xy 445.018083 -74.859789) (xy 444.966754 -74.881601) (xy 444.912797 -74.895707)
			(xy 444.85736 -74.901807) (xy 444.801626 -74.89977) (xy 444.746783 -74.88964) (xy 444.693999 -74.871633)
			(xy 444.644399 -74.846132) (xy 444.599041 -74.813681) (xy 444.558892 -74.774972) (xy 444.524806 -74.730829)
			(xy 444.49751 -74.682194) (xy 444.477587 -74.630103) (xy 444.465461 -74.575666) (xy 444.46139 -74.520044)
			(xy 443.774364 -74.520044) (xy 443.781426 -74.566311) (xy 443.781942 -74.595228) (xy 443.781454 -74.622479)
			(xy 443.773695 -74.676425) (xy 443.758338 -74.728719) (xy 443.735695 -74.778295) (xy 443.706229 -74.824144)
			(xy 443.670538 -74.865334) (xy 443.629349 -74.901025) (xy 443.606506 -74.915706) (xy 448.803264 -74.915706)
			(xy 448.803264 -74.83101) (xy 448.811315 -74.746696) (xy 448.827344 -74.66353) (xy 448.851205 -74.582263)
			(xy 448.882684 -74.503633) (xy 448.921495 -74.428352) (xy 448.967285 -74.3571) (xy 449.019641 -74.290524)
			(xy 449.078089 -74.229226) (xy 449.142099 -74.173761) (xy 449.211091 -74.124632) (xy 449.284441 -74.082283)
			(xy 449.361484 -74.047099) (xy 449.441523 -74.019397) (xy 449.523832 -73.999429) (xy 449.607667 -73.987376)
			(xy 449.692268 -73.983346) (xy 449.776869 -73.987376) (xy 449.860704 -73.999429) (xy 449.943013 -74.019397)
			(xy 450.023052 -74.047099) (xy 450.100095 -74.082283) (xy 450.173445 -74.124632) (xy 450.242437 -74.173761)
			(xy 450.306447 -74.229226) (xy 450.364895 -74.290524) (xy 450.417251 -74.3571) (xy 450.463041 -74.428352)
			(xy 450.501852 -74.503633) (xy 450.533331 -74.582263) (xy 450.557192 -74.66353) (xy 450.573221 -74.746696)
			(xy 450.581272 -74.83101) (xy 450.581776 -74.873358) (xy 450.581272 -74.915706) (xy 456.311504 -74.915706)
			(xy 456.311504 -74.83101) (xy 456.319555 -74.746696) (xy 456.335584 -74.66353) (xy 456.359445 -74.582263)
			(xy 456.390924 -74.503633) (xy 456.429735 -74.428352) (xy 456.475525 -74.3571) (xy 456.527881 -74.290524)
			(xy 456.586329 -74.229226) (xy 456.650339 -74.173761) (xy 456.719331 -74.124632) (xy 456.792681 -74.082283)
			(xy 456.869724 -74.047099) (xy 456.949763 -74.019397) (xy 457.032072 -73.999429) (xy 457.115907 -73.987376)
			(xy 457.200508 -73.983346) (xy 457.285109 -73.987376) (xy 457.368944 -73.999429) (xy 457.451253 -74.019397)
			(xy 457.531292 -74.047099) (xy 457.608335 -74.082283) (xy 457.681685 -74.124632) (xy 457.750677 -74.173761)
			(xy 457.814687 -74.229226) (xy 457.873135 -74.290524) (xy 457.925491 -74.3571) (xy 457.971281 -74.428352)
			(xy 458.010092 -74.503633) (xy 458.041571 -74.582263) (xy 458.065432 -74.66353) (xy 458.081461 -74.746696)
			(xy 458.089512 -74.83101) (xy 458.090016 -74.873358) (xy 458.089512 -74.915706) (xy 458.081461 -75.00002)
			(xy 458.065432 -75.083186) (xy 458.041571 -75.164453) (xy 458.010092 -75.243083) (xy 457.971281 -75.318364)
			(xy 457.925491 -75.389616) (xy 457.873135 -75.456192) (xy 457.814687 -75.51749) (xy 457.750677 -75.572955)
			(xy 457.681685 -75.622084) (xy 457.608335 -75.664433) (xy 457.531292 -75.699617) (xy 457.451253 -75.727319)
			(xy 457.368944 -75.747287) (xy 457.285109 -75.75934) (xy 457.200508 -75.763371) (xy 457.115907 -75.75934)
			(xy 457.032072 -75.747287) (xy 456.949763 -75.727319) (xy 456.869724 -75.699617) (xy 456.792681 -75.664433)
			(xy 456.719331 -75.622084) (xy 456.650339 -75.572955) (xy 456.586329 -75.51749) (xy 456.527881 -75.456192)
			(xy 456.475525 -75.389616) (xy 456.429735 -75.318364) (xy 456.390924 -75.243083) (xy 456.359445 -75.164453)
			(xy 456.335584 -75.083186) (xy 456.319555 -75.00002) (xy 456.311504 -74.915706) (xy 450.581272 -74.915706)
			(xy 450.573221 -75.00002) (xy 450.557192 -75.083186) (xy 450.533331 -75.164453) (xy 450.501852 -75.243083)
			(xy 450.463041 -75.318364) (xy 450.417251 -75.389616) (xy 450.364895 -75.456192) (xy 450.306447 -75.51749)
			(xy 450.242437 -75.572955) (xy 450.173445 -75.622084) (xy 450.100095 -75.664433) (xy 450.023052 -75.699617)
			(xy 449.943013 -75.727319) (xy 449.860704 -75.747287) (xy 449.776869 -75.75934) (xy 449.692268 -75.763371)
			(xy 449.607667 -75.75934) (xy 449.523832 -75.747287) (xy 449.441523 -75.727319) (xy 449.361484 -75.699617)
			(xy 449.284441 -75.664433) (xy 449.211091 -75.622084) (xy 449.142099 -75.572955) (xy 449.078089 -75.51749)
			(xy 449.019641 -75.456192) (xy 448.967285 -75.389616) (xy 448.921495 -75.318364) (xy 448.882684 -75.243083)
			(xy 448.851205 -75.164453) (xy 448.827344 -75.083186) (xy 448.811315 -75.00002) (xy 448.803264 -74.915706)
			(xy 443.606506 -74.915706) (xy 443.5835 -74.930492) (xy 443.533924 -74.953135) (xy 443.481631 -74.968493)
			(xy 443.427685 -74.976254) (xy 443.400434 -74.976736) (xy 443.370309 -74.976169) (xy 443.310809 -74.966701)
			(xy 443.253538 -74.947994) (xy 443.19992 -74.920513) (xy 443.151291 -74.884944) (xy 443.12967 -74.86396)
			(xy 443.122273 -74.857112) (xy 443.103674 -74.849379) (xy 443.093602 -74.848974) (xy 443.021466 -74.848974)
			(xy 443.011398 -74.849403) (xy 442.9928 -74.857123) (xy 442.985398 -74.86396) (xy 442.963774 -74.884942)
			(xy 442.915141 -74.920506) (xy 442.861525 -74.947988) (xy 442.804256 -74.966704) (xy 442.744758 -74.976191)
			(xy 442.714634 -74.976736) (xy 442.687266 -74.976259) (xy 442.633093 -74.968426) (xy 442.580597 -74.95293)
			(xy 442.530854 -74.930089) (xy 442.484887 -74.900372) (xy 442.463936 -74.882756) (xy 442.463682 -74.882756)
			(xy 442.463682 -74.882502) (xy 442.456594 -74.876919) (xy 442.439677 -74.870683) (xy 442.430662 -74.87031)
			(xy 442.363606 -74.87031) (xy 442.354589 -74.870669) (xy 442.337673 -74.876915) (xy 442.330586 -74.882502)
			(xy 442.330332 -74.882756) (xy 442.314076 -74.896218) (xy 442.305239 -74.903806) (xy 442.295036 -74.924715)
			(xy 442.294518 -74.93635) (xy 442.294518 -75.016106) (xy 442.295097 -75.027725) (xy 442.305292 -75.048609)
			(xy 442.314076 -75.056238) (xy 442.334855 -75.072992) (xy 442.371979 -75.111346) (xy 442.403394 -75.154501)
			(xy 442.428487 -75.201612) (xy 442.446768 -75.251762) (xy 442.45788 -75.30397) (xy 442.461607 -75.357217)
			(xy 442.457875 -75.410464) (xy 442.446758 -75.462671) (xy 442.428472 -75.512819) (xy 442.403375 -75.559929)
			(xy 442.371957 -75.60308) (xy 442.33483 -75.641431) (xy 442.314076 -75.658218) (xy 442.305239 -75.665806)
			(xy 442.295036 -75.686715) (xy 442.294518 -75.69835) (xy 442.294518 -75.778106) (xy 442.295097 -75.789725)
			(xy 442.305292 -75.810609) (xy 442.314076 -75.818238) (xy 442.336563 -75.836427) (xy 442.376306 -75.878443)
			(xy 442.409251 -75.925976) (xy 442.434642 -75.977939) (xy 442.451899 -76.033138) (xy 442.460626 -76.090311)
			(xy 442.461142 -76.119228) (xy 442.460559 -76.149127) (xy 442.451228 -76.208193) (xy 442.432799 -76.265081)
			(xy 442.405723 -76.318398) (xy 442.370663 -76.36684) (xy 442.328476 -76.409221) (xy 442.304678 -76.42733)
			(xy 442.295026 -76.434442) (xy 442.284358 -76.455016) (xy 442.28131 -76.55941) (xy 442.291216 -76.580492)
			(xy 442.30036 -76.588112) (xy 442.321895 -76.606331) (xy 442.359883 -76.648029) (xy 442.391321 -76.694864)
			(xy 442.415524 -76.745815) (xy 442.431965 -76.799774) (xy 442.440286 -76.855564) (xy 442.440822 -76.883768)
			(xy 442.44029 -76.912685) (xy 442.431566 -76.969857) (xy 442.414313 -77.025057) (xy 442.388926 -77.077021)
			(xy 442.355987 -77.124559) (xy 442.31625 -77.16658) (xy 442.293756 -77.184758) (xy 442.284929 -77.19235)
			(xy 442.274746 -77.213259) (xy 442.274198 -77.22489) (xy 442.274198 -77.304646) (xy 442.274764 -77.316272)
			(xy 442.284942 -77.337178) (xy 442.293756 -77.344778) (xy 442.316241 -77.362968) (xy 442.355982 -77.404984)
			(xy 442.388923 -77.452518) (xy 442.414311 -77.50448) (xy 442.431563 -77.55968) (xy 442.440284 -77.616851)
			(xy 442.440822 -77.645768) (xy 442.440361 -77.673023) (xy 442.432608 -77.726978) (xy 442.417255 -77.77928)
			(xy 442.394615 -77.828866) (xy 442.365148 -77.874724) (xy 442.329454 -77.915921) (xy 442.288261 -77.95162)
			(xy 442.242406 -77.981092) (xy 442.192824 -78.003739) (xy 442.140523 -78.019098) (xy 442.086569 -78.026858)
			(xy 442.059314 -78.027276) (xy 442.031946 -78.026798) (xy 441.977774 -78.018963) (xy 441.925278 -78.003466)
			(xy 441.875536 -77.980625) (xy 441.829569 -77.950909) (xy 441.808616 -77.933296) (xy 441.808362 -77.933296)
			(xy 441.808362 -77.933042) (xy 441.801275 -77.927458) (xy 441.784357 -77.921224) (xy 441.775342 -77.92085)
			(xy 441.708286 -77.92085) (xy 441.69927 -77.921211) (xy 441.682353 -77.927457) (xy 441.675266 -77.933042)
			(xy 441.675012 -77.933296) (xy 441.654079 -77.950937) (xy 441.608111 -77.980661) (xy 441.558365 -78.003507)
			(xy 441.505863 -78.019003) (xy 441.451685 -78.026832) (xy 441.396943 -78.026832) (xy 441.342765 -78.019003)
			(xy 441.290263 -78.003507) (xy 441.240517 -77.980661) (xy 441.194549 -77.950937) (xy 441.173616 -77.933296)
			(xy 441.173362 -77.933296) (xy 441.173362 -77.933042) (xy 441.166275 -77.927458) (xy 441.149357 -77.921224)
			(xy 441.140342 -77.92085) (xy 441.073286 -77.92085) (xy 441.06427 -77.921211) (xy 441.047353 -77.927457)
			(xy 441.040266 -77.933042) (xy 441.040012 -77.933296) (xy 441.019081 -77.950939) (xy 440.973115 -77.980667)
			(xy 440.923368 -78.003512) (xy 440.870865 -78.019004) (xy 440.816685 -78.026824) (xy 440.789314 -78.027276)
			(xy 440.76061 -78.026759) (xy 440.703849 -78.018161) (xy 440.649017 -78.001157) (xy 440.59735 -77.976131)
			(xy 440.550016 -77.943647) (xy 440.52871 -77.924406) (xy 440.521311 -77.918055) (xy 440.50315 -77.911)
			(xy 440.493404 -77.91069) (xy 440.412886 -77.911706) (xy 440.394598 -77.91958) (xy 440.38774 -77.926438)
			(xy 440.366149 -77.947085) (xy 440.317738 -77.982085) (xy 440.264464 -78.009114) (xy 440.20763 -78.027512)
			(xy 440.148623 -78.036829) (xy 440.118754 -78.037436) (xy 440.091385 -78.036961) (xy 440.037211 -78.02913)
			(xy 439.984713 -78.013636) (xy 439.934968 -77.990797) (xy 439.888999 -77.961081) (xy 439.868056 -77.943456)
			(xy 439.867802 -77.943456) (xy 439.867802 -77.943202) (xy 439.860715 -77.937616) (xy 439.843798 -77.931373)
			(xy 439.834782 -77.93101) (xy 439.767726 -77.93101) (xy 439.758708 -77.931365) (xy 439.741787 -77.937607)
			(xy 439.734706 -77.943202) (xy 439.734452 -77.943456) (xy 439.713521 -77.961097) (xy 439.667554 -77.990821)
			(xy 439.617807 -78.01366) (xy 439.565303 -78.029146) (xy 439.511124 -78.036959) (xy 439.483754 -78.037436)
			(xy 439.456504 -78.036947) (xy 439.40256 -78.029185) (xy 439.350269 -78.013827) (xy 439.300696 -77.991183)
			(xy 439.254849 -77.961716) (xy 439.213662 -77.926025) (xy 439.177973 -77.884836) (xy 439.148508 -77.838988)
			(xy 439.125867 -77.789414) (xy 439.110511 -77.737122) (xy 439.102752 -77.683178) (xy 439.102246 -77.655928)
			(xy 439.102778 -77.627011) (xy 439.111502 -77.569838) (xy 439.128755 -77.514637) (xy 439.154141 -77.462672)
			(xy 439.187078 -77.415134) (xy 439.226813 -77.373111) (xy 439.249312 -77.354938) (xy 439.258143 -77.347348)
			(xy 439.26833 -77.326438) (xy 439.26887 -77.314806) (xy 439.26887 -77.23505) (xy 439.268302 -77.223426)
			(xy 439.258119 -77.202525) (xy 439.249312 -77.194918) (xy 439.226829 -77.176727) (xy 439.187092 -77.13471)
			(xy 439.154153 -77.087175) (xy 439.128768 -77.035213) (xy 439.111518 -76.980014) (xy 439.102799 -76.922844)
			(xy 439.102246 -76.893928) (xy 439.102833 -76.86403) (xy 439.112169 -76.804968) (xy 439.130602 -76.748085)
			(xy 439.157681 -76.694772) (xy 439.192743 -76.646335) (xy 439.23493 -76.603958) (xy 439.25871 -76.585826)
			(xy 439.268362 -76.578714) (xy 439.27903 -76.55814) (xy 439.282078 -76.453746) (xy 439.272172 -76.432664)
			(xy 439.263028 -76.425044) (xy 439.241486 -76.406828) (xy 439.203483 -76.365135) (xy 439.172031 -76.318303)
			(xy 439.147815 -76.267351) (xy 439.131362 -76.21339) (xy 439.123031 -76.157595) (xy 439.122566 -76.129388)
			(xy 439.123101 -76.100472) (xy 439.131831 -76.043304) (xy 439.149088 -75.988107) (xy 439.174478 -75.936148)
			(xy 439.207419 -75.888615) (xy 439.247156 -75.846598) (xy 439.269632 -75.828398) (xy 439.278454 -75.820804)
			(xy 439.288621 -75.799894) (xy 439.28919 -75.788266) (xy 439.28919 -75.70851) (xy 439.288615 -75.696889)
			(xy 439.278425 -75.675999) (xy 439.269632 -75.668378) (xy 439.248851 -75.651624) (xy 439.211725 -75.61327)
			(xy 439.180307 -75.570115) (xy 439.155212 -75.523003) (xy 439.136928 -75.472852) (xy 439.125814 -75.420642)
			(xy 439.122085 -75.367393) (xy 439.125816 -75.314143) (xy 439.136932 -75.261934) (xy 439.155218 -75.211784)
			(xy 439.180315 -75.164672) (xy 439.211734 -75.121519) (xy 439.248862 -75.083166) (xy 439.269632 -75.066398)
			(xy 439.278454 -75.058804) (xy 439.288621 -75.037894) (xy 439.28919 -75.026266) (xy 439.28919 -74.94651)
			(xy 439.288615 -74.934889) (xy 439.278425 -74.913999) (xy 439.269632 -74.906378) (xy 439.247144 -74.888189)
			(xy 439.207399 -74.846175) (xy 439.174451 -74.798641) (xy 439.149056 -74.746679) (xy 439.131797 -74.691479)
			(xy 439.123068 -74.634306) (xy 439.122566 -74.605388) (xy 439.122999 -74.580031) (xy 439.129742 -74.529765)
			(xy 439.143067 -74.480832) (xy 439.152538 -74.457306) (xy 439.157618 -74.445368) (xy 439.155078 -74.420222)
			(xy 439.10123 -74.338942) (xy 439.093715 -74.328877) (xy 439.071608 -74.317011) (xy 439.059066 -74.316336)
			(xy 438.56275 -74.316336) (xy 438.552752 -74.316833) (xy 438.534283 -74.324503) (xy 438.520154 -74.338655)
			(xy 438.512516 -74.357137) (xy 438.51195 -74.367136) (xy 438.51195 -80.868012) (xy 438.512377 -80.87808)
			(xy 438.5201 -80.896677) (xy 438.526936 -80.90408) (xy 439.836306 -82.21345) (xy 439.843702 -82.220301)
			(xy 439.862301 -82.228041) (xy 439.872374 -82.228436) (xy 444.970916 -82.228436) (xy 444.975936 -82.228525)
			(xy 444.98579 -82.23044) (xy 444.990474 -82.232246) (xy 445.007746 -82.239612) (xy 445.012432 -82.241415)
			(xy 445.022284 -82.243343) (xy 445.027304 -82.243422) (xy 455.081132 -82.243422)
		)
		(stroke
			(width 0)
			(type solid)
		)
		(fill yes)
		(layer "In6.Cu")
		(net "GND")
	)
	(gr_poly
		(pts
			(xy 233.390694 -320.904362) (xy 233.400764 -320.903939) (xy 233.419366 -320.896222) (xy 233.426762 -320.889376)
			(xy 234.709208 -319.60693) (xy 234.716043 -319.599527) (xy 234.72375 -319.580929) (xy 234.724194 -319.570862)
			(xy 234.724194 -308.568598) (xy 234.724617 -308.558528) (xy 234.732331 -308.539923) (xy 234.73918 -308.53253)
			(xy 235.779056 -307.492654) (xy 235.786455 -307.48581) (xy 235.805054 -307.478088) (xy 235.815124 -307.477668)
			(xy 261.472426 -307.477668) (xy 261.482493 -307.477239) (xy 261.501088 -307.469515) (xy 261.508494 -307.462682)
			(xy 262.153146 -306.81803) (xy 262.159987 -306.81063) (xy 262.167705 -306.792031) (xy 262.168132 -306.781962)
			(xy 262.168132 -254.545084) (xy 262.167707 -254.535014) (xy 262.159992 -254.516411) (xy 262.153146 -254.509016)
			(xy 261.094728 -253.450598) (xy 261.087326 -253.443763) (xy 261.068727 -253.436055) (xy 261.05866 -253.435612)
			(xy 220.220286 -253.435612) (xy 220.210217 -253.436038) (xy 220.191618 -253.443757) (xy 220.184218 -253.450598)
			(xy 218.958668 -254.676148) (xy 218.951822 -254.683546) (xy 218.944094 -254.702145) (xy 218.943682 -254.712216)
			(xy 218.943682 -263.481566) (xy 254.402842 -263.481566) (xy 254.406913 -263.425944) (xy 254.419039 -263.371507)
			(xy 254.438962 -263.319416) (xy 254.466258 -263.270781) (xy 254.500344 -263.226638) (xy 254.540493 -263.187929)
			(xy 254.585851 -263.155478) (xy 254.635451 -263.129977) (xy 254.688235 -263.11197) (xy 254.743078 -263.10184)
			(xy 254.798812 -263.099803) (xy 254.854249 -263.105903) (xy 254.908206 -263.120009) (xy 254.959535 -263.141821)
			(xy 255.007141 -263.170875) (xy 255.050009 -263.20655) (xy 255.087226 -263.248087) (xy 255.117999 -263.2946)
			(xy 255.141671 -263.345097) (xy 255.157739 -263.398504) (xy 255.165859 -263.45368) (xy 255.166368 -263.481566)
			(xy 255.165859 -263.509452) (xy 255.157739 -263.564628) (xy 255.141671 -263.618035) (xy 255.117999 -263.668532)
			(xy 255.087226 -263.715045) (xy 255.050009 -263.756582) (xy 255.007141 -263.792257) (xy 254.959535 -263.821311)
			(xy 254.908206 -263.843123) (xy 254.854249 -263.857229) (xy 254.798812 -263.863329) (xy 254.743078 -263.861292)
			(xy 254.688235 -263.851162) (xy 254.635451 -263.833155) (xy 254.585851 -263.807654) (xy 254.540493 -263.775203)
			(xy 254.500344 -263.736494) (xy 254.466258 -263.692351) (xy 254.438962 -263.643716) (xy 254.419039 -263.591625)
			(xy 254.406913 -263.537188) (xy 254.402842 -263.481566) (xy 218.943682 -263.481566) (xy 218.943682 -269.770955)
			(xy 221.508737 -269.770955) (xy 221.508737 -269.716445) (xy 221.516495 -269.662489) (xy 221.531853 -269.610186)
			(xy 221.554499 -269.560602) (xy 221.583971 -269.514745) (xy 221.619669 -269.473549) (xy 221.660867 -269.437854)
			(xy 221.706726 -269.408385) (xy 221.756312 -269.385743) (xy 221.808616 -269.370389) (xy 221.862573 -269.362635)
			(xy 221.889828 -269.362174) (xy 221.918744 -269.362716) (xy 221.975916 -269.371436) (xy 222.031115 -269.388688)
			(xy 222.083078 -269.414075) (xy 222.130612 -269.447016) (xy 222.172628 -269.486755) (xy 222.190818 -269.50924)
			(xy 222.19837 -269.518012) (xy 222.219136 -269.528188) (xy 222.230696 -269.528798) (xy 222.31096 -269.528798)
			(xy 222.322525 -269.528205) (xy 222.343296 -269.518027) (xy 222.350838 -269.50924) (xy 222.367591 -269.488457)
			(xy 222.405945 -269.451327) (xy 222.449099 -269.419905) (xy 222.496213 -269.394806) (xy 222.546365 -269.37652)
			(xy 222.598576 -269.365403) (xy 222.651828 -269.361673) (xy 222.70508 -269.365403) (xy 222.757291 -269.37652)
			(xy 222.807443 -269.394806) (xy 222.854557 -269.419905) (xy 222.897711 -269.451327) (xy 222.936065 -269.488457)
			(xy 222.952818 -269.50924) (xy 222.96037 -269.518012) (xy 222.981136 -269.528188) (xy 222.992696 -269.528798)
			(xy 223.07296 -269.528798) (xy 223.084525 -269.528205) (xy 223.105296 -269.518027) (xy 223.112838 -269.50924)
			(xy 223.129591 -269.488457) (xy 223.167945 -269.451327) (xy 223.211099 -269.419905) (xy 223.258213 -269.394806)
			(xy 223.308365 -269.37652) (xy 223.360576 -269.365403) (xy 223.413828 -269.361673) (xy 223.46708 -269.365403)
			(xy 223.519291 -269.37652) (xy 223.569443 -269.394806) (xy 223.616557 -269.419905) (xy 223.659711 -269.451327)
			(xy 223.698065 -269.488457) (xy 223.714818 -269.50924) (xy 223.72237 -269.518012) (xy 223.743136 -269.528188)
			(xy 223.754696 -269.528798) (xy 223.83496 -269.528798) (xy 223.846525 -269.528205) (xy 223.867296 -269.518027)
			(xy 223.874838 -269.50924) (xy 223.893018 -269.486747) (xy 223.935039 -269.44701) (xy 223.982575 -269.414071)
			(xy 224.034539 -269.388684) (xy 224.089739 -269.371431) (xy 224.146911 -269.362706) (xy 224.175828 -269.362174)
			(xy 224.203077 -269.362698) (xy 224.257019 -269.370458) (xy 224.309308 -269.385814) (xy 224.358879 -269.408456)
			(xy 224.404724 -269.437922) (xy 224.445908 -269.473611) (xy 224.481595 -269.514799) (xy 224.511057 -269.560646)
			(xy 224.533695 -269.610219) (xy 224.549048 -269.662509) (xy 224.556804 -269.716451) (xy 224.556804 -269.770949)
			(xy 224.549048 -269.824891) (xy 224.533695 -269.877181) (xy 224.511057 -269.926754) (xy 224.481595 -269.972601)
			(xy 224.445908 -270.013789) (xy 224.404724 -270.049478) (xy 224.358879 -270.078944) (xy 224.309308 -270.101586)
			(xy 224.257019 -270.116942) (xy 224.203077 -270.124702) (xy 224.175828 -270.12519) (xy 224.146912 -270.124655)
			(xy 224.089741 -270.11593) (xy 224.034542 -270.098676) (xy 223.982581 -270.073287) (xy 223.935046 -270.040346)
			(xy 223.893029 -270.000608) (xy 223.874838 -269.978124) (xy 223.867268 -269.969371) (xy 223.846515 -269.959186)
			(xy 223.83496 -269.958566) (xy 223.754696 -269.958566) (xy 223.743124 -269.959111) (xy 223.722352 -269.969321)
			(xy 223.714818 -269.978124) (xy 223.698065 -269.998907) (xy 223.659711 -270.036037) (xy 223.616557 -270.067459)
			(xy 223.569443 -270.092558) (xy 223.519291 -270.110844) (xy 223.46708 -270.121961) (xy 223.413828 -270.125691)
			(xy 223.360576 -270.121961) (xy 223.308365 -270.110844) (xy 223.258213 -270.092558) (xy 223.211099 -270.067459)
			(xy 223.167945 -270.036037) (xy 223.129591 -269.998907) (xy 223.112838 -269.978124) (xy 223.105268 -269.969371)
			(xy 223.084515 -269.959186) (xy 223.07296 -269.958566) (xy 222.992696 -269.958566) (xy 222.981124 -269.959111)
			(xy 222.960352 -269.969321) (xy 222.952818 -269.978124) (xy 222.936065 -269.998907) (xy 222.897711 -270.036037)
			(xy 222.854557 -270.067459) (xy 222.807443 -270.092558) (xy 222.757291 -270.110844) (xy 222.70508 -270.121961)
			(xy 222.651828 -270.125691) (xy 222.598576 -270.121961) (xy 222.546365 -270.110844) (xy 222.496213 -270.092558)
			(xy 222.449099 -270.067459) (xy 222.405945 -270.036037) (xy 222.367591 -269.998907) (xy 222.350838 -269.978124)
			(xy 222.343268 -269.969371) (xy 222.322515 -269.959186) (xy 222.31096 -269.958566) (xy 222.230696 -269.958566)
			(xy 222.219124 -269.959111) (xy 222.198352 -269.969321) (xy 222.190818 -269.978124) (xy 222.172623 -270.000604)
			(xy 222.130603 -270.040338) (xy 222.083069 -270.073277) (xy 222.031109 -270.098666) (xy 221.975912 -270.115923)
			(xy 221.918744 -270.124654) (xy 221.889828 -270.12519) (xy 221.862573 -270.124765) (xy 221.808616 -270.117011)
			(xy 221.756312 -270.101657) (xy 221.706726 -270.079015) (xy 221.660867 -270.049546) (xy 221.619669 -270.013851)
			(xy 221.583971 -269.972655) (xy 221.554499 -269.926798) (xy 221.531853 -269.877214) (xy 221.516495 -269.824911)
			(xy 221.508737 -269.770955) (xy 218.943682 -269.770955) (xy 218.943682 -271.407389) (xy 221.507795 -271.407389)
			(xy 221.511527 -271.354135) (xy 221.522646 -271.301921) (xy 221.540936 -271.251767) (xy 221.566039 -271.204652)
			(xy 221.597465 -271.161497) (xy 221.6346 -271.123145) (xy 221.655386 -271.106392) (xy 221.664145 -271.098827)
			(xy 221.674331 -271.078071) (xy 221.674944 -271.066514) (xy 221.674944 -270.98625) (xy 221.674365 -270.974683)
			(xy 221.664178 -270.95391) (xy 221.655386 -270.946372) (xy 221.632886 -270.9282) (xy 221.593153 -270.886176)
			(xy 221.560216 -270.838637) (xy 221.534831 -270.786672) (xy 221.517578 -270.731471) (xy 221.508853 -270.674299)
			(xy 221.50832 -270.645382) (xy 221.508738 -270.618127) (xy 221.516498 -270.564173) (xy 221.531858 -270.511873)
			(xy 221.554505 -270.462291) (xy 221.583977 -270.416436) (xy 221.619676 -270.375243) (xy 221.660873 -270.33955)
			(xy 221.706731 -270.310083) (xy 221.756316 -270.287442) (xy 221.808618 -270.272089) (xy 221.862573 -270.264335)
			(xy 221.889828 -270.263874) (xy 221.918744 -270.264416) (xy 221.975916 -270.273136) (xy 222.031115 -270.290388)
			(xy 222.083078 -270.315775) (xy 222.130612 -270.348716) (xy 222.172628 -270.388455) (xy 222.190818 -270.41094)
			(xy 222.19837 -270.419712) (xy 222.219136 -270.429888) (xy 222.230696 -270.430498) (xy 222.31096 -270.430498)
			(xy 222.322525 -270.429905) (xy 222.343296 -270.419727) (xy 222.350838 -270.41094) (xy 222.369018 -270.388447)
			(xy 222.411039 -270.34871) (xy 222.458575 -270.315771) (xy 222.510539 -270.290384) (xy 222.565739 -270.273131)
			(xy 222.622911 -270.264406) (xy 222.651828 -270.263874) (xy 222.679079 -270.264352) (xy 222.733026 -270.272112)
			(xy 222.78532 -270.287469) (xy 222.834896 -270.310112) (xy 222.880746 -270.33958) (xy 222.921935 -270.375272)
			(xy 222.957626 -270.416463) (xy 222.987092 -270.462313) (xy 223.009734 -270.511889) (xy 223.025091 -270.564184)
			(xy 223.032849 -270.618131) (xy 223.033336 -270.645382) (xy 223.032829 -270.6743) (xy 223.024101 -270.731472)
			(xy 223.006843 -270.786673) (xy 222.981449 -270.838635) (xy 222.948502 -270.886168) (xy 222.908757 -270.928183)
			(xy 222.88627 -270.946372) (xy 222.87752 -270.953945) (xy 222.867331 -270.974696) (xy 222.866712 -270.98625)
			(xy 222.866712 -271.066514) (xy 222.86727 -271.078084) (xy 222.877473 -271.098855) (xy 222.88627 -271.106392)
			(xy 222.907034 -271.123167) (xy 222.944161 -271.161519) (xy 222.975581 -271.204672) (xy 223.000678 -271.251783)
			(xy 223.018964 -271.301932) (xy 223.03008 -271.354141) (xy 223.033811 -271.407389) (xy 223.030083 -271.460638)
			(xy 223.01897 -271.512847) (xy 223.000687 -271.562997) (xy 222.975592 -271.610109) (xy 222.944176 -271.653264)
			(xy 222.90705 -271.691618) (xy 222.88627 -271.708372) (xy 222.87752 -271.715945) (xy 222.867331 -271.736696)
			(xy 222.866712 -271.74825) (xy 222.866712 -271.828514) (xy 222.86727 -271.840084) (xy 222.877473 -271.860855)
			(xy 222.88627 -271.868392) (xy 222.908743 -271.886595) (xy 222.948481 -271.928611) (xy 222.981422 -271.976144)
			(xy 223.006812 -272.028103) (xy 223.02407 -272.083298) (xy 223.0328 -272.140467) (xy 223.033336 -272.169382)
			(xy 223.032805 -272.196631) (xy 223.025052 -272.250576) (xy 223.0097 -272.302868) (xy 222.987063 -272.352443)
			(xy 222.957602 -272.398293) (xy 222.921915 -272.439482) (xy 222.880729 -272.475174) (xy 222.84236 -272.499836)
			(xy 231.378258 -272.499836) (xy 231.382272 -272.294152) (xy 231.394308 -272.088782) (xy 231.414347 -271.884038)
			(xy 231.44236 -271.680231) (xy 231.478303 -271.477672) (xy 231.522122 -271.27667) (xy 231.573749 -271.077531)
			(xy 231.633107 -270.880558) (xy 231.700105 -270.68605) (xy 231.774641 -270.494305) (xy 231.856601 -270.305614)
			(xy 231.945861 -270.120264) (xy 232.042284 -269.938538) (xy 232.145725 -269.760712) (xy 232.256024 -269.587058)
			(xy 232.373015 -269.417839) (xy 232.496519 -269.253313) (xy 232.626348 -269.093732) (xy 232.762305 -268.939337)
			(xy 232.904182 -268.790365) (xy 233.051763 -268.647041) (xy 233.204824 -268.509585) (xy 233.363131 -268.378205)
			(xy 233.526444 -268.253102) (xy 233.694513 -268.134465) (xy 233.867083 -268.022477) (xy 234.043891 -267.917306)
			(xy 234.224668 -267.819115) (xy 234.409138 -267.728051) (xy 234.59702 -267.644254) (xy 234.78803 -267.567851)
			(xy 234.981874 -267.498958) (xy 235.178259 -267.437681) (xy 235.376885 -267.384113) (xy 235.57745 -267.338336)
			(xy 235.779648 -267.300418) (xy 235.983172 -267.270419) (xy 236.187711 -267.248382) (xy 236.392954 -267.234343)
			(xy 236.598589 -267.228323) (xy 236.804302 -267.23033) (xy 237.00978 -267.240362) (xy 237.21471 -267.258403)
			(xy 237.41878 -267.284426) (xy 237.62168 -267.318391) (xy 237.8231 -267.360246) (xy 238.022733 -267.409928)
			(xy 238.220276 -267.467362) (xy 238.415428 -267.532459) (xy 238.607892 -267.60512) (xy 238.797374 -267.685236)
			(xy 238.983585 -267.772683) (xy 239.166244 -267.867329) (xy 239.34507 -267.969029) (xy 239.519792 -268.077629)
			(xy 239.690145 -268.192964) (xy 239.855867 -268.314857) (xy 240.016708 -268.443123) (xy 240.172421 -268.577566)
			(xy 240.322771 -268.717983) (xy 240.467528 -268.864159) (xy 240.606471 -269.015871) (xy 240.739389 -269.172889)
			(xy 240.86608 -269.334974) (xy 240.98635 -269.501877) (xy 241.072241 -269.631446) (xy 249.332814 -269.631446)
			(xy 249.332814 -269.576954) (xy 249.340569 -269.523015) (xy 249.35592 -269.47073) (xy 249.378555 -269.421161)
			(xy 249.408014 -269.375317) (xy 249.443696 -269.334132) (xy 249.484877 -269.298444) (xy 249.530717 -269.268979)
			(xy 249.580283 -269.246337) (xy 249.632567 -269.230979) (xy 249.686504 -269.223218) (xy 249.71375 -269.222728)
			(xy 249.742666 -269.223272) (xy 249.799837 -269.231994) (xy 249.855035 -269.249246) (xy 249.906997 -269.274633)
			(xy 249.954532 -269.307573) (xy 249.99655 -269.34731) (xy 250.01474 -269.369794) (xy 250.02229 -269.378569)
			(xy 250.043058 -269.388745) (xy 250.054618 -269.389352) (xy 250.134882 -269.389352) (xy 250.146451 -269.388788)
			(xy 250.167223 -269.37859) (xy 250.17476 -269.369794) (xy 250.191513 -269.349011) (xy 250.229867 -269.311881)
			(xy 250.273021 -269.280459) (xy 250.320135 -269.25536) (xy 250.370287 -269.237074) (xy 250.422498 -269.225957)
			(xy 250.47575 -269.222227) (xy 250.529002 -269.225957) (xy 250.581213 -269.237074) (xy 250.631365 -269.25536)
			(xy 250.678479 -269.280459) (xy 250.721633 -269.311881) (xy 250.759987 -269.349011) (xy 250.77674 -269.369794)
			(xy 250.78429 -269.378569) (xy 250.805058 -269.388745) (xy 250.816618 -269.389352) (xy 250.896882 -269.389352)
			(xy 250.908451 -269.388788) (xy 250.929223 -269.37859) (xy 250.93676 -269.369794) (xy 250.953513 -269.349011)
			(xy 250.991867 -269.311881) (xy 251.035021 -269.280459) (xy 251.082135 -269.25536) (xy 251.132287 -269.237074)
			(xy 251.184498 -269.225957) (xy 251.23775 -269.222227) (xy 251.291002 -269.225957) (xy 251.343213 -269.237074)
			(xy 251.393365 -269.25536) (xy 251.440479 -269.280459) (xy 251.483633 -269.311881) (xy 251.521987 -269.349011)
			(xy 251.53874 -269.369794) (xy 251.54629 -269.378569) (xy 251.567058 -269.388745) (xy 251.578618 -269.389352)
			(xy 251.658882 -269.389352) (xy 251.670451 -269.388788) (xy 251.691223 -269.37859) (xy 251.69876 -269.369794)
			(xy 251.716972 -269.347328) (xy 251.758988 -269.307592) (xy 251.806518 -269.274651) (xy 251.858475 -269.24926)
			(xy 251.913669 -269.232) (xy 251.970835 -269.223266) (xy 251.99975 -269.222728) (xy 252.027008 -269.223116)
			(xy 252.080969 -269.230867) (xy 252.133278 -269.246221) (xy 252.182869 -269.268862) (xy 252.228733 -269.298332)
			(xy 252.269936 -269.334029) (xy 252.305638 -269.375227) (xy 252.335114 -269.421087) (xy 252.357762 -269.470675)
			(xy 252.373122 -269.522982) (xy 252.380881 -269.576942) (xy 252.380881 -269.631458) (xy 252.373122 -269.685418)
			(xy 252.357762 -269.737725) (xy 252.335114 -269.787313) (xy 252.305638 -269.833173) (xy 252.269936 -269.874371)
			(xy 252.228733 -269.910068) (xy 252.182869 -269.939538) (xy 252.133278 -269.962179) (xy 252.080969 -269.977533)
			(xy 252.027008 -269.985284) (xy 251.99975 -269.985744) (xy 251.970833 -269.985211) (xy 251.913662 -269.976488)
			(xy 251.858462 -269.959235) (xy 251.8065 -269.933846) (xy 251.758966 -269.900904) (xy 251.71695 -269.861163)
			(xy 251.69876 -269.838678) (xy 251.691215 -269.829899) (xy 251.670443 -269.819726) (xy 251.658882 -269.81912)
			(xy 251.578618 -269.81912) (xy 251.56705 -269.819694) (xy 251.546279 -269.829885) (xy 251.53874 -269.838678)
			(xy 251.521987 -269.859461) (xy 251.483633 -269.896591) (xy 251.440479 -269.928013) (xy 251.393365 -269.953112)
			(xy 251.343213 -269.971398) (xy 251.291002 -269.982515) (xy 251.23775 -269.986245) (xy 251.184498 -269.982515)
			(xy 251.132287 -269.971398) (xy 251.082135 -269.953112) (xy 251.035021 -269.928013) (xy 250.991867 -269.896591)
			(xy 250.953513 -269.859461) (xy 250.93676 -269.838678) (xy 250.929215 -269.829899) (xy 250.908443 -269.819726)
			(xy 250.896882 -269.81912) (xy 250.816618 -269.81912) (xy 250.80505 -269.819694) (xy 250.784279 -269.829885)
			(xy 250.77674 -269.838678) (xy 250.759987 -269.859461) (xy 250.721633 -269.896591) (xy 250.678479 -269.928013)
			(xy 250.631365 -269.953112) (xy 250.581213 -269.971398) (xy 250.529002 -269.982515) (xy 250.47575 -269.986245)
			(xy 250.422498 -269.982515) (xy 250.370287 -269.971398) (xy 250.320135 -269.953112) (xy 250.273021 -269.928013)
			(xy 250.229867 -269.896591) (xy 250.191513 -269.859461) (xy 250.17476 -269.838678) (xy 250.167215 -269.829899)
			(xy 250.146443 -269.819726) (xy 250.134882 -269.81912) (xy 250.054618 -269.81912) (xy 250.04305 -269.819694)
			(xy 250.022279 -269.829885) (xy 250.01474 -269.838678) (xy 249.996521 -269.861138) (xy 249.954508 -269.900875)
			(xy 249.906979 -269.933818) (xy 249.855023 -269.959211) (xy 249.79983 -269.976472) (xy 249.742664 -269.985206)
			(xy 249.71375 -269.985744) (xy 249.686504 -269.985182) (xy 249.632567 -269.977421) (xy 249.580283 -269.962063)
			(xy 249.530717 -269.939421) (xy 249.484877 -269.909956) (xy 249.443697 -269.874268) (xy 249.408014 -269.833083)
			(xy 249.378555 -269.787239) (xy 249.35592 -269.73767) (xy 249.340569 -269.685385) (xy 249.332814 -269.631446)
			(xy 241.072241 -269.631446) (xy 241.100017 -269.673347) (xy 241.206907 -269.84912) (xy 241.306858 -270.02893)
			(xy 241.399717 -270.212503) (xy 241.485344 -270.399559) (xy 241.563606 -270.589814) (xy 241.634387 -270.782977)
			(xy 241.697577 -270.978755) (xy 241.75308 -271.176849) (xy 241.774804 -271.267922) (xy 250.855751 -271.267922)
			(xy 250.859478 -271.214673) (xy 250.870593 -271.162463) (xy 250.888877 -271.112313) (xy 250.913975 -271.065201)
			(xy 250.945396 -271.022049) (xy 250.982526 -270.983698) (xy 251.003308 -270.966946) (xy 251.012046 -270.959361)
			(xy 251.022242 -270.93862) (xy 251.022866 -270.927068) (xy 251.022866 -270.846804) (xy 251.022305 -270.835235)
			(xy 251.012105 -270.814463) (xy 251.003308 -270.806926) (xy 250.980839 -270.788718) (xy 250.941102 -270.746702)
			(xy 250.908161 -270.699171) (xy 250.88277 -270.647213) (xy 250.865511 -270.592018) (xy 250.856779 -270.534851)
			(xy 250.856242 -270.505936) (xy 250.856689 -270.478682) (xy 250.864442 -270.424728) (xy 250.879796 -270.372426)
			(xy 250.902438 -270.322843) (xy 250.931907 -270.276987) (xy 250.967603 -270.235793) (xy 251.008799 -270.200099)
			(xy 251.054655 -270.170632) (xy 251.10424 -270.147991) (xy 251.156541 -270.132639) (xy 251.210496 -270.124888)
			(xy 251.23775 -270.124428) (xy 251.266666 -270.124972) (xy 251.323837 -270.133694) (xy 251.379035 -270.150946)
			(xy 251.430997 -270.176333) (xy 251.478532 -270.209273) (xy 251.52055 -270.24901) (xy 251.53874 -270.271494)
			(xy 251.54629 -270.280269) (xy 251.567058 -270.290445) (xy 251.578618 -270.291052) (xy 251.658882 -270.291052)
			(xy 251.670451 -270.290488) (xy 251.691223 -270.28029) (xy 251.69876 -270.271494) (xy 251.716972 -270.249028)
			(xy 251.758988 -270.209292) (xy 251.806518 -270.176351) (xy 251.858475 -270.15096) (xy 251.913669 -270.1337)
			(xy 251.970835 -270.124966) (xy 251.99975 -270.124428) (xy 252.027003 -270.124902) (xy 252.080956 -270.132653)
			(xy 252.133256 -270.148005) (xy 252.182838 -270.170644) (xy 252.228693 -270.20011) (xy 252.269887 -270.235803)
			(xy 252.305582 -270.276996) (xy 252.335049 -270.32285) (xy 252.357691 -270.372431) (xy 252.373044 -270.424731)
			(xy 252.380797 -270.478683) (xy 252.381258 -270.505936) (xy 252.38071 -270.534852) (xy 252.371989 -270.592023)
			(xy 252.354738 -270.647221) (xy 252.329352 -270.699184) (xy 252.296413 -270.746718) (xy 252.256676 -270.788736)
			(xy 252.234192 -270.806926) (xy 252.225422 -270.81448) (xy 252.215243 -270.835245) (xy 252.214634 -270.846804)
			(xy 252.214634 -270.927068) (xy 252.215211 -270.938635) (xy 252.2254 -270.959407) (xy 252.234192 -270.966946)
			(xy 252.255013 -270.983656) (xy 252.292148 -271.022012) (xy 252.323574 -271.065171) (xy 252.348675 -271.112289)
			(xy 252.366962 -271.162447) (xy 252.378078 -271.214665) (xy 252.381806 -271.267922) (xy 252.378072 -271.321179)
			(xy 252.36695 -271.373395) (xy 252.348657 -271.423551) (xy 252.32355 -271.470667) (xy 252.29212 -271.513822)
			(xy 252.25498 -271.552174) (xy 252.234192 -271.568926) (xy 252.225422 -271.57648) (xy 252.215243 -271.597245)
			(xy 252.214634 -271.608804) (xy 252.214634 -271.689068) (xy 252.215211 -271.700635) (xy 252.2254 -271.721407)
			(xy 252.234192 -271.728946) (xy 252.256648 -271.74717) (xy 252.296385 -271.789182) (xy 252.329328 -271.83671)
			(xy 252.354721 -271.888665) (xy 252.371983 -271.943857) (xy 252.380719 -272.001022) (xy 252.381258 -272.029936)
			(xy 252.380878 -272.057192) (xy 252.373115 -272.111149) (xy 252.357752 -272.163451) (xy 252.335102 -272.213035)
			(xy 252.305625 -272.25889) (xy 252.269923 -272.300084) (xy 252.228721 -272.335777) (xy 252.182859 -272.365243)
			(xy 252.13327 -272.387882) (xy 252.080964 -272.403234) (xy 252.027006 -272.410985) (xy 251.99975 -272.411444)
			(xy 251.970833 -272.410911) (xy 251.913662 -272.402188) (xy 251.858462 -272.384935) (xy 251.8065 -272.359546)
			(xy 251.758966 -272.326604) (xy 251.71695 -272.286863) (xy 251.69876 -272.264378) (xy 251.691215 -272.255599)
			(xy 251.670443 -272.245426) (xy 251.658882 -272.24482) (xy 251.578618 -272.24482) (xy 251.56705 -272.245394)
			(xy 251.546279 -272.255585) (xy 251.53874 -272.264378) (xy 251.520521 -272.286838) (xy 251.478508 -272.326575)
			(xy 251.430979 -272.359518) (xy 251.379023 -272.384911) (xy 251.32383 -272.402172) (xy 251.266664 -272.410906)
			(xy 251.23775 -272.411444) (xy 251.2105 -272.410898) (xy 251.156554 -272.403149) (xy 251.10426 -272.387801)
			(xy 251.054682 -272.365167) (xy 251.008831 -272.335708) (xy 250.967638 -272.300023) (xy 250.931944 -272.258838)
			(xy 250.902474 -272.212993) (xy 250.879829 -272.163421) (xy 250.864469 -272.11113) (xy 250.856708 -272.057186)
			(xy 250.856242 -272.029936) (xy 250.85677 -272.001019) (xy 250.865495 -271.943848) (xy 250.88275 -271.888648)
			(xy 250.90814 -271.836686) (xy 250.941082 -271.789152) (xy 250.980823 -271.747136) (xy 251.003308 -271.728946)
			(xy 251.012046 -271.721361) (xy 251.022242 -271.70062) (xy 251.022866 -271.689068) (xy 251.022866 -271.608804)
			(xy 251.022305 -271.597235) (xy 251.012105 -271.576463) (xy 251.003308 -271.568926) (xy 250.982558 -271.552131)
			(xy 250.945424 -271.513785) (xy 250.913999 -271.470636) (xy 250.888895 -271.423528) (xy 250.870605 -271.37338)
			(xy 250.859485 -271.321171) (xy 250.855751 -271.267922) (xy 241.774804 -271.267922) (xy 241.800812 -271.376958)
			(xy 241.840701 -271.578776) (xy 241.872685 -271.781998) (xy 241.896715 -271.986312) (xy 241.912756 -272.191408)
			(xy 241.920782 -272.396975) (xy 241.921284 -272.499836) (xy 241.920782 -272.602697) (xy 241.912756 -272.808264)
			(xy 241.900979 -272.958846) (xy 249.332814 -272.958846) (xy 249.332814 -272.904354) (xy 249.340569 -272.850415)
			(xy 249.35592 -272.79813) (xy 249.378555 -272.748561) (xy 249.408014 -272.702717) (xy 249.443696 -272.661532)
			(xy 249.484877 -272.625844) (xy 249.530717 -272.596379) (xy 249.580283 -272.573737) (xy 249.632567 -272.558379)
			(xy 249.686504 -272.550618) (xy 249.71375 -272.550128) (xy 249.742666 -272.550672) (xy 249.799837 -272.559394)
			(xy 249.855035 -272.576646) (xy 249.906997 -272.602033) (xy 249.954532 -272.634973) (xy 249.99655 -272.67471)
			(xy 250.01474 -272.697194) (xy 250.02229 -272.705969) (xy 250.043058 -272.716145) (xy 250.054618 -272.716752)
			(xy 250.134882 -272.716752) (xy 250.146451 -272.716188) (xy 250.167223 -272.70599) (xy 250.17476 -272.697194)
			(xy 250.191513 -272.676411) (xy 250.229867 -272.639281) (xy 250.273021 -272.607859) (xy 250.320135 -272.58276)
			(xy 250.370287 -272.564474) (xy 250.422498 -272.553357) (xy 250.47575 -272.549627) (xy 250.529002 -272.553357)
			(xy 250.581213 -272.564474) (xy 250.631365 -272.58276) (xy 250.678479 -272.607859) (xy 250.721633 -272.639281)
			(xy 250.759987 -272.676411) (xy 250.77674 -272.697194) (xy 250.78429 -272.705969) (xy 250.805058 -272.716145)
			(xy 250.816618 -272.716752) (xy 250.896882 -272.716752) (xy 250.908451 -272.716188) (xy 250.929223 -272.70599)
			(xy 250.93676 -272.697194) (xy 250.953513 -272.676411) (xy 250.991867 -272.639281) (xy 251.035021 -272.607859)
			(xy 251.082135 -272.58276) (xy 251.132287 -272.564474) (xy 251.184498 -272.553357) (xy 251.23775 -272.549627)
			(xy 251.291002 -272.553357) (xy 251.343213 -272.564474) (xy 251.393365 -272.58276) (xy 251.440479 -272.607859)
			(xy 251.483633 -272.639281) (xy 251.521987 -272.676411) (xy 251.53874 -272.697194) (xy 251.54629 -272.705969)
			(xy 251.567058 -272.716145) (xy 251.578618 -272.716752) (xy 251.658882 -272.716752) (xy 251.670451 -272.716188)
			(xy 251.691223 -272.70599) (xy 251.69876 -272.697194) (xy 251.716972 -272.674728) (xy 251.758988 -272.634992)
			(xy 251.806518 -272.602051) (xy 251.858475 -272.57666) (xy 251.913669 -272.5594) (xy 251.970835 -272.550666)
			(xy 251.99975 -272.550128) (xy 252.027008 -272.550516) (xy 252.080969 -272.558267) (xy 252.133278 -272.573621)
			(xy 252.182869 -272.596262) (xy 252.228733 -272.625732) (xy 252.269936 -272.661429) (xy 252.305638 -272.702627)
			(xy 252.335114 -272.748487) (xy 252.357762 -272.798075) (xy 252.373122 -272.850382) (xy 252.380881 -272.904342)
			(xy 252.380881 -272.958858) (xy 252.373122 -273.012818) (xy 252.357762 -273.065125) (xy 252.335114 -273.114713)
			(xy 252.305638 -273.160573) (xy 252.269936 -273.201771) (xy 252.228733 -273.237468) (xy 252.182869 -273.266938)
			(xy 252.133278 -273.289579) (xy 252.080969 -273.304933) (xy 252.027008 -273.312684) (xy 251.99975 -273.313144)
			(xy 251.970833 -273.312611) (xy 251.913662 -273.303888) (xy 251.858462 -273.286635) (xy 251.8065 -273.261246)
			(xy 251.758966 -273.228304) (xy 251.71695 -273.188563) (xy 251.69876 -273.166078) (xy 251.691215 -273.157299)
			(xy 251.670443 -273.147126) (xy 251.658882 -273.14652) (xy 251.578618 -273.14652) (xy 251.56705 -273.147094)
			(xy 251.546279 -273.157285) (xy 251.53874 -273.166078) (xy 251.521987 -273.186861) (xy 251.483633 -273.223991)
			(xy 251.440479 -273.255413) (xy 251.393365 -273.280512) (xy 251.343213 -273.298798) (xy 251.291002 -273.309915)
			(xy 251.23775 -273.313645) (xy 251.184498 -273.309915) (xy 251.132287 -273.298798) (xy 251.082135 -273.280512)
			(xy 251.035021 -273.255413) (xy 250.991867 -273.223991) (xy 250.953513 -273.186861) (xy 250.93676 -273.166078)
			(xy 250.929215 -273.157299) (xy 250.908443 -273.147126) (xy 250.896882 -273.14652) (xy 250.816618 -273.14652)
			(xy 250.80505 -273.147094) (xy 250.784279 -273.157285) (xy 250.77674 -273.166078) (xy 250.759987 -273.186861)
			(xy 250.721633 -273.223991) (xy 250.678479 -273.255413) (xy 250.631365 -273.280512) (xy 250.581213 -273.298798)
			(xy 250.529002 -273.309915) (xy 250.47575 -273.313645) (xy 250.422498 -273.309915) (xy 250.370287 -273.298798)
			(xy 250.320135 -273.280512) (xy 250.273021 -273.255413) (xy 250.229867 -273.223991) (xy 250.191513 -273.186861)
			(xy 250.17476 -273.166078) (xy 250.167215 -273.157299) (xy 250.146443 -273.147126) (xy 250.134882 -273.14652)
			(xy 250.054618 -273.14652) (xy 250.04305 -273.147094) (xy 250.022279 -273.157285) (xy 250.01474 -273.166078)
			(xy 249.996521 -273.188538) (xy 249.954508 -273.228275) (xy 249.906979 -273.261218) (xy 249.855023 -273.286611)
			(xy 249.79983 -273.303872) (xy 249.742664 -273.312606) (xy 249.71375 -273.313144) (xy 249.686504 -273.312582)
			(xy 249.632567 -273.304821) (xy 249.580283 -273.289463) (xy 249.530717 -273.266821) (xy 249.484877 -273.237356)
			(xy 249.443697 -273.201668) (xy 249.408014 -273.160483) (xy 249.378555 -273.114639) (xy 249.35592 -273.06507)
			(xy 249.340569 -273.012785) (xy 249.332814 -272.958846) (xy 241.900979 -272.958846) (xy 241.896715 -273.01336)
			(xy 241.872685 -273.217674) (xy 241.840701 -273.420896) (xy 241.800812 -273.622714) (xy 241.75308 -273.822823)
			(xy 241.697577 -274.020917) (xy 241.634387 -274.216695) (xy 241.563606 -274.409858) (xy 241.485344 -274.600113)
			(xy 241.399717 -274.787169) (xy 241.306858 -274.970742) (xy 241.206907 -275.150552) (xy 241.100017 -275.326325)
			(xy 240.98635 -275.497795) (xy 240.86608 -275.664698) (xy 240.739389 -275.826783) (xy 240.606471 -275.983801)
			(xy 240.467528 -276.135513) (xy 240.322771 -276.281689) (xy 240.172421 -276.422106) (xy 240.016708 -276.556549)
			(xy 239.855867 -276.684815) (xy 239.690145 -276.806708) (xy 239.519792 -276.922043) (xy 239.34507 -277.030643)
			(xy 239.166244 -277.132343) (xy 238.983585 -277.226989) (xy 238.797374 -277.314436) (xy 238.607892 -277.394552)
			(xy 238.415428 -277.467213) (xy 238.220276 -277.53231) (xy 238.022733 -277.589744) (xy 237.8231 -277.639426)
			(xy 237.62168 -277.681281) (xy 237.41878 -277.715246) (xy 237.21471 -277.741269) (xy 237.00978 -277.75931)
			(xy 236.804302 -277.769342) (xy 236.598589 -277.771349) (xy 236.392954 -277.765329) (xy 236.187711 -277.75129)
			(xy 235.983172 -277.729253) (xy 235.779648 -277.699254) (xy 235.57745 -277.661336) (xy 235.376885 -277.615559)
			(xy 235.178259 -277.561991) (xy 234.981874 -277.500714) (xy 234.78803 -277.431821) (xy 234.59702 -277.355418)
			(xy 234.409138 -277.271621) (xy 234.224668 -277.180557) (xy 234.043891 -277.082366) (xy 233.867083 -276.977195)
			(xy 233.694513 -276.865207) (xy 233.526444 -276.74657) (xy 233.363131 -276.621467) (xy 233.204824 -276.490087)
			(xy 233.051763 -276.352631) (xy 232.904182 -276.209307) (xy 232.762305 -276.060335) (xy 232.626348 -275.90594)
			(xy 232.496519 -275.746359) (xy 232.373015 -275.581833) (xy 232.256024 -275.412614) (xy 232.145725 -275.23896)
			(xy 232.042284 -275.061134) (xy 231.945861 -274.879408) (xy 231.856601 -274.694058) (xy 231.774641 -274.505367)
			(xy 231.700105 -274.313622) (xy 231.633107 -274.119114) (xy 231.573749 -273.922141) (xy 231.522122 -273.723002)
			(xy 231.478303 -273.522) (xy 231.44236 -273.319441) (xy 231.414347 -273.115634) (xy 231.394308 -272.91089)
			(xy 231.382272 -272.70552) (xy 231.378258 -272.499836) (xy 222.84236 -272.499836) (xy 222.834884 -272.504641)
			(xy 222.785311 -272.527284) (xy 222.733021 -272.542642) (xy 222.679077 -272.550402) (xy 222.651828 -272.55089)
			(xy 222.622912 -272.550355) (xy 222.565741 -272.54163) (xy 222.510542 -272.524376) (xy 222.458581 -272.498987)
			(xy 222.411046 -272.466046) (xy 222.369029 -272.426308) (xy 222.350838 -272.403824) (xy 222.343268 -272.395071)
			(xy 222.322515 -272.384886) (xy 222.31096 -272.384266) (xy 222.230696 -272.384266) (xy 222.219124 -272.384811)
			(xy 222.198352 -272.395021) (xy 222.190818 -272.403824) (xy 222.172623 -272.426304) (xy 222.130603 -272.466038)
			(xy 222.083069 -272.498977) (xy 222.031109 -272.524366) (xy 221.975912 -272.541623) (xy 221.918744 -272.550354)
			(xy 221.889828 -272.55089) (xy 221.862575 -272.550419) (xy 221.808623 -272.542665) (xy 221.756325 -272.527312)
			(xy 221.706743 -272.504671) (xy 221.660889 -272.475204) (xy 221.619696 -272.439511) (xy 221.584002 -272.398319)
			(xy 221.554534 -272.352465) (xy 221.531892 -272.302885) (xy 221.516537 -272.250586) (xy 221.508782 -272.196635)
			(xy 221.50832 -272.169382) (xy 221.508889 -272.140467) (xy 221.517607 -272.083298) (xy 221.534854 -272.0281)
			(xy 221.560236 -271.976137) (xy 221.593171 -271.928602) (xy 221.632904 -271.886583) (xy 221.655386 -271.868392)
			(xy 221.664145 -271.860827) (xy 221.674331 -271.840071) (xy 221.674944 -271.828514) (xy 221.674944 -271.74825)
			(xy 221.674365 -271.736683) (xy 221.664178 -271.71591) (xy 221.655386 -271.708372) (xy 221.634584 -271.691641)
			(xy 221.597451 -271.653286) (xy 221.566027 -271.610129) (xy 221.540927 -271.563013) (xy 221.52264 -271.512858)
			(xy 221.511524 -271.460643) (xy 221.507795 -271.407389) (xy 218.943682 -271.407389) (xy 218.943682 -273.098355)
			(xy 221.508737 -273.098355) (xy 221.508737 -273.043845) (xy 221.516495 -272.989889) (xy 221.531853 -272.937586)
			(xy 221.554499 -272.888002) (xy 221.583971 -272.842145) (xy 221.619669 -272.800949) (xy 221.660867 -272.765254)
			(xy 221.706726 -272.735785) (xy 221.756312 -272.713143) (xy 221.808616 -272.697789) (xy 221.862573 -272.690035)
			(xy 221.889828 -272.689574) (xy 221.918744 -272.690116) (xy 221.975916 -272.698836) (xy 222.031115 -272.716088)
			(xy 222.083078 -272.741475) (xy 222.130612 -272.774416) (xy 222.172628 -272.814155) (xy 222.190818 -272.83664)
			(xy 222.19837 -272.845412) (xy 222.219136 -272.855588) (xy 222.230696 -272.856198) (xy 222.31096 -272.856198)
			(xy 222.322525 -272.855605) (xy 222.343296 -272.845427) (xy 222.350838 -272.83664) (xy 222.367591 -272.815857)
			(xy 222.405945 -272.778727) (xy 222.449099 -272.747305) (xy 222.496213 -272.722206) (xy 222.546365 -272.70392)
			(xy 222.598576 -272.692803) (xy 222.651828 -272.689073) (xy 222.70508 -272.692803) (xy 222.757291 -272.70392)
			(xy 222.807443 -272.722206) (xy 222.854557 -272.747305) (xy 222.897711 -272.778727) (xy 222.936065 -272.815857)
			(xy 222.952818 -272.83664) (xy 222.96037 -272.845412) (xy 222.981136 -272.855588) (xy 222.992696 -272.856198)
			(xy 223.07296 -272.856198) (xy 223.084525 -272.855605) (xy 223.105296 -272.845427) (xy 223.112838 -272.83664)
			(xy 223.129591 -272.815857) (xy 223.167945 -272.778727) (xy 223.211099 -272.747305) (xy 223.258213 -272.722206)
			(xy 223.308365 -272.70392) (xy 223.360576 -272.692803) (xy 223.413828 -272.689073) (xy 223.46708 -272.692803)
			(xy 223.519291 -272.70392) (xy 223.569443 -272.722206) (xy 223.616557 -272.747305) (xy 223.659711 -272.778727)
			(xy 223.698065 -272.815857) (xy 223.714818 -272.83664) (xy 223.72237 -272.845412) (xy 223.743136 -272.855588)
			(xy 223.754696 -272.856198) (xy 223.83496 -272.856198) (xy 223.846525 -272.855605) (xy 223.867296 -272.845427)
			(xy 223.874838 -272.83664) (xy 223.893018 -272.814147) (xy 223.935039 -272.77441) (xy 223.982575 -272.741471)
			(xy 224.034539 -272.716084) (xy 224.089739 -272.698831) (xy 224.146911 -272.690106) (xy 224.175828 -272.689574)
			(xy 224.203077 -272.690098) (xy 224.257019 -272.697858) (xy 224.309308 -272.713214) (xy 224.358879 -272.735856)
			(xy 224.404724 -272.765322) (xy 224.445908 -272.801011) (xy 224.481595 -272.842199) (xy 224.511057 -272.888046)
			(xy 224.533695 -272.937619) (xy 224.549048 -272.989909) (xy 224.556804 -273.043851) (xy 224.556804 -273.098349)
			(xy 224.549048 -273.152291) (xy 224.533695 -273.204581) (xy 224.511057 -273.254154) (xy 224.481595 -273.300001)
			(xy 224.445908 -273.341189) (xy 224.404724 -273.376878) (xy 224.358879 -273.406344) (xy 224.309308 -273.428986)
			(xy 224.257019 -273.444342) (xy 224.203077 -273.452102) (xy 224.175828 -273.45259) (xy 224.146912 -273.452055)
			(xy 224.089741 -273.44333) (xy 224.034542 -273.426076) (xy 223.982581 -273.400687) (xy 223.935046 -273.367746)
			(xy 223.893029 -273.328008) (xy 223.874838 -273.305524) (xy 223.867268 -273.296771) (xy 223.846515 -273.286586)
			(xy 223.83496 -273.285966) (xy 223.754696 -273.285966) (xy 223.743124 -273.286511) (xy 223.722352 -273.296721)
			(xy 223.714818 -273.305524) (xy 223.698065 -273.326307) (xy 223.659711 -273.363437) (xy 223.616557 -273.394859)
			(xy 223.569443 -273.419958) (xy 223.519291 -273.438244) (xy 223.46708 -273.449361) (xy 223.413828 -273.453091)
			(xy 223.360576 -273.449361) (xy 223.308365 -273.438244) (xy 223.258213 -273.419958) (xy 223.211099 -273.394859)
			(xy 223.167945 -273.363437) (xy 223.129591 -273.326307) (xy 223.112838 -273.305524) (xy 223.105268 -273.296771)
			(xy 223.084515 -273.286586) (xy 223.07296 -273.285966) (xy 222.992696 -273.285966) (xy 222.981124 -273.286511)
			(xy 222.960352 -273.296721) (xy 222.952818 -273.305524) (xy 222.936065 -273.326307) (xy 222.897711 -273.363437)
			(xy 222.854557 -273.394859) (xy 222.807443 -273.419958) (xy 222.757291 -273.438244) (xy 222.70508 -273.449361)
			(xy 222.651828 -273.453091) (xy 222.598576 -273.449361) (xy 222.546365 -273.438244) (xy 222.496213 -273.419958)
			(xy 222.449099 -273.394859) (xy 222.405945 -273.363437) (xy 222.367591 -273.326307) (xy 222.350838 -273.305524)
			(xy 222.343268 -273.296771) (xy 222.322515 -273.286586) (xy 222.31096 -273.285966) (xy 222.230696 -273.285966)
			(xy 222.219124 -273.286511) (xy 222.198352 -273.296721) (xy 222.190818 -273.305524) (xy 222.172623 -273.328004)
			(xy 222.130603 -273.367738) (xy 222.083069 -273.400677) (xy 222.031109 -273.426066) (xy 221.975912 -273.443323)
			(xy 221.918744 -273.452054) (xy 221.889828 -273.45259) (xy 221.862573 -273.452165) (xy 221.808616 -273.444411)
			(xy 221.756312 -273.429057) (xy 221.706726 -273.406415) (xy 221.660867 -273.376946) (xy 221.619669 -273.341251)
			(xy 221.583971 -273.300055) (xy 221.554499 -273.254198) (xy 221.531853 -273.204614) (xy 221.516495 -273.152311)
			(xy 221.508737 -273.098355) (xy 218.943682 -273.098355) (xy 218.943682 -288.15538) (xy 225.493324 -288.15538)
			(xy 225.497395 -288.099758) (xy 225.509521 -288.045321) (xy 225.529444 -287.99323) (xy 225.55674 -287.944595)
			(xy 225.590826 -287.900452) (xy 225.630975 -287.861743) (xy 225.676333 -287.829292) (xy 225.725933 -287.803791)
			(xy 225.778717 -287.785784) (xy 225.83356 -287.775654) (xy 225.889294 -287.773617) (xy 225.944731 -287.779717)
			(xy 225.998688 -287.793823) (xy 226.050017 -287.815635) (xy 226.097623 -287.844689) (xy 226.140491 -287.880364)
			(xy 226.177708 -287.921901) (xy 226.208481 -287.968414) (xy 226.232153 -288.018911) (xy 226.248221 -288.072318)
			(xy 226.255698 -288.123122) (xy 237.653574 -288.123122) (xy 237.657645 -288.0675) (xy 237.669771 -288.013063)
			(xy 237.689694 -287.960972) (xy 237.71699 -287.912337) (xy 237.751076 -287.868194) (xy 237.791225 -287.829485)
			(xy 237.836583 -287.797034) (xy 237.886183 -287.771533) (xy 237.938967 -287.753526) (xy 237.99381 -287.743396)
			(xy 238.049544 -287.741359) (xy 238.104981 -287.747459) (xy 238.158938 -287.761565) (xy 238.210267 -287.783377)
			(xy 238.257873 -287.812431) (xy 238.300741 -287.848106) (xy 238.337958 -287.889643) (xy 238.368731 -287.936156)
			(xy 238.392403 -287.986653) (xy 238.408471 -288.04006) (xy 238.416591 -288.095236) (xy 238.4171 -288.123122)
			(xy 238.416591 -288.151008) (xy 238.408471 -288.206184) (xy 238.392403 -288.259591) (xy 238.368731 -288.310088)
			(xy 238.337958 -288.356601) (xy 238.300741 -288.398138) (xy 238.257873 -288.433813) (xy 238.210267 -288.462867)
			(xy 238.158938 -288.484679) (xy 238.104981 -288.498785) (xy 238.049544 -288.504885) (xy 237.99381 -288.502848)
			(xy 237.938967 -288.492718) (xy 237.886183 -288.474711) (xy 237.836583 -288.44921) (xy 237.791225 -288.416759)
			(xy 237.751076 -288.37805) (xy 237.71699 -288.333907) (xy 237.689694 -288.285272) (xy 237.669771 -288.233181)
			(xy 237.657645 -288.178744) (xy 237.653574 -288.123122) (xy 226.255698 -288.123122) (xy 226.256341 -288.127494)
			(xy 226.25685 -288.15538) (xy 226.256341 -288.183266) (xy 226.248221 -288.238442) (xy 226.232153 -288.291849)
			(xy 226.208481 -288.342346) (xy 226.177708 -288.388859) (xy 226.140491 -288.430396) (xy 226.097623 -288.466071)
			(xy 226.050017 -288.495125) (xy 225.998688 -288.516937) (xy 225.944731 -288.531043) (xy 225.889294 -288.537143)
			(xy 225.83356 -288.535106) (xy 225.778717 -288.524976) (xy 225.725933 -288.506969) (xy 225.676333 -288.481468)
			(xy 225.630975 -288.449017) (xy 225.590826 -288.410308) (xy 225.55674 -288.366165) (xy 225.529444 -288.31753)
			(xy 225.509521 -288.265439) (xy 225.497395 -288.211002) (xy 225.493324 -288.15538) (xy 218.943682 -288.15538)
			(xy 218.943682 -288.939732) (xy 228.82352 -288.939732) (xy 228.824006 -288.912481) (xy 228.831762 -288.858533)
			(xy 228.847117 -288.806238) (xy 228.869759 -288.756661) (xy 228.899225 -288.710811) (xy 228.934916 -288.66962)
			(xy 228.976107 -288.633929) (xy 229.021957 -288.604463) (xy 229.071534 -288.581821) (xy 229.123829 -288.566466)
			(xy 229.177777 -288.55871) (xy 229.232279 -288.55871) (xy 229.286227 -288.566466) (xy 229.338522 -288.581821)
			(xy 229.388099 -288.604463) (xy 229.433949 -288.633929) (xy 229.47514 -288.66962) (xy 229.510831 -288.710811)
			(xy 229.540297 -288.756661) (xy 229.562939 -288.806238) (xy 229.578294 -288.858533) (xy 229.58605 -288.912481)
			(xy 229.586536 -288.939732) (xy 240.76787 -288.939732) (xy 240.768356 -288.912481) (xy 240.776112 -288.858533)
			(xy 240.791467 -288.806238) (xy 240.814109 -288.756661) (xy 240.843575 -288.710811) (xy 240.879266 -288.66962)
			(xy 240.920457 -288.633929) (xy 240.966307 -288.604463) (xy 241.015884 -288.581821) (xy 241.068179 -288.566466)
			(xy 241.122127 -288.55871) (xy 241.176629 -288.55871) (xy 241.230577 -288.566466) (xy 241.282872 -288.581821)
			(xy 241.332449 -288.604463) (xy 241.378299 -288.633929) (xy 241.41949 -288.66962) (xy 241.455181 -288.710811)
			(xy 241.484647 -288.756661) (xy 241.507289 -288.806238) (xy 241.522644 -288.858533) (xy 241.5304 -288.912481)
			(xy 241.530886 -288.939732) (xy 241.530366 -288.967593) (xy 241.522273 -289.022725) (xy 241.506249 -289.076094)
			(xy 241.482635 -289.126566) (xy 241.451932 -289.173067) (xy 241.414794 -289.214609) (xy 241.393726 -289.232848)
			(xy 241.384582 -289.240468) (xy 241.37493 -289.26155) (xy 241.378486 -289.365436) (xy 241.389408 -289.38601)
			(xy 241.39906 -289.393122) (xy 241.41961 -289.408545) (xy 241.456743 -289.444058) (xy 241.488774 -289.484233)
			(xy 241.515123 -289.528344) (xy 241.535312 -289.575593) (xy 241.548976 -289.625124) (xy 241.555869 -289.676041)
			(xy 241.556286 -289.701732) (xy 241.5558 -289.728983) (xy 241.548044 -289.782931) (xy 241.532689 -289.835226)
			(xy 241.510047 -289.884803) (xy 241.480581 -289.930653) (xy 241.44489 -289.971844) (xy 241.403699 -290.007535)
			(xy 241.357849 -290.037001) (xy 241.308272 -290.059643) (xy 241.255977 -290.074998) (xy 241.202029 -290.082754)
			(xy 241.147527 -290.082754) (xy 241.093579 -290.074998) (xy 241.041284 -290.059643) (xy 240.991707 -290.037001)
			(xy 240.945857 -290.007535) (xy 240.904666 -289.971844) (xy 240.868975 -289.930653) (xy 240.839509 -289.884803)
			(xy 240.816867 -289.835226) (xy 240.801512 -289.782931) (xy 240.793756 -289.728983) (xy 240.79327 -289.701732)
			(xy 240.793781 -289.67387) (xy 240.801878 -289.618739) (xy 240.817905 -289.565371) (xy 240.841521 -289.514899)
			(xy 240.872224 -289.468398) (xy 240.909363 -289.426856) (xy 240.93043 -289.408616) (xy 240.939574 -289.400996)
			(xy 240.949226 -289.379914) (xy 240.94567 -289.276028) (xy 240.934748 -289.255454) (xy 240.925096 -289.248342)
			(xy 240.904589 -289.232864) (xy 240.867451 -289.197363) (xy 240.835415 -289.157198) (xy 240.809061 -289.113096)
			(xy 240.788864 -289.065855) (xy 240.775192 -289.016331) (xy 240.768292 -288.96542) (xy 240.76787 -288.939732)
			(xy 229.586536 -288.939732) (xy 229.585998 -288.967593) (xy 229.577906 -289.022723) (xy 229.561885 -289.076091)
			(xy 229.538274 -289.126562) (xy 229.507575 -289.173063) (xy 229.470441 -289.214608) (xy 229.449376 -289.232848)
			(xy 229.440232 -289.240468) (xy 229.43058 -289.26155) (xy 229.434136 -289.365436) (xy 229.445058 -289.38601)
			(xy 229.45471 -289.393122) (xy 229.475249 -289.408559) (xy 229.512385 -289.444068) (xy 229.544418 -289.48424)
			(xy 229.570769 -289.528349) (xy 229.59096 -289.575596) (xy 229.604625 -289.625126) (xy 229.611519 -289.676042)
			(xy 229.611936 -289.701732) (xy 229.61145 -289.728983) (xy 229.603694 -289.782931) (xy 229.588339 -289.835226)
			(xy 229.565697 -289.884803) (xy 229.536231 -289.930653) (xy 229.50054 -289.971844) (xy 229.459349 -290.007535)
			(xy 229.413499 -290.037001) (xy 229.363922 -290.059643) (xy 229.311627 -290.074998) (xy 229.257679 -290.082754)
			(xy 229.203177 -290.082754) (xy 229.149229 -290.074998) (xy 229.096934 -290.059643) (xy 229.047357 -290.037001)
			(xy 229.001507 -290.007535) (xy 228.960316 -289.971844) (xy 228.924625 -289.930653) (xy 228.895159 -289.884803)
			(xy 228.872517 -289.835226) (xy 228.857162 -289.782931) (xy 228.849406 -289.728983) (xy 228.84892 -289.701732)
			(xy 228.849448 -289.673871) (xy 228.857544 -289.618741) (xy 228.873569 -289.565374) (xy 228.897182 -289.514903)
			(xy 228.927881 -289.468402) (xy 228.965015 -289.426857) (xy 228.98608 -289.408616) (xy 228.995224 -289.400996)
			(xy 229.004876 -289.379914) (xy 229.00132 -289.276028) (xy 228.990398 -289.255454) (xy 228.980746 -289.248342)
			(xy 228.960228 -289.232879) (xy 228.923093 -289.197373) (xy 228.891059 -289.157205) (xy 228.864707 -289.1131)
			(xy 228.844512 -289.065858) (xy 228.830842 -289.016333) (xy 228.823942 -288.965421) (xy 228.82352 -288.939732)
			(xy 218.943682 -288.939732) (xy 218.943682 -290.844732) (xy 236.659418 -290.844732) (xy 236.663489 -290.78911)
			(xy 236.675615 -290.734673) (xy 236.695538 -290.682582) (xy 236.722834 -290.633947) (xy 236.75692 -290.589804)
			(xy 236.797069 -290.551095) (xy 236.842427 -290.518644) (xy 236.892027 -290.493143) (xy 236.944811 -290.475136)
			(xy 236.999654 -290.465006) (xy 237.055388 -290.462969) (xy 237.110825 -290.469069) (xy 237.164782 -290.483175)
			(xy 237.216111 -290.504987) (xy 237.263717 -290.534041) (xy 237.306585 -290.569716) (xy 237.343802 -290.611253)
			(xy 237.374575 -290.657766) (xy 237.398247 -290.708263) (xy 237.414315 -290.76167) (xy 237.422435 -290.816846)
			(xy 237.422944 -290.844732) (xy 237.422435 -290.872618) (xy 237.414315 -290.927794) (xy 237.398247 -290.981201)
			(xy 237.374575 -291.031698) (xy 237.343802 -291.078211) (xy 237.306585 -291.119748) (xy 237.263717 -291.155423)
			(xy 237.216111 -291.184477) (xy 237.164782 -291.206289) (xy 237.110825 -291.220395) (xy 237.055388 -291.226495)
			(xy 236.999654 -291.224458) (xy 236.944811 -291.214328) (xy 236.892027 -291.196321) (xy 236.842427 -291.17082)
			(xy 236.797069 -291.138369) (xy 236.75692 -291.09966) (xy 236.722834 -291.055517) (xy 236.695538 -291.006882)
			(xy 236.675615 -290.954791) (xy 236.663489 -290.900354) (xy 236.659418 -290.844732) (xy 218.943682 -290.844732)
			(xy 218.943682 -291.614098) (xy 237.461804 -291.614098) (xy 237.465875 -291.558476) (xy 237.478001 -291.504039)
			(xy 237.497924 -291.451948) (xy 237.52522 -291.403313) (xy 237.559306 -291.35917) (xy 237.599455 -291.320461)
			(xy 237.644813 -291.28801) (xy 237.694413 -291.262509) (xy 237.747197 -291.244502) (xy 237.80204 -291.234372)
			(xy 237.857774 -291.232335) (xy 237.913211 -291.238435) (xy 237.967168 -291.252541) (xy 238.018497 -291.274353)
			(xy 238.066103 -291.303407) (xy 238.108971 -291.339082) (xy 238.146188 -291.380619) (xy 238.176961 -291.427132)
			(xy 238.200633 -291.477629) (xy 238.216701 -291.531036) (xy 238.224821 -291.586212) (xy 238.22533 -291.614098)
			(xy 238.224821 -291.641984) (xy 238.216701 -291.69716) (xy 238.200633 -291.750567) (xy 238.176961 -291.801064)
			(xy 238.146188 -291.847577) (xy 238.108971 -291.889114) (xy 238.066103 -291.924789) (xy 238.018497 -291.953843)
			(xy 237.967168 -291.975655) (xy 237.913211 -291.989761) (xy 237.857774 -291.995861) (xy 237.80204 -291.993824)
			(xy 237.747197 -291.983694) (xy 237.694413 -291.965687) (xy 237.644813 -291.940186) (xy 237.599455 -291.907735)
			(xy 237.559306 -291.869026) (xy 237.52522 -291.824883) (xy 237.497924 -291.776248) (xy 237.478001 -291.724157)
			(xy 237.465875 -291.66972) (xy 237.461804 -291.614098) (xy 218.943682 -291.614098) (xy 218.943682 -292.025578)
			(xy 226.184966 -292.025578) (xy 226.189037 -291.969956) (xy 226.201163 -291.915519) (xy 226.221086 -291.863428)
			(xy 226.248382 -291.814793) (xy 226.282468 -291.77065) (xy 226.322617 -291.731941) (xy 226.367975 -291.69949)
			(xy 226.417575 -291.673989) (xy 226.470359 -291.655982) (xy 226.525202 -291.645852) (xy 226.580936 -291.643815)
			(xy 226.636373 -291.649915) (xy 226.69033 -291.664021) (xy 226.741659 -291.685833) (xy 226.789265 -291.714887)
			(xy 226.832133 -291.750562) (xy 226.86935 -291.792099) (xy 226.900123 -291.838612) (xy 226.923795 -291.889109)
			(xy 226.939863 -291.942516) (xy 226.947983 -291.997692) (xy 226.948492 -292.025578) (xy 226.947983 -292.053464)
			(xy 226.939863 -292.10864) (xy 226.923795 -292.162047) (xy 226.900123 -292.212544) (xy 226.86935 -292.259057)
			(xy 226.836853 -292.295326) (xy 228.289102 -292.295326) (xy 228.293173 -292.239704) (xy 228.305299 -292.185267)
			(xy 228.325222 -292.133176) (xy 228.352518 -292.084541) (xy 228.386604 -292.040398) (xy 228.426753 -292.001689)
			(xy 228.472111 -291.969238) (xy 228.521711 -291.943737) (xy 228.574495 -291.92573) (xy 228.629338 -291.9156)
			(xy 228.685072 -291.913563) (xy 228.740509 -291.919663) (xy 228.794466 -291.933769) (xy 228.845795 -291.955581)
			(xy 228.893401 -291.984635) (xy 228.936269 -292.02031) (xy 228.973486 -292.061847) (xy 229.004259 -292.10836)
			(xy 229.027931 -292.158857) (xy 229.043999 -292.212264) (xy 229.052119 -292.26744) (xy 229.052628 -292.295326)
			(xy 240.233452 -292.295326) (xy 240.237523 -292.239704) (xy 240.249649 -292.185267) (xy 240.269572 -292.133176)
			(xy 240.296868 -292.084541) (xy 240.330954 -292.040398) (xy 240.371103 -292.001689) (xy 240.416461 -291.969238)
			(xy 240.466061 -291.943737) (xy 240.518845 -291.92573) (xy 240.573688 -291.9156) (xy 240.629422 -291.913563)
			(xy 240.684859 -291.919663) (xy 240.738816 -291.933769) (xy 240.790145 -291.955581) (xy 240.837751 -291.984635)
			(xy 240.880619 -292.02031) (xy 240.917836 -292.061847) (xy 240.948609 -292.10836) (xy 240.972281 -292.158857)
			(xy 240.988349 -292.212264) (xy 240.996469 -292.26744) (xy 240.996978 -292.295326) (xy 240.996469 -292.323212)
			(xy 240.988349 -292.378388) (xy 240.972281 -292.431795) (xy 240.948609 -292.482292) (xy 240.917836 -292.528805)
			(xy 240.880619 -292.570342) (xy 240.837751 -292.606017) (xy 240.790145 -292.635071) (xy 240.738816 -292.656883)
			(xy 240.684859 -292.670989) (xy 240.629422 -292.677089) (xy 240.573688 -292.675052) (xy 240.518845 -292.664922)
			(xy 240.466061 -292.646915) (xy 240.416461 -292.621414) (xy 240.371103 -292.588963) (xy 240.330954 -292.550254)
			(xy 240.296868 -292.506111) (xy 240.269572 -292.457476) (xy 240.249649 -292.405385) (xy 240.237523 -292.350948)
			(xy 240.233452 -292.295326) (xy 229.052628 -292.295326) (xy 229.052119 -292.323212) (xy 229.043999 -292.378388)
			(xy 229.027931 -292.431795) (xy 229.004259 -292.482292) (xy 228.973486 -292.528805) (xy 228.936269 -292.570342)
			(xy 228.893401 -292.606017) (xy 228.845795 -292.635071) (xy 228.794466 -292.656883) (xy 228.740509 -292.670989)
			(xy 228.685072 -292.677089) (xy 228.629338 -292.675052) (xy 228.574495 -292.664922) (xy 228.521711 -292.646915)
			(xy 228.472111 -292.621414) (xy 228.426753 -292.588963) (xy 228.386604 -292.550254) (xy 228.352518 -292.506111)
			(xy 228.325222 -292.457476) (xy 228.305299 -292.405385) (xy 228.293173 -292.350948) (xy 228.289102 -292.295326)
			(xy 226.836853 -292.295326) (xy 226.832133 -292.300594) (xy 226.789265 -292.336269) (xy 226.741659 -292.365323)
			(xy 226.69033 -292.387135) (xy 226.636373 -292.401241) (xy 226.580936 -292.407341) (xy 226.525202 -292.405304)
			(xy 226.470359 -292.395174) (xy 226.417575 -292.377167) (xy 226.367975 -292.351666) (xy 226.322617 -292.319215)
			(xy 226.282468 -292.280506) (xy 226.248382 -292.236363) (xy 226.221086 -292.187728) (xy 226.201163 -292.135637)
			(xy 226.189037 -292.0812) (xy 226.184966 -292.025578) (xy 218.943682 -292.025578) (xy 218.943682 -293.537132)
			(xy 233.241848 -293.537132) (xy 233.245919 -293.48151) (xy 233.258045 -293.427073) (xy 233.277968 -293.374982)
			(xy 233.305264 -293.326347) (xy 233.33935 -293.282204) (xy 233.379499 -293.243495) (xy 233.424857 -293.211044)
			(xy 233.474457 -293.185543) (xy 233.527241 -293.167536) (xy 233.582084 -293.157406) (xy 233.637818 -293.155369)
			(xy 233.693255 -293.161469) (xy 233.747212 -293.175575) (xy 233.798541 -293.197387) (xy 233.846147 -293.226441)
			(xy 233.889015 -293.262116) (xy 233.926232 -293.303653) (xy 233.957005 -293.350166) (xy 233.980677 -293.400663)
			(xy 233.996745 -293.45407) (xy 234.004865 -293.509246) (xy 234.005374 -293.537132) (xy 245.186198 -293.537132)
			(xy 245.190269 -293.48151) (xy 245.202395 -293.427073) (xy 245.222318 -293.374982) (xy 245.249614 -293.326347)
			(xy 245.2837 -293.282204) (xy 245.323849 -293.243495) (xy 245.369207 -293.211044) (xy 245.418807 -293.185543)
			(xy 245.471591 -293.167536) (xy 245.526434 -293.157406) (xy 245.582168 -293.155369) (xy 245.637605 -293.161469)
			(xy 245.691562 -293.175575) (xy 245.742891 -293.197387) (xy 245.790497 -293.226441) (xy 245.833365 -293.262116)
			(xy 245.870582 -293.303653) (xy 245.901355 -293.350166) (xy 245.925027 -293.400663) (xy 245.941095 -293.45407)
			(xy 245.949215 -293.509246) (xy 245.949724 -293.537132) (xy 245.949215 -293.565018) (xy 245.941095 -293.620194)
			(xy 245.925027 -293.673601) (xy 245.901355 -293.724098) (xy 245.870582 -293.770611) (xy 245.833365 -293.812148)
			(xy 245.790497 -293.847823) (xy 245.742891 -293.876877) (xy 245.691562 -293.898689) (xy 245.637605 -293.912795)
			(xy 245.582168 -293.918895) (xy 245.526434 -293.916858) (xy 245.471591 -293.906728) (xy 245.418807 -293.888721)
			(xy 245.369207 -293.86322) (xy 245.323849 -293.830769) (xy 245.2837 -293.79206) (xy 245.249614 -293.747917)
			(xy 245.222318 -293.699282) (xy 245.202395 -293.647191) (xy 245.190269 -293.592754) (xy 245.186198 -293.537132)
			(xy 234.005374 -293.537132) (xy 234.004865 -293.565018) (xy 233.996745 -293.620194) (xy 233.980677 -293.673601)
			(xy 233.957005 -293.724098) (xy 233.926232 -293.770611) (xy 233.889015 -293.812148) (xy 233.846147 -293.847823)
			(xy 233.798541 -293.876877) (xy 233.747212 -293.898689) (xy 233.693255 -293.912795) (xy 233.637818 -293.918895)
			(xy 233.582084 -293.916858) (xy 233.527241 -293.906728) (xy 233.474457 -293.888721) (xy 233.424857 -293.86322)
			(xy 233.379499 -293.830769) (xy 233.33935 -293.79206) (xy 233.305264 -293.747917) (xy 233.277968 -293.699282)
			(xy 233.258045 -293.647191) (xy 233.245919 -293.592754) (xy 233.241848 -293.537132) (xy 218.943682 -293.537132)
			(xy 218.943682 -310.520088) (xy 225.232699 -310.520088) (xy 225.236431 -310.466833) (xy 225.247551 -310.414618)
			(xy 225.265842 -310.364464) (xy 225.290946 -310.317349) (xy 225.322373 -310.274194) (xy 225.35951 -310.235842)
			(xy 225.380296 -310.21909) (xy 225.389057 -310.211527) (xy 225.399241 -310.190769) (xy 225.399854 -310.179212)
			(xy 225.399854 -310.098948) (xy 225.399272 -310.087381) (xy 225.389087 -310.066609) (xy 225.380296 -310.05907)
			(xy 225.357797 -310.040897) (xy 225.318063 -309.998873) (xy 225.285126 -309.951335) (xy 225.25974 -309.89937)
			(xy 225.242488 -309.844169) (xy 225.233763 -309.786997) (xy 225.23323 -309.75808) (xy 225.233636 -309.730825)
			(xy 225.241397 -309.67687) (xy 225.256758 -309.624569) (xy 225.279405 -309.574986) (xy 225.308879 -309.529131)
			(xy 225.344579 -309.487937) (xy 225.385777 -309.452244) (xy 225.431637 -309.422777) (xy 225.481223 -309.400137)
			(xy 225.533527 -309.384785) (xy 225.587483 -309.377032) (xy 225.614738 -309.376572) (xy 225.643655 -309.377108)
			(xy 225.700826 -309.385829) (xy 225.756026 -309.403082) (xy 225.807988 -309.42847) (xy 225.855522 -309.461412)
			(xy 225.897538 -309.501153) (xy 225.915728 -309.523638) (xy 225.923276 -309.532414) (xy 225.944045 -309.542588)
			(xy 225.955606 -309.543196) (xy 226.03587 -309.543196) (xy 226.047436 -309.54261) (xy 226.068207 -309.532426)
			(xy 226.075748 -309.523638) (xy 226.093978 -309.501187) (xy 226.135988 -309.461448) (xy 226.183515 -309.428504)
			(xy 226.235469 -309.40311) (xy 226.29066 -309.385847) (xy 226.347824 -309.377111) (xy 226.376738 -309.376572)
			(xy 226.403989 -309.377042) (xy 226.457937 -309.384804) (xy 226.51023 -309.400163) (xy 226.559806 -309.422807)
			(xy 226.605656 -309.452275) (xy 226.646845 -309.487968) (xy 226.682536 -309.529159) (xy 226.712002 -309.575009)
			(xy 226.734644 -309.624587) (xy 226.75 -309.676881) (xy 226.757759 -309.730829) (xy 226.758246 -309.75808)
			(xy 226.757734 -309.786997) (xy 226.749006 -309.84417) (xy 226.731749 -309.89937) (xy 226.706356 -309.951332)
			(xy 226.67341 -309.998865) (xy 226.633667 -310.040881) (xy 226.61118 -310.05907) (xy 226.602433 -310.066646)
			(xy 226.592242 -310.087394) (xy 226.591622 -310.098948) (xy 226.591622 -310.179212) (xy 226.592178 -310.190782)
			(xy 226.602382 -310.211553) (xy 226.61118 -310.21909) (xy 226.631941 -310.235868) (xy 226.669068 -310.27422)
			(xy 226.700486 -310.317372) (xy 226.725583 -310.364483) (xy 226.743868 -310.414632) (xy 226.754985 -310.46684)
			(xy 226.758716 -310.520088) (xy 231.279453 -310.520088) (xy 231.283184 -310.466835) (xy 231.294301 -310.414623)
			(xy 231.312588 -310.36447) (xy 231.337687 -310.317356) (xy 231.369108 -310.2742) (xy 231.406237 -310.235845)
			(xy 231.42702 -310.21909) (xy 231.435785 -310.211532) (xy 231.445966 -310.19077) (xy 231.446578 -310.179212)
			(xy 231.446578 -310.098948) (xy 231.445988 -310.087383) (xy 231.435808 -310.066611) (xy 231.42702 -310.05907)
			(xy 231.404526 -310.040891) (xy 231.364791 -309.998869) (xy 231.331852 -309.951332) (xy 231.306466 -309.899368)
			(xy 231.289212 -309.844168) (xy 231.280487 -309.786997) (xy 231.279954 -309.75808) (xy 231.280459 -309.73083)
			(xy 231.288217 -309.676885) (xy 231.303573 -309.624593) (xy 231.326214 -309.575018) (xy 231.355679 -309.52917)
			(xy 231.391368 -309.487981) (xy 231.432555 -309.452289) (xy 231.478402 -309.422822) (xy 231.527976 -309.400179)
			(xy 231.580267 -309.384821) (xy 231.634212 -309.37706) (xy 231.661462 -309.376572) (xy 231.690379 -309.37709)
			(xy 231.747552 -309.385815) (xy 231.802752 -309.403071) (xy 231.854714 -309.428463) (xy 231.902248 -309.461408)
			(xy 231.944263 -309.501151) (xy 231.962452 -309.523638) (xy 231.970033 -309.53238) (xy 231.990777 -309.542573)
			(xy 232.00233 -309.543196) (xy 232.082594 -309.543196) (xy 232.094162 -309.542624) (xy 232.114933 -309.532431)
			(xy 232.122472 -309.523638) (xy 232.140688 -309.501176) (xy 232.182702 -309.461438) (xy 232.230231 -309.428495)
			(xy 232.282188 -309.403103) (xy 232.337381 -309.385842) (xy 232.394547 -309.377109) (xy 232.423462 -309.376572)
			(xy 232.450713 -309.377091) (xy 232.504661 -309.384842) (xy 232.556957 -309.400192) (xy 232.606535 -309.422829)
			(xy 232.652388 -309.452291) (xy 232.69358 -309.487979) (xy 232.729274 -309.529166) (xy 232.758743 -309.575014)
			(xy 232.781388 -309.624589) (xy 232.796746 -309.676882) (xy 232.804505 -309.730829) (xy 232.80497 -309.75808)
			(xy 232.804449 -309.786997) (xy 232.795722 -309.844169) (xy 232.778465 -309.899368) (xy 232.753074 -309.95133)
			(xy 232.720131 -309.998864) (xy 232.68039 -310.04088) (xy 232.657904 -310.05907) (xy 232.649161 -310.06665)
			(xy 232.638967 -310.087395) (xy 232.638346 -310.098948) (xy 232.638346 -310.179212) (xy 232.638894 -310.190783)
			(xy 232.649103 -310.211555) (xy 232.657904 -310.21909) (xy 232.678669 -310.235866) (xy 232.715802 -310.274215)
			(xy 232.747227 -310.317366) (xy 232.772329 -310.364477) (xy 232.790618 -310.414627) (xy 232.801737 -310.466837)
			(xy 232.805469 -310.520088) (xy 232.80174 -310.573338) (xy 232.790625 -310.625549) (xy 232.772339 -310.675701)
			(xy 232.74724 -310.722813) (xy 232.715818 -310.765966) (xy 232.678687 -310.804317) (xy 232.657904 -310.82107)
			(xy 232.649161 -310.82865) (xy 232.638967 -310.849395) (xy 232.638346 -310.860948) (xy 232.638346 -310.941212)
			(xy 232.638894 -310.952783) (xy 232.649103 -310.973555) (xy 232.657904 -310.98109) (xy 232.680384 -310.999286)
			(xy 232.720119 -311.041305) (xy 232.753058 -311.088839) (xy 232.778447 -311.140799) (xy 232.795704 -311.195996)
			(xy 232.804434 -311.253164) (xy 232.80497 -311.28208) (xy 232.804526 -311.309334) (xy 232.796771 -311.363288)
			(xy 232.781415 -311.415588) (xy 232.758772 -311.465171) (xy 232.729303 -311.511026) (xy 232.693607 -311.55222)
			(xy 232.652411 -311.587914) (xy 232.606555 -311.617381) (xy 232.556971 -311.640022) (xy 232.50467 -311.655375)
			(xy 232.450716 -311.663127) (xy 232.423462 -311.663588) (xy 232.394547 -311.66303) (xy 232.337377 -311.65431)
			(xy 232.282179 -311.63706) (xy 232.230217 -311.611676) (xy 232.182682 -311.578739) (xy 232.140663 -311.539005)
			(xy 232.122472 -311.516522) (xy 232.114931 -311.507739) (xy 232.094156 -311.49757) (xy 232.082594 -311.496964)
			(xy 232.00233 -311.496964) (xy 231.990761 -311.497529) (xy 231.969988 -311.507725) (xy 231.962452 -311.516522)
			(xy 231.944237 -311.538985) (xy 231.902222 -311.578721) (xy 231.854692 -311.611661) (xy 231.802735 -311.637053)
			(xy 231.747542 -311.654314) (xy 231.690376 -311.663049) (xy 231.661462 -311.663588) (xy 231.634209 -311.663157)
			(xy 231.580258 -311.655395) (xy 231.527961 -311.640034) (xy 231.478382 -311.617387) (xy 231.432531 -311.587915)
			(xy 231.391341 -311.552218) (xy 231.35565 -311.511022) (xy 231.326185 -311.465167) (xy 231.303545 -311.415584)
			(xy 231.288192 -311.363285) (xy 231.280438 -311.309333) (xy 231.279954 -311.28208) (xy 231.280509 -311.253164)
			(xy 231.289228 -311.195994) (xy 231.306477 -311.140795) (xy 231.331862 -311.088833) (xy 231.3648 -311.041298)
			(xy 231.404537 -310.999281) (xy 231.42702 -310.98109) (xy 231.435785 -310.973532) (xy 231.445966 -310.95277)
			(xy 231.446578 -310.941212) (xy 231.446578 -310.860948) (xy 231.445988 -310.849383) (xy 231.435808 -310.828611)
			(xy 231.42702 -310.82107) (xy 231.406219 -310.804339) (xy 231.369092 -310.765981) (xy 231.337674 -310.722823)
			(xy 231.312578 -310.675707) (xy 231.294295 -310.625553) (xy 231.283181 -310.57334) (xy 231.279453 -310.520088)
			(xy 226.758716 -310.520088) (xy 226.754988 -310.573336) (xy 226.743875 -310.625544) (xy 226.725593 -310.675694)
			(xy 226.700499 -310.722807) (xy 226.669084 -310.765961) (xy 226.63196 -310.804316) (xy 226.61118 -310.82107)
			(xy 226.602433 -310.828646) (xy 226.592242 -310.849394) (xy 226.591622 -310.860948) (xy 226.591622 -310.941212)
			(xy 226.592178 -310.952782) (xy 226.602382 -310.973553) (xy 226.61118 -310.98109) (xy 226.633655 -310.999292)
			(xy 226.673391 -311.041309) (xy 226.706332 -311.088841) (xy 226.731722 -311.1408) (xy 226.74898 -311.195996)
			(xy 226.75771 -311.253165) (xy 226.758246 -311.28208) (xy 226.757703 -311.309329) (xy 226.74995 -311.363273)
			(xy 226.7346 -311.415564) (xy 226.711964 -311.465139) (xy 226.682503 -311.510987) (xy 226.646818 -311.552177)
			(xy 226.605634 -311.587868) (xy 226.559789 -311.617336) (xy 226.510218 -311.63998) (xy 226.457929 -311.655338)
			(xy 226.403987 -311.663099) (xy 226.376738 -311.663588) (xy 226.347822 -311.663047) (xy 226.290652 -311.654323)
			(xy 226.235453 -311.63707) (xy 226.183491 -311.611683) (xy 226.135957 -311.578743) (xy 226.093939 -311.539006)
			(xy 226.075748 -311.516522) (xy 226.068174 -311.507773) (xy 226.047424 -311.497586) (xy 226.03587 -311.496964)
			(xy 225.955606 -311.496964) (xy 225.944035 -311.497516) (xy 225.923263 -311.507721) (xy 225.915728 -311.516522)
			(xy 225.897527 -311.538997) (xy 225.855508 -311.578731) (xy 225.807975 -311.611671) (xy 225.756016 -311.63706)
			(xy 225.700821 -311.654319) (xy 225.643653 -311.663051) (xy 225.614738 -311.663588) (xy 225.587485 -311.663109)
			(xy 225.533534 -311.655357) (xy 225.481235 -311.640005) (xy 225.431654 -311.617365) (xy 225.385799 -311.587899)
			(xy 225.344606 -311.552207) (xy 225.308911 -311.511015) (xy 225.279443 -311.465162) (xy 225.256802 -311.415582)
			(xy 225.241447 -311.363284) (xy 225.233692 -311.309333) (xy 225.23323 -311.28208) (xy 225.233795 -311.253165)
			(xy 225.242513 -311.195995) (xy 225.259761 -311.140797) (xy 225.285143 -311.088835) (xy 225.31808 -311.0413)
			(xy 225.357814 -310.999281) (xy 225.380296 -310.98109) (xy 225.389057 -310.973527) (xy 225.399241 -310.952769)
			(xy 225.399854 -310.941212) (xy 225.399854 -310.860948) (xy 225.399272 -310.849381) (xy 225.389087 -310.828609)
			(xy 225.380296 -310.82107) (xy 225.359492 -310.804341) (xy 225.322357 -310.765987) (xy 225.290933 -310.72283)
			(xy 225.265832 -310.675714) (xy 225.247545 -310.625558) (xy 225.236428 -310.573343) (xy 225.232699 -310.520088)
			(xy 218.943682 -310.520088) (xy 218.943682 -313.076827) (xy 222.352414 -313.076827) (xy 222.356139 -313.023581)
			(xy 222.36725 -312.971374) (xy 222.38553 -312.921226) (xy 222.410622 -312.874115) (xy 222.442035 -312.830962)
			(xy 222.479157 -312.792608) (xy 222.499936 -312.775854) (xy 222.50872 -312.768314) (xy 222.51889 -312.747538)
			(xy 222.519494 -312.735976) (xy 222.519494 -312.655712) (xy 222.518919 -312.644145) (xy 222.508728 -312.623374)
			(xy 222.499936 -312.615834) (xy 222.477476 -312.597615) (xy 222.437738 -312.555602) (xy 222.404795 -312.508073)
			(xy 222.379402 -312.456117) (xy 222.362141 -312.400924) (xy 222.353407 -312.343759) (xy 222.35287 -312.314844)
			(xy 222.353356 -312.287593) (xy 222.361112 -312.233645) (xy 222.376467 -312.18135) (xy 222.399109 -312.131773)
			(xy 222.428575 -312.085923) (xy 222.464266 -312.044732) (xy 222.505457 -312.009041) (xy 222.551307 -311.979575)
			(xy 222.600884 -311.956933) (xy 222.653179 -311.941578) (xy 222.707127 -311.933822) (xy 222.761629 -311.933822)
			(xy 222.815577 -311.941578) (xy 222.867872 -311.956933) (xy 222.917449 -311.979575) (xy 222.963299 -312.009041)
			(xy 223.00449 -312.044732) (xy 223.040181 -312.085923) (xy 223.069647 -312.131773) (xy 223.092289 -312.18135)
			(xy 223.107644 -312.233645) (xy 223.1154 -312.287593) (xy 223.115886 -312.314844) (xy 223.115333 -312.34376)
			(xy 223.106612 -312.40093) (xy 223.089361 -312.456128) (xy 223.063976 -312.50809) (xy 223.031038 -312.555625)
			(xy 222.991303 -312.597643) (xy 222.96882 -312.615834) (xy 222.960034 -312.623372) (xy 222.949867 -312.644149)
			(xy 222.949262 -312.655712) (xy 222.949262 -312.735976) (xy 222.949825 -312.747545) (xy 222.960023 -312.768318)
			(xy 222.96882 -312.775854) (xy 222.989647 -312.792555) (xy 223.02678 -312.830913) (xy 223.058203 -312.874074)
			(xy 223.083303 -312.921193) (xy 223.101588 -312.971352) (xy 223.112703 -313.02357) (xy 223.116429 -313.076827)
			(xy 223.113276 -313.121801) (xy 223.568279 -313.121801) (xy 223.572008 -313.068551) (xy 223.583124 -313.01634)
			(xy 223.601408 -312.966188) (xy 223.626505 -312.919075) (xy 223.657924 -312.87592) (xy 223.695052 -312.837566)
			(xy 223.715834 -312.820812) (xy 223.724592 -312.813246) (xy 223.734776 -312.79249) (xy 223.735392 -312.780934)
			(xy 223.735392 -312.70067) (xy 223.734784 -312.689107) (xy 223.724616 -312.668335) (xy 223.715834 -312.660792)
			(xy 223.693354 -312.642597) (xy 223.653617 -312.600579) (xy 223.620676 -312.553045) (xy 223.595287 -312.501085)
			(xy 223.578031 -312.445887) (xy 223.569302 -312.388718) (xy 223.568768 -312.359802) (xy 223.569254 -312.332551)
			(xy 223.57701 -312.278603) (xy 223.592365 -312.226308) (xy 223.615007 -312.176731) (xy 223.644473 -312.130881)
			(xy 223.680164 -312.08969) (xy 223.721355 -312.053999) (xy 223.767205 -312.024533) (xy 223.816782 -312.001891)
			(xy 223.869077 -311.986536) (xy 223.923025 -311.97878) (xy 223.977527 -311.97878) (xy 224.031475 -311.986536)
			(xy 224.08377 -312.001891) (xy 224.133347 -312.024533) (xy 224.179197 -312.053999) (xy 224.220388 -312.08969)
			(xy 224.256079 -312.130881) (xy 224.285545 -312.176731) (xy 224.308187 -312.226308) (xy 224.323542 -312.278603)
			(xy 224.331298 -312.332551) (xy 224.331784 -312.359802) (xy 224.331273 -312.388719) (xy 224.322543 -312.445891)
			(xy 224.305284 -312.50109) (xy 224.279891 -312.553052) (xy 224.246946 -312.600586) (xy 224.207204 -312.642602)
			(xy 224.184718 -312.660792) (xy 224.17595 -312.668347) (xy 224.165773 -312.689112) (xy 224.16516 -312.70067)
			(xy 224.16516 -312.780934) (xy 224.165747 -312.7925) (xy 224.175928 -312.813273) (xy 224.184718 -312.820812)
			(xy 224.205504 -312.837562) (xy 224.242637 -312.875915) (xy 224.27406 -312.919069) (xy 224.29916 -312.966183)
			(xy 224.317448 -313.016336) (xy 224.328565 -313.068549) (xy 224.332295 -313.121801) (xy 224.329501 -313.161688)
			(xy 224.841563 -313.161688) (xy 224.845294 -313.108435) (xy 224.856412 -313.056222) (xy 224.874699 -313.006069)
			(xy 224.899799 -312.958954) (xy 224.931222 -312.915799) (xy 224.968353 -312.877444) (xy 224.989136 -312.86069)
			(xy 224.997904 -312.853134) (xy 225.008083 -312.832371) (xy 225.008694 -312.820812) (xy 225.008694 -312.740548)
			(xy 225.008098 -312.728983) (xy 224.997922 -312.708212) (xy 224.989136 -312.70067) (xy 224.966646 -312.682487)
			(xy 224.926909 -312.640467) (xy 224.89397 -312.59293) (xy 224.868582 -312.540967) (xy 224.851328 -312.485768)
			(xy 224.842603 -312.428597) (xy 224.84207 -312.39968) (xy 224.842556 -312.372429) (xy 224.850312 -312.318481)
			(xy 224.865667 -312.266186) (xy 224.888309 -312.216609) (xy 224.917775 -312.170759) (xy 224.953466 -312.129568)
			(xy 224.994657 -312.093877) (xy 225.040507 -312.064411) (xy 225.090084 -312.041769) (xy 225.142379 -312.026414)
			(xy 225.196327 -312.018658) (xy 225.250829 -312.018658) (xy 225.304777 -312.026414) (xy 225.357072 -312.041769)
			(xy 225.406649 -312.064411) (xy 225.452499 -312.093877) (xy 225.49369 -312.129568) (xy 225.529381 -312.170759)
			(xy 225.558847 -312.216609) (xy 225.581489 -312.266186) (xy 225.596844 -312.318481) (xy 225.6046 -312.372429)
			(xy 225.605086 -312.39968) (xy 225.604559 -312.428597) (xy 225.595832 -312.485768) (xy 225.578576 -312.540966)
			(xy 225.553186 -312.592928) (xy 225.520244 -312.640462) (xy 225.480505 -312.68248) (xy 225.45802 -312.70067)
			(xy 225.449263 -312.708236) (xy 225.43908 -312.728992) (xy 225.438462 -312.740548) (xy 225.438462 -312.820812)
			(xy 225.439004 -312.832384) (xy 225.449217 -312.853156) (xy 225.45802 -312.86069) (xy 225.478784 -312.877467)
			(xy 225.515916 -312.915816) (xy 225.547339 -312.958968) (xy 225.57244 -313.006078) (xy 225.590728 -313.056228)
			(xy 225.601847 -313.108438) (xy 225.605578 -313.161688) (xy 225.60185 -313.214938) (xy 225.590735 -313.267148)
			(xy 225.57245 -313.317299) (xy 225.547352 -313.364412) (xy 225.515932 -313.407565) (xy 225.478802 -313.445917)
			(xy 225.45802 -313.46267) (xy 225.449263 -313.470236) (xy 225.43908 -313.490992) (xy 225.438462 -313.502548)
			(xy 225.438462 -313.582812) (xy 225.439004 -313.594384) (xy 225.449217 -313.615156) (xy 225.45802 -313.62269)
			(xy 225.480503 -313.640882) (xy 225.520237 -313.682902) (xy 225.553176 -313.730437) (xy 225.578564 -313.782398)
			(xy 225.595821 -313.837595) (xy 225.60455 -313.894764) (xy 225.605086 -313.92368) (xy 225.6046 -313.950931)
			(xy 225.596844 -314.004879) (xy 225.581489 -314.057174) (xy 225.558847 -314.106751) (xy 225.529381 -314.152601)
			(xy 225.49369 -314.193792) (xy 225.452499 -314.229483) (xy 225.406649 -314.258949) (xy 225.357072 -314.281591)
			(xy 225.304777 -314.296946) (xy 225.250829 -314.304702) (xy 225.196327 -314.304702) (xy 225.142379 -314.296946)
			(xy 225.090084 -314.281591) (xy 225.040507 -314.258949) (xy 224.994657 -314.229483) (xy 224.953466 -314.193792)
			(xy 224.917775 -314.152601) (xy 224.888309 -314.106751) (xy 224.865667 -314.057174) (xy 224.850312 -314.004879)
			(xy 224.842556 -313.950931) (xy 224.84207 -313.92368) (xy 224.842619 -313.894764) (xy 224.851338 -313.837593)
			(xy 224.868588 -313.782394) (xy 224.893974 -313.730431) (xy 224.926914 -313.682897) (xy 224.966652 -313.64088)
			(xy 224.989136 -313.62269) (xy 224.997904 -313.615134) (xy 225.008083 -313.594371) (xy 225.008694 -313.582812)
			(xy 225.008694 -313.502548) (xy 225.008098 -313.490983) (xy 224.997922 -313.470212) (xy 224.989136 -313.46267)
			(xy 224.968334 -313.44594) (xy 224.931206 -313.407583) (xy 224.899786 -313.364425) (xy 224.874689 -313.317309)
			(xy 224.856405 -313.267154) (xy 224.845291 -313.214941) (xy 224.841563 -313.161688) (xy 224.329501 -313.161688)
			(xy 224.328565 -313.175054) (xy 224.317447 -313.227266) (xy 224.299159 -313.277419) (xy 224.274059 -313.324533)
			(xy 224.242635 -313.367687) (xy 224.205502 -313.406039) (xy 224.184718 -313.422792) (xy 224.17595 -313.430347)
			(xy 224.165773 -313.451112) (xy 224.16516 -313.46267) (xy 224.16516 -313.542934) (xy 224.165747 -313.5545)
			(xy 224.175928 -313.575273) (xy 224.184718 -313.582812) (xy 224.207211 -313.600992) (xy 224.246945 -313.643014)
			(xy 224.279882 -313.690552) (xy 224.305269 -313.742515) (xy 224.322523 -313.797714) (xy 224.33125 -313.854885)
			(xy 224.331784 -313.883802) (xy 224.331355 -313.909545) (xy 224.324435 -313.960563) (xy 224.310722 -314.010189)
			(xy 224.290463 -314.057521) (xy 224.264028 -314.101701) (xy 224.231894 -314.141928) (xy 224.194646 -314.177471)
			(xy 224.17405 -314.19292) (xy 224.163636 -314.200286) (xy 224.15246 -314.222892) (xy 224.156524 -314.332874)
			(xy 224.169224 -314.354718) (xy 224.180146 -314.361576) (xy 224.203415 -314.376576) (xy 224.245749 -314.41225)
			(xy 224.282478 -314.453672) (xy 224.312831 -314.49997) (xy 224.336169 -314.550171) (xy 224.352002 -314.603219)
			(xy 224.359997 -314.658) (xy 224.360486 -314.68568) (xy 224.359959 -314.714597) (xy 224.351232 -314.771768)
			(xy 224.333976 -314.826966) (xy 224.308586 -314.878928) (xy 224.275644 -314.926462) (xy 224.235905 -314.96848)
			(xy 224.21342 -314.98667) (xy 224.204663 -314.994236) (xy 224.19448 -315.014992) (xy 224.193862 -315.026548)
			(xy 224.193862 -315.106812) (xy 224.194404 -315.118384) (xy 224.204617 -315.139156) (xy 224.21342 -315.14669)
			(xy 224.235903 -315.164882) (xy 224.275637 -315.206902) (xy 224.308576 -315.254437) (xy 224.333964 -315.306398)
			(xy 224.351221 -315.361595) (xy 224.35995 -315.418764) (xy 224.360486 -315.44768) (xy 227.43287 -315.44768)
			(xy 227.433419 -315.418764) (xy 227.442138 -315.361593) (xy 227.459388 -315.306394) (xy 227.484774 -315.254431)
			(xy 227.517714 -315.206897) (xy 227.557452 -315.16488) (xy 227.579936 -315.14669) (xy 227.588704 -315.139134)
			(xy 227.598883 -315.118371) (xy 227.599494 -315.106812) (xy 227.599494 -315.026548) (xy 227.598898 -315.014983)
			(xy 227.588722 -314.994212) (xy 227.579936 -314.98667) (xy 227.557446 -314.968487) (xy 227.517709 -314.926467)
			(xy 227.48477 -314.87893) (xy 227.459382 -314.826967) (xy 227.442128 -314.771768) (xy 227.433403 -314.714597)
			(xy 227.43287 -314.68568) (xy 227.433289 -314.659704) (xy 227.440335 -314.608231) (xy 227.454307 -314.558193)
			(xy 227.474946 -314.510516) (xy 227.501871 -314.466085) (xy 227.53458 -314.425723) (xy 227.572469 -314.390177)
			(xy 227.593398 -314.374784) (xy 227.603304 -314.367672) (xy 227.61448 -314.346336) (xy 227.616766 -314.240926)
			(xy 227.606606 -314.219082) (xy 227.596954 -314.211716) (xy 227.576197 -314.194932) (xy 227.539067 -314.156582)
			(xy 227.507646 -314.113431) (xy 227.482547 -314.066321) (xy 227.46426 -314.016173) (xy 227.453142 -313.963964)
			(xy 227.44941 -313.910716) (xy 227.453137 -313.857467) (xy 227.464251 -313.805258) (xy 227.482534 -313.755108)
			(xy 227.507629 -313.707996) (xy 227.539047 -313.664842) (xy 227.576173 -313.626489) (xy 227.596954 -313.609736)
			(xy 227.605704 -313.602164) (xy 227.615892 -313.581412) (xy 227.616512 -313.569858) (xy 227.616512 -313.489594)
			(xy 227.615941 -313.478026) (xy 227.605746 -313.457256) (xy 227.596954 -313.449716) (xy 227.576197 -313.432932)
			(xy 227.539067 -313.394582) (xy 227.507646 -313.351431) (xy 227.482547 -313.304321) (xy 227.46426 -313.254173)
			(xy 227.453142 -313.201964) (xy 227.44941 -313.148716) (xy 227.453137 -313.095467) (xy 227.464251 -313.043258)
			(xy 227.482534 -312.993108) (xy 227.507629 -312.945996) (xy 227.539047 -312.902842) (xy 227.576173 -312.864489)
			(xy 227.596954 -312.847736) (xy 227.605704 -312.840164) (xy 227.615892 -312.819412) (xy 227.616512 -312.807858)
			(xy 227.616512 -312.727594) (xy 227.615941 -312.716026) (xy 227.605746 -312.695256) (xy 227.596954 -312.687716)
			(xy 227.574469 -312.669528) (xy 227.534736 -312.627506) (xy 227.501798 -312.57997) (xy 227.476411 -312.528008)
			(xy 227.459154 -312.472811) (xy 227.450424 -312.415642) (xy 227.449888 -312.386726) (xy 227.450374 -312.359475)
			(xy 227.45813 -312.305527) (xy 227.473485 -312.253232) (xy 227.496127 -312.203655) (xy 227.525593 -312.157805)
			(xy 227.561284 -312.116614) (xy 227.602475 -312.080923) (xy 227.648325 -312.051457) (xy 227.697902 -312.028815)
			(xy 227.750197 -312.01346) (xy 227.804145 -312.005704) (xy 227.858647 -312.005704) (xy 227.912595 -312.01346)
			(xy 227.96489 -312.028815) (xy 228.014467 -312.051457) (xy 228.060317 -312.080923) (xy 228.101508 -312.116614)
			(xy 228.137199 -312.157805) (xy 228.166665 -312.203655) (xy 228.189307 -312.253232) (xy 228.204662 -312.305527)
			(xy 228.212418 -312.359475) (xy 228.212904 -312.386726) (xy 228.212369 -312.415643) (xy 228.203648 -312.472815)
			(xy 228.186396 -312.528015) (xy 228.161008 -312.579977) (xy 228.128065 -312.627511) (xy 228.088324 -312.669527)
			(xy 228.065838 -312.687716) (xy 228.057063 -312.695265) (xy 228.046889 -312.716034) (xy 228.04628 -312.727594)
			(xy 228.04628 -312.807858) (xy 228.046882 -312.819422) (xy 228.057055 -312.840192) (xy 228.065838 -312.847736)
			(xy 228.086647 -312.864459) (xy 228.123778 -312.902815) (xy 228.155199 -312.945974) (xy 228.180298 -312.993091)
			(xy 228.198583 -313.043246) (xy 228.209698 -313.095461) (xy 228.213426 -313.148716) (xy 228.21216 -313.166775)
			(xy 229.48998 -313.166775) (xy 229.493714 -313.113519) (xy 229.504836 -313.061303) (xy 229.523128 -313.011147)
			(xy 229.548235 -312.964031) (xy 229.579664 -312.920875) (xy 229.616803 -312.882522) (xy 229.63759 -312.86577)
			(xy 229.646359 -312.858215) (xy 229.656539 -312.837451) (xy 229.657148 -312.825892) (xy 229.657148 -312.745628)
			(xy 229.656579 -312.734059) (xy 229.646385 -312.713287) (xy 229.63759 -312.70575) (xy 229.615128 -312.687533)
			(xy 229.575392 -312.645519) (xy 229.542451 -312.597989) (xy 229.517059 -312.546033) (xy 229.499798 -312.49084)
			(xy 229.491063 -312.433674) (xy 229.490524 -312.40476) (xy 229.49101 -312.377509) (xy 229.498766 -312.323561)
			(xy 229.514121 -312.271266) (xy 229.536763 -312.221689) (xy 229.566229 -312.175839) (xy 229.60192 -312.134648)
			(xy 229.643111 -312.098957) (xy 229.688961 -312.069491) (xy 229.738538 -312.046849) (xy 229.790833 -312.031494)
			(xy 229.844781 -312.023738) (xy 229.899283 -312.023738) (xy 229.953231 -312.031494) (xy 230.005526 -312.046849)
			(xy 230.055103 -312.069491) (xy 230.100953 -312.098957) (xy 230.142144 -312.134648) (xy 230.177835 -312.175839)
			(xy 230.207301 -312.221689) (xy 230.229943 -312.271266) (xy 230.245298 -312.323561) (xy 230.253054 -312.377509)
			(xy 230.25354 -312.40476) (xy 230.253016 -312.433677) (xy 230.244291 -312.490849) (xy 230.227036 -312.546049)
			(xy 230.201646 -312.598011) (xy 230.168702 -312.645545) (xy 230.12896 -312.687561) (xy 230.106474 -312.70575)
			(xy 230.097735 -312.713333) (xy 230.08754 -312.734076) (xy 230.086916 -312.745628) (xy 230.086916 -312.825892)
			(xy 230.087486 -312.83746) (xy 230.09768 -312.858231) (xy 230.106474 -312.86577) (xy 230.127216 -312.882571)
			(xy 230.164343 -312.92092) (xy 230.195762 -312.96407) (xy 230.220859 -313.011178) (xy 230.239146 -313.061324)
			(xy 230.250264 -313.11353) (xy 230.253639 -313.161688) (xy 230.937563 -313.161688) (xy 230.941294 -313.108435)
			(xy 230.952412 -313.056222) (xy 230.970699 -313.006069) (xy 230.995799 -312.958954) (xy 231.027222 -312.915799)
			(xy 231.064353 -312.877444) (xy 231.085136 -312.86069) (xy 231.093904 -312.853134) (xy 231.104083 -312.832371)
			(xy 231.104694 -312.820812) (xy 231.104694 -312.740548) (xy 231.104098 -312.728983) (xy 231.093922 -312.708212)
			(xy 231.085136 -312.70067) (xy 231.062646 -312.682487) (xy 231.022909 -312.640467) (xy 230.98997 -312.59293)
			(xy 230.964582 -312.540967) (xy 230.947328 -312.485768) (xy 230.938603 -312.428597) (xy 230.93807 -312.39968)
			(xy 230.938556 -312.372429) (xy 230.946312 -312.318481) (xy 230.961667 -312.266186) (xy 230.984309 -312.216609)
			(xy 231.013775 -312.170759) (xy 231.049466 -312.129568) (xy 231.090657 -312.093877) (xy 231.136507 -312.064411)
			(xy 231.186084 -312.041769) (xy 231.238379 -312.026414) (xy 231.292327 -312.018658) (xy 231.346829 -312.018658)
			(xy 231.400777 -312.026414) (xy 231.453072 -312.041769) (xy 231.502649 -312.064411) (xy 231.548499 -312.093877)
			(xy 231.58969 -312.129568) (xy 231.625381 -312.170759) (xy 231.654847 -312.216609) (xy 231.677489 -312.266186)
			(xy 231.692844 -312.318481) (xy 231.7006 -312.372429) (xy 231.701086 -312.39968) (xy 231.700559 -312.428597)
			(xy 231.691832 -312.485768) (xy 231.674576 -312.540966) (xy 231.649186 -312.592928) (xy 231.616244 -312.640462)
			(xy 231.576505 -312.68248) (xy 231.55402 -312.70067) (xy 231.545263 -312.708236) (xy 231.53508 -312.728992)
			(xy 231.534462 -312.740548) (xy 231.534462 -312.820812) (xy 231.535004 -312.832384) (xy 231.545217 -312.853156)
			(xy 231.55402 -312.86069) (xy 231.574784 -312.877467) (xy 231.611916 -312.915816) (xy 231.643339 -312.958968)
			(xy 231.66844 -313.006078) (xy 231.686728 -313.056228) (xy 231.697847 -313.108438) (xy 231.701578 -313.161688)
			(xy 231.69785 -313.214938) (xy 231.686735 -313.267148) (xy 231.66845 -313.317299) (xy 231.643352 -313.364412)
			(xy 231.611932 -313.407565) (xy 231.574802 -313.445917) (xy 231.55402 -313.46267) (xy 231.545263 -313.470236)
			(xy 231.53508 -313.490992) (xy 231.534462 -313.502548) (xy 231.534462 -313.582812) (xy 231.535004 -313.594384)
			(xy 231.545217 -313.615156) (xy 231.55402 -313.62269) (xy 231.576503 -313.640882) (xy 231.616237 -313.682902)
			(xy 231.649176 -313.730437) (xy 231.674564 -313.782398) (xy 231.691821 -313.837595) (xy 231.70055 -313.894764)
			(xy 231.701086 -313.92368) (xy 231.7006 -313.950931) (xy 231.692844 -314.004879) (xy 231.677489 -314.057174)
			(xy 231.654847 -314.106751) (xy 231.625381 -314.152601) (xy 231.58969 -314.193792) (xy 231.548499 -314.229483)
			(xy 231.502649 -314.258949) (xy 231.453072 -314.281591) (xy 231.400777 -314.296946) (xy 231.346829 -314.304702)
			(xy 231.292327 -314.304702) (xy 231.238379 -314.296946) (xy 231.186084 -314.281591) (xy 231.136507 -314.258949)
			(xy 231.090657 -314.229483) (xy 231.049466 -314.193792) (xy 231.013775 -314.152601) (xy 230.984309 -314.106751)
			(xy 230.961667 -314.057174) (xy 230.946312 -314.004879) (xy 230.938556 -313.950931) (xy 230.93807 -313.92368)
			(xy 230.938619 -313.894764) (xy 230.947338 -313.837593) (xy 230.964588 -313.782394) (xy 230.989974 -313.730431)
			(xy 231.022914 -313.682897) (xy 231.062652 -313.64088) (xy 231.085136 -313.62269) (xy 231.093904 -313.615134)
			(xy 231.104083 -313.594371) (xy 231.104694 -313.582812) (xy 231.104694 -313.502548) (xy 231.104098 -313.490983)
			(xy 231.093922 -313.470212) (xy 231.085136 -313.46267) (xy 231.064334 -313.44594) (xy 231.027206 -313.407583)
			(xy 230.995786 -313.364425) (xy 230.970689 -313.317309) (xy 230.952405 -313.267154) (xy 230.941291 -313.214941)
			(xy 230.937563 -313.161688) (xy 230.253639 -313.161688) (xy 230.253996 -313.166775) (xy 230.250271 -313.220022)
			(xy 230.239159 -313.272229) (xy 230.220879 -313.322377) (xy 230.195788 -313.369488) (xy 230.164375 -313.412642)
			(xy 230.127253 -313.450996) (xy 230.106474 -313.46775) (xy 230.097735 -313.475333) (xy 230.08754 -313.496076)
			(xy 230.086916 -313.507628) (xy 230.086916 -313.587892) (xy 230.087486 -313.59946) (xy 230.09768 -313.620231)
			(xy 230.106474 -313.62777) (xy 230.128938 -313.645985) (xy 230.168675 -313.687999) (xy 230.201617 -313.735528)
			(xy 230.227009 -313.787485) (xy 230.24427 -313.842679) (xy 230.253003 -313.899845) (xy 230.25354 -313.92876)
			(xy 230.253041 -313.957405) (xy 230.244467 -314.014049) (xy 230.227521 -314.068776) (xy 230.202583 -314.120353)
			(xy 230.170215 -314.167623) (xy 230.131143 -314.209522) (xy 230.109014 -314.227718) (xy 230.09987 -314.235084)
			(xy 230.08971 -314.255658) (xy 230.08971 -314.359036) (xy 230.099616 -314.37961) (xy 230.109014 -314.386976)
			(xy 230.131125 -314.405145) (xy 230.170123 -314.44703) (xy 230.202428 -314.494269) (xy 230.227313 -314.545805)
			(xy 230.244221 -314.600479) (xy 230.252773 -314.657065) (xy 230.253286 -314.68568) (xy 230.253286 -314.685688)
			(xy 233.325163 -314.685688) (xy 233.328894 -314.632435) (xy 233.340012 -314.580222) (xy 233.358299 -314.530069)
			(xy 233.383399 -314.482954) (xy 233.414822 -314.439799) (xy 233.451953 -314.401444) (xy 233.472736 -314.38469)
			(xy 233.481504 -314.377134) (xy 233.491683 -314.356371) (xy 233.492294 -314.344812) (xy 233.492294 -314.264548)
			(xy 233.491698 -314.252983) (xy 233.481522 -314.232212) (xy 233.472736 -314.22467) (xy 233.451934 -314.20794)
			(xy 233.414806 -314.169583) (xy 233.383386 -314.126425) (xy 233.358289 -314.079309) (xy 233.340005 -314.029154)
			(xy 233.328891 -313.976941) (xy 233.325163 -313.923688) (xy 233.328894 -313.870435) (xy 233.340012 -313.818222)
			(xy 233.358299 -313.768069) (xy 233.383399 -313.720954) (xy 233.414822 -313.677799) (xy 233.451953 -313.639444)
			(xy 233.472736 -313.62269) (xy 233.481504 -313.615134) (xy 233.491683 -313.594371) (xy 233.492294 -313.582812)
			(xy 233.492294 -313.502548) (xy 233.491698 -313.490983) (xy 233.481522 -313.470212) (xy 233.472736 -313.46267)
			(xy 233.451934 -313.44594) (xy 233.414806 -313.407583) (xy 233.383386 -313.364425) (xy 233.358289 -313.317309)
			(xy 233.340005 -313.267154) (xy 233.328891 -313.214941) (xy 233.325163 -313.161688) (xy 233.328894 -313.108435)
			(xy 233.340012 -313.056222) (xy 233.358299 -313.006069) (xy 233.383399 -312.958954) (xy 233.414822 -312.915799)
			(xy 233.451953 -312.877444) (xy 233.472736 -312.86069) (xy 233.481504 -312.853134) (xy 233.491683 -312.832371)
			(xy 233.492294 -312.820812) (xy 233.492294 -312.740548) (xy 233.491698 -312.728983) (xy 233.481522 -312.708212)
			(xy 233.472736 -312.70067) (xy 233.450246 -312.682487) (xy 233.410509 -312.640467) (xy 233.37757 -312.59293)
			(xy 233.352182 -312.540967) (xy 233.334928 -312.485768) (xy 233.326203 -312.428597) (xy 233.32567 -312.39968)
			(xy 233.326156 -312.372429) (xy 233.333912 -312.318481) (xy 233.349267 -312.266186) (xy 233.371909 -312.216609)
			(xy 233.401375 -312.170759) (xy 233.437066 -312.129568) (xy 233.478257 -312.093877) (xy 233.524107 -312.064411)
			(xy 233.573684 -312.041769) (xy 233.625979 -312.026414) (xy 233.679927 -312.018658) (xy 233.734429 -312.018658)
			(xy 233.788377 -312.026414) (xy 233.840672 -312.041769) (xy 233.890249 -312.064411) (xy 233.936099 -312.093877)
			(xy 233.97729 -312.129568) (xy 234.012981 -312.170759) (xy 234.042447 -312.216609) (xy 234.065089 -312.266186)
			(xy 234.080444 -312.318481) (xy 234.0882 -312.372429) (xy 234.088686 -312.39968) (xy 234.088159 -312.428597)
			(xy 234.079432 -312.485768) (xy 234.062176 -312.540966) (xy 234.036786 -312.592928) (xy 234.003844 -312.640462)
			(xy 233.964105 -312.68248) (xy 233.94162 -312.70067) (xy 233.932863 -312.708236) (xy 233.92268 -312.728992)
			(xy 233.922062 -312.740548) (xy 233.922062 -312.820812) (xy 233.922604 -312.832384) (xy 233.932817 -312.853156)
			(xy 233.94162 -312.86069) (xy 233.962384 -312.877467) (xy 233.999516 -312.915816) (xy 234.030939 -312.958968)
			(xy 234.05604 -313.006078) (xy 234.074328 -313.056228) (xy 234.085447 -313.108438) (xy 234.089178 -313.161688)
			(xy 234.08545 -313.214938) (xy 234.074335 -313.267148) (xy 234.05605 -313.317299) (xy 234.030952 -313.364412)
			(xy 233.999532 -313.407565) (xy 233.962402 -313.445917) (xy 233.94162 -313.46267) (xy 233.932863 -313.470236)
			(xy 233.92268 -313.490992) (xy 233.922062 -313.502548) (xy 233.922062 -313.582812) (xy 233.922604 -313.594384)
			(xy 233.932817 -313.615156) (xy 233.94162 -313.62269) (xy 233.962384 -313.639467) (xy 233.999516 -313.677816)
			(xy 234.030939 -313.720968) (xy 234.05604 -313.768078) (xy 234.074328 -313.818228) (xy 234.085447 -313.870438)
			(xy 234.089178 -313.923688) (xy 234.08545 -313.976938) (xy 234.074335 -314.029148) (xy 234.05605 -314.079299)
			(xy 234.030952 -314.126412) (xy 233.999532 -314.169565) (xy 233.962402 -314.207917) (xy 233.94162 -314.22467)
			(xy 233.932863 -314.232236) (xy 233.92268 -314.252992) (xy 233.922062 -314.264548) (xy 233.922062 -314.344812)
			(xy 233.922604 -314.356384) (xy 233.932817 -314.377156) (xy 233.94162 -314.38469) (xy 233.962384 -314.401467)
			(xy 233.999516 -314.439816) (xy 234.030939 -314.482968) (xy 234.05604 -314.530078) (xy 234.074328 -314.580228)
			(xy 234.085447 -314.632438) (xy 234.089178 -314.685688) (xy 234.08545 -314.738938) (xy 234.074335 -314.791148)
			(xy 234.05605 -314.841299) (xy 234.030952 -314.888412) (xy 233.999532 -314.931565) (xy 233.962402 -314.969917)
			(xy 233.94162 -314.98667) (xy 233.932863 -314.994236) (xy 233.92268 -315.014992) (xy 233.922062 -315.026548)
			(xy 233.922062 -315.106812) (xy 233.922604 -315.118384) (xy 233.932817 -315.139156) (xy 233.94162 -315.14669)
			(xy 233.964103 -315.164882) (xy 234.003837 -315.206902) (xy 234.036776 -315.254437) (xy 234.062164 -315.306398)
			(xy 234.079421 -315.361595) (xy 234.08815 -315.418764) (xy 234.088686 -315.44768) (xy 234.0882 -315.474931)
			(xy 234.080444 -315.528879) (xy 234.065089 -315.581174) (xy 234.042447 -315.630751) (xy 234.012981 -315.676601)
			(xy 233.97729 -315.717792) (xy 233.936099 -315.753483) (xy 233.890249 -315.782949) (xy 233.840672 -315.805591)
			(xy 233.788377 -315.820946) (xy 233.734429 -315.828702) (xy 233.679927 -315.828702) (xy 233.625979 -315.820946)
			(xy 233.573684 -315.805591) (xy 233.524107 -315.782949) (xy 233.478257 -315.753483) (xy 233.437066 -315.717792)
			(xy 233.401375 -315.676601) (xy 233.371909 -315.630751) (xy 233.349267 -315.581174) (xy 233.333912 -315.528879)
			(xy 233.326156 -315.474931) (xy 233.32567 -315.44768) (xy 233.326219 -315.418764) (xy 233.334938 -315.361593)
			(xy 233.352188 -315.306394) (xy 233.377574 -315.254431) (xy 233.410514 -315.206897) (xy 233.450252 -315.16488)
			(xy 233.472736 -315.14669) (xy 233.481504 -315.139134) (xy 233.491683 -315.118371) (xy 233.492294 -315.106812)
			(xy 233.492294 -315.026548) (xy 233.491698 -315.014983) (xy 233.481522 -314.994212) (xy 233.472736 -314.98667)
			(xy 233.451934 -314.96994) (xy 233.414806 -314.931583) (xy 233.383386 -314.888425) (xy 233.358289 -314.841309)
			(xy 233.340005 -314.791154) (xy 233.328891 -314.738941) (xy 233.325163 -314.685688) (xy 230.253286 -314.685688)
			(xy 230.252759 -314.714597) (xy 230.244032 -314.771768) (xy 230.226776 -314.826966) (xy 230.201386 -314.878928)
			(xy 230.168444 -314.926462) (xy 230.128705 -314.96848) (xy 230.10622 -314.98667) (xy 230.097463 -314.994236)
			(xy 230.08728 -315.014992) (xy 230.086662 -315.026548) (xy 230.086662 -315.106812) (xy 230.087204 -315.118384)
			(xy 230.097417 -315.139156) (xy 230.10622 -315.14669) (xy 230.128703 -315.164882) (xy 230.168437 -315.206902)
			(xy 230.201376 -315.254437) (xy 230.226764 -315.306398) (xy 230.244021 -315.361595) (xy 230.25275 -315.418764)
			(xy 230.253286 -315.44768) (xy 230.2528 -315.474931) (xy 230.245044 -315.528879) (xy 230.229689 -315.581174)
			(xy 230.207047 -315.630751) (xy 230.177581 -315.676601) (xy 230.14189 -315.717792) (xy 230.100699 -315.753483)
			(xy 230.054849 -315.782949) (xy 230.005272 -315.805591) (xy 229.952977 -315.820946) (xy 229.899029 -315.828702)
			(xy 229.844527 -315.828702) (xy 229.790579 -315.820946) (xy 229.738284 -315.805591) (xy 229.688707 -315.782949)
			(xy 229.642857 -315.753483) (xy 229.601666 -315.717792) (xy 229.565975 -315.676601) (xy 229.536509 -315.630751)
			(xy 229.513867 -315.581174) (xy 229.498512 -315.528879) (xy 229.490756 -315.474931) (xy 229.49027 -315.44768)
			(xy 229.490819 -315.418764) (xy 229.499538 -315.361593) (xy 229.516788 -315.306394) (xy 229.542174 -315.254431)
			(xy 229.575114 -315.206897) (xy 229.614852 -315.16488) (xy 229.637336 -315.14669) (xy 229.646104 -315.139134)
			(xy 229.656283 -315.118371) (xy 229.656894 -315.106812) (xy 229.656894 -315.026548) (xy 229.656298 -315.014983)
			(xy 229.646122 -314.994212) (xy 229.637336 -314.98667) (xy 229.614846 -314.968487) (xy 229.575109 -314.926467)
			(xy 229.54217 -314.87893) (xy 229.516782 -314.826967) (xy 229.499528 -314.771768) (xy 229.490803 -314.714597)
			(xy 229.49027 -314.68568) (xy 229.490794 -314.657036) (xy 229.499362 -314.600392) (xy 229.516303 -314.545666)
			(xy 229.541236 -314.494089) (xy 229.5736 -314.446818) (xy 229.612668 -314.404918) (xy 229.634796 -314.386722)
			(xy 229.64394 -314.379356) (xy 229.6541 -314.358782) (xy 229.6541 -314.255404) (xy 229.644194 -314.23483)
			(xy 229.634796 -314.227464) (xy 229.612706 -314.20927) (xy 229.573706 -314.167391) (xy 229.541399 -314.120157)
			(xy 229.51651 -314.068626) (xy 229.499597 -314.013956) (xy 229.49104 -313.957373) (xy 229.490524 -313.92876)
			(xy 229.491076 -313.899844) (xy 229.499797 -313.842674) (xy 229.517047 -313.787476) (xy 229.542433 -313.735514)
			(xy 229.575371 -313.687979) (xy 229.615107 -313.645961) (xy 229.63759 -313.62777) (xy 229.646359 -313.620215)
			(xy 229.656539 -313.599451) (xy 229.657148 -313.587892) (xy 229.657148 -313.507628) (xy 229.656579 -313.496059)
			(xy 229.646385 -313.475287) (xy 229.63759 -313.46775) (xy 229.616766 -313.451045) (xy 229.579632 -313.412687)
			(xy 229.548208 -313.369527) (xy 229.523108 -313.322408) (xy 229.504822 -313.27225) (xy 229.493707 -313.220033)
			(xy 229.48998 -313.166775) (xy 228.21216 -313.166775) (xy 228.209694 -313.20197) (xy 228.198574 -313.254184)
			(xy 228.180285 -313.304339) (xy 228.155182 -313.351454) (xy 228.123757 -313.394609) (xy 228.086623 -313.432963)
			(xy 228.065838 -313.449716) (xy 228.057063 -313.457265) (xy 228.046889 -313.478034) (xy 228.04628 -313.489594)
			(xy 228.04628 -313.569858) (xy 228.046882 -313.581422) (xy 228.057055 -313.602192) (xy 228.065838 -313.609736)
			(xy 228.088347 -313.627897) (xy 228.128079 -313.669924) (xy 228.161013 -313.717466) (xy 228.186397 -313.769433)
			(xy 228.203648 -313.824635) (xy 228.212372 -313.881808) (xy 228.212904 -313.910726) (xy 228.212459 -313.936701)
			(xy 228.205413 -313.988171) (xy 228.191444 -314.038207) (xy 228.170808 -314.085883) (xy 228.143888 -314.130314)
			(xy 228.111184 -314.170678) (xy 228.073301 -314.206227) (xy 228.052376 -314.221622) (xy 228.04247 -314.228734)
			(xy 228.031294 -314.25007) (xy 228.029008 -314.35548) (xy 228.039168 -314.377324) (xy 228.04882 -314.38469)
			(xy 228.069584 -314.401467) (xy 228.106716 -314.439816) (xy 228.138139 -314.482968) (xy 228.16324 -314.530078)
			(xy 228.181528 -314.580228) (xy 228.192647 -314.632438) (xy 228.196378 -314.685688) (xy 228.19265 -314.738938)
			(xy 228.181535 -314.791148) (xy 228.16325 -314.841299) (xy 228.138152 -314.888412) (xy 228.106732 -314.931565)
			(xy 228.069602 -314.969917) (xy 228.04882 -314.98667) (xy 228.040063 -314.994236) (xy 228.02988 -315.014992)
			(xy 228.029262 -315.026548) (xy 228.029262 -315.106812) (xy 228.029804 -315.118384) (xy 228.040017 -315.139156)
			(xy 228.04882 -315.14669) (xy 228.071303 -315.164882) (xy 228.111037 -315.206902) (xy 228.143976 -315.254437)
			(xy 228.169364 -315.306398) (xy 228.186621 -315.361595) (xy 228.19535 -315.418764) (xy 228.195886 -315.44768)
			(xy 228.1954 -315.474931) (xy 228.187644 -315.528879) (xy 228.172289 -315.581174) (xy 228.149647 -315.630751)
			(xy 228.120181 -315.676601) (xy 228.08449 -315.717792) (xy 228.043299 -315.753483) (xy 227.997449 -315.782949)
			(xy 227.947872 -315.805591) (xy 227.895577 -315.820946) (xy 227.841629 -315.828702) (xy 227.787127 -315.828702)
			(xy 227.733179 -315.820946) (xy 227.680884 -315.805591) (xy 227.631307 -315.782949) (xy 227.585457 -315.753483)
			(xy 227.544266 -315.717792) (xy 227.508575 -315.676601) (xy 227.479109 -315.630751) (xy 227.456467 -315.581174)
			(xy 227.441112 -315.528879) (xy 227.433356 -315.474931) (xy 227.43287 -315.44768) (xy 224.360486 -315.44768)
			(xy 224.36 -315.474931) (xy 224.352244 -315.528879) (xy 224.336889 -315.581174) (xy 224.314247 -315.630751)
			(xy 224.284781 -315.676601) (xy 224.24909 -315.717792) (xy 224.207899 -315.753483) (xy 224.162049 -315.782949)
			(xy 224.112472 -315.805591) (xy 224.060177 -315.820946) (xy 224.006229 -315.828702) (xy 223.951727 -315.828702)
			(xy 223.897779 -315.820946) (xy 223.845484 -315.805591) (xy 223.795907 -315.782949) (xy 223.750057 -315.753483)
			(xy 223.708866 -315.717792) (xy 223.673175 -315.676601) (xy 223.643709 -315.630751) (xy 223.621067 -315.581174)
			(xy 223.605712 -315.528879) (xy 223.597956 -315.474931) (xy 223.59747 -315.44768) (xy 223.598019 -315.418764)
			(xy 223.606738 -315.361593) (xy 223.623988 -315.306394) (xy 223.649374 -315.254431) (xy 223.682314 -315.206897)
			(xy 223.722052 -315.16488) (xy 223.744536 -315.14669) (xy 223.753304 -315.139134) (xy 223.763483 -315.118371)
			(xy 223.764094 -315.106812) (xy 223.764094 -315.026548) (xy 223.763498 -315.014983) (xy 223.753322 -314.994212)
			(xy 223.744536 -314.98667) (xy 223.722046 -314.968487) (xy 223.682309 -314.926467) (xy 223.64937 -314.87893)
			(xy 223.623982 -314.826967) (xy 223.606728 -314.771768) (xy 223.598003 -314.714597) (xy 223.59747 -314.68568)
			(xy 223.597864 -314.659936) (xy 223.604787 -314.608915) (xy 223.618505 -314.559288) (xy 223.638768 -314.511955)
			(xy 223.66521 -314.467775) (xy 223.69735 -314.427549) (xy 223.734605 -314.392009) (xy 223.755204 -314.376562)
			(xy 223.765618 -314.369196) (xy 223.776794 -314.34659) (xy 223.77273 -314.236608) (xy 223.76003 -314.214764)
			(xy 223.749108 -314.207906) (xy 223.725821 -314.192934) (xy 223.683489 -314.157253) (xy 223.646763 -314.115826)
			(xy 223.616413 -314.069523) (xy 223.593077 -314.019318) (xy 223.577247 -313.966267) (xy 223.569256 -313.911484)
			(xy 223.568768 -313.883802) (xy 223.569262 -313.854884) (xy 223.577992 -313.79771) (xy 223.595253 -313.74251)
			(xy 223.62065 -313.690548) (xy 223.653599 -313.643015) (xy 223.693346 -313.601) (xy 223.715834 -313.582812)
			(xy 223.724592 -313.575246) (xy 223.734776 -313.55449) (xy 223.735392 -313.542934) (xy 223.735392 -313.46267)
			(xy 223.734784 -313.451107) (xy 223.724616 -313.430335) (xy 223.715834 -313.422792) (xy 223.695054 -313.406036)
			(xy 223.657926 -313.367682) (xy 223.626507 -313.324527) (xy 223.601409 -313.277414) (xy 223.583124 -313.227262)
			(xy 223.572008 -313.175052) (xy 223.568279 -313.121801) (xy 223.113276 -313.121801) (xy 223.112695 -313.130084)
			(xy 223.101573 -313.1823) (xy 223.083281 -313.232456) (xy 223.058175 -313.279572) (xy 223.026745 -313.322728)
			(xy 222.989607 -313.361081) (xy 222.96882 -313.377834) (xy 222.960034 -313.385372) (xy 222.949867 -313.406149)
			(xy 222.949262 -313.417712) (xy 222.949262 -313.497976) (xy 222.949825 -313.509545) (xy 222.960023 -313.530318)
			(xy 222.96882 -313.537854) (xy 222.991286 -313.556066) (xy 223.031021 -313.598082) (xy 223.063962 -313.645613)
			(xy 223.089353 -313.69757) (xy 223.106613 -313.752763) (xy 223.115348 -313.809929) (xy 223.115886 -313.838844)
			(xy 223.1154 -313.866095) (xy 223.107644 -313.920043) (xy 223.092289 -313.972338) (xy 223.069647 -314.021915)
			(xy 223.040181 -314.067765) (xy 223.00449 -314.108956) (xy 222.963299 -314.144647) (xy 222.917449 -314.174113)
			(xy 222.867872 -314.196755) (xy 222.815577 -314.21211) (xy 222.761629 -314.219866) (xy 222.707127 -314.219866)
			(xy 222.653179 -314.21211) (xy 222.600884 -314.196755) (xy 222.551307 -314.174113) (xy 222.505457 -314.144647)
			(xy 222.464266 -314.108956) (xy 222.428575 -314.067765) (xy 222.399109 -314.021915) (xy 222.376467 -313.972338)
			(xy 222.361112 -313.920043) (xy 222.353356 -313.866095) (xy 222.35287 -313.838844) (xy 222.353393 -313.809927)
			(xy 222.362117 -313.752755) (xy 222.379373 -313.697555) (xy 222.404763 -313.645592) (xy 222.437707 -313.598059)
			(xy 222.47745 -313.556043) (xy 222.499936 -313.537854) (xy 222.50872 -313.530314) (xy 222.51889 -313.509538)
			(xy 222.519494 -313.497976) (xy 222.519494 -313.417712) (xy 222.518919 -313.406145) (xy 222.508728 -313.385374)
			(xy 222.499936 -313.377834) (xy 222.479198 -313.361028) (xy 222.44207 -313.32268) (xy 222.41065 -313.279531)
			(xy 222.385552 -313.232424) (xy 222.367265 -313.182278) (xy 222.356147 -313.130073) (xy 222.352414 -313.076827)
			(xy 218.943682 -313.076827) (xy 218.943682 -314.83808) (xy 222.356424 -314.83808) (xy 222.360495 -314.782458)
			(xy 222.372621 -314.728021) (xy 222.392544 -314.67593) (xy 222.41984 -314.627295) (xy 222.453926 -314.583152)
			(xy 222.494075 -314.544443) (xy 222.539433 -314.511992) (xy 222.589033 -314.486491) (xy 222.641817 -314.468484)
			(xy 222.69666 -314.458354) (xy 222.752394 -314.456317) (xy 222.807831 -314.462417) (xy 222.861788 -314.476523)
			(xy 222.913117 -314.498335) (xy 222.960723 -314.527389) (xy 223.003591 -314.563064) (xy 223.040808 -314.604601)
			(xy 223.071581 -314.651114) (xy 223.095253 -314.701611) (xy 223.111321 -314.755018) (xy 223.119441 -314.810194)
			(xy 223.11995 -314.83808) (xy 223.119441 -314.865966) (xy 223.111321 -314.921142) (xy 223.095253 -314.974549)
			(xy 223.071581 -315.025046) (xy 223.040808 -315.071559) (xy 223.003591 -315.113096) (xy 222.960723 -315.148771)
			(xy 222.913117 -315.177825) (xy 222.861788 -315.199637) (xy 222.807831 -315.213743) (xy 222.752394 -315.219843)
			(xy 222.69666 -315.217806) (xy 222.641817 -315.207676) (xy 222.589033 -315.189669) (xy 222.539433 -315.164168)
			(xy 222.494075 -315.131717) (xy 222.453926 -315.093008) (xy 222.41984 -315.048865) (xy 222.392544 -315.00023)
			(xy 222.372621 -314.948139) (xy 222.360495 -314.893702) (xy 222.356424 -314.83808) (xy 218.943682 -314.83808)
			(xy 218.943682 -316.51702) (xy 218.944108 -316.527089) (xy 218.951826 -316.54569) (xy 218.958668 -316.553088)
			(xy 223.294956 -320.889376) (xy 223.302357 -320.896216) (xy 223.320955 -320.903934) (xy 223.331024 -320.904362)
		)
		(stroke
			(width 0)
			(type solid)
		)
		(fill yes)
		(layer "In6.Cu")
		(net "GND")
	)
	(gr_poly
		(pts
			(xy 259.53085 -220.58884) (xy 259.540915 -220.588406) (xy 259.5595 -220.580672) (xy 259.566918 -220.573854)
			(xy 263.993122 -216.14765) (xy 263.999969 -216.140253) (xy 264.007698 -216.121653) (xy 264.008108 -216.111582)
			(xy 264.008108 -199.711056) (xy 264.008539 -199.70099) (xy 264.016266 -199.682397) (xy 264.023094 -199.674988)
			(xy 265.251692 -198.44639) (xy 265.254994 -198.409814) (xy 265.24458 -198.394574) (xy 265.229178 -198.371341)
			(xy 265.204793 -198.321218) (xy 265.188221 -198.267999) (xy 265.179838 -198.212894) (xy 265.179302 -198.185024)
			(xy 265.179748 -198.158678) (xy 265.187244 -198.10652) (xy 265.202087 -198.055961) (xy 265.223975 -198.008029)
			(xy 265.252461 -197.9637) (xy 265.286967 -197.923877) (xy 265.326789 -197.88937) (xy 265.371117 -197.860881)
			(xy 265.419048 -197.838992) (xy 265.469607 -197.824147) (xy 265.521764 -197.816649) (xy 265.54811 -197.816216)
			(xy 265.575981 -197.816727) (xy 265.631087 -197.825115) (xy 265.684304 -197.841698) (xy 265.73442 -197.8661)
			(xy 265.75766 -197.881494) (xy 265.765124 -197.886288) (xy 265.782259 -197.890842) (xy 265.799918 -197.889259)
			(xy 265.815969 -197.881728) (xy 265.82243 -197.875652) (xy 266.905994 -196.792088) (xy 266.913388 -196.785231)
			(xy 266.931987 -196.777481) (xy 266.942062 -196.777102) (xy 269.218156 -196.777102) (xy 269.230821 -196.776348)
			(xy 269.253069 -196.764218) (xy 269.260574 -196.753988) (xy 269.314168 -196.671692) (xy 269.3162 -196.646292)
			(xy 269.310866 -196.634354) (xy 269.30091 -196.610728) (xy 269.286882 -196.561416) (xy 269.279814 -196.510637)
			(xy 269.27937 -196.485002) (xy 269.279886 -196.457402) (xy 269.288113 -196.402819) (xy 269.304383 -196.350072)
			(xy 269.328333 -196.30034) (xy 269.359428 -196.254732) (xy 269.396973 -196.214268) (xy 269.44013 -196.179851)
			(xy 269.487934 -196.152252) (xy 269.539318 -196.132085) (xy 269.593133 -196.119802) (xy 269.648178 -196.115677)
			(xy 269.703223 -196.119802) (xy 269.757038 -196.132085) (xy 269.808422 -196.152252) (xy 269.856226 -196.179851)
			(xy 269.899383 -196.214268) (xy 269.936928 -196.254732) (xy 269.968023 -196.30034) (xy 269.991973 -196.350072)
			(xy 270.008243 -196.402819) (xy 270.01647 -196.457402) (xy 270.016986 -196.485002) (xy 270.016565 -196.510638)
			(xy 270.009498 -196.56142) (xy 269.995459 -196.610732) (xy 269.98549 -196.634354) (xy 269.980156 -196.646292)
			(xy 269.982188 -196.671692) (xy 270.035782 -196.753988) (xy 270.04325 -196.764263) (xy 270.065518 -196.776412)
			(xy 270.0782 -196.777102) (xy 276.76221 -196.777102) (xy 276.774881 -196.776358) (xy 276.797146 -196.764239)
			(xy 276.804628 -196.753988) (xy 276.858222 -196.671692) (xy 276.860254 -196.646292) (xy 276.85492 -196.634354)
			(xy 276.844962 -196.610728) (xy 276.830933 -196.561416) (xy 276.823863 -196.510637) (xy 276.823424 -196.485002)
			(xy 276.82394 -196.457402) (xy 276.832167 -196.402819) (xy 276.848437 -196.350072) (xy 276.872387 -196.30034)
			(xy 276.903482 -196.254732) (xy 276.941027 -196.214268) (xy 276.984184 -196.179851) (xy 277.031988 -196.152252)
			(xy 277.083372 -196.132085) (xy 277.137187 -196.119802) (xy 277.192232 -196.115677) (xy 277.247277 -196.119802)
			(xy 277.301092 -196.132085) (xy 277.352476 -196.152252) (xy 277.40028 -196.179851) (xy 277.443437 -196.214268)
			(xy 277.480982 -196.254732) (xy 277.512077 -196.30034) (xy 277.536027 -196.350072) (xy 277.552297 -196.402819)
			(xy 277.560524 -196.457402) (xy 277.56104 -196.485002) (xy 277.560619 -196.510638) (xy 277.553553 -196.561421)
			(xy 277.539516 -196.610733) (xy 277.529544 -196.634354) (xy 277.52421 -196.646292) (xy 277.526242 -196.671692)
			(xy 277.579836 -196.753988) (xy 277.587308 -196.764254) (xy 277.609577 -196.776379) (xy 277.622254 -196.777102)
			(xy 278.41067 -196.777102) (xy 278.42028 -196.776689) (xy 278.438163 -196.769644) (xy 278.445468 -196.763386)
			(xy 278.463753 -196.746764) (xy 278.504391 -196.718654) (xy 278.548793 -196.696972) (xy 278.59595 -196.682212)
			(xy 278.64479 -196.674708) (xy 278.669496 -196.674232) (xy 278.899874 -196.674232) (xy 278.924583 -196.6747)
			(xy 278.973432 -196.682174) (xy 279.020597 -196.696925) (xy 279.064999 -196.718616) (xy 279.105626 -196.746751)
			(xy 279.123902 -196.763386) (xy 279.131194 -196.769667) (xy 279.149084 -196.776717) (xy 279.1587 -196.777102)
			(xy 282.89885 -196.777102) (xy 282.908842 -196.776574) (xy 282.927287 -196.768873) (xy 282.934664 -196.762116)
			(xy 283.017722 -196.679058) (xy 283.036243 -196.661254) (xy 283.077806 -196.631062) (xy 283.12358 -196.607741)
			(xy 283.172437 -196.591866) (xy 283.223176 -196.583826) (xy 283.248862 -196.5833) (xy 284.265624 -196.5833)
			(xy 284.27559 -196.582821) (xy 284.294025 -196.575244) (xy 284.301438 -196.568568) (xy 284.359604 -196.51091)
			(xy 284.367224 -196.492876) (xy 284.367224 -196.482462) (xy 284.36792 -196.454987) (xy 284.37645 -196.400693)
			(xy 284.392942 -196.348267) (xy 284.417031 -196.298869) (xy 284.448184 -196.253592) (xy 284.48571 -196.213439)
			(xy 284.52878 -196.179299) (xy 284.576439 -196.151929) (xy 284.627632 -196.131934) (xy 284.681225 -196.119757)
			(xy 284.736032 -196.115668) (xy 284.790839 -196.119757) (xy 284.844432 -196.131934) (xy 284.895625 -196.151929)
			(xy 284.943284 -196.179299) (xy 284.986354 -196.213439) (xy 285.02388 -196.253592) (xy 285.055033 -196.298869)
			(xy 285.079122 -196.348267) (xy 285.095614 -196.400693) (xy 285.104144 -196.454987) (xy 285.10484 -196.482462)
			(xy 285.10484 -196.492876) (xy 285.11246 -196.51091) (xy 285.170626 -196.568568) (xy 285.177997 -196.575309)
			(xy 285.196459 -196.582897) (xy 285.20644 -196.5833) (xy 285.954978 -196.5833) (xy 285.980668 -196.583776)
			(xy 286.031415 -196.591813) (xy 286.080279 -196.607691) (xy 286.126057 -196.63102) (xy 286.16762 -196.661225)
			(xy 286.186118 -196.679058) (xy 286.269176 -196.762116) (xy 286.276521 -196.768924) (xy 286.294985 -196.776642)
			(xy 286.30499 -196.777102) (xy 290.44519 -196.777102) (xy 290.455178 -196.776566) (xy 290.473613 -196.768856)
			(xy 290.481004 -196.762116) (xy 290.564062 -196.679058) (xy 290.582582 -196.66125) (xy 290.624144 -196.631051)
			(xy 290.669916 -196.607722) (xy 290.718774 -196.591837) (xy 290.769515 -196.583788) (xy 290.795202 -196.5833)
			(xy 291.809678 -196.5833) (xy 291.819639 -196.582812) (xy 291.83806 -196.575221) (xy 291.845492 -196.568568)
			(xy 291.903658 -196.51091) (xy 291.911278 -196.492876) (xy 291.911278 -196.482462) (xy 291.911974 -196.454987)
			(xy 291.920504 -196.400693) (xy 291.936996 -196.348267) (xy 291.961085 -196.298869) (xy 291.992238 -196.253592)
			(xy 292.029764 -196.213439) (xy 292.072834 -196.179299) (xy 292.120493 -196.151929) (xy 292.171686 -196.131934)
			(xy 292.225279 -196.119757) (xy 292.280086 -196.115668) (xy 292.334893 -196.119757) (xy 292.388486 -196.131934)
			(xy 292.439679 -196.151929) (xy 292.487338 -196.179299) (xy 292.530408 -196.213439) (xy 292.567934 -196.253592)
			(xy 292.599087 -196.298869) (xy 292.623176 -196.348267) (xy 292.639668 -196.400693) (xy 292.648198 -196.454987)
			(xy 292.648894 -196.482462) (xy 292.648894 -196.492876) (xy 292.656514 -196.51091) (xy 292.71468 -196.568568)
			(xy 292.722087 -196.575259) (xy 292.740523 -196.582853) (xy 292.750494 -196.5833) (xy 293.630858 -196.5833)
			(xy 293.656548 -196.583775) (xy 293.707297 -196.591809) (xy 293.756163 -196.607685) (xy 293.801943 -196.631012)
			(xy 293.843509 -196.661216) (xy 293.861998 -196.679058) (xy 293.945056 -196.762116) (xy 293.9524 -196.768927)
			(xy 293.970864 -196.776652) (xy 293.98087 -196.777102) (xy 298.02709 -196.777102) (xy 298.037078 -196.776566)
			(xy 298.055513 -196.768856) (xy 298.062904 -196.762116) (xy 298.145962 -196.679058) (xy 298.164482 -196.66125)
			(xy 298.206044 -196.631051) (xy 298.251816 -196.607722) (xy 298.300674 -196.591837) (xy 298.351415 -196.583788)
			(xy 298.377102 -196.5833) (xy 299.353732 -196.5833) (xy 299.363697 -196.58282) (xy 299.38213 -196.575241)
			(xy 299.389546 -196.568568) (xy 299.447712 -196.51091) (xy 299.455332 -196.492876) (xy 299.455332 -196.482462)
			(xy 299.456028 -196.454987) (xy 299.464558 -196.400693) (xy 299.48105 -196.348267) (xy 299.505139 -196.298869)
			(xy 299.536292 -196.253592) (xy 299.573818 -196.213439) (xy 299.616888 -196.179299) (xy 299.664547 -196.151929)
			(xy 299.71574 -196.131934) (xy 299.769333 -196.119757) (xy 299.82414 -196.115668) (xy 299.878947 -196.119757)
			(xy 299.93254 -196.131934) (xy 299.983733 -196.151929) (xy 300.031392 -196.179299) (xy 300.074462 -196.213439)
			(xy 300.111988 -196.253592) (xy 300.143141 -196.298869) (xy 300.16723 -196.348267) (xy 300.183722 -196.400693)
			(xy 300.192252 -196.454987) (xy 300.192948 -196.482462) (xy 300.192948 -196.492876) (xy 300.200568 -196.51091)
			(xy 300.258734 -196.568568) (xy 300.266105 -196.575308) (xy 300.284567 -196.582893) (xy 300.294548 -196.5833)
			(xy 301.174658 -196.5833) (xy 301.200348 -196.583775) (xy 301.251097 -196.591809) (xy 301.299963 -196.607685)
			(xy 301.345743 -196.631012) (xy 301.387309 -196.661216) (xy 301.405798 -196.679058) (xy 301.488856 -196.762116)
			(xy 301.4962 -196.768927) (xy 301.514664 -196.776652) (xy 301.52467 -196.777102) (xy 304.625756 -196.777102)
			(xy 304.635822 -196.776669) (xy 304.654411 -196.76894) (xy 304.661824 -196.762116) (xy 305.713892 -195.710048)
			(xy 305.720731 -195.702647) (xy 305.728448 -195.684049) (xy 305.728878 -195.67398) (xy 305.728878 -193.948558)
			(xy 305.728447 -193.938492) (xy 305.720719 -193.9199) (xy 305.713892 -193.91249) (xy 304.951892 -193.15049)
			(xy 304.945312 -193.144359) (xy 304.929027 -193.136752) (xy 304.911118 -193.135231) (xy 304.902362 -193.137282)
			(xy 304.80381 -193.16446) (xy 304.78476 -193.184018) (xy 304.781458 -193.19748) (xy 304.774355 -193.223675)
			(xy 304.753512 -193.273785) (xy 304.72555 -193.3203) (xy 304.691072 -193.362214) (xy 304.650822 -193.398621)
			(xy 304.605671 -193.428736) (xy 304.556594 -193.451907) (xy 304.50465 -193.467635) (xy 304.450962 -193.475579)
			(xy 304.423826 -193.476118) (xy 304.397479 -193.475672) (xy 304.34532 -193.468177) (xy 304.29476 -193.453334)
			(xy 304.246826 -193.431447) (xy 304.202495 -193.402961) (xy 304.16267 -193.368455) (xy 304.128161 -193.328633)
			(xy 304.09967 -193.284305) (xy 304.077778 -193.236374) (xy 304.062931 -193.185815) (xy 304.05543 -193.133657)
			(xy 304.055018 -193.10731) (xy 304.055468 -193.081229) (xy 304.062815 -193.029586) (xy 304.077364 -192.979494)
			(xy 304.098824 -192.931951) (xy 304.126768 -192.887905) (xy 304.160638 -192.848235) (xy 304.199759 -192.813731)
			(xy 304.243351 -192.785083) (xy 304.290543 -192.762862) (xy 304.340395 -192.74751) (xy 304.391913 -192.739335)
			(xy 304.417984 -192.738502) (xy 304.428144 -192.738502) (xy 304.446178 -192.730628) (xy 304.45329 -192.72377)
			(xy 304.459982 -192.716322) (xy 304.467587 -192.697822) (xy 304.467595 -192.677819) (xy 304.460005 -192.659312)
			(xy 304.45329 -192.651888) (xy 304.437796 -192.636394) (xy 304.430397 -192.629549) (xy 304.411799 -192.621817)
			(xy 304.401728 -192.621408) (xy 303.034192 -192.621408) (xy 303.021688 -192.62206) (xy 302.999596 -192.633784)
			(xy 302.992028 -192.64376) (xy 302.937672 -192.72377) (xy 302.935132 -192.748662) (xy 302.939704 -192.7606)
			(xy 302.954618 -192.799373) (xy 302.977916 -192.87912) (xy 302.993573 -192.960712) (xy 303.001448 -193.043418)
			(xy 303.001934 -193.084958) (xy 303.001464 -193.125779) (xy 302.993871 -193.207067) (xy 302.978756 -193.287298)
			(xy 302.95625 -193.365777) (xy 302.926548 -193.441824) (xy 302.889907 -193.514782) (xy 302.846645 -193.584019)
			(xy 302.797134 -193.648936) (xy 302.741805 -193.70897) (xy 302.681136 -193.763602) (xy 302.615652 -193.81236)
			(xy 302.54592 -193.85482) (xy 302.509428 -193.87312) (xy 302.500813 -193.877812) (xy 302.487702 -193.892381)
			(xy 302.481029 -193.910809) (xy 302.48098 -193.920618) (xy 302.481234 -193.935096) (xy 302.480718 -193.962696)
			(xy 302.472491 -194.017279) (xy 302.456221 -194.070026) (xy 302.432271 -194.119759) (xy 302.401176 -194.165366)
			(xy 302.363631 -194.20583) (xy 302.320474 -194.240247) (xy 302.27267 -194.267846) (xy 302.221286 -194.288013)
			(xy 302.167471 -194.300296) (xy 302.112426 -194.304421) (xy 302.057381 -194.300296) (xy 302.003566 -194.288013)
			(xy 301.952182 -194.267846) (xy 301.904378 -194.240247) (xy 301.861221 -194.20583) (xy 301.823676 -194.165366)
			(xy 301.792581 -194.119759) (xy 301.768631 -194.070026) (xy 301.752361 -194.017279) (xy 301.744134 -193.962696)
			(xy 301.743618 -193.935096) (xy 301.74438 -193.909696) (xy 301.74461 -193.899875) (xy 301.738532 -193.881213)
			(xy 301.725913 -193.86618) (xy 301.717456 -193.861182) (xy 301.692513 -193.847825) (xy 301.644216 -193.818336)
			(xy 301.620936 -193.802254) (xy 301.608744 -193.793872) (xy 301.57928 -193.792348) (xy 301.473616 -193.8528)
			(xy 301.4599 -193.879216) (xy 301.46117 -193.893948) (xy 301.462948 -193.935096) (xy 301.462508 -193.965157)
			(xy 301.45524 -194.024839) (xy 301.440811 -194.083204) (xy 301.419432 -194.139397) (xy 301.391416 -194.192593)
			(xy 301.357175 -194.242013) (xy 301.31721 -194.28693) (xy 301.272109 -194.326687) (xy 301.247556 -194.344036)
			(xy 301.237904 -194.35064) (xy 301.226474 -194.370452) (xy 301.219362 -194.473576) (xy 301.227998 -194.494912)
			(xy 301.236634 -194.502786) (xy 301.255917 -194.520941) (xy 301.289786 -194.561657) (xy 301.317695 -194.606669)
			(xy 301.339108 -194.655109) (xy 301.353613 -194.706045) (xy 301.36093 -194.758499) (xy 301.361348 -194.78498)
			(xy 301.587169 -194.78498) (xy 301.591104 -194.731209) (xy 301.602827 -194.678585) (xy 301.622087 -194.628228)
			(xy 301.648473 -194.581211) (xy 301.681425 -194.538538) (xy 301.720238 -194.501117) (xy 301.764086 -194.469747)
			(xy 301.812034 -194.445095) (xy 301.863061 -194.427687) (xy 301.916079 -194.417894) (xy 301.969958 -194.415925)
			(xy 302.023549 -194.421822) (xy 302.07571 -194.435458) (xy 302.12533 -194.456545) (xy 302.171351 -194.484631)
			(xy 302.212793 -194.519119) (xy 302.248771 -194.559273) (xy 302.278519 -194.604237) (xy 302.301404 -194.653054)
			(xy 302.316936 -194.704683) (xy 302.324786 -194.758023) (xy 302.325278 -194.78498) (xy 302.324786 -194.811937)
			(xy 302.316936 -194.865277) (xy 302.310909 -194.88531) (xy 304.054525 -194.88531) (xy 304.05846 -194.831539)
			(xy 304.070183 -194.778915) (xy 304.089443 -194.728558) (xy 304.115829 -194.681541) (xy 304.148781 -194.638868)
			(xy 304.187594 -194.601447) (xy 304.231442 -194.570077) (xy 304.27939 -194.545425) (xy 304.330417 -194.528017)
			(xy 304.383435 -194.518224) (xy 304.437314 -194.516255) (xy 304.490905 -194.522152) (xy 304.543066 -194.535788)
			(xy 304.592686 -194.556875) (xy 304.638707 -194.584961) (xy 304.680149 -194.619449) (xy 304.716127 -194.659603)
			(xy 304.745875 -194.704567) (xy 304.76876 -194.753384) (xy 304.784292 -194.805013) (xy 304.792142 -194.858353)
			(xy 304.792634 -194.88531) (xy 304.792142 -194.912267) (xy 304.784292 -194.965607) (xy 304.76876 -195.017236)
			(xy 304.745875 -195.066053) (xy 304.716127 -195.111017) (xy 304.680149 -195.151171) (xy 304.638707 -195.185659)
			(xy 304.592686 -195.213745) (xy 304.543066 -195.234832) (xy 304.490905 -195.248468) (xy 304.437314 -195.254365)
			(xy 304.383435 -195.252396) (xy 304.330417 -195.242603) (xy 304.27939 -195.225195) (xy 304.231442 -195.200543)
			(xy 304.187594 -195.169173) (xy 304.148781 -195.131752) (xy 304.115829 -195.089079) (xy 304.089443 -195.042062)
			(xy 304.070183 -194.991705) (xy 304.05846 -194.939081) (xy 304.054525 -194.88531) (xy 302.310909 -194.88531)
			(xy 302.301404 -194.916906) (xy 302.278519 -194.965723) (xy 302.248771 -195.010687) (xy 302.212793 -195.050841)
			(xy 302.171351 -195.085329) (xy 302.12533 -195.113415) (xy 302.07571 -195.134502) (xy 302.023549 -195.148138)
			(xy 301.969958 -195.154035) (xy 301.916079 -195.152066) (xy 301.863061 -195.142273) (xy 301.812034 -195.124865)
			(xy 301.764086 -195.100213) (xy 301.720238 -195.068843) (xy 301.681425 -195.031422) (xy 301.648473 -194.988749)
			(xy 301.622087 -194.941732) (xy 301.602827 -194.891375) (xy 301.591104 -194.838751) (xy 301.587169 -194.78498)
			(xy 301.361348 -194.78498) (xy 301.360894 -194.811403) (xy 301.353591 -194.863744) (xy 301.339137 -194.914576)
			(xy 301.317808 -194.962928) (xy 301.290012 -195.007874) (xy 301.256281 -195.048556) (xy 301.217259 -195.084194)
			(xy 301.173693 -195.114108) (xy 301.150274 -195.126356) (xy 301.13732 -195.132706) (xy 301.122334 -195.15709)
			(xy 301.121572 -195.27647) (xy 301.136304 -195.300854) (xy 301.149004 -195.307458) (xy 301.174372 -195.321184)
			(xy 301.220875 -195.3553) (xy 301.261505 -195.396236) (xy 301.29527 -195.442995) (xy 301.321348 -195.494438)
			(xy 301.339104 -195.549312) (xy 301.348107 -195.60628) (xy 301.348648 -195.635118) (xy 301.348132 -195.662718)
			(xy 301.339905 -195.717301) (xy 301.323635 -195.770048) (xy 301.299685 -195.819781) (xy 301.26859 -195.865388)
			(xy 301.231045 -195.905852) (xy 301.187888 -195.940269) (xy 301.140084 -195.967868) (xy 301.0887 -195.988035)
			(xy 301.034885 -196.000318) (xy 300.97984 -196.004443) (xy 300.924795 -196.000318) (xy 300.87098 -195.988035)
			(xy 300.819596 -195.967868) (xy 300.771792 -195.940269) (xy 300.728635 -195.905852) (xy 300.69109 -195.865388)
			(xy 300.659995 -195.819781) (xy 300.636045 -195.770048) (xy 300.619775 -195.717301) (xy 300.611548 -195.662718)
			(xy 300.611032 -195.635118) (xy 300.611589 -195.60628) (xy 300.62057 -195.549309) (xy 300.638315 -195.494431)
			(xy 300.664392 -195.442988) (xy 300.698164 -195.396235) (xy 300.738806 -195.355312) (xy 300.785327 -195.32122)
			(xy 300.810676 -195.307458) (xy 300.823376 -195.300854) (xy 300.838108 -195.27647) (xy 300.837346 -195.15709)
			(xy 300.82236 -195.132706) (xy 300.809406 -195.126356) (xy 300.78596 -195.114153) (xy 300.742378 -195.084247)
			(xy 300.703342 -195.04861) (xy 300.669602 -195.007924) (xy 300.641804 -194.962968) (xy 300.620479 -194.914605)
			(xy 300.606038 -194.86376) (xy 300.598755 -194.811408) (xy 300.598332 -194.78498) (xy 300.598759 -194.759461)
			(xy 300.605564 -194.70888) (xy 300.619049 -194.659657) (xy 300.638974 -194.612669) (xy 300.664983 -194.568757)
			(xy 300.696613 -194.528703) (xy 300.714664 -194.51066) (xy 300.7233 -194.502532) (xy 300.731174 -194.480942)
			(xy 300.721014 -194.378072) (xy 300.709076 -194.358514) (xy 300.698916 -194.352164) (xy 300.67313 -194.334994)
			(xy 300.625622 -194.295231) (xy 300.583432 -194.249865) (xy 300.547217 -194.1996) (xy 300.51754 -194.145218)
			(xy 300.494863 -194.087566) (xy 300.479537 -194.027539) (xy 300.471802 -193.966072) (xy 300.471332 -193.935096)
			(xy 300.47184 -193.902633) (xy 300.480315 -193.838264) (xy 300.49712 -193.775551) (xy 300.521968 -193.715569)
			(xy 300.554432 -193.659343) (xy 300.593958 -193.607836) (xy 300.639869 -193.561929) (xy 300.69138 -193.522408)
			(xy 300.747608 -193.489948) (xy 300.807593 -193.465106) (xy 300.870307 -193.448307) (xy 300.934677 -193.439837)
			(xy 300.96714 -193.439288) (xy 300.999192 -193.439791) (xy 301.062761 -193.448056) (xy 301.124732 -193.464458)
			(xy 301.154592 -193.476118) (xy 301.168308 -193.481706) (xy 301.197264 -193.476372) (xy 301.286672 -193.393822)
			(xy 301.294292 -193.365374) (xy 301.28972 -193.35115) (xy 301.277224 -193.310269) (xy 301.25929 -193.22668)
			(xy 301.253906 -193.184272) (xy 301.252636 -193.17335) (xy 301.242222 -193.155316) (xy 301.164752 -193.09842)
			(xy 301.144178 -193.093848) (xy 301.133764 -193.09588) (xy 301.092515 -193.103364) (xy 301.009059 -193.111376)
			(xy 300.96714 -193.111882) (xy 300.924083 -193.111356) (xy 300.838382 -193.102919) (xy 300.753921 -193.086123)
			(xy 300.671513 -193.061129) (xy 300.591952 -193.028178) (xy 300.516004 -192.987587) (xy 300.4444 -192.939748)
			(xy 300.37783 -192.88512) (xy 300.316935 -192.824231) (xy 300.262301 -192.757666) (xy 300.214455 -192.686066)
			(xy 300.19371 -192.648332) (xy 300.189045 -192.640442) (xy 300.175282 -192.628355) (xy 300.158162 -192.621846)
			(xy 300.149006 -192.621408) (xy 295.490138 -192.621408) (xy 295.477629 -192.62205) (xy 295.45552 -192.633763)
			(xy 295.447974 -192.64376) (xy 295.393618 -192.72377) (xy 295.391078 -192.748662) (xy 295.39565 -192.7606)
			(xy 295.410564 -192.799374) (xy 295.43386 -192.87912) (xy 295.449516 -192.960712) (xy 295.457391 -193.043418)
			(xy 295.45788 -193.084958) (xy 295.457623 -193.10731) (xy 296.510471 -193.10731) (xy 296.514406 -193.053539)
			(xy 296.526129 -193.000915) (xy 296.545389 -192.950558) (xy 296.571775 -192.903541) (xy 296.604727 -192.860868)
			(xy 296.64354 -192.823447) (xy 296.687388 -192.792077) (xy 296.735336 -192.767425) (xy 296.786363 -192.750017)
			(xy 296.839381 -192.740224) (xy 296.89326 -192.738255) (xy 296.946851 -192.744152) (xy 296.999012 -192.757788)
			(xy 297.048632 -192.778875) (xy 297.094653 -192.806961) (xy 297.136095 -192.841449) (xy 297.172073 -192.881603)
			(xy 297.201821 -192.926567) (xy 297.224706 -192.975384) (xy 297.240238 -193.027013) (xy 297.248088 -193.080353)
			(xy 297.24858 -193.10731) (xy 297.248088 -193.134267) (xy 297.240238 -193.187607) (xy 297.224706 -193.239236)
			(xy 297.201821 -193.288053) (xy 297.172073 -193.333017) (xy 297.136095 -193.373171) (xy 297.094653 -193.407659)
			(xy 297.048632 -193.435745) (xy 296.999012 -193.456832) (xy 296.946851 -193.470468) (xy 296.89326 -193.476365)
			(xy 296.839381 -193.474396) (xy 296.786363 -193.464603) (xy 296.735336 -193.447195) (xy 296.687388 -193.422543)
			(xy 296.64354 -193.391173) (xy 296.604727 -193.353752) (xy 296.571775 -193.311079) (xy 296.545389 -193.264062)
			(xy 296.526129 -193.213705) (xy 296.514406 -193.161081) (xy 296.510471 -193.10731) (xy 295.457623 -193.10731)
			(xy 295.45741 -193.125779) (xy 295.449817 -193.207066) (xy 295.434701 -193.287295) (xy 295.412195 -193.365773)
			(xy 295.382492 -193.441819) (xy 295.345849 -193.514775) (xy 295.302585 -193.58401) (xy 295.253073 -193.648924)
			(xy 295.197743 -193.708956) (xy 295.137072 -193.763585) (xy 295.071587 -193.812339) (xy 295.001853 -193.854795)
			(xy 294.965374 -193.87312) (xy 294.956766 -193.877817) (xy 294.94367 -193.892389) (xy 294.937004 -193.910812)
			(xy 294.936926 -193.920618) (xy 294.93718 -193.935096) (xy 294.936617 -193.963919) (xy 294.931509 -193.99631)
			(xy 298.299139 -193.99631) (xy 298.303074 -193.942539) (xy 298.314797 -193.889915) (xy 298.334057 -193.839558)
			(xy 298.360443 -193.792541) (xy 298.393395 -193.749868) (xy 298.432208 -193.712447) (xy 298.476056 -193.681077)
			(xy 298.524004 -193.656425) (xy 298.575031 -193.639017) (xy 298.628049 -193.629224) (xy 298.681928 -193.627255)
			(xy 298.735519 -193.633152) (xy 298.78768 -193.646788) (xy 298.8373 -193.667875) (xy 298.883321 -193.695961)
			(xy 298.924763 -193.730449) (xy 298.960741 -193.770603) (xy 298.990489 -193.815567) (xy 299.013374 -193.864384)
			(xy 299.028906 -193.916013) (xy 299.036756 -193.969353) (xy 299.037248 -193.99631) (xy 299.036756 -194.023267)
			(xy 299.028906 -194.076607) (xy 299.013374 -194.128236) (xy 298.990489 -194.177053) (xy 298.960741 -194.222017)
			(xy 298.924763 -194.262171) (xy 298.883321 -194.296659) (xy 298.8373 -194.324745) (xy 298.78768 -194.345832)
			(xy 298.735519 -194.359468) (xy 298.681928 -194.365365) (xy 298.628049 -194.363396) (xy 298.575031 -194.353603)
			(xy 298.524004 -194.336195) (xy 298.476056 -194.311543) (xy 298.432208 -194.280173) (xy 298.393395 -194.242752)
			(xy 298.360443 -194.200079) (xy 298.334057 -194.153062) (xy 298.314797 -194.102705) (xy 298.303074 -194.050081)
			(xy 298.299139 -193.99631) (xy 294.931509 -193.99631) (xy 294.927638 -194.020862) (xy 294.909912 -194.075715)
			(xy 294.883871 -194.127145) (xy 294.850149 -194.173898) (xy 294.809566 -194.214839) (xy 294.76311 -194.248971)
			(xy 294.73779 -194.262756) (xy 294.72509 -194.26936) (xy 294.710358 -194.293744) (xy 294.71112 -194.413124)
			(xy 294.726106 -194.437254) (xy 294.73906 -194.443858) (xy 294.762464 -194.456076) (xy 294.805964 -194.485995)
			(xy 294.844924 -194.521625) (xy 294.8786 -194.562285) (xy 294.906351 -194.607199) (xy 294.927646 -194.655509)
			(xy 294.942078 -194.706293) (xy 294.949372 -194.758582) (xy 294.94988 -194.78498) (xy 294.949394 -194.812231)
			(xy 294.941638 -194.866179) (xy 294.936021 -194.88531) (xy 296.510471 -194.88531) (xy 296.514406 -194.831539)
			(xy 296.526129 -194.778915) (xy 296.545389 -194.728558) (xy 296.571775 -194.681541) (xy 296.604727 -194.638868)
			(xy 296.64354 -194.601447) (xy 296.687388 -194.570077) (xy 296.735336 -194.545425) (xy 296.786363 -194.528017)
			(xy 296.839381 -194.518224) (xy 296.89326 -194.516255) (xy 296.946851 -194.522152) (xy 296.999012 -194.535788)
			(xy 297.048632 -194.556875) (xy 297.094653 -194.584961) (xy 297.136095 -194.619449) (xy 297.172073 -194.659603)
			(xy 297.201821 -194.704567) (xy 297.224706 -194.753384) (xy 297.240238 -194.805013) (xy 297.248088 -194.858353)
			(xy 297.24858 -194.88531) (xy 297.248422 -194.893946) (xy 298.286422 -194.893946) (xy 298.290493 -194.838324)
			(xy 298.302619 -194.783887) (xy 298.322542 -194.731796) (xy 298.349838 -194.683161) (xy 298.383924 -194.639018)
			(xy 298.424073 -194.600309) (xy 298.469431 -194.567858) (xy 298.519031 -194.542357) (xy 298.571815 -194.52435)
			(xy 298.626658 -194.51422) (xy 298.682392 -194.512183) (xy 298.737829 -194.518283) (xy 298.791786 -194.532389)
			(xy 298.843115 -194.554201) (xy 298.890721 -194.583255) (xy 298.933589 -194.61893) (xy 298.970806 -194.660467)
			(xy 299.001579 -194.70698) (xy 299.025251 -194.757477) (xy 299.041319 -194.810884) (xy 299.049439 -194.86606)
			(xy 299.049948 -194.893946) (xy 299.049439 -194.921832) (xy 299.041319 -194.977008) (xy 299.025251 -195.030415)
			(xy 299.001579 -195.080912) (xy 298.970806 -195.127425) (xy 298.933589 -195.168962) (xy 298.890721 -195.204637)
			(xy 298.843115 -195.233691) (xy 298.791786 -195.255503) (xy 298.737829 -195.269609) (xy 298.682392 -195.275709)
			(xy 298.626658 -195.273672) (xy 298.571815 -195.263542) (xy 298.519031 -195.245535) (xy 298.469431 -195.220034)
			(xy 298.424073 -195.187583) (xy 298.383924 -195.148874) (xy 298.349838 -195.104731) (xy 298.322542 -195.056096)
			(xy 298.302619 -195.004005) (xy 298.290493 -194.949568) (xy 298.286422 -194.893946) (xy 297.248422 -194.893946)
			(xy 297.248088 -194.912267) (xy 297.240238 -194.965607) (xy 297.224706 -195.017236) (xy 297.201821 -195.066053)
			(xy 297.172073 -195.111017) (xy 297.136095 -195.151171) (xy 297.094653 -195.185659) (xy 297.048632 -195.213745)
			(xy 296.999012 -195.234832) (xy 296.946851 -195.248468) (xy 296.89326 -195.254365) (xy 296.839381 -195.252396)
			(xy 296.786363 -195.242603) (xy 296.735336 -195.225195) (xy 296.687388 -195.200543) (xy 296.64354 -195.169173)
			(xy 296.604727 -195.131752) (xy 296.571775 -195.089079) (xy 296.545389 -195.042062) (xy 296.526129 -194.991705)
			(xy 296.514406 -194.939081) (xy 296.510471 -194.88531) (xy 294.936021 -194.88531) (xy 294.926283 -194.918474)
			(xy 294.903641 -194.968051) (xy 294.874175 -195.013901) (xy 294.838484 -195.055092) (xy 294.797293 -195.090783)
			(xy 294.751443 -195.120249) (xy 294.701866 -195.142891) (xy 294.649571 -195.158246) (xy 294.595623 -195.166002)
			(xy 294.541121 -195.166002) (xy 294.487173 -195.158246) (xy 294.434878 -195.142891) (xy 294.385301 -195.120249)
			(xy 294.339451 -195.090783) (xy 294.29826 -195.055092) (xy 294.262569 -195.013901) (xy 294.233103 -194.968051)
			(xy 294.210461 -194.918474) (xy 294.195106 -194.866179) (xy 294.18735 -194.812231) (xy 294.186864 -194.78498)
			(xy 294.187307 -194.758576) (xy 294.194582 -194.706273) (xy 294.209005 -194.655473) (xy 294.230299 -194.607149)
			(xy 294.258057 -194.562226) (xy 294.291748 -194.521562) (xy 294.330727 -194.485937) (xy 294.37425 -194.45603)
			(xy 294.397684 -194.443858) (xy 294.410638 -194.437254) (xy 294.425624 -194.413124) (xy 294.426386 -194.293744)
			(xy 294.411654 -194.26936) (xy 294.398954 -194.262756) (xy 294.373601 -194.249025) (xy 294.327129 -194.214901)
			(xy 294.286536 -194.173958) (xy 294.252813 -194.127194) (xy 294.226782 -194.07575) (xy 294.209079 -194.020881)
			(xy 294.200134 -193.963924) (xy 294.199564 -193.935096) (xy 294.200326 -193.909696) (xy 294.200556 -193.899874)
			(xy 294.194481 -193.881207) (xy 294.181868 -193.866165) (xy 294.173402 -193.861182) (xy 294.148458 -193.847826)
			(xy 294.10016 -193.81834) (xy 294.076882 -193.802254) (xy 294.06469 -193.793872) (xy 294.035226 -193.792348)
			(xy 293.929562 -193.8528) (xy 293.915846 -193.879216) (xy 293.917116 -193.893948) (xy 293.918894 -193.935096)
			(xy 293.918348 -193.968489) (xy 293.90938 -194.034669) (xy 293.891605 -194.099045) (xy 293.865346 -194.160452)
			(xy 293.831078 -194.217775) (xy 293.789422 -194.269977) (xy 293.741133 -194.316112) (xy 293.714424 -194.336162)
			(xy 293.70528 -194.342766) (xy 293.694358 -194.362578) (xy 293.687754 -194.463162) (xy 293.696136 -194.484244)
			(xy 293.704264 -194.492118) (xy 293.722689 -194.510185) (xy 293.754995 -194.550425) (xy 293.781577 -194.594654)
			(xy 293.80195 -194.642065) (xy 293.815741 -194.691791) (xy 293.822699 -194.742923) (xy 293.823136 -194.768724)
			(xy 293.82265 -194.795975) (xy 293.814894 -194.849923) (xy 293.799539 -194.902218) (xy 293.776897 -194.951795)
			(xy 293.747431 -194.997645) (xy 293.71174 -195.038836) (xy 293.670549 -195.074527) (xy 293.624699 -195.103993)
			(xy 293.575122 -195.126635) (xy 293.522827 -195.14199) (xy 293.468879 -195.149746) (xy 293.414377 -195.149746)
			(xy 293.360429 -195.14199) (xy 293.308134 -195.126635) (xy 293.258557 -195.103993) (xy 293.212707 -195.074527)
			(xy 293.171516 -195.038836) (xy 293.135825 -194.997645) (xy 293.106359 -194.951795) (xy 293.083717 -194.902218)
			(xy 293.068362 -194.849923) (xy 293.060606 -194.795975) (xy 293.06012 -194.768724) (xy 293.06065 -194.739461)
			(xy 293.069583 -194.681621) (xy 293.087243 -194.625823) (xy 293.113215 -194.573376) (xy 293.146891 -194.525509)
			(xy 293.1668 -194.504056) (xy 293.174674 -194.495928) (xy 293.18204 -194.474592) (xy 293.170864 -194.374262)
			(xy 293.15918 -194.354958) (xy 293.149782 -194.348862) (xy 293.124511 -194.331606) (xy 293.078009 -194.291828)
			(xy 293.036752 -194.246634) (xy 293.001365 -194.19671) (xy 292.972386 -194.142813) (xy 292.950254 -194.085761)
			(xy 292.935307 -194.026421) (xy 292.92777 -193.965693) (xy 292.927278 -193.935096) (xy 292.927809 -193.902634)
			(xy 292.936284 -193.838264) (xy 292.953088 -193.775552) (xy 292.977933 -193.715569) (xy 293.010395 -193.659343)
			(xy 293.049918 -193.607834) (xy 293.095827 -193.561925) (xy 293.147334 -193.522401) (xy 293.20356 -193.489938)
			(xy 293.263543 -193.465091) (xy 293.326255 -193.448286) (xy 293.390624 -193.43981) (xy 293.423086 -193.439288)
			(xy 293.455139 -193.439787) (xy 293.51871 -193.448046) (xy 293.580684 -193.464442) (xy 293.610538 -193.476118)
			(xy 293.624254 -193.481706) (xy 293.65321 -193.476372) (xy 293.742618 -193.393822) (xy 293.750238 -193.365374)
			(xy 293.745666 -193.35115) (xy 293.733169 -193.310269) (xy 293.715234 -193.22668) (xy 293.709852 -193.184272)
			(xy 293.708582 -193.17335) (xy 293.698168 -193.155316) (xy 293.620698 -193.09842) (xy 293.600124 -193.093848)
			(xy 293.58971 -193.09588) (xy 293.548461 -193.103366) (xy 293.465006 -193.111383) (xy 293.423086 -193.111882)
			(xy 293.38003 -193.111353) (xy 293.294333 -193.102912) (xy 293.209875 -193.086111) (xy 293.127471 -193.061114)
			(xy 293.047914 -193.02816) (xy 292.97197 -192.987567) (xy 292.90037 -192.939725) (xy 292.833804 -192.885097)
			(xy 292.772913 -192.824207) (xy 292.718283 -192.757642) (xy 292.670441 -192.686043) (xy 292.649656 -192.648332)
			(xy 292.644993 -192.640437) (xy 292.631233 -192.628338) (xy 292.614111 -192.621813) (xy 292.604952 -192.621408)
			(xy 287.946084 -192.621408) (xy 287.933581 -192.622061) (xy 287.911492 -192.633788) (xy 287.90392 -192.64376)
			(xy 287.849564 -192.72377) (xy 287.847024 -192.748662) (xy 287.851596 -192.7606) (xy 287.86651 -192.799373)
			(xy 287.889809 -192.87912) (xy 287.905466 -192.960712) (xy 287.913341 -193.043418) (xy 287.913826 -193.084958)
			(xy 287.913569 -193.10731) (xy 288.966417 -193.10731) (xy 288.970352 -193.053539) (xy 288.982075 -193.000915)
			(xy 289.001335 -192.950558) (xy 289.027721 -192.903541) (xy 289.060673 -192.860868) (xy 289.099486 -192.823447)
			(xy 289.143334 -192.792077) (xy 289.191282 -192.767425) (xy 289.242309 -192.750017) (xy 289.295327 -192.740224)
			(xy 289.349206 -192.738255) (xy 289.402797 -192.744152) (xy 289.454958 -192.757788) (xy 289.504578 -192.778875)
			(xy 289.550599 -192.806961) (xy 289.592041 -192.841449) (xy 289.628019 -192.881603) (xy 289.657767 -192.926567)
			(xy 289.680652 -192.975384) (xy 289.696184 -193.027013) (xy 289.704034 -193.080353) (xy 289.704526 -193.10731)
			(xy 289.704034 -193.134267) (xy 289.696184 -193.187607) (xy 289.680652 -193.239236) (xy 289.657767 -193.288053)
			(xy 289.628019 -193.333017) (xy 289.592041 -193.373171) (xy 289.550599 -193.407659) (xy 289.504578 -193.435745)
			(xy 289.454958 -193.456832) (xy 289.402797 -193.470468) (xy 289.349206 -193.476365) (xy 289.295327 -193.474396)
			(xy 289.242309 -193.464603) (xy 289.191282 -193.447195) (xy 289.143334 -193.422543) (xy 289.099486 -193.391173)
			(xy 289.060673 -193.353752) (xy 289.027721 -193.311079) (xy 289.001335 -193.264062) (xy 288.982075 -193.213705)
			(xy 288.970352 -193.161081) (xy 288.966417 -193.10731) (xy 287.913569 -193.10731) (xy 287.913356 -193.125779)
			(xy 287.905763 -193.207067) (xy 287.890648 -193.287298) (xy 287.868142 -193.365776) (xy 287.83844 -193.441824)
			(xy 287.801799 -193.514781) (xy 287.758536 -193.584018) (xy 287.709025 -193.648934) (xy 287.653696 -193.708968)
			(xy 287.593026 -193.7636) (xy 287.527542 -193.812357) (xy 287.45781 -193.854817) (xy 287.42132 -193.87312)
			(xy 287.412706 -193.877813) (xy 287.399597 -193.892382) (xy 287.392925 -193.91081) (xy 287.392872 -193.920618)
			(xy 287.393126 -193.935096) (xy 287.392563 -193.96392) (xy 287.387456 -193.99631) (xy 290.755339 -193.99631)
			(xy 290.759274 -193.942539) (xy 290.770997 -193.889915) (xy 290.790257 -193.839558) (xy 290.816643 -193.792541)
			(xy 290.849595 -193.749868) (xy 290.888408 -193.712447) (xy 290.932256 -193.681077) (xy 290.980204 -193.656425)
			(xy 291.031231 -193.639017) (xy 291.084249 -193.629224) (xy 291.138128 -193.627255) (xy 291.191719 -193.633152)
			(xy 291.24388 -193.646788) (xy 291.2935 -193.667875) (xy 291.339521 -193.695961) (xy 291.380963 -193.730449)
			(xy 291.416941 -193.770603) (xy 291.446689 -193.815567) (xy 291.469574 -193.864384) (xy 291.485106 -193.916013)
			(xy 291.492956 -193.969353) (xy 291.493448 -193.99631) (xy 291.492956 -194.023267) (xy 291.485106 -194.076607)
			(xy 291.469574 -194.128236) (xy 291.446689 -194.177053) (xy 291.416941 -194.222017) (xy 291.380963 -194.262171)
			(xy 291.339521 -194.296659) (xy 291.2935 -194.324745) (xy 291.24388 -194.345832) (xy 291.191719 -194.359468)
			(xy 291.138128 -194.365365) (xy 291.084249 -194.363396) (xy 291.031231 -194.353603) (xy 290.980204 -194.336195)
			(xy 290.932256 -194.311543) (xy 290.888408 -194.280173) (xy 290.849595 -194.242752) (xy 290.816643 -194.200079)
			(xy 290.790257 -194.153062) (xy 290.770997 -194.102705) (xy 290.759274 -194.050081) (xy 290.755339 -193.99631)
			(xy 287.387456 -193.99631) (xy 287.383584 -194.020864) (xy 287.36586 -194.075719) (xy 287.339821 -194.127151)
			(xy 287.306101 -194.173908) (xy 287.26552 -194.214853) (xy 287.219067 -194.24899) (xy 287.193736 -194.262756)
			(xy 287.181036 -194.26936) (xy 287.166304 -194.293744) (xy 287.167066 -194.413124) (xy 287.182052 -194.437254)
			(xy 287.195006 -194.443858) (xy 287.218413 -194.456074) (xy 287.261918 -194.48599) (xy 287.300883 -194.521617)
			(xy 287.334565 -194.562277) (xy 287.36232 -194.607191) (xy 287.383618 -194.655503) (xy 287.398052 -194.706289)
			(xy 287.405347 -194.758581) (xy 287.405826 -194.78498) (xy 287.40534 -194.812231) (xy 287.397584 -194.866179)
			(xy 287.391967 -194.88531) (xy 288.966417 -194.88531) (xy 288.970352 -194.831539) (xy 288.982075 -194.778915)
			(xy 289.001335 -194.728558) (xy 289.027721 -194.681541) (xy 289.060673 -194.638868) (xy 289.099486 -194.601447)
			(xy 289.143334 -194.570077) (xy 289.191282 -194.545425) (xy 289.242309 -194.528017) (xy 289.295327 -194.518224)
			(xy 289.349206 -194.516255) (xy 289.402797 -194.522152) (xy 289.454958 -194.535788) (xy 289.504578 -194.556875)
			(xy 289.550599 -194.584961) (xy 289.592041 -194.619449) (xy 289.628019 -194.659603) (xy 289.657767 -194.704567)
			(xy 289.680652 -194.753384) (xy 289.696184 -194.805013) (xy 289.704034 -194.858353) (xy 289.704526 -194.88531)
			(xy 289.704368 -194.893946) (xy 290.742622 -194.893946) (xy 290.746693 -194.838324) (xy 290.758819 -194.783887)
			(xy 290.778742 -194.731796) (xy 290.806038 -194.683161) (xy 290.840124 -194.639018) (xy 290.880273 -194.600309)
			(xy 290.925631 -194.567858) (xy 290.975231 -194.542357) (xy 291.028015 -194.52435) (xy 291.082858 -194.51422)
			(xy 291.138592 -194.512183) (xy 291.194029 -194.518283) (xy 291.247986 -194.532389) (xy 291.299315 -194.554201)
			(xy 291.346921 -194.583255) (xy 291.389789 -194.61893) (xy 291.427006 -194.660467) (xy 291.457779 -194.70698)
			(xy 291.481451 -194.757477) (xy 291.497519 -194.810884) (xy 291.505639 -194.86606) (xy 291.506148 -194.893946)
			(xy 291.505639 -194.921832) (xy 291.497519 -194.977008) (xy 291.481451 -195.030415) (xy 291.457779 -195.080912)
			(xy 291.427006 -195.127425) (xy 291.389789 -195.168962) (xy 291.346921 -195.204637) (xy 291.299315 -195.233691)
			(xy 291.247986 -195.255503) (xy 291.194029 -195.269609) (xy 291.138592 -195.275709) (xy 291.082858 -195.273672)
			(xy 291.028015 -195.263542) (xy 290.975231 -195.245535) (xy 290.925631 -195.220034) (xy 290.880273 -195.187583)
			(xy 290.840124 -195.148874) (xy 290.806038 -195.104731) (xy 290.778742 -195.056096) (xy 290.758819 -195.004005)
			(xy 290.746693 -194.949568) (xy 290.742622 -194.893946) (xy 289.704368 -194.893946) (xy 289.704034 -194.912267)
			(xy 289.696184 -194.965607) (xy 289.680652 -195.017236) (xy 289.657767 -195.066053) (xy 289.628019 -195.111017)
			(xy 289.592041 -195.151171) (xy 289.550599 -195.185659) (xy 289.504578 -195.213745) (xy 289.454958 -195.234832)
			(xy 289.402797 -195.248468) (xy 289.349206 -195.254365) (xy 289.295327 -195.252396) (xy 289.242309 -195.242603)
			(xy 289.191282 -195.225195) (xy 289.143334 -195.200543) (xy 289.099486 -195.169173) (xy 289.060673 -195.131752)
			(xy 289.027721 -195.089079) (xy 289.001335 -195.042062) (xy 288.982075 -194.991705) (xy 288.970352 -194.939081)
			(xy 288.966417 -194.88531) (xy 287.391967 -194.88531) (xy 287.382229 -194.918474) (xy 287.359587 -194.968051)
			(xy 287.330121 -195.013901) (xy 287.29443 -195.055092) (xy 287.253239 -195.090783) (xy 287.207389 -195.120249)
			(xy 287.157812 -195.142891) (xy 287.105517 -195.158246) (xy 287.051569 -195.166002) (xy 286.997067 -195.166002)
			(xy 286.943119 -195.158246) (xy 286.890824 -195.142891) (xy 286.841247 -195.120249) (xy 286.795397 -195.090783)
			(xy 286.754206 -195.055092) (xy 286.718515 -195.013901) (xy 286.689049 -194.968051) (xy 286.666407 -194.918474)
			(xy 286.651052 -194.866179) (xy 286.643296 -194.812231) (xy 286.64281 -194.78498) (xy 286.643253 -194.758577)
			(xy 286.650529 -194.706274) (xy 286.664953 -194.655476) (xy 286.686248 -194.607155) (xy 286.714008 -194.562234)
			(xy 286.747701 -194.521574) (xy 286.786682 -194.485952) (xy 286.830206 -194.45605) (xy 286.85363 -194.443858)
			(xy 286.866584 -194.437254) (xy 286.88157 -194.413124) (xy 286.882332 -194.293744) (xy 286.8676 -194.26936)
			(xy 286.8549 -194.262756) (xy 286.82955 -194.249022) (xy 286.783084 -194.214895) (xy 286.742497 -194.17395)
			(xy 286.70878 -194.127187) (xy 286.682753 -194.075744) (xy 286.665052 -194.020876) (xy 286.656109 -193.963922)
			(xy 286.65551 -193.935096) (xy 286.656272 -193.909696) (xy 286.656502 -193.899875) (xy 286.650423 -193.881214)
			(xy 286.637803 -193.866183) (xy 286.629348 -193.861182) (xy 286.604405 -193.847825) (xy 286.556108 -193.818336)
			(xy 286.532828 -193.802254) (xy 286.520636 -193.793872) (xy 286.491172 -193.792348) (xy 286.385508 -193.8528)
			(xy 286.371792 -193.879216) (xy 286.373062 -193.893948) (xy 286.37484 -193.935096) (xy 286.374379 -193.965834)
			(xy 286.366785 -194.02684) (xy 286.351714 -194.086441) (xy 286.329396 -194.143723) (xy 286.300174 -194.19781)
			(xy 286.264494 -194.247874) (xy 286.222903 -194.293146) (xy 286.176038 -194.332934) (xy 286.150558 -194.350132)
			(xy 286.140398 -194.356736) (xy 286.12846 -194.376548) (xy 286.120586 -194.480942) (xy 286.129222 -194.502532)
			(xy 286.138112 -194.51066) (xy 286.157025 -194.528208) (xy 286.190249 -194.567679) (xy 286.217643 -194.611398)
			(xy 286.238671 -194.658511) (xy 286.252924 -194.708096) (xy 286.260122 -194.759184) (xy 286.26054 -194.78498)
			(xy 286.260024 -194.81258) (xy 286.251797 -194.867163) (xy 286.235527 -194.91991) (xy 286.211577 -194.969643)
			(xy 286.180482 -195.01525) (xy 286.142937 -195.055714) (xy 286.09978 -195.090131) (xy 286.051976 -195.11773)
			(xy 286.000592 -195.137897) (xy 285.946777 -195.15018) (xy 285.891732 -195.154305) (xy 285.836687 -195.15018)
			(xy 285.782872 -195.137897) (xy 285.731488 -195.11773) (xy 285.683684 -195.090131) (xy 285.640527 -195.055714)
			(xy 285.602982 -195.01525) (xy 285.571887 -194.969643) (xy 285.547937 -194.91991) (xy 285.531667 -194.867163)
			(xy 285.52344 -194.81258) (xy 285.522924 -194.78498) (xy 285.523502 -194.755114) (xy 285.533126 -194.696164)
			(xy 285.552121 -194.639533) (xy 285.579989 -194.586702) (xy 285.616004 -194.539049) (xy 285.637224 -194.518026)
			(xy 285.64586 -194.509644) (xy 285.653988 -194.488054) (xy 285.642812 -194.383914) (xy 285.630366 -194.364356)
			(xy 285.620206 -194.358006) (xy 285.593454 -194.341048) (xy 285.544078 -194.301375) (xy 285.500157 -194.255737)
			(xy 285.462406 -194.204877) (xy 285.43144 -194.149623) (xy 285.407763 -194.090875) (xy 285.391761 -194.02959)
			(xy 285.383694 -193.966766) (xy 285.383224 -193.935096) (xy 285.383732 -193.902633) (xy 285.392207 -193.838263)
			(xy 285.409012 -193.77555) (xy 285.43386 -193.715567) (xy 285.466324 -193.659341) (xy 285.50585 -193.607834)
			(xy 285.551761 -193.561926) (xy 285.603271 -193.522404) (xy 285.6595 -193.489944) (xy 285.719484 -193.465101)
			(xy 285.782199 -193.4483) (xy 285.846569 -193.43983) (xy 285.879032 -193.439288) (xy 285.911084 -193.43979)
			(xy 285.974654 -193.448055) (xy 286.036625 -193.464455) (xy 286.066484 -193.476118) (xy 286.0802 -193.481706)
			(xy 286.109156 -193.476372) (xy 286.198564 -193.393822) (xy 286.206184 -193.365374) (xy 286.201612 -193.35115)
			(xy 286.189115 -193.310269) (xy 286.171179 -193.226681) (xy 286.165798 -193.184272) (xy 286.164528 -193.17335)
			(xy 286.154114 -193.155316) (xy 286.076644 -193.09842) (xy 286.05607 -193.093848) (xy 286.045656 -193.09588)
			(xy 286.004407 -193.103363) (xy 285.920951 -193.111375) (xy 285.879032 -193.111882) (xy 285.835975 -193.111356)
			(xy 285.750275 -193.102918) (xy 285.665814 -193.086121) (xy 285.583407 -193.061127) (xy 285.503847 -193.028175)
			(xy 285.427899 -192.987584) (xy 285.356295 -192.939744) (xy 285.289726 -192.885117) (xy 285.228831 -192.824227)
			(xy 285.174198 -192.757662) (xy 285.126353 -192.686063) (xy 285.105602 -192.648332) (xy 285.100936 -192.640443)
			(xy 285.087174 -192.628358) (xy 285.070053 -192.621851) (xy 285.060898 -192.621408) (xy 280.40203 -192.621408)
			(xy 280.389522 -192.622051) (xy 280.367416 -192.633767) (xy 280.359866 -192.64376) (xy 280.30551 -192.72377)
			(xy 280.30297 -192.748662) (xy 280.307542 -192.7606) (xy 280.322456 -192.799374) (xy 280.345753 -192.87912)
			(xy 280.361409 -192.960712) (xy 280.369283 -193.043418) (xy 280.369772 -193.084958) (xy 280.369515 -193.10731)
			(xy 281.422363 -193.10731) (xy 281.426298 -193.053539) (xy 281.438021 -193.000915) (xy 281.457281 -192.950558)
			(xy 281.483667 -192.903541) (xy 281.516619 -192.860868) (xy 281.555432 -192.823447) (xy 281.59928 -192.792077)
			(xy 281.647228 -192.767425) (xy 281.698255 -192.750017) (xy 281.751273 -192.740224) (xy 281.805152 -192.738255)
			(xy 281.858743 -192.744152) (xy 281.910904 -192.757788) (xy 281.960524 -192.778875) (xy 282.006545 -192.806961)
			(xy 282.047987 -192.841449) (xy 282.083965 -192.881603) (xy 282.113713 -192.926567) (xy 282.136598 -192.975384)
			(xy 282.15213 -193.027013) (xy 282.15998 -193.080353) (xy 282.160472 -193.10731) (xy 282.15998 -193.134267)
			(xy 282.15213 -193.187607) (xy 282.136598 -193.239236) (xy 282.113713 -193.288053) (xy 282.083965 -193.333017)
			(xy 282.047987 -193.373171) (xy 282.006545 -193.407659) (xy 281.960524 -193.435745) (xy 281.910904 -193.456832)
			(xy 281.858743 -193.470468) (xy 281.805152 -193.476365) (xy 281.751273 -193.474396) (xy 281.698255 -193.464603)
			(xy 281.647228 -193.447195) (xy 281.59928 -193.422543) (xy 281.555432 -193.391173) (xy 281.516619 -193.353752)
			(xy 281.483667 -193.311079) (xy 281.457281 -193.264062) (xy 281.438021 -193.213705) (xy 281.426298 -193.161081)
			(xy 281.422363 -193.10731) (xy 280.369515 -193.10731) (xy 280.369302 -193.125778) (xy 280.361709 -193.207066)
			(xy 280.346593 -193.287295) (xy 280.324086 -193.365772) (xy 280.294383 -193.441818) (xy 280.257741 -193.514774)
			(xy 280.214476 -193.584009) (xy 280.164964 -193.648923) (xy 280.109633 -193.708954) (xy 280.048962 -193.763582)
			(xy 279.983477 -193.812336) (xy 279.913744 -193.854792) (xy 279.877266 -193.87312) (xy 279.868659 -193.877818)
			(xy 279.855565 -193.89239) (xy 279.8489 -193.910812) (xy 279.848818 -193.920618) (xy 279.849072 -193.935096)
			(xy 279.848509 -193.963919) (xy 279.843401 -193.99631) (xy 283.211285 -193.99631) (xy 283.21522 -193.942539)
			(xy 283.226943 -193.889915) (xy 283.246203 -193.839558) (xy 283.272589 -193.792541) (xy 283.305541 -193.749868)
			(xy 283.344354 -193.712447) (xy 283.388202 -193.681077) (xy 283.43615 -193.656425) (xy 283.487177 -193.639017)
			(xy 283.540195 -193.629224) (xy 283.594074 -193.627255) (xy 283.647665 -193.633152) (xy 283.699826 -193.646788)
			(xy 283.749446 -193.667875) (xy 283.795467 -193.695961) (xy 283.836909 -193.730449) (xy 283.872887 -193.770603)
			(xy 283.902635 -193.815567) (xy 283.92552 -193.864384) (xy 283.941052 -193.916013) (xy 283.948902 -193.969353)
			(xy 283.949394 -193.99631) (xy 283.948902 -194.023267) (xy 283.941052 -194.076607) (xy 283.92552 -194.128236)
			(xy 283.902635 -194.177053) (xy 283.872887 -194.222017) (xy 283.836909 -194.262171) (xy 283.795467 -194.296659)
			(xy 283.749446 -194.324745) (xy 283.699826 -194.345832) (xy 283.647665 -194.359468) (xy 283.594074 -194.365365)
			(xy 283.540195 -194.363396) (xy 283.487177 -194.353603) (xy 283.43615 -194.336195) (xy 283.388202 -194.311543)
			(xy 283.344354 -194.280173) (xy 283.305541 -194.242752) (xy 283.272589 -194.200079) (xy 283.246203 -194.153062)
			(xy 283.226943 -194.102705) (xy 283.21522 -194.050081) (xy 283.211285 -193.99631) (xy 279.843401 -193.99631)
			(xy 279.839529 -194.020861) (xy 279.821803 -194.075714) (xy 279.795762 -194.127143) (xy 279.76204 -194.173897)
			(xy 279.721457 -194.214837) (xy 279.675 -194.248967) (xy 279.649682 -194.262756) (xy 279.636982 -194.26936)
			(xy 279.62225 -194.293744) (xy 279.623012 -194.413124) (xy 279.637998 -194.437254) (xy 279.650952 -194.443858)
			(xy 279.674356 -194.456076) (xy 279.717857 -194.485994) (xy 279.756818 -194.521624) (xy 279.790495 -194.562283)
			(xy 279.818247 -194.607197) (xy 279.839542 -194.655508) (xy 279.853974 -194.706293) (xy 279.861268 -194.758582)
			(xy 279.861772 -194.78498) (xy 279.861286 -194.812231) (xy 279.85353 -194.866179) (xy 279.847913 -194.88531)
			(xy 281.422363 -194.88531) (xy 281.426298 -194.831539) (xy 281.438021 -194.778915) (xy 281.457281 -194.728558)
			(xy 281.483667 -194.681541) (xy 281.516619 -194.638868) (xy 281.555432 -194.601447) (xy 281.59928 -194.570077)
			(xy 281.647228 -194.545425) (xy 281.698255 -194.528017) (xy 281.751273 -194.518224) (xy 281.805152 -194.516255)
			(xy 281.858743 -194.522152) (xy 281.910904 -194.535788) (xy 281.960524 -194.556875) (xy 282.006545 -194.584961)
			(xy 282.047987 -194.619449) (xy 282.083965 -194.659603) (xy 282.113713 -194.704567) (xy 282.136598 -194.753384)
			(xy 282.15213 -194.805013) (xy 282.15998 -194.858353) (xy 282.160472 -194.88531) (xy 282.160314 -194.893946)
			(xy 283.198568 -194.893946) (xy 283.202639 -194.838324) (xy 283.214765 -194.783887) (xy 283.234688 -194.731796)
			(xy 283.261984 -194.683161) (xy 283.29607 -194.639018) (xy 283.336219 -194.600309) (xy 283.381577 -194.567858)
			(xy 283.431177 -194.542357) (xy 283.483961 -194.52435) (xy 283.538804 -194.51422) (xy 283.594538 -194.512183)
			(xy 283.649975 -194.518283) (xy 283.703932 -194.532389) (xy 283.755261 -194.554201) (xy 283.802867 -194.583255)
			(xy 283.845735 -194.61893) (xy 283.882952 -194.660467) (xy 283.913725 -194.70698) (xy 283.937397 -194.757477)
			(xy 283.953465 -194.810884) (xy 283.961585 -194.86606) (xy 283.962094 -194.893946) (xy 283.961585 -194.921832)
			(xy 283.953465 -194.977008) (xy 283.937397 -195.030415) (xy 283.913725 -195.080912) (xy 283.882952 -195.127425)
			(xy 283.845735 -195.168962) (xy 283.802867 -195.204637) (xy 283.755261 -195.233691) (xy 283.703932 -195.255503)
			(xy 283.649975 -195.269609) (xy 283.594538 -195.275709) (xy 283.538804 -195.273672) (xy 283.483961 -195.263542)
			(xy 283.431177 -195.245535) (xy 283.381577 -195.220034) (xy 283.336219 -195.187583) (xy 283.29607 -195.148874)
			(xy 283.261984 -195.104731) (xy 283.234688 -195.056096) (xy 283.214765 -195.004005) (xy 283.202639 -194.949568)
			(xy 283.198568 -194.893946) (xy 282.160314 -194.893946) (xy 282.15998 -194.912267) (xy 282.15213 -194.965607)
			(xy 282.136598 -195.017236) (xy 282.113713 -195.066053) (xy 282.083965 -195.111017) (xy 282.047987 -195.151171)
			(xy 282.006545 -195.185659) (xy 281.960524 -195.213745) (xy 281.910904 -195.234832) (xy 281.858743 -195.248468)
			(xy 281.805152 -195.254365) (xy 281.751273 -195.252396) (xy 281.698255 -195.242603) (xy 281.647228 -195.225195)
			(xy 281.59928 -195.200543) (xy 281.555432 -195.169173) (xy 281.516619 -195.131752) (xy 281.483667 -195.089079)
			(xy 281.457281 -195.042062) (xy 281.438021 -194.991705) (xy 281.426298 -194.939081) (xy 281.422363 -194.88531)
			(xy 279.847913 -194.88531) (xy 279.838175 -194.918474) (xy 279.815533 -194.968051) (xy 279.786067 -195.013901)
			(xy 279.750376 -195.055092) (xy 279.709185 -195.090783) (xy 279.663335 -195.120249) (xy 279.613758 -195.142891)
			(xy 279.561463 -195.158246) (xy 279.507515 -195.166002) (xy 279.453013 -195.166002) (xy 279.399065 -195.158246)
			(xy 279.34677 -195.142891) (xy 279.297193 -195.120249) (xy 279.251343 -195.090783) (xy 279.210152 -195.055092)
			(xy 279.174461 -195.013901) (xy 279.144995 -194.968051) (xy 279.122353 -194.918474) (xy 279.106998 -194.866179)
			(xy 279.099242 -194.812231) (xy 279.098756 -194.78498) (xy 279.099199 -194.758577) (xy 279.106476 -194.706276)
			(xy 279.1209 -194.65548) (xy 279.142197 -194.60716) (xy 279.169959 -194.562242) (xy 279.203654 -194.521585)
			(xy 279.242637 -194.485967) (xy 279.286163 -194.45607) (xy 279.309576 -194.443858) (xy 279.32253 -194.437254)
			(xy 279.337516 -194.413124) (xy 279.338278 -194.293744) (xy 279.323546 -194.26936) (xy 279.310846 -194.262756)
			(xy 279.285493 -194.249025) (xy 279.239022 -194.2149) (xy 279.19843 -194.173957) (xy 279.164708 -194.127193)
			(xy 279.138678 -194.075749) (xy 279.120975 -194.02088) (xy 279.11203 -193.963924) (xy 279.111456 -193.935096)
			(xy 279.112218 -193.909696) (xy 279.112448 -193.899874) (xy 279.106373 -193.881208) (xy 279.093759 -193.866168)
			(xy 279.085294 -193.861182) (xy 279.060418 -193.847885) (xy 279.012248 -193.818523) (xy 278.989028 -193.802508)
			(xy 278.976582 -193.793872) (xy 278.947626 -193.792348) (xy 278.841708 -193.853308) (xy 278.827992 -193.878962)
			(xy 278.829262 -193.893948) (xy 278.83104 -193.935096) (xy 278.830579 -193.965834) (xy 278.822985 -194.02684)
			(xy 278.807914 -194.086441) (xy 278.785596 -194.143723) (xy 278.756374 -194.19781) (xy 278.720694 -194.247874)
			(xy 278.679103 -194.293146) (xy 278.632238 -194.332934) (xy 278.606758 -194.350132) (xy 278.596598 -194.356736)
			(xy 278.58466 -194.376548) (xy 278.576786 -194.480942) (xy 278.585422 -194.502532) (xy 278.594312 -194.51066)
			(xy 278.613225 -194.528208) (xy 278.646449 -194.567679) (xy 278.673843 -194.611398) (xy 278.694871 -194.658511)
			(xy 278.709124 -194.708096) (xy 278.716322 -194.759184) (xy 278.71674 -194.78498) (xy 278.716224 -194.81258)
			(xy 278.707997 -194.867163) (xy 278.691727 -194.91991) (xy 278.667777 -194.969643) (xy 278.636682 -195.01525)
			(xy 278.599137 -195.055714) (xy 278.55598 -195.090131) (xy 278.508176 -195.11773) (xy 278.456792 -195.137897)
			(xy 278.402977 -195.15018) (xy 278.347932 -195.154305) (xy 278.292887 -195.15018) (xy 278.239072 -195.137897)
			(xy 278.187688 -195.11773) (xy 278.139884 -195.090131) (xy 278.096727 -195.055714) (xy 278.059182 -195.01525)
			(xy 278.028087 -194.969643) (xy 278.004137 -194.91991) (xy 277.987867 -194.867163) (xy 277.97964 -194.81258)
			(xy 277.979124 -194.78498) (xy 277.979702 -194.755114) (xy 277.989326 -194.696164) (xy 278.008321 -194.639533)
			(xy 278.036189 -194.586702) (xy 278.072204 -194.539049) (xy 278.093424 -194.518026) (xy 278.10206 -194.509644)
			(xy 278.110188 -194.488054) (xy 278.099012 -194.383914) (xy 278.086566 -194.364356) (xy 278.076406 -194.358006)
			(xy 278.049654 -194.341048) (xy 278.000278 -194.301375) (xy 277.956357 -194.255737) (xy 277.918606 -194.204877)
			(xy 277.88764 -194.149623) (xy 277.863963 -194.090875) (xy 277.847961 -194.02959) (xy 277.839894 -193.966766)
			(xy 277.839424 -193.935096) (xy 277.839932 -193.902633) (xy 277.848407 -193.838263) (xy 277.865212 -193.77555)
			(xy 277.89006 -193.715567) (xy 277.922524 -193.659341) (xy 277.96205 -193.607834) (xy 278.007961 -193.561926)
			(xy 278.059471 -193.522404) (xy 278.1157 -193.489944) (xy 278.175684 -193.465101) (xy 278.238399 -193.4483)
			(xy 278.302769 -193.43983) (xy 278.335232 -193.439288) (xy 278.367232 -193.439776) (xy 278.430704 -193.447984)
			(xy 278.492594 -193.464283) (xy 278.52243 -193.475864) (xy 278.5364 -193.481706) (xy 278.564848 -193.476372)
			(xy 278.65451 -193.393568) (xy 278.66213 -193.365374) (xy 278.657558 -193.35115) (xy 278.645061 -193.310269)
			(xy 278.627126 -193.22668) (xy 278.621744 -193.184272) (xy 278.620474 -193.173604) (xy 278.61006 -193.155316)
			(xy 278.53259 -193.09842) (xy 278.51227 -193.093848) (xy 278.501602 -193.09588) (xy 278.460414 -193.103339)
			(xy 278.377087 -193.111354) (xy 278.335232 -193.111882) (xy 278.292175 -193.111356) (xy 278.206475 -193.102918)
			(xy 278.122014 -193.086121) (xy 278.039607 -193.061127) (xy 277.960047 -193.028175) (xy 277.884099 -192.987584)
			(xy 277.812495 -192.939744) (xy 277.745926 -192.885117) (xy 277.685031 -192.824227) (xy 277.630398 -192.757662)
			(xy 277.582553 -192.686063) (xy 277.561802 -192.648332) (xy 277.557136 -192.640443) (xy 277.543374 -192.628358)
			(xy 277.526253 -192.621851) (xy 277.517098 -192.621408) (xy 272.85823 -192.621408) (xy 272.845722 -192.622051)
			(xy 272.823616 -192.633767) (xy 272.816066 -192.64376) (xy 272.76171 -192.72377) (xy 272.75917 -192.748662)
			(xy 272.763742 -192.7606) (xy 272.778656 -192.799374) (xy 272.801953 -192.87912) (xy 272.817609 -192.960712)
			(xy 272.825483 -193.043418) (xy 272.825972 -193.084958) (xy 272.825715 -193.10731) (xy 273.878563 -193.10731)
			(xy 273.882498 -193.053539) (xy 273.894221 -193.000915) (xy 273.913481 -192.950558) (xy 273.939867 -192.903541)
			(xy 273.972819 -192.860868) (xy 274.011632 -192.823447) (xy 274.05548 -192.792077) (xy 274.103428 -192.767425)
			(xy 274.154455 -192.750017) (xy 274.207473 -192.740224) (xy 274.261352 -192.738255) (xy 274.314943 -192.744152)
			(xy 274.367104 -192.757788) (xy 274.416724 -192.778875) (xy 274.462745 -192.806961) (xy 274.504187 -192.841449)
			(xy 274.540165 -192.881603) (xy 274.569913 -192.926567) (xy 274.592798 -192.975384) (xy 274.60833 -193.027013)
			(xy 274.61618 -193.080353) (xy 274.616672 -193.10731) (xy 274.61618 -193.134267) (xy 274.60833 -193.187607)
			(xy 274.592798 -193.239236) (xy 274.569913 -193.288053) (xy 274.540165 -193.333017) (xy 274.504187 -193.373171)
			(xy 274.462745 -193.407659) (xy 274.416724 -193.435745) (xy 274.367104 -193.456832) (xy 274.314943 -193.470468)
			(xy 274.261352 -193.476365) (xy 274.207473 -193.474396) (xy 274.154455 -193.464603) (xy 274.103428 -193.447195)
			(xy 274.05548 -193.422543) (xy 274.011632 -193.391173) (xy 273.972819 -193.353752) (xy 273.939867 -193.311079)
			(xy 273.913481 -193.264062) (xy 273.894221 -193.213705) (xy 273.882498 -193.161081) (xy 273.878563 -193.10731)
			(xy 272.825715 -193.10731) (xy 272.825502 -193.125778) (xy 272.817909 -193.207066) (xy 272.802793 -193.287295)
			(xy 272.780286 -193.365772) (xy 272.750583 -193.441818) (xy 272.713941 -193.514774) (xy 272.670676 -193.584009)
			(xy 272.621164 -193.648923) (xy 272.565833 -193.708954) (xy 272.505162 -193.763582) (xy 272.439677 -193.812336)
			(xy 272.369944 -193.854792) (xy 272.333466 -193.87312) (xy 272.324859 -193.877818) (xy 272.311765 -193.89239)
			(xy 272.3051 -193.910812) (xy 272.305018 -193.920618) (xy 272.305272 -193.935096) (xy 272.304709 -193.963919)
			(xy 272.299601 -193.99631) (xy 275.667231 -193.99631) (xy 275.671166 -193.942539) (xy 275.682889 -193.889915)
			(xy 275.702149 -193.839558) (xy 275.728535 -193.792541) (xy 275.761487 -193.749868) (xy 275.8003 -193.712447)
			(xy 275.844148 -193.681077) (xy 275.892096 -193.656425) (xy 275.943123 -193.639017) (xy 275.996141 -193.629224)
			(xy 276.05002 -193.627255) (xy 276.103611 -193.633152) (xy 276.155772 -193.646788) (xy 276.205392 -193.667875)
			(xy 276.251413 -193.695961) (xy 276.292855 -193.730449) (xy 276.328833 -193.770603) (xy 276.358581 -193.815567)
			(xy 276.381466 -193.864384) (xy 276.396998 -193.916013) (xy 276.404848 -193.969353) (xy 276.40534 -193.99631)
			(xy 276.404848 -194.023267) (xy 276.396998 -194.076607) (xy 276.381466 -194.128236) (xy 276.358581 -194.177053)
			(xy 276.328833 -194.222017) (xy 276.292855 -194.262171) (xy 276.251413 -194.296659) (xy 276.205392 -194.324745)
			(xy 276.155772 -194.345832) (xy 276.103611 -194.359468) (xy 276.05002 -194.365365) (xy 275.996141 -194.363396)
			(xy 275.943123 -194.353603) (xy 275.892096 -194.336195) (xy 275.844148 -194.311543) (xy 275.8003 -194.280173)
			(xy 275.761487 -194.242752) (xy 275.728535 -194.200079) (xy 275.702149 -194.153062) (xy 275.682889 -194.102705)
			(xy 275.671166 -194.050081) (xy 275.667231 -193.99631) (xy 272.299601 -193.99631) (xy 272.295729 -194.020861)
			(xy 272.278003 -194.075714) (xy 272.251962 -194.127143) (xy 272.21824 -194.173897) (xy 272.177657 -194.214837)
			(xy 272.1312 -194.248967) (xy 272.105882 -194.262756) (xy 272.093182 -194.26936) (xy 272.07845 -194.293744)
			(xy 272.079212 -194.413124) (xy 272.094198 -194.437254) (xy 272.107152 -194.443858) (xy 272.130556 -194.456076)
			(xy 272.174057 -194.485994) (xy 272.213018 -194.521624) (xy 272.246695 -194.562283) (xy 272.274447 -194.607197)
			(xy 272.295742 -194.655508) (xy 272.310174 -194.706293) (xy 272.317468 -194.758582) (xy 272.317972 -194.78498)
			(xy 272.317486 -194.812231) (xy 272.30973 -194.866179) (xy 272.304113 -194.88531) (xy 273.878563 -194.88531)
			(xy 273.882498 -194.831539) (xy 273.894221 -194.778915) (xy 273.913481 -194.728558) (xy 273.939867 -194.681541)
			(xy 273.972819 -194.638868) (xy 274.011632 -194.601447) (xy 274.05548 -194.570077) (xy 274.103428 -194.545425)
			(xy 274.154455 -194.528017) (xy 274.207473 -194.518224) (xy 274.261352 -194.516255) (xy 274.314943 -194.522152)
			(xy 274.367104 -194.535788) (xy 274.416724 -194.556875) (xy 274.462745 -194.584961) (xy 274.504187 -194.619449)
			(xy 274.540165 -194.659603) (xy 274.569913 -194.704567) (xy 274.592798 -194.753384) (xy 274.60833 -194.805013)
			(xy 274.61618 -194.858353) (xy 274.616672 -194.88531) (xy 274.616514 -194.893946) (xy 275.654514 -194.893946)
			(xy 275.658585 -194.838324) (xy 275.670711 -194.783887) (xy 275.690634 -194.731796) (xy 275.71793 -194.683161)
			(xy 275.752016 -194.639018) (xy 275.792165 -194.600309) (xy 275.837523 -194.567858) (xy 275.887123 -194.542357)
			(xy 275.939907 -194.52435) (xy 275.99475 -194.51422) (xy 276.050484 -194.512183) (xy 276.105921 -194.518283)
			(xy 276.159878 -194.532389) (xy 276.211207 -194.554201) (xy 276.258813 -194.583255) (xy 276.301681 -194.61893)
			(xy 276.338898 -194.660467) (xy 276.369671 -194.70698) (xy 276.393343 -194.757477) (xy 276.409411 -194.810884)
			(xy 276.417531 -194.86606) (xy 276.41804 -194.893946) (xy 276.417531 -194.921832) (xy 276.409411 -194.977008)
			(xy 276.393343 -195.030415) (xy 276.369671 -195.080912) (xy 276.338898 -195.127425) (xy 276.301681 -195.168962)
			(xy 276.258813 -195.204637) (xy 276.211207 -195.233691) (xy 276.159878 -195.255503) (xy 276.105921 -195.269609)
			(xy 276.050484 -195.275709) (xy 275.99475 -195.273672) (xy 275.939907 -195.263542) (xy 275.887123 -195.245535)
			(xy 275.837523 -195.220034) (xy 275.792165 -195.187583) (xy 275.752016 -195.148874) (xy 275.71793 -195.104731)
			(xy 275.690634 -195.056096) (xy 275.670711 -195.004005) (xy 275.658585 -194.949568) (xy 275.654514 -194.893946)
			(xy 274.616514 -194.893946) (xy 274.61618 -194.912267) (xy 274.60833 -194.965607) (xy 274.592798 -195.017236)
			(xy 274.569913 -195.066053) (xy 274.540165 -195.111017) (xy 274.504187 -195.151171) (xy 274.462745 -195.185659)
			(xy 274.416724 -195.213745) (xy 274.367104 -195.234832) (xy 274.314943 -195.248468) (xy 274.261352 -195.254365)
			(xy 274.207473 -195.252396) (xy 274.154455 -195.242603) (xy 274.103428 -195.225195) (xy 274.05548 -195.200543)
			(xy 274.011632 -195.169173) (xy 273.972819 -195.131752) (xy 273.939867 -195.089079) (xy 273.913481 -195.042062)
			(xy 273.894221 -194.991705) (xy 273.882498 -194.939081) (xy 273.878563 -194.88531) (xy 272.304113 -194.88531)
			(xy 272.294375 -194.918474) (xy 272.271733 -194.968051) (xy 272.242267 -195.013901) (xy 272.206576 -195.055092)
			(xy 272.165385 -195.090783) (xy 272.119535 -195.120249) (xy 272.069958 -195.142891) (xy 272.017663 -195.158246)
			(xy 271.963715 -195.166002) (xy 271.909213 -195.166002) (xy 271.855265 -195.158246) (xy 271.80297 -195.142891)
			(xy 271.753393 -195.120249) (xy 271.707543 -195.090783) (xy 271.666352 -195.055092) (xy 271.630661 -195.013901)
			(xy 271.601195 -194.968051) (xy 271.578553 -194.918474) (xy 271.563198 -194.866179) (xy 271.555442 -194.812231)
			(xy 271.554956 -194.78498) (xy 271.555399 -194.758577) (xy 271.562676 -194.706276) (xy 271.5771 -194.65548)
			(xy 271.598397 -194.60716) (xy 271.626159 -194.562242) (xy 271.659854 -194.521585) (xy 271.698837 -194.485967)
			(xy 271.742363 -194.45607) (xy 271.765776 -194.443858) (xy 271.77873 -194.437254) (xy 271.793716 -194.413124)
			(xy 271.794478 -194.293744) (xy 271.779746 -194.26936) (xy 271.767046 -194.262756) (xy 271.741693 -194.249025)
			(xy 271.695222 -194.2149) (xy 271.65463 -194.173957) (xy 271.620908 -194.127193) (xy 271.594878 -194.075749)
			(xy 271.577175 -194.02088) (xy 271.56823 -193.963924) (xy 271.567656 -193.935096) (xy 271.568418 -193.909696)
			(xy 271.568648 -193.899874) (xy 271.562573 -193.881208) (xy 271.549959 -193.866168) (xy 271.541494 -193.861182)
			(xy 271.51655 -193.847826) (xy 271.468252 -193.818339) (xy 271.444974 -193.802254) (xy 271.432782 -193.793872)
			(xy 271.403318 -193.792348) (xy 271.297654 -193.8528) (xy 271.283938 -193.879216) (xy 271.285208 -193.893948)
			(xy 271.286986 -193.935096) (xy 271.286525 -193.965834) (xy 271.278931 -194.026839) (xy 271.263859 -194.086438)
			(xy 271.241539 -194.143719) (xy 271.212314 -194.197803) (xy 271.176632 -194.247864) (xy 271.135039 -194.293132)
			(xy 271.088172 -194.332916) (xy 271.062704 -194.350132) (xy 271.052544 -194.356736) (xy 271.040606 -194.376548)
			(xy 271.032732 -194.480942) (xy 271.041368 -194.502532) (xy 271.050258 -194.51066) (xy 271.06917 -194.528209)
			(xy 271.102389 -194.567682) (xy 271.12978 -194.611401) (xy 271.150806 -194.658514) (xy 271.165057 -194.708098)
			(xy 271.172254 -194.759184) (xy 271.172686 -194.78498) (xy 271.17217 -194.81258) (xy 271.163943 -194.867163)
			(xy 271.147673 -194.91991) (xy 271.123723 -194.969643) (xy 271.092628 -195.01525) (xy 271.055083 -195.055714)
			(xy 271.011926 -195.090131) (xy 270.964122 -195.11773) (xy 270.912738 -195.137897) (xy 270.858923 -195.15018)
			(xy 270.803878 -195.154305) (xy 270.748833 -195.15018) (xy 270.695018 -195.137897) (xy 270.643634 -195.11773)
			(xy 270.59583 -195.090131) (xy 270.552673 -195.055714) (xy 270.515128 -195.01525) (xy 270.484033 -194.969643)
			(xy 270.460083 -194.91991) (xy 270.443813 -194.867163) (xy 270.435586 -194.81258) (xy 270.43507 -194.78498)
			(xy 270.435648 -194.755115) (xy 270.445274 -194.696165) (xy 270.46427 -194.639536) (xy 270.492141 -194.586707)
			(xy 270.528159 -194.539058) (xy 270.54937 -194.518026) (xy 270.558006 -194.509644) (xy 270.566134 -194.488054)
			(xy 270.554958 -194.383914) (xy 270.542512 -194.364356) (xy 270.532352 -194.358006) (xy 270.505598 -194.34105)
			(xy 270.456218 -194.301379) (xy 270.412293 -194.255742) (xy 270.374538 -194.204882) (xy 270.343569 -194.149628)
			(xy 270.319889 -194.090879) (xy 270.303886 -194.029592) (xy 270.295819 -193.966767) (xy 270.29537 -193.935096)
			(xy 270.295901 -193.902633) (xy 270.304376 -193.838264) (xy 270.321179 -193.775551) (xy 270.346025 -193.715568)
			(xy 270.378487 -193.659341) (xy 270.41801 -193.607832) (xy 270.463918 -193.561922) (xy 270.515426 -193.522397)
			(xy 270.571652 -193.489933) (xy 270.631634 -193.465085) (xy 270.694346 -193.448279) (xy 270.758715 -193.439802)
			(xy 270.791178 -193.439288) (xy 270.823231 -193.439787) (xy 270.886803 -193.448045) (xy 270.948777 -193.464439)
			(xy 270.97863 -193.476118) (xy 270.992346 -193.481706) (xy 271.021302 -193.476372) (xy 271.11071 -193.393822)
			(xy 271.11833 -193.365374) (xy 271.113758 -193.35115) (xy 271.101261 -193.310269) (xy 271.083326 -193.22668)
			(xy 271.077944 -193.184272) (xy 271.076674 -193.17335) (xy 271.06626 -193.155316) (xy 270.98879 -193.09842)
			(xy 270.968216 -193.093848) (xy 270.957802 -193.09588) (xy 270.916553 -193.103365) (xy 270.833098 -193.111382)
			(xy 270.791178 -193.111882) (xy 270.748119 -193.111375) (xy 270.662415 -193.102941) (xy 270.57795 -193.086147)
			(xy 270.495537 -193.061156) (xy 270.415972 -193.028206) (xy 270.340019 -192.987616) (xy 270.268411 -192.939777)
			(xy 270.201836 -192.885149) (xy 270.140937 -192.824259) (xy 270.0863 -192.757692) (xy 270.03845 -192.686091)
			(xy 270.017748 -192.648332) (xy 270.013085 -192.640438) (xy 269.999324 -192.628341) (xy 269.982202 -192.621819)
			(xy 269.973044 -192.621408) (xy 265.314176 -192.621408) (xy 265.301662 -192.622041) (xy 265.279539 -192.633746)
			(xy 265.272012 -192.64376) (xy 265.217656 -192.72377) (xy 265.215116 -192.748662) (xy 265.219688 -192.7606)
			(xy 265.234603 -192.799373) (xy 265.257901 -192.87912) (xy 265.273558 -192.960712) (xy 265.281433 -193.043418)
			(xy 265.281918 -193.084958) (xy 265.281661 -193.10731) (xy 266.334509 -193.10731) (xy 266.338444 -193.053539)
			(xy 266.350167 -193.000915) (xy 266.369427 -192.950558) (xy 266.395813 -192.903541) (xy 266.428765 -192.860868)
			(xy 266.467578 -192.823447) (xy 266.511426 -192.792077) (xy 266.559374 -192.767425) (xy 266.610401 -192.750017)
			(xy 266.663419 -192.740224) (xy 266.717298 -192.738255) (xy 266.770889 -192.744152) (xy 266.82305 -192.757788)
			(xy 266.87267 -192.778875) (xy 266.918691 -192.806961) (xy 266.960133 -192.841449) (xy 266.996111 -192.881603)
			(xy 267.025859 -192.926567) (xy 267.048744 -192.975384) (xy 267.064276 -193.027013) (xy 267.072126 -193.080353)
			(xy 267.072618 -193.10731) (xy 267.072126 -193.134267) (xy 267.064276 -193.187607) (xy 267.048744 -193.239236)
			(xy 267.025859 -193.288053) (xy 266.996111 -193.333017) (xy 266.960133 -193.373171) (xy 266.918691 -193.407659)
			(xy 266.87267 -193.435745) (xy 266.82305 -193.456832) (xy 266.770889 -193.470468) (xy 266.717298 -193.476365)
			(xy 266.663419 -193.474396) (xy 266.610401 -193.464603) (xy 266.559374 -193.447195) (xy 266.511426 -193.422543)
			(xy 266.467578 -193.391173) (xy 266.428765 -193.353752) (xy 266.395813 -193.311079) (xy 266.369427 -193.264062)
			(xy 266.350167 -193.213705) (xy 266.338444 -193.161081) (xy 266.334509 -193.10731) (xy 265.281661 -193.10731)
			(xy 265.281448 -193.125779) (xy 265.273855 -193.207067) (xy 265.25874 -193.287297) (xy 265.236234 -193.365776)
			(xy 265.206532 -193.441823) (xy 265.16989 -193.51478) (xy 265.126627 -193.584017) (xy 265.077116 -193.648932)
			(xy 265.021787 -193.708966) (xy 264.961117 -193.763597) (xy 264.895633 -193.812354) (xy 264.8259 -193.854813)
			(xy 264.789412 -193.87312) (xy 264.780799 -193.877813) (xy 264.767693 -193.892383) (xy 264.761022 -193.91081)
			(xy 264.760964 -193.920618) (xy 264.761218 -193.935096) (xy 264.760655 -193.96392) (xy 264.755548 -193.99631)
			(xy 268.123177 -193.99631) (xy 268.127112 -193.942539) (xy 268.138835 -193.889915) (xy 268.158095 -193.839558)
			(xy 268.184481 -193.792541) (xy 268.217433 -193.749868) (xy 268.256246 -193.712447) (xy 268.300094 -193.681077)
			(xy 268.348042 -193.656425) (xy 268.399069 -193.639017) (xy 268.452087 -193.629224) (xy 268.505966 -193.627255)
			(xy 268.559557 -193.633152) (xy 268.611718 -193.646788) (xy 268.661338 -193.667875) (xy 268.707359 -193.695961)
			(xy 268.748801 -193.730449) (xy 268.784779 -193.770603) (xy 268.814527 -193.815567) (xy 268.837412 -193.864384)
			(xy 268.852944 -193.916013) (xy 268.860794 -193.969353) (xy 268.861286 -193.99631) (xy 268.860794 -194.023267)
			(xy 268.852944 -194.076607) (xy 268.837412 -194.128236) (xy 268.814527 -194.177053) (xy 268.784779 -194.222017)
			(xy 268.748801 -194.262171) (xy 268.707359 -194.296659) (xy 268.661338 -194.324745) (xy 268.611718 -194.345832)
			(xy 268.559557 -194.359468) (xy 268.505966 -194.365365) (xy 268.452087 -194.363396) (xy 268.399069 -194.353603)
			(xy 268.348042 -194.336195) (xy 268.300094 -194.311543) (xy 268.256246 -194.280173) (xy 268.217433 -194.242752)
			(xy 268.184481 -194.200079) (xy 268.158095 -194.153062) (xy 268.138835 -194.102705) (xy 268.127112 -194.050081)
			(xy 268.123177 -193.99631) (xy 264.755548 -193.99631) (xy 264.751676 -194.020864) (xy 264.733951 -194.075718)
			(xy 264.707912 -194.12715) (xy 264.674192 -194.173906) (xy 264.633611 -194.214851) (xy 264.587157 -194.248986)
			(xy 264.561828 -194.262756) (xy 264.549128 -194.26936) (xy 264.534396 -194.293744) (xy 264.535158 -194.413124)
			(xy 264.550144 -194.437254) (xy 264.563098 -194.443858) (xy 264.586505 -194.456074) (xy 264.630011 -194.485989)
			(xy 264.668977 -194.521616) (xy 264.70266 -194.562275) (xy 264.730415 -194.60719) (xy 264.751714 -194.655502)
			(xy 264.766149 -194.706289) (xy 264.773444 -194.758581) (xy 264.773918 -194.78498) (xy 264.773432 -194.812231)
			(xy 264.765676 -194.866179) (xy 264.760059 -194.88531) (xy 266.334509 -194.88531) (xy 266.338444 -194.831539)
			(xy 266.350167 -194.778915) (xy 266.369427 -194.728558) (xy 266.395813 -194.681541) (xy 266.428765 -194.638868)
			(xy 266.467578 -194.601447) (xy 266.511426 -194.570077) (xy 266.559374 -194.545425) (xy 266.610401 -194.528017)
			(xy 266.663419 -194.518224) (xy 266.717298 -194.516255) (xy 266.770889 -194.522152) (xy 266.82305 -194.535788)
			(xy 266.87267 -194.556875) (xy 266.918691 -194.584961) (xy 266.960133 -194.619449) (xy 266.996111 -194.659603)
			(xy 267.025859 -194.704567) (xy 267.048744 -194.753384) (xy 267.064276 -194.805013) (xy 267.072126 -194.858353)
			(xy 267.072618 -194.88531) (xy 267.07246 -194.893946) (xy 268.11046 -194.893946) (xy 268.114531 -194.838324)
			(xy 268.126657 -194.783887) (xy 268.14658 -194.731796) (xy 268.173876 -194.683161) (xy 268.207962 -194.639018)
			(xy 268.248111 -194.600309) (xy 268.293469 -194.567858) (xy 268.343069 -194.542357) (xy 268.395853 -194.52435)
			(xy 268.450696 -194.51422) (xy 268.50643 -194.512183) (xy 268.561867 -194.518283) (xy 268.615824 -194.532389)
			(xy 268.667153 -194.554201) (xy 268.714759 -194.583255) (xy 268.757627 -194.61893) (xy 268.794844 -194.660467)
			(xy 268.825617 -194.70698) (xy 268.849289 -194.757477) (xy 268.865357 -194.810884) (xy 268.873477 -194.86606)
			(xy 268.873986 -194.893946) (xy 268.873477 -194.921832) (xy 268.865357 -194.977008) (xy 268.849289 -195.030415)
			(xy 268.825617 -195.080912) (xy 268.794844 -195.127425) (xy 268.757627 -195.168962) (xy 268.714759 -195.204637)
			(xy 268.667153 -195.233691) (xy 268.615824 -195.255503) (xy 268.561867 -195.269609) (xy 268.50643 -195.275709)
			(xy 268.450696 -195.273672) (xy 268.395853 -195.263542) (xy 268.343069 -195.245535) (xy 268.293469 -195.220034)
			(xy 268.248111 -195.187583) (xy 268.207962 -195.148874) (xy 268.173876 -195.104731) (xy 268.14658 -195.056096)
			(xy 268.126657 -195.004005) (xy 268.114531 -194.949568) (xy 268.11046 -194.893946) (xy 267.07246 -194.893946)
			(xy 267.072126 -194.912267) (xy 267.064276 -194.965607) (xy 267.048744 -195.017236) (xy 267.025859 -195.066053)
			(xy 266.996111 -195.111017) (xy 266.960133 -195.151171) (xy 266.918691 -195.185659) (xy 266.87267 -195.213745)
			(xy 266.82305 -195.234832) (xy 266.770889 -195.248468) (xy 266.717298 -195.254365) (xy 266.663419 -195.252396)
			(xy 266.610401 -195.242603) (xy 266.559374 -195.225195) (xy 266.511426 -195.200543) (xy 266.467578 -195.169173)
			(xy 266.428765 -195.131752) (xy 266.395813 -195.089079) (xy 266.369427 -195.042062) (xy 266.350167 -194.991705)
			(xy 266.338444 -194.939081) (xy 266.334509 -194.88531) (xy 264.760059 -194.88531) (xy 264.750321 -194.918474)
			(xy 264.727679 -194.968051) (xy 264.698213 -195.013901) (xy 264.662522 -195.055092) (xy 264.621331 -195.090783)
			(xy 264.575481 -195.120249) (xy 264.525904 -195.142891) (xy 264.473609 -195.158246) (xy 264.419661 -195.166002)
			(xy 264.365159 -195.166002) (xy 264.311211 -195.158246) (xy 264.258916 -195.142891) (xy 264.209339 -195.120249)
			(xy 264.163489 -195.090783) (xy 264.122298 -195.055092) (xy 264.086607 -195.013901) (xy 264.057141 -194.968051)
			(xy 264.034499 -194.918474) (xy 264.019144 -194.866179) (xy 264.011388 -194.812231) (xy 264.010902 -194.78498)
			(xy 264.011345 -194.758577) (xy 264.018621 -194.706274) (xy 264.033044 -194.655476) (xy 264.05434 -194.607154)
			(xy 264.082099 -194.562233) (xy 264.115792 -194.521572) (xy 264.154773 -194.485949) (xy 264.198296 -194.456046)
			(xy 264.221722 -194.443858) (xy 264.234676 -194.437254) (xy 264.249662 -194.413124) (xy 264.250424 -194.293744)
			(xy 264.235692 -194.26936) (xy 264.222992 -194.262756) (xy 264.197642 -194.249022) (xy 264.151177 -194.214894)
			(xy 264.110591 -194.173949) (xy 264.076875 -194.127185) (xy 264.050849 -194.075743) (xy 264.033148 -194.020876)
			(xy 264.024205 -193.963922) (xy 264.023602 -193.935096) (xy 264.024364 -193.909696) (xy 264.024594 -193.899876)
			(xy 264.018514 -193.881215) (xy 264.005894 -193.866185) (xy 263.99744 -193.861182) (xy 263.959315 -193.840565)
			(xy 263.886928 -193.792888) (xy 263.819598 -193.738302) (xy 263.757982 -193.677339) (xy 263.70268 -193.610595)
			(xy 263.654234 -193.538721) (xy 263.613114 -193.462417) (xy 263.579724 -193.382429) (xy 263.554387 -193.299537)
			(xy 263.537353 -193.21455) (xy 263.528786 -193.128297) (xy 263.528302 -193.084958) (xy 263.528788 -193.043417)
			(xy 263.536647 -192.960709) (xy 263.552302 -192.879116) (xy 263.575611 -192.799371) (xy 263.590532 -192.7606)
			(xy 263.595104 -192.748662) (xy 263.592564 -192.72377) (xy 263.538208 -192.64376) (xy 263.530683 -192.633734)
			(xy 263.508565 -192.621995) (xy 263.496044 -192.621408) (xy 262.108188 -192.621408) (xy 262.098119 -192.621834)
			(xy 262.079518 -192.629552) (xy 262.07212 -192.636394) (xy 260.871716 -193.836798) (xy 260.86503 -193.844207)
			(xy 260.857444 -193.862643) (xy 260.856984 -193.872612) (xy 260.856984 -194.492626) (xy 260.856448 -194.521542)
			(xy 260.847717 -194.57871) (xy 260.83046 -194.633907) (xy 260.805071 -194.685867) (xy 260.772132 -194.733401)
			(xy 260.732398 -194.775421) (xy 260.709918 -194.793616) (xy 260.70052 -194.800982) (xy 260.69036 -194.82181)
			(xy 260.69036 -194.925696) (xy 260.70052 -194.946524) (xy 260.709918 -194.95389) (xy 260.732359 -194.972082)
			(xy 260.772017 -195.014085) (xy 260.804891 -195.061586) (xy 260.83023 -195.113499) (xy 260.847455 -195.168637)
			(xy 260.856173 -195.225743) (xy 260.85673 -195.254626) (xy 260.856244 -195.281877) (xy 260.848488 -195.335825)
			(xy 260.833133 -195.38812) (xy 260.810491 -195.437697) (xy 260.781025 -195.483547) (xy 260.745334 -195.524738)
			(xy 260.704143 -195.560429) (xy 260.658293 -195.589895) (xy 260.608716 -195.612537) (xy 260.556421 -195.627892)
			(xy 260.502473 -195.635648) (xy 260.447971 -195.635648) (xy 260.394023 -195.627892) (xy 260.341728 -195.612537)
			(xy 260.292151 -195.589895) (xy 260.246301 -195.560429) (xy 260.20511 -195.524738) (xy 260.169419 -195.483547)
			(xy 260.139953 -195.437697) (xy 260.117311 -195.38812) (xy 260.101956 -195.335825) (xy 260.0942 -195.281877)
			(xy 260.093714 -195.254626) (xy 260.094245 -195.22574) (xy 260.102954 -195.168629) (xy 260.120177 -195.113485)
			(xy 260.145521 -195.061569) (xy 260.178404 -195.01407) (xy 260.218075 -194.972073) (xy 260.240526 -194.95389)
			(xy 260.249924 -194.946524) (xy 260.260084 -194.925696) (xy 260.260084 -194.82181) (xy 260.249924 -194.800982)
			(xy 260.240526 -194.793616) (xy 260.218777 -194.775968) (xy 260.180139 -194.735421) (xy 260.163564 -194.712844)
			(xy 260.15696 -194.7037) (xy 260.13791 -194.692524) (xy 260.04901 -194.684904) (xy 260.03792 -194.684571)
			(xy 260.017109 -194.692197) (xy 260.008878 -194.699636) (xy 258.218686 -196.489828) (xy 262.672322 -196.489828)
			(xy 262.672939 -196.460584) (xy 262.68187 -196.402781) (xy 262.699512 -196.347016) (xy 262.725453 -196.294594)
			(xy 262.759084 -196.246742) (xy 262.79962 -196.204579) (xy 262.846113 -196.16909) (xy 262.897473 -196.141108)
			(xy 262.924798 -196.130672) (xy 262.93799 -196.125447) (xy 262.961056 -196.108948) (xy 262.978684 -196.086733)
			(xy 262.989509 -196.06052) (xy 262.992692 -196.032339) (xy 262.987987 -196.004372) (xy 262.975759 -195.978784)
			(xy 262.966708 -195.967858) (xy 262.948749 -195.946842) (xy 262.918476 -195.900588) (xy 262.8952 -195.850447)
			(xy 262.87941 -195.79747) (xy 262.871437 -195.742768) (xy 262.87095 -195.715128) (xy 262.871436 -195.687877)
			(xy 262.879192 -195.633929) (xy 262.894547 -195.581634) (xy 262.917189 -195.532057) (xy 262.946655 -195.486207)
			(xy 262.982346 -195.445016) (xy 263.023537 -195.409325) (xy 263.069387 -195.379859) (xy 263.118964 -195.357217)
			(xy 263.171259 -195.341862) (xy 263.225207 -195.334106) (xy 263.279709 -195.334106) (xy 263.333657 -195.341862)
			(xy 263.385952 -195.357217) (xy 263.435529 -195.379859) (xy 263.481379 -195.409325) (xy 263.52257 -195.445016)
			(xy 263.558261 -195.486207) (xy 263.587727 -195.532057) (xy 263.610369 -195.581634) (xy 263.625724 -195.633929)
			(xy 263.63348 -195.687877) (xy 263.633966 -195.715128) (xy 263.633405 -195.744374) (xy 263.624465 -195.80218)
			(xy 263.606815 -195.857947) (xy 263.606221 -195.859146) (xy 268.11046 -195.859146) (xy 268.114531 -195.803524)
			(xy 268.126657 -195.749087) (xy 268.14658 -195.696996) (xy 268.173876 -195.648361) (xy 268.207962 -195.604218)
			(xy 268.248111 -195.565509) (xy 268.293469 -195.533058) (xy 268.343069 -195.507557) (xy 268.395853 -195.48955)
			(xy 268.450696 -195.47942) (xy 268.50643 -195.477383) (xy 268.561867 -195.483483) (xy 268.615824 -195.497589)
			(xy 268.667153 -195.519401) (xy 268.714759 -195.548455) (xy 268.757627 -195.58413) (xy 268.794844 -195.625667)
			(xy 268.801097 -195.635118) (xy 270.434577 -195.635118) (xy 270.438512 -195.581347) (xy 270.450235 -195.528723)
			(xy 270.469495 -195.478366) (xy 270.495881 -195.431349) (xy 270.528833 -195.388676) (xy 270.567646 -195.351255)
			(xy 270.611494 -195.319885) (xy 270.659442 -195.295233) (xy 270.710469 -195.277825) (xy 270.763487 -195.268032)
			(xy 270.817366 -195.266063) (xy 270.870957 -195.27196) (xy 270.923118 -195.285596) (xy 270.972738 -195.306683)
			(xy 271.018759 -195.334769) (xy 271.060201 -195.369257) (xy 271.096179 -195.409411) (xy 271.125927 -195.454375)
			(xy 271.148812 -195.503192) (xy 271.164344 -195.554821) (xy 271.172194 -195.608161) (xy 271.172686 -195.635118)
			(xy 271.172194 -195.662075) (xy 271.164344 -195.715415) (xy 271.148812 -195.767044) (xy 271.125927 -195.815861)
			(xy 271.09729 -195.859146) (xy 275.654514 -195.859146) (xy 275.658585 -195.803524) (xy 275.670711 -195.749087)
			(xy 275.690634 -195.696996) (xy 275.71793 -195.648361) (xy 275.752016 -195.604218) (xy 275.792165 -195.565509)
			(xy 275.837523 -195.533058) (xy 275.887123 -195.507557) (xy 275.939907 -195.48955) (xy 275.99475 -195.47942)
			(xy 276.050484 -195.477383) (xy 276.105921 -195.483483) (xy 276.159878 -195.497589) (xy 276.211207 -195.519401)
			(xy 276.258813 -195.548455) (xy 276.301681 -195.58413) (xy 276.338898 -195.625667) (xy 276.345151 -195.635118)
			(xy 277.978631 -195.635118) (xy 277.982566 -195.581347) (xy 277.994289 -195.528723) (xy 278.013549 -195.478366)
			(xy 278.039935 -195.431349) (xy 278.072887 -195.388676) (xy 278.1117 -195.351255) (xy 278.155548 -195.319885)
			(xy 278.203496 -195.295233) (xy 278.254523 -195.277825) (xy 278.307541 -195.268032) (xy 278.36142 -195.266063)
			(xy 278.415011 -195.27196) (xy 278.467172 -195.285596) (xy 278.516792 -195.306683) (xy 278.562813 -195.334769)
			(xy 278.604255 -195.369257) (xy 278.640233 -195.409411) (xy 278.669981 -195.454375) (xy 278.692866 -195.503192)
			(xy 278.708398 -195.554821) (xy 278.716248 -195.608161) (xy 278.71674 -195.635118) (xy 278.716248 -195.662075)
			(xy 278.708398 -195.715415) (xy 278.692866 -195.767044) (xy 278.669981 -195.815861) (xy 278.641344 -195.859146)
			(xy 283.198568 -195.859146) (xy 283.202639 -195.803524) (xy 283.214765 -195.749087) (xy 283.234688 -195.696996)
			(xy 283.261984 -195.648361) (xy 283.29607 -195.604218) (xy 283.336219 -195.565509) (xy 283.381577 -195.533058)
			(xy 283.431177 -195.507557) (xy 283.483961 -195.48955) (xy 283.538804 -195.47942) (xy 283.594538 -195.477383)
			(xy 283.649975 -195.483483) (xy 283.703932 -195.497589) (xy 283.755261 -195.519401) (xy 283.802867 -195.548455)
			(xy 283.845735 -195.58413) (xy 283.882952 -195.625667) (xy 283.889205 -195.635118) (xy 285.522431 -195.635118)
			(xy 285.526366 -195.581347) (xy 285.538089 -195.528723) (xy 285.557349 -195.478366) (xy 285.583735 -195.431349)
			(xy 285.616687 -195.388676) (xy 285.6555 -195.351255) (xy 285.699348 -195.319885) (xy 285.747296 -195.295233)
			(xy 285.798323 -195.277825) (xy 285.851341 -195.268032) (xy 285.90522 -195.266063) (xy 285.958811 -195.27196)
			(xy 286.010972 -195.285596) (xy 286.060592 -195.306683) (xy 286.106613 -195.334769) (xy 286.148055 -195.369257)
			(xy 286.184033 -195.409411) (xy 286.213781 -195.454375) (xy 286.236666 -195.503192) (xy 286.252198 -195.554821)
			(xy 286.260048 -195.608161) (xy 286.26054 -195.635118) (xy 286.260048 -195.662075) (xy 286.252198 -195.715415)
			(xy 286.236666 -195.767044) (xy 286.213781 -195.815861) (xy 286.185144 -195.859146) (xy 290.742622 -195.859146)
			(xy 290.746693 -195.803524) (xy 290.758819 -195.749087) (xy 290.778742 -195.696996) (xy 290.806038 -195.648361)
			(xy 290.840124 -195.604218) (xy 290.880273 -195.565509) (xy 290.925631 -195.533058) (xy 290.975231 -195.507557)
			(xy 291.028015 -195.48955) (xy 291.082858 -195.47942) (xy 291.138592 -195.477383) (xy 291.194029 -195.483483)
			(xy 291.247986 -195.497589) (xy 291.299315 -195.519401) (xy 291.346921 -195.548455) (xy 291.389789 -195.58413)
			(xy 291.427006 -195.625667) (xy 291.433259 -195.635118) (xy 293.066485 -195.635118) (xy 293.07042 -195.581347)
			(xy 293.082143 -195.528723) (xy 293.101403 -195.478366) (xy 293.127789 -195.431349) (xy 293.160741 -195.388676)
			(xy 293.199554 -195.351255) (xy 293.243402 -195.319885) (xy 293.29135 -195.295233) (xy 293.342377 -195.277825)
			(xy 293.395395 -195.268032) (xy 293.449274 -195.266063) (xy 293.502865 -195.27196) (xy 293.555026 -195.285596)
			(xy 293.604646 -195.306683) (xy 293.650667 -195.334769) (xy 293.692109 -195.369257) (xy 293.728087 -195.409411)
			(xy 293.757835 -195.454375) (xy 293.78072 -195.503192) (xy 293.796252 -195.554821) (xy 293.804102 -195.608161)
			(xy 293.804594 -195.635118) (xy 293.804102 -195.662075) (xy 293.796252 -195.715415) (xy 293.78072 -195.767044)
			(xy 293.757835 -195.815861) (xy 293.729198 -195.859146) (xy 298.286422 -195.859146) (xy 298.290493 -195.803524)
			(xy 298.302619 -195.749087) (xy 298.322542 -195.696996) (xy 298.349838 -195.648361) (xy 298.383924 -195.604218)
			(xy 298.424073 -195.565509) (xy 298.469431 -195.533058) (xy 298.519031 -195.507557) (xy 298.571815 -195.48955)
			(xy 298.626658 -195.47942) (xy 298.682392 -195.477383) (xy 298.737829 -195.483483) (xy 298.791786 -195.497589)
			(xy 298.843115 -195.519401) (xy 298.890721 -195.548455) (xy 298.933589 -195.58413) (xy 298.970806 -195.625667)
			(xy 299.001579 -195.67218) (xy 299.025251 -195.722677) (xy 299.041319 -195.776084) (xy 299.049439 -195.83126)
			(xy 299.049948 -195.859146) (xy 299.049439 -195.887032) (xy 299.041319 -195.942208) (xy 299.025251 -195.995615)
			(xy 299.001579 -196.046112) (xy 298.970806 -196.092625) (xy 298.933589 -196.134162) (xy 298.890721 -196.169837)
			(xy 298.843115 -196.198891) (xy 298.791786 -196.220703) (xy 298.737829 -196.234809) (xy 298.682392 -196.240909)
			(xy 298.626658 -196.238872) (xy 298.571815 -196.228742) (xy 298.519031 -196.210735) (xy 298.469431 -196.185234)
			(xy 298.424073 -196.152783) (xy 298.383924 -196.114074) (xy 298.349838 -196.069931) (xy 298.322542 -196.021296)
			(xy 298.302619 -195.969205) (xy 298.290493 -195.914768) (xy 298.286422 -195.859146) (xy 293.729198 -195.859146)
			(xy 293.728087 -195.860825) (xy 293.692109 -195.900979) (xy 293.650667 -195.935467) (xy 293.604646 -195.963553)
			(xy 293.555026 -195.98464) (xy 293.502865 -195.998276) (xy 293.449274 -196.004173) (xy 293.395395 -196.002204)
			(xy 293.342377 -195.992411) (xy 293.29135 -195.975003) (xy 293.243402 -195.950351) (xy 293.199554 -195.918981)
			(xy 293.160741 -195.88156) (xy 293.127789 -195.838887) (xy 293.101403 -195.79187) (xy 293.082143 -195.741513)
			(xy 293.07042 -195.688889) (xy 293.066485 -195.635118) (xy 291.433259 -195.635118) (xy 291.457779 -195.67218)
			(xy 291.481451 -195.722677) (xy 291.497519 -195.776084) (xy 291.505639 -195.83126) (xy 291.506148 -195.859146)
			(xy 291.505639 -195.887032) (xy 291.497519 -195.942208) (xy 291.481451 -195.995615) (xy 291.457779 -196.046112)
			(xy 291.427006 -196.092625) (xy 291.389789 -196.134162) (xy 291.346921 -196.169837) (xy 291.299315 -196.198891)
			(xy 291.247986 -196.220703) (xy 291.194029 -196.234809) (xy 291.138592 -196.240909) (xy 291.082858 -196.238872)
			(xy 291.028015 -196.228742) (xy 290.975231 -196.210735) (xy 290.925631 -196.185234) (xy 290.880273 -196.152783)
			(xy 290.840124 -196.114074) (xy 290.806038 -196.069931) (xy 290.778742 -196.021296) (xy 290.758819 -195.969205)
			(xy 290.746693 -195.914768) (xy 290.742622 -195.859146) (xy 286.185144 -195.859146) (xy 286.184033 -195.860825)
			(xy 286.148055 -195.900979) (xy 286.106613 -195.935467) (xy 286.060592 -195.963553) (xy 286.010972 -195.98464)
			(xy 285.958811 -195.998276) (xy 285.90522 -196.004173) (xy 285.851341 -196.002204) (xy 285.798323 -195.992411)
			(xy 285.747296 -195.975003) (xy 285.699348 -195.950351) (xy 285.6555 -195.918981) (xy 285.616687 -195.88156)
			(xy 285.583735 -195.838887) (xy 285.557349 -195.79187) (xy 285.538089 -195.741513) (xy 285.526366 -195.688889)
			(xy 285.522431 -195.635118) (xy 283.889205 -195.635118) (xy 283.913725 -195.67218) (xy 283.937397 -195.722677)
			(xy 283.953465 -195.776084) (xy 283.961585 -195.83126) (xy 283.962094 -195.859146) (xy 283.961585 -195.887032)
			(xy 283.953465 -195.942208) (xy 283.937397 -195.995615) (xy 283.913725 -196.046112) (xy 283.882952 -196.092625)
			(xy 283.845735 -196.134162) (xy 283.802867 -196.169837) (xy 283.755261 -196.198891) (xy 283.703932 -196.220703)
			(xy 283.649975 -196.234809) (xy 283.594538 -196.240909) (xy 283.538804 -196.238872) (xy 283.483961 -196.228742)
			(xy 283.431177 -196.210735) (xy 283.381577 -196.185234) (xy 283.336219 -196.152783) (xy 283.29607 -196.114074)
			(xy 283.261984 -196.069931) (xy 283.234688 -196.021296) (xy 283.214765 -195.969205) (xy 283.202639 -195.914768)
			(xy 283.198568 -195.859146) (xy 278.641344 -195.859146) (xy 278.640233 -195.860825) (xy 278.604255 -195.900979)
			(xy 278.562813 -195.935467) (xy 278.516792 -195.963553) (xy 278.467172 -195.98464) (xy 278.415011 -195.998276)
			(xy 278.36142 -196.004173) (xy 278.307541 -196.002204) (xy 278.254523 -195.992411) (xy 278.203496 -195.975003)
			(xy 278.155548 -195.950351) (xy 278.1117 -195.918981) (xy 278.072887 -195.88156) (xy 278.039935 -195.838887)
			(xy 278.013549 -195.79187) (xy 277.994289 -195.741513) (xy 277.982566 -195.688889) (xy 277.978631 -195.635118)
			(xy 276.345151 -195.635118) (xy 276.369671 -195.67218) (xy 276.393343 -195.722677) (xy 276.409411 -195.776084)
			(xy 276.417531 -195.83126) (xy 276.41804 -195.859146) (xy 276.417531 -195.887032) (xy 276.409411 -195.942208)
			(xy 276.393343 -195.995615) (xy 276.369671 -196.046112) (xy 276.338898 -196.092625) (xy 276.301681 -196.134162)
			(xy 276.258813 -196.169837) (xy 276.211207 -196.198891) (xy 276.159878 -196.220703) (xy 276.105921 -196.234809)
			(xy 276.050484 -196.240909) (xy 275.99475 -196.238872) (xy 275.939907 -196.228742) (xy 275.887123 -196.210735)
			(xy 275.837523 -196.185234) (xy 275.792165 -196.152783) (xy 275.752016 -196.114074) (xy 275.71793 -196.069931)
			(xy 275.690634 -196.021296) (xy 275.670711 -195.969205) (xy 275.658585 -195.914768) (xy 275.654514 -195.859146)
			(xy 271.09729 -195.859146) (xy 271.096179 -195.860825) (xy 271.060201 -195.900979) (xy 271.018759 -195.935467)
			(xy 270.972738 -195.963553) (xy 270.923118 -195.98464) (xy 270.870957 -195.998276) (xy 270.817366 -196.004173)
			(xy 270.763487 -196.002204) (xy 270.710469 -195.992411) (xy 270.659442 -195.975003) (xy 270.611494 -195.950351)
			(xy 270.567646 -195.918981) (xy 270.528833 -195.88156) (xy 270.495881 -195.838887) (xy 270.469495 -195.79187)
			(xy 270.450235 -195.741513) (xy 270.438512 -195.688889) (xy 270.434577 -195.635118) (xy 268.801097 -195.635118)
			(xy 268.825617 -195.67218) (xy 268.849289 -195.722677) (xy 268.865357 -195.776084) (xy 268.873477 -195.83126)
			(xy 268.873986 -195.859146) (xy 268.873477 -195.887032) (xy 268.865357 -195.942208) (xy 268.849289 -195.995615)
			(xy 268.825617 -196.046112) (xy 268.794844 -196.092625) (xy 268.757627 -196.134162) (xy 268.714759 -196.169837)
			(xy 268.667153 -196.198891) (xy 268.615824 -196.220703) (xy 268.561867 -196.234809) (xy 268.50643 -196.240909)
			(xy 268.450696 -196.238872) (xy 268.395853 -196.228742) (xy 268.343069 -196.210735) (xy 268.293469 -196.185234)
			(xy 268.248111 -196.152783) (xy 268.207962 -196.114074) (xy 268.173876 -196.069931) (xy 268.14658 -196.021296)
			(xy 268.126657 -195.969205) (xy 268.114531 -195.914768) (xy 268.11046 -195.859146) (xy 263.606221 -195.859146)
			(xy 263.580866 -195.910369) (xy 263.547227 -195.958221) (xy 263.506683 -196.000383) (xy 263.460184 -196.035869)
			(xy 263.408817 -196.063849) (xy 263.38149 -196.074284) (xy 263.368262 -196.079426) (xy 263.345189 -196.09594)
			(xy 263.32756 -196.118171) (xy 263.316739 -196.1444) (xy 263.313563 -196.172595) (xy 263.318279 -196.200574)
			(xy 263.330521 -196.22617) (xy 263.33958 -196.237098) (xy 263.357517 -196.258132) (xy 263.387793 -196.304381)
			(xy 263.411074 -196.354517) (xy 263.426869 -196.40749) (xy 263.434848 -196.462189) (xy 263.435338 -196.489828)
			(xy 263.434852 -196.517079) (xy 263.427096 -196.571027) (xy 263.411741 -196.623322) (xy 263.389099 -196.672899)
			(xy 263.359633 -196.718749) (xy 263.323942 -196.75994) (xy 263.282751 -196.795631) (xy 263.236901 -196.825097)
			(xy 263.20462 -196.83984) (xy 263.4902 -196.83984) (xy 263.494271 -196.784218) (xy 263.506397 -196.729781)
			(xy 263.52632 -196.67769) (xy 263.553616 -196.629055) (xy 263.587702 -196.584912) (xy 263.627851 -196.546203)
			(xy 263.673209 -196.513752) (xy 263.722809 -196.488251) (xy 263.775593 -196.470244) (xy 263.830436 -196.460114)
			(xy 263.88617 -196.458077) (xy 263.941607 -196.464177) (xy 263.995564 -196.478283) (xy 264.046893 -196.500095)
			(xy 264.094499 -196.529149) (xy 264.137367 -196.564824) (xy 264.174584 -196.606361) (xy 264.205357 -196.652874)
			(xy 264.229029 -196.703371) (xy 264.245097 -196.756778) (xy 264.253217 -196.811954) (xy 264.253726 -196.83984)
			(xy 264.253217 -196.867726) (xy 264.245097 -196.922902) (xy 264.229029 -196.976309) (xy 264.205357 -197.026806)
			(xy 264.174584 -197.073319) (xy 264.137367 -197.114856) (xy 264.094499 -197.150531) (xy 264.046893 -197.179585)
			(xy 263.995564 -197.201397) (xy 263.941607 -197.215503) (xy 263.88617 -197.221603) (xy 263.830436 -197.219566)
			(xy 263.775593 -197.209436) (xy 263.722809 -197.191429) (xy 263.673209 -197.165928) (xy 263.627851 -197.133477)
			(xy 263.587702 -197.094768) (xy 263.553616 -197.050625) (xy 263.52632 -197.00199) (xy 263.506397 -196.949899)
			(xy 263.494271 -196.895462) (xy 263.4902 -196.83984) (xy 263.20462 -196.83984) (xy 263.187324 -196.847739)
			(xy 263.135029 -196.863094) (xy 263.081081 -196.87085) (xy 263.026579 -196.87085) (xy 262.972631 -196.863094)
			(xy 262.920336 -196.847739) (xy 262.870759 -196.825097) (xy 262.824909 -196.795631) (xy 262.783718 -196.75994)
			(xy 262.748027 -196.718749) (xy 262.718561 -196.672899) (xy 262.695919 -196.623322) (xy 262.680564 -196.571027)
			(xy 262.672808 -196.517079) (xy 262.672322 -196.489828) (xy 258.218686 -196.489828) (xy 257.569208 -197.139306)
			(xy 257.562362 -197.146705) (xy 257.554628 -197.165303) (xy 257.554222 -197.175374) (xy 257.554222 -197.33514)
			(xy 265.178809 -197.33514) (xy 265.182744 -197.281369) (xy 265.194467 -197.228745) (xy 265.213727 -197.178388)
			(xy 265.240113 -197.131371) (xy 265.273065 -197.088698) (xy 265.311878 -197.051277) (xy 265.355726 -197.019907)
			(xy 265.403674 -196.995255) (xy 265.454701 -196.977847) (xy 265.507719 -196.968054) (xy 265.561598 -196.966085)
			(xy 265.615189 -196.971982) (xy 265.66735 -196.985618) (xy 265.71697 -197.006705) (xy 265.762991 -197.034791)
			(xy 265.804433 -197.069279) (xy 265.840411 -197.109433) (xy 265.870159 -197.154397) (xy 265.893044 -197.203214)
			(xy 265.908576 -197.254843) (xy 265.916426 -197.308183) (xy 265.916918 -197.33514) (xy 265.916426 -197.362097)
			(xy 265.908576 -197.415437) (xy 265.893044 -197.467066) (xy 265.870159 -197.515883) (xy 265.840411 -197.560847)
			(xy 265.804433 -197.601001) (xy 265.762991 -197.635489) (xy 265.71697 -197.663575) (xy 265.66735 -197.684662)
			(xy 265.615189 -197.698298) (xy 265.561598 -197.704195) (xy 265.507719 -197.702226) (xy 265.454701 -197.692433)
			(xy 265.403674 -197.675025) (xy 265.355726 -197.650373) (xy 265.311878 -197.619003) (xy 265.273065 -197.581582)
			(xy 265.240113 -197.538909) (xy 265.213727 -197.491892) (xy 265.194467 -197.441535) (xy 265.182744 -197.388911)
			(xy 265.178809 -197.33514) (xy 257.554222 -197.33514) (xy 257.554222 -213.882986) (xy 257.553715 -213.893036)
			(xy 257.545992 -213.911595) (xy 257.539236 -213.919054) (xy 256.646934 -214.811356) (xy 256.639534 -214.818197)
			(xy 256.620935 -214.825914) (xy 256.610866 -214.826342) (xy 236.138466 -214.826342) (xy 236.1284 -214.826773)
			(xy 236.109808 -214.8345) (xy 236.102398 -214.841328) (xy 234.979972 -215.963754) (xy 234.973126 -215.971152)
			(xy 234.9654 -215.989751) (xy 234.964986 -215.999822) (xy 234.964986 -217.130587) (xy 244.220994 -217.130587)
			(xy 244.220994 -217.066665) (xy 244.229005 -217.003247) (xy 244.244902 -216.941333) (xy 244.268434 -216.8819)
			(xy 244.299228 -216.825885) (xy 244.336801 -216.77417) (xy 244.380558 -216.727573) (xy 244.429811 -216.686828)
			(xy 244.483782 -216.652577) (xy 244.541621 -216.62536) (xy 244.602414 -216.605607) (xy 244.665204 -216.593629)
			(xy 244.729 -216.589616) (xy 244.792796 -216.593629) (xy 244.855586 -216.605607) (xy 244.916379 -216.62536)
			(xy 244.974218 -216.652577) (xy 245.028189 -216.686828) (xy 245.077442 -216.727573) (xy 245.121199 -216.77417)
			(xy 245.158772 -216.825885) (xy 245.189566 -216.8819) (xy 245.213098 -216.941333) (xy 245.228995 -217.003247)
			(xy 245.237006 -217.066665) (xy 245.237508 -217.098626) (xy 245.237006 -217.130587) (xy 245.228995 -217.194005)
			(xy 245.213098 -217.255919) (xy 245.189566 -217.315352) (xy 245.158772 -217.371367) (xy 245.121199 -217.423082)
			(xy 245.077442 -217.469679) (xy 245.028189 -217.510424) (xy 244.974218 -217.544675) (xy 244.916379 -217.571892)
			(xy 244.855586 -217.591645) (xy 244.792796 -217.603623) (xy 244.729 -217.607637) (xy 244.665204 -217.603623)
			(xy 244.602414 -217.591645) (xy 244.541621 -217.571892) (xy 244.483782 -217.544675) (xy 244.429811 -217.510424)
			(xy 244.380558 -217.469679) (xy 244.336801 -217.423082) (xy 244.299228 -217.371367) (xy 244.268434 -217.315352)
			(xy 244.244902 -217.255919) (xy 244.229005 -217.194005) (xy 244.220994 -217.130587) (xy 234.964986 -217.130587)
			(xy 234.964986 -218.67495) (xy 236.072932 -218.67495) (xy 236.077003 -218.619328) (xy 236.089129 -218.564891)
			(xy 236.109052 -218.5128) (xy 236.136348 -218.464165) (xy 236.170434 -218.420022) (xy 236.210583 -218.381313)
			(xy 236.255941 -218.348862) (xy 236.305541 -218.323361) (xy 236.358325 -218.305354) (xy 236.413168 -218.295224)
			(xy 236.468902 -218.293187) (xy 236.524339 -218.299287) (xy 236.578296 -218.313393) (xy 236.629625 -218.335205)
			(xy 236.677231 -218.364259) (xy 236.720099 -218.399934) (xy 236.743936 -218.426538) (xy 238.490013 -218.426538)
			(xy 238.493948 -218.372767) (xy 238.505671 -218.320143) (xy 238.524931 -218.269786) (xy 238.551317 -218.222769)
			(xy 238.584269 -218.180096) (xy 238.623082 -218.142675) (xy 238.66693 -218.111305) (xy 238.714878 -218.086653)
			(xy 238.765905 -218.069245) (xy 238.818923 -218.059452) (xy 238.872802 -218.057483) (xy 238.926393 -218.06338)
			(xy 238.978554 -218.077016) (xy 239.028174 -218.098103) (xy 239.074195 -218.126189) (xy 239.115637 -218.160677)
			(xy 239.151615 -218.200831) (xy 239.181363 -218.245795) (xy 239.204248 -218.294612) (xy 239.21978 -218.346241)
			(xy 239.22763 -218.399581) (xy 239.228122 -218.426538) (xy 239.22763 -218.453495) (xy 239.21978 -218.506835)
			(xy 239.204248 -218.558464) (xy 239.181363 -218.607281) (xy 239.151615 -218.652245) (xy 239.115637 -218.692399)
			(xy 239.074195 -218.726887) (xy 239.028174 -218.754973) (xy 238.978554 -218.77606) (xy 238.926393 -218.789696)
			(xy 238.872802 -218.795593) (xy 238.818923 -218.793624) (xy 238.765905 -218.783831) (xy 238.714878 -218.766423)
			(xy 238.66693 -218.741771) (xy 238.623082 -218.710401) (xy 238.584269 -218.67298) (xy 238.551317 -218.630307)
			(xy 238.524931 -218.58329) (xy 238.505671 -218.532933) (xy 238.493948 -218.480309) (xy 238.490013 -218.426538)
			(xy 236.743936 -218.426538) (xy 236.757316 -218.441471) (xy 236.788089 -218.487984) (xy 236.811761 -218.538481)
			(xy 236.827829 -218.591888) (xy 236.835949 -218.647064) (xy 236.836458 -218.67495) (xy 236.835949 -218.702836)
			(xy 236.827829 -218.758012) (xy 236.811761 -218.811419) (xy 236.788089 -218.861916) (xy 236.757316 -218.908429)
			(xy 236.720099 -218.949966) (xy 236.677231 -218.985641) (xy 236.629625 -219.014695) (xy 236.578296 -219.036507)
			(xy 236.524339 -219.050613) (xy 236.468902 -219.056713) (xy 236.413168 -219.054676) (xy 236.358325 -219.044546)
			(xy 236.305541 -219.026539) (xy 236.255941 -219.001038) (xy 236.210583 -218.968587) (xy 236.170434 -218.929878)
			(xy 236.136348 -218.885735) (xy 236.109052 -218.8371) (xy 236.089129 -218.785009) (xy 236.077003 -218.730572)
			(xy 236.072932 -218.67495) (xy 234.964986 -218.67495) (xy 234.964986 -219.10548) (xy 237.869982 -219.10548)
			(xy 237.874053 -219.049858) (xy 237.886179 -218.995421) (xy 237.906102 -218.94333) (xy 237.933398 -218.894695)
			(xy 237.967484 -218.850552) (xy 238.007633 -218.811843) (xy 238.052991 -218.779392) (xy 238.102591 -218.753891)
			(xy 238.155375 -218.735884) (xy 238.210218 -218.725754) (xy 238.265952 -218.723717) (xy 238.321389 -218.729817)
			(xy 238.375346 -218.743923) (xy 238.426675 -218.765735) (xy 238.474281 -218.794789) (xy 238.517149 -218.830464)
			(xy 238.554366 -218.872001) (xy 238.585139 -218.918514) (xy 238.608811 -218.969011) (xy 238.624879 -219.022418)
			(xy 238.632999 -219.077594) (xy 238.633508 -219.10548) (xy 238.632999 -219.133366) (xy 238.629515 -219.157042)
			(xy 239.139982 -219.157042) (xy 239.144053 -219.10142) (xy 239.156179 -219.046983) (xy 239.176102 -218.994892)
			(xy 239.203398 -218.946257) (xy 239.237484 -218.902114) (xy 239.277633 -218.863405) (xy 239.322991 -218.830954)
			(xy 239.372591 -218.805453) (xy 239.425375 -218.787446) (xy 239.480218 -218.777316) (xy 239.535952 -218.775279)
			(xy 239.591389 -218.781379) (xy 239.645346 -218.795485) (xy 239.696675 -218.817297) (xy 239.744281 -218.846351)
			(xy 239.787149 -218.882026) (xy 239.824366 -218.923563) (xy 239.840534 -218.948) (xy 242.950492 -218.948)
			(xy 242.950919 -218.922421) (xy 242.957762 -218.871724) (xy 242.971311 -218.822394) (xy 242.991325 -218.775314)
			(xy 243.017445 -218.731327) (xy 243.049203 -218.691221) (xy 243.067332 -218.673172) (xy 243.074444 -218.666314)
			(xy 243.082572 -218.64828) (xy 243.08562 -218.557602) (xy 243.078762 -218.53906) (xy 243.072158 -218.531694)
			(xy 243.054167 -218.511239) (xy 243.023832 -218.465992) (xy 243.000486 -218.416774) (xy 242.984637 -218.364656)
			(xy 242.97663 -218.310773) (xy 242.976146 -218.283536) (xy 242.976662 -218.255936) (xy 242.984889 -218.201353)
			(xy 243.001159 -218.148606) (xy 243.025109 -218.098874) (xy 243.056204 -218.053266) (xy 243.093749 -218.012802)
			(xy 243.136906 -217.978385) (xy 243.18471 -217.950786) (xy 243.236094 -217.930619) (xy 243.289909 -217.918336)
			(xy 243.344954 -217.914211) (xy 243.399999 -217.918336) (xy 243.453814 -217.930619) (xy 243.505198 -217.950786)
			(xy 243.553002 -217.978385) (xy 243.596159 -218.012802) (xy 243.633704 -218.053266) (xy 243.664799 -218.098874)
			(xy 243.688749 -218.148606) (xy 243.705019 -218.201353) (xy 243.713246 -218.255936) (xy 243.713762 -218.283536)
			(xy 243.713181 -218.312209) (xy 243.704308 -218.368864) (xy 243.700467 -218.380818) (xy 246.90273 -218.380818)
			(xy 246.906801 -218.325196) (xy 246.918927 -218.270759) (xy 246.93885 -218.218668) (xy 246.966146 -218.170033)
			(xy 247.000232 -218.12589) (xy 247.040381 -218.087181) (xy 247.085739 -218.05473) (xy 247.135339 -218.029229)
			(xy 247.188123 -218.011222) (xy 247.242966 -218.001092) (xy 247.2987 -217.999055) (xy 247.354137 -218.005155)
			(xy 247.408094 -218.019261) (xy 247.459423 -218.041073) (xy 247.507029 -218.070127) (xy 247.549897 -218.105802)
			(xy 247.587114 -218.147339) (xy 247.617887 -218.193852) (xy 247.641559 -218.244349) (xy 247.657627 -218.297756)
			(xy 247.665747 -218.352932) (xy 247.666256 -218.380818) (xy 247.665747 -218.408704) (xy 247.657627 -218.46388)
			(xy 247.641559 -218.517287) (xy 247.617887 -218.567784) (xy 247.587114 -218.614297) (xy 247.549897 -218.655834)
			(xy 247.507029 -218.691509) (xy 247.459423 -218.720563) (xy 247.408094 -218.742375) (xy 247.354137 -218.756481)
			(xy 247.2987 -218.762581) (xy 247.242966 -218.760544) (xy 247.188123 -218.750414) (xy 247.135339 -218.732407)
			(xy 247.085739 -218.706906) (xy 247.040381 -218.674455) (xy 247.000232 -218.635746) (xy 246.966146 -218.591603)
			(xy 246.93885 -218.542968) (xy 246.918927 -218.490877) (xy 246.906801 -218.43644) (xy 246.90273 -218.380818)
			(xy 243.700467 -218.380818) (xy 243.686766 -218.423461) (xy 243.660979 -218.474682) (xy 243.627569 -218.52129)
			(xy 243.607844 -218.542108) (xy 243.600986 -218.54922) (xy 243.593366 -218.567508) (xy 243.592858 -218.658186)
			(xy 243.600224 -218.676474) (xy 243.607082 -218.683586) (xy 243.626914 -218.705059) (xy 243.66051 -218.752888)
			(xy 243.68642 -218.80528) (xy 243.704038 -218.86101) (xy 243.71295 -218.918776) (xy 243.713508 -218.948)
			(xy 243.713022 -218.975251) (xy 243.705266 -219.029199) (xy 243.689911 -219.081494) (xy 243.667269 -219.131071)
			(xy 243.637803 -219.176921) (xy 243.602112 -219.218112) (xy 243.560921 -219.253803) (xy 243.515071 -219.283269)
			(xy 243.465494 -219.305911) (xy 243.413199 -219.321266) (xy 243.359251 -219.329022) (xy 243.304749 -219.329022)
			(xy 243.250801 -219.321266) (xy 243.198506 -219.305911) (xy 243.148929 -219.283269) (xy 243.103079 -219.253803)
			(xy 243.061888 -219.218112) (xy 243.026197 -219.176921) (xy 242.996731 -219.131071) (xy 242.974089 -219.081494)
			(xy 242.958734 -219.029199) (xy 242.950978 -218.975251) (xy 242.950492 -218.948) (xy 239.840534 -218.948)
			(xy 239.855139 -218.970076) (xy 239.878811 -219.020573) (xy 239.894879 -219.07398) (xy 239.902999 -219.129156)
			(xy 239.903508 -219.157042) (xy 239.902999 -219.184928) (xy 239.894879 -219.240104) (xy 239.878811 -219.293511)
			(xy 239.855139 -219.344008) (xy 239.824366 -219.390521) (xy 239.787149 -219.432058) (xy 239.744281 -219.467733)
			(xy 239.696675 -219.496787) (xy 239.645346 -219.518599) (xy 239.591389 -219.532705) (xy 239.535952 -219.538805)
			(xy 239.480218 -219.536768) (xy 239.425375 -219.526638) (xy 239.372591 -219.508631) (xy 239.322991 -219.48313)
			(xy 239.277633 -219.450679) (xy 239.237484 -219.41197) (xy 239.203398 -219.367827) (xy 239.176102 -219.319192)
			(xy 239.156179 -219.267101) (xy 239.144053 -219.212664) (xy 239.139982 -219.157042) (xy 238.629515 -219.157042)
			(xy 238.624879 -219.188542) (xy 238.608811 -219.241949) (xy 238.585139 -219.292446) (xy 238.554366 -219.338959)
			(xy 238.517149 -219.380496) (xy 238.474281 -219.416171) (xy 238.426675 -219.445225) (xy 238.375346 -219.467037)
			(xy 238.321389 -219.481143) (xy 238.265952 -219.487243) (xy 238.210218 -219.485206) (xy 238.155375 -219.475076)
			(xy 238.102591 -219.457069) (xy 238.052991 -219.431568) (xy 238.007633 -219.399117) (xy 237.967484 -219.360408)
			(xy 237.933398 -219.316265) (xy 237.906102 -219.26763) (xy 237.886179 -219.215539) (xy 237.874053 -219.161102)
			(xy 237.869982 -219.10548) (xy 234.964986 -219.10548) (xy 234.964986 -219.837) (xy 242.949982 -219.837)
			(xy 242.954053 -219.781378) (xy 242.966179 -219.726941) (xy 242.986102 -219.67485) (xy 243.013398 -219.626215)
			(xy 243.047484 -219.582072) (xy 243.087633 -219.543363) (xy 243.132991 -219.510912) (xy 243.182591 -219.485411)
			(xy 243.235375 -219.467404) (xy 243.290218 -219.457274) (xy 243.345952 -219.455237) (xy 243.401389 -219.461337)
			(xy 243.455346 -219.475443) (xy 243.506675 -219.497255) (xy 243.554281 -219.526309) (xy 243.597149 -219.561984)
			(xy 243.634366 -219.603521) (xy 243.665139 -219.650034) (xy 243.688811 -219.700531) (xy 243.704879 -219.753938)
			(xy 243.712999 -219.809114) (xy 243.713508 -219.837) (xy 243.712999 -219.864886) (xy 243.704879 -219.920062)
			(xy 243.688811 -219.973469) (xy 243.665139 -220.023966) (xy 243.634366 -220.070479) (xy 243.597149 -220.112016)
			(xy 243.554281 -220.147691) (xy 243.506675 -220.176745) (xy 243.455346 -220.198557) (xy 243.401389 -220.212663)
			(xy 243.345952 -220.218763) (xy 243.290218 -220.216726) (xy 243.235375 -220.206596) (xy 243.182591 -220.188589)
			(xy 243.132991 -220.163088) (xy 243.087633 -220.130637) (xy 243.047484 -220.091928) (xy 243.013398 -220.047785)
			(xy 242.986102 -219.99915) (xy 242.966179 -219.947059) (xy 242.954053 -219.892622) (xy 242.949982 -219.837)
			(xy 234.964986 -219.837) (xy 234.964986 -219.87637) (xy 234.965421 -219.886435) (xy 234.973152 -219.905022)
			(xy 234.979972 -219.912438) (xy 235.641388 -220.573854) (xy 235.648784 -220.580707) (xy 235.667382 -220.588453)
			(xy 235.677456 -220.58884)
		)
		(stroke
			(width 0)
			(type solid)
		)
		(fill yes)
		(layer "In6.Cu")
		(net "P3V3")
	)
	(gr_poly
		(pts
			(xy 242.478814 -252.43663) (xy 242.488884 -252.436205) (xy 242.507487 -252.428491) (xy 242.514882 -252.421644)
			(xy 243.658136 -251.27839) (xy 243.664988 -251.270994) (xy 243.672728 -251.252395) (xy 243.673122 -251.242322)
			(xy 243.673122 -231.236266) (xy 243.672693 -231.226198) (xy 243.664973 -231.2076) (xy 243.658136 -231.200198)
			(xy 243.215922 -230.757984) (xy 243.192808 -230.750618) (xy 243.180616 -230.75265) (xy 243.159877 -230.755885)
			(xy 243.118039 -230.759322) (xy 243.09705 -230.759508) (xy 243.066321 -230.759041) (xy 243.005312 -230.751628)
			(xy 242.945641 -230.736915) (xy 242.888178 -230.715117) (xy 242.833761 -230.686552) (xy 242.783184 -230.651637)
			(xy 242.737184 -230.61088) (xy 242.696432 -230.564876) (xy 242.661522 -230.514296) (xy 242.632963 -230.459877)
			(xy 242.61117 -230.402412) (xy 242.596463 -230.342739) (xy 242.589056 -230.281729) (xy 242.588542 -230.251)
			(xy 242.588747 -230.230011) (xy 242.592179 -230.188175) (xy 242.5954 -230.167434) (xy 242.597432 -230.155242)
			(xy 242.590066 -230.132128) (xy 236.231938 -223.774) (xy 236.209078 -223.766634) (xy 236.19714 -223.768412)
			(xy 236.17777 -223.77125) (xy 236.138738 -223.774301) (xy 236.119162 -223.774508) (xy 236.088433 -223.774042)
			(xy 236.027422 -223.766629) (xy 235.96775 -223.751918) (xy 235.910286 -223.730121) (xy 235.855868 -223.701556)
			(xy 235.80529 -223.666641) (xy 235.759289 -223.625884) (xy 235.718535 -223.57988) (xy 235.683624 -223.529299)
			(xy 235.655064 -223.474879) (xy 235.633271 -223.417414) (xy 235.618564 -223.357741) (xy 235.611156 -223.29673)
			(xy 235.610654 -223.266) (xy 235.610859 -223.246424) (xy 235.613912 -223.207392) (xy 235.61675 -223.188022)
			(xy 235.618528 -223.176084) (xy 235.611162 -223.153224) (xy 234.302046 -221.844108) (xy 234.295193 -221.836712)
			(xy 234.287449 -221.818114) (xy 234.28706 -221.80804) (xy 234.28706 -215.293956) (xy 234.287493 -215.283891)
			(xy 234.295225 -215.265304) (xy 234.302046 -215.257888) (xy 234.653582 -214.906352) (xy 234.659746 -214.899588)
			(xy 234.667271 -214.882921) (xy 234.668528 -214.864677) (xy 234.666282 -214.855806) (xy 234.63631 -214.756492)
			(xy 234.615736 -214.737696) (xy 234.601766 -214.734902) (xy 234.576783 -214.729406) (xy 234.528522 -214.712445)
			(xy 234.483063 -214.688988) (xy 234.441275 -214.659483) (xy 234.403958 -214.624495) (xy 234.371824 -214.584694)
			(xy 234.345489 -214.540839) (xy 234.335066 -214.517478) (xy 234.329732 -214.504524) (xy 234.30738 -214.488268)
			(xy 234.191048 -214.47633) (xy 234.165902 -214.48776) (xy 234.158028 -214.499444) (xy 234.140205 -214.524494)
			(xy 234.099445 -214.570522) (xy 234.053431 -214.611298) (xy 234.002835 -214.646226) (xy 233.948396 -214.674797)
			(xy 233.890908 -214.696593) (xy 233.831211 -214.711296) (xy 233.770177 -214.718691) (xy 233.739436 -214.719154)
			(xy 233.707469 -214.718675) (xy 233.64404 -214.710666) (xy 233.582114 -214.69477) (xy 233.522669 -214.671238)
			(xy 233.466642 -214.640441) (xy 233.414917 -214.602864) (xy 233.36831 -214.5591) (xy 233.327556 -214.50984)
			(xy 233.293298 -214.45586) (xy 233.266075 -214.398012) (xy 233.246318 -214.337208) (xy 233.234337 -214.274407)
			(xy 233.230322 -214.2106) (xy 233.234337 -214.146793) (xy 233.246318 -214.083992) (xy 233.266075 -214.023188)
			(xy 233.293298 -213.96534) (xy 233.327556 -213.91136) (xy 233.36831 -213.8621) (xy 233.414917 -213.818336)
			(xy 233.466642 -213.780759) (xy 233.522669 -213.749962) (xy 233.582114 -213.72643) (xy 233.64404 -213.710534)
			(xy 233.707469 -213.702525) (xy 233.739436 -213.702138) (xy 233.7728 -213.702659) (xy 233.838956 -213.71138)
			(xy 233.903403 -213.728678) (xy 233.965033 -213.754258) (xy 234.022787 -213.787681) (xy 234.075674 -213.82837)
			(xy 234.122783 -213.875628) (xy 234.163307 -213.928642) (xy 234.196547 -213.986501) (xy 234.221934 -214.048211)
			(xy 234.230926 -214.080344) (xy 234.234482 -214.093806) (xy 234.254294 -214.11311) (xy 234.367832 -214.141304)
			(xy 234.394248 -214.13343) (xy 234.403646 -214.12327) (xy 234.421171 -214.10491) (xy 234.460389 -214.072691)
			(xy 234.503657 -214.046158) (xy 234.550157 -214.025813) (xy 234.599007 -214.012039) (xy 234.649286 -214.005097)
			(xy 234.674664 -214.004652) (xy 234.701011 -214.005119) (xy 234.753169 -214.012613) (xy 234.803729 -214.027454)
			(xy 234.851663 -214.049339) (xy 234.895994 -214.077822) (xy 234.935821 -214.112325) (xy 234.970332 -214.152145)
			(xy 234.998825 -214.19647) (xy 235.02072 -214.2444) (xy 235.035571 -214.294957) (xy 235.043075 -214.347113)
			(xy 235.043472 -214.37346) (xy 235.042964 -214.391748) (xy 235.042456 -214.40267) (xy 235.050076 -214.422482)
			(xy 235.05795 -214.430356) (xy 235.065362 -214.43704) (xy 235.083795 -214.444637) (xy 235.103733 -214.444637)
			(xy 235.122166 -214.43704) (xy 235.129578 -214.430356) (xy 235.161074 -214.39886) (xy 235.167932 -214.372952)
			(xy 235.164376 -214.359744) (xy 235.156194 -214.327339) (xy 235.147409 -214.261082) (xy 235.14685 -214.227664)
			(xy 235.147316 -214.196933) (xy 235.154728 -214.135921) (xy 235.169439 -214.076246) (xy 235.191235 -214.01878)
			(xy 235.219799 -213.96436) (xy 235.254714 -213.913778) (xy 235.29547 -213.867774) (xy 235.341474 -213.827017)
			(xy 235.392054 -213.792102) (xy 235.446475 -213.763538) (xy 235.503941 -213.741741) (xy 235.563615 -213.727029)
			(xy 235.624627 -213.719616) (xy 235.655358 -213.719156) (xy 235.685638 -213.719579) (xy 235.745772 -213.726744)
			(xy 235.80463 -213.741002) (xy 235.833158 -213.75116) (xy 235.841794 -213.754462) (xy 252.96876 -213.754462)
			(xy 252.978825 -213.754027) (xy 252.99741 -213.746293) (xy 253.004828 -213.739476) (xy 253.664974 -213.07933)
			(xy 253.671812 -213.071929) (xy 253.679525 -213.05333) (xy 253.67996 -213.043262) (xy 253.67996 -202.388216)
			(xy 253.67952 -202.378154) (xy 253.67178 -202.359575) (xy 253.664974 -202.352148) (xy 251.624592 -200.311766)
			(xy 251.617196 -200.304914) (xy 251.598597 -200.297172) (xy 251.588524 -200.29678) (xy 242.613942 -200.29678)
			(xy 242.606157 -200.297069) (xy 242.591299 -200.301731) (xy 242.584732 -200.305924) (xy 240.724944 -201.608436)
			(xy 240.68962 -201.632479) (xy 240.614709 -201.67359) (xy 240.535769 -201.706307) (xy 240.453738 -201.730242)
			(xy 240.411762 -201.73823) (xy 236.486954 -202.43038) (xy 236.453253 -202.435887) (xy 236.385211 -202.441739)
			(xy 236.351064 -202.442064) (xy 236.316916 -202.441758) (xy 236.248873 -202.435906) (xy 236.215174 -202.43038)
			(xy 233.492548 -201.95032) (xy 233.480383 -201.94889) (xy 233.457043 -201.956199) (xy 233.447844 -201.96429)
			(xy 231.070404 -204.34173) (xy 241.270536 -204.34173) (xy 241.271038 -204.309769) (xy 241.279049 -204.246351)
			(xy 241.294946 -204.184437) (xy 241.318478 -204.125004) (xy 241.349272 -204.068989) (xy 241.386845 -204.017274)
			(xy 241.430602 -203.970677) (xy 241.479855 -203.929932) (xy 241.533826 -203.895681) (xy 241.591665 -203.868464)
			(xy 241.652458 -203.848711) (xy 241.715248 -203.836733) (xy 241.779044 -203.83272) (xy 241.84284 -203.836733)
			(xy 241.90563 -203.848711) (xy 241.966423 -203.868464) (xy 242.024262 -203.895681) (xy 242.078233 -203.929932)
			(xy 242.127486 -203.970677) (xy 242.171243 -204.017274) (xy 242.208816 -204.068989) (xy 242.23961 -204.125004)
			(xy 242.263142 -204.184437) (xy 242.279039 -204.246351) (xy 242.28705 -204.309769) (xy 242.287552 -204.34173)
			(xy 242.287076 -204.373196) (xy 242.279307 -204.435646) (xy 242.263892 -204.496661) (xy 242.241066 -204.555307)
			(xy 242.211178 -204.610688) (xy 242.174686 -204.661959) (xy 242.132146 -204.708335) (xy 242.108482 -204.72908)
			(xy 242.099592 -204.736446) (xy 242.090448 -204.756766) (xy 242.090702 -204.856842) (xy 242.1001 -204.876908)
			(xy 242.108736 -204.884274) (xy 242.132676 -204.904997) (xy 242.175679 -204.951478) (xy 242.212581 -205.002936)
			(xy 242.242811 -205.058576) (xy 242.265902 -205.117537) (xy 242.281498 -205.178909) (xy 242.289356 -205.241741)
			(xy 242.289838 -205.273402) (xy 242.289336 -205.305363) (xy 242.281325 -205.368781) (xy 242.265428 -205.430695)
			(xy 242.241896 -205.490128) (xy 242.211102 -205.546143) (xy 242.173529 -205.597858) (xy 242.129772 -205.644455)
			(xy 242.080519 -205.6852) (xy 242.026548 -205.719451) (xy 241.968709 -205.746668) (xy 241.907916 -205.766421)
			(xy 241.845126 -205.778399) (xy 241.78133 -205.782413) (xy 241.717534 -205.778399) (xy 241.654744 -205.766421)
			(xy 241.593951 -205.746668) (xy 241.536112 -205.719451) (xy 241.482141 -205.6852) (xy 241.432888 -205.644455)
			(xy 241.389131 -205.597858) (xy 241.351558 -205.546143) (xy 241.320764 -205.490128) (xy 241.297232 -205.430695)
			(xy 241.281335 -205.368781) (xy 241.273324 -205.305363) (xy 241.272822 -205.273402) (xy 241.27333 -205.241937)
			(xy 241.281094 -205.179489) (xy 241.296505 -205.118475) (xy 241.319325 -205.059829) (xy 241.349208 -205.004447)
			(xy 241.385696 -204.953176) (xy 241.428231 -204.906798) (xy 241.451892 -204.886052) (xy 241.460782 -204.878686)
			(xy 241.469926 -204.858366) (xy 241.469672 -204.75829) (xy 241.460274 -204.738224) (xy 241.451638 -204.730858)
			(xy 241.427728 -204.7101) (xy 241.384721 -204.663628) (xy 241.347814 -204.612177) (xy 241.317579 -204.556543)
			(xy 241.294483 -204.497586) (xy 241.278883 -204.436219) (xy 241.27102 -204.37339) (xy 241.270536 -204.34173)
			(xy 231.070404 -204.34173) (xy 229.369834 -206.0423) (xy 240.446549 -206.0423) (xy 240.450563 -205.978501)
			(xy 240.462541 -205.915708) (xy 240.482295 -205.854911) (xy 240.509512 -205.79707) (xy 240.543764 -205.743095)
			(xy 240.58451 -205.693839) (xy 240.631109 -205.650078) (xy 240.682824 -205.612503) (xy 240.738841 -205.581705)
			(xy 240.798276 -205.55817) (xy 240.860193 -205.54227) (xy 240.923613 -205.534255) (xy 240.955576 -205.533752)
			(xy 240.987225 -205.534291) (xy 241.050033 -205.542145) (xy 241.111381 -205.557733) (xy 241.17032 -205.580815)
			(xy 241.225938 -205.611034) (xy 241.277375 -205.647922) (xy 241.323836 -205.69091) (xy 241.364602 -205.739331)
			(xy 241.399043 -205.792438) (xy 241.426627 -205.84941) (xy 241.446926 -205.909364) (xy 241.459626 -205.971374)
			(xy 241.46256 -206.00289) (xy 241.463576 -206.01559) (xy 241.476784 -206.036672) (xy 241.57051 -206.091536)
			(xy 241.595148 -206.092552) (xy 241.606578 -206.087218) (xy 241.631845 -206.076042) (xy 241.684805 -206.060308)
			(xy 241.739482 -206.05238) (xy 241.767106 -206.051912) (xy 241.79436 -206.05235) (xy 241.848313 -206.060108)
			(xy 241.900612 -206.075466) (xy 241.950194 -206.098111) (xy 241.996048 -206.127581) (xy 242.037241 -206.163277)
			(xy 242.072935 -206.204473) (xy 242.102402 -206.250329) (xy 242.125043 -206.299912) (xy 242.140397 -206.352213)
			(xy 242.148152 -206.406166) (xy 242.148614 -206.43342) (xy 242.148062 -206.462225) (xy 242.13939 -206.51918)
			(xy 242.122262 -206.574186) (xy 242.097067 -206.625995) (xy 242.064375 -206.673432) (xy 242.024928 -206.71542)
			(xy 241.979622 -206.751007) (xy 241.954812 -206.765652) (xy 241.943128 -206.772256) (xy 241.929412 -206.794862)
			(xy 241.925856 -206.9084) (xy 241.938302 -206.932022) (xy 241.949478 -206.939134) (xy 241.975722 -206.956781)
			(xy 242.024061 -206.997561) (xy 242.066972 -207.044019) (xy 242.103792 -207.095439) (xy 242.133954 -207.151026)
			(xy 242.156993 -207.209924) (xy 242.172552 -207.271223) (xy 242.180392 -207.333978) (xy 242.180872 -207.3656)
			(xy 242.18037 -207.397561) (xy 242.172359 -207.460979) (xy 242.156462 -207.522893) (xy 242.13293 -207.582326)
			(xy 242.102136 -207.638341) (xy 242.064563 -207.690056) (xy 242.020806 -207.736653) (xy 241.971553 -207.777398)
			(xy 241.917582 -207.811649) (xy 241.859743 -207.838866) (xy 241.79895 -207.858619) (xy 241.73616 -207.870597)
			(xy 241.672364 -207.874611) (xy 241.608568 -207.870597) (xy 241.545778 -207.858619) (xy 241.484985 -207.838866)
			(xy 241.427146 -207.811649) (xy 241.373175 -207.777398) (xy 241.323922 -207.736653) (xy 241.280165 -207.690056)
			(xy 241.242592 -207.638341) (xy 241.211798 -207.582326) (xy 241.188266 -207.522893) (xy 241.172369 -207.460979)
			(xy 241.164358 -207.397561) (xy 241.163856 -207.3656) (xy 241.164296 -207.335152) (xy 241.171557 -207.274691)
			(xy 241.185989 -207.21553) (xy 241.207383 -207.158517) (xy 241.235435 -207.104467) (xy 241.269741 -207.054155)
			(xy 241.309812 -207.0083) (xy 241.355072 -206.96756) (xy 241.404875 -206.932518) (xy 241.458507 -206.903675)
			(xy 241.48669 -206.892144) (xy 241.499136 -206.887318) (xy 241.5159 -206.866744) (xy 241.535458 -206.75473)
			(xy 241.526568 -206.729838) (xy 241.516408 -206.720948) (xy 241.494606 -206.701238) (xy 241.456741 -206.656288)
			(xy 241.42621 -206.606068) (xy 241.403735 -206.551762) (xy 241.396266 -206.523336) (xy 241.393472 -206.511144)
			(xy 241.376962 -206.492602) (xy 241.275616 -206.453486) (xy 241.251232 -206.45628) (xy 241.240818 -206.463392)
			(xy 241.215476 -206.479983) (xy 241.161636 -206.507741) (xy 241.10488 -206.528904) (xy 241.046011 -206.543172)
			(xy 240.985863 -206.550344) (xy 240.955576 -206.550768) (xy 240.923613 -206.550345) (xy 240.860193 -206.54233)
			(xy 240.798276 -206.52643) (xy 240.738841 -206.502895) (xy 240.682824 -206.472097) (xy 240.631109 -206.434522)
			(xy 240.58451 -206.390761) (xy 240.543764 -206.341505) (xy 240.509512 -206.28753) (xy 240.482295 -206.229689)
			(xy 240.462541 -206.168892) (xy 240.450563 -206.106099) (xy 240.446549 -206.0423) (xy 229.369834 -206.0423)
			(xy 225.951542 -209.460592) (xy 225.94469 -209.467988) (xy 225.936946 -209.486586) (xy 225.936556 -209.49666)
			(xy 225.936556 -211.130134) (xy 228.167946 -211.130134) (xy 228.168359 -211.100259) (xy 228.175368 -211.040922)
			(xy 228.189282 -210.982815) (xy 228.209908 -210.926739) (xy 228.236964 -210.873466) (xy 228.270076 -210.823731)
			(xy 228.289104 -210.800696) (xy 228.294699 -210.793615) (xy 228.30094 -210.776694) (xy 228.301296 -210.767676)
			(xy 228.301296 -210.73745) (xy 228.300916 -210.728435) (xy 228.294684 -210.711518) (xy 228.289104 -210.70443)
			(xy 228.270073 -210.681397) (xy 228.236962 -210.631662) (xy 228.209909 -210.578389) (xy 228.189286 -210.522311)
			(xy 228.175378 -210.464204) (xy 228.168376 -210.404867) (xy 228.167946 -210.374992) (xy 228.168448 -210.344263)
			(xy 228.175857 -210.283252) (xy 228.190565 -210.223579) (xy 228.212358 -210.166114) (xy 228.240918 -210.111694)
			(xy 228.27583 -210.061114) (xy 228.316583 -210.01511) (xy 228.362584 -209.974353) (xy 228.413162 -209.939438)
			(xy 228.467579 -209.910874) (xy 228.525043 -209.889076) (xy 228.584715 -209.874364) (xy 228.645725 -209.866951)
			(xy 228.676454 -209.866484) (xy 228.708161 -209.866989) (xy 228.771083 -209.874882) (xy 228.80193 -209.882232)
			(xy 228.8159 -209.885788) (xy 228.84257 -209.87766) (xy 228.922072 -209.789522) (xy 228.927406 -209.762344)
			(xy 228.922326 -209.748882) (xy 228.912477 -209.720771) (xy 228.898675 -209.662824) (xy 228.891745 -209.60366)
			(xy 228.891338 -209.573876) (xy 228.891715 -209.543142) (xy 228.899128 -209.482121) (xy 228.913841 -209.42244)
			(xy 228.935642 -209.364966) (xy 228.964211 -209.31054) (xy 228.999132 -209.259955) (xy 229.039897 -209.213947)
			(xy 229.08591 -209.173189) (xy 229.1365 -209.138275) (xy 229.19093 -209.109713) (xy 229.248406 -209.08792)
			(xy 229.30809 -209.073215) (xy 229.369112 -209.065811) (xy 229.399846 -209.065368) (xy 229.430335 -209.065833)
			(xy 229.490876 -209.07313) (xy 229.550109 -209.087612) (xy 229.607187 -209.109073) (xy 229.661288 -209.137205)
			(xy 229.711638 -209.171604) (xy 229.734872 -209.191352) (xy 229.741984 -209.197448) (xy 229.759002 -209.204052)
			(xy 229.8446 -209.204052) (xy 229.861618 -209.197702) (xy 229.86873 -209.191352) (xy 229.878886 -209.182617)
			(xy 229.899979 -209.166098) (xy 229.910894 -209.158332) (xy 229.9208 -209.15122) (xy 229.931976 -209.130138)
			(xy 229.934262 -209.023458) (xy 229.923594 -209.001868) (xy 229.913942 -208.994502) (xy 229.887704 -208.973821)
			(xy 229.840346 -208.926698) (xy 229.799566 -208.87378) (xy 229.766064 -208.815978) (xy 229.740419 -208.754288)
			(xy 229.723072 -208.689771) (xy 229.71432 -208.623538) (xy 229.71379 -208.590134) (xy 229.714226 -208.558667)
			(xy 229.722 -208.496214) (xy 229.737421 -208.435198) (xy 229.760253 -208.376552) (xy 229.790147 -208.32117)
			(xy 229.826646 -208.269901) (xy 229.869193 -208.223527) (xy 229.89286 -208.202784) (xy 229.899689 -208.19638)
			(xy 229.90869 -208.179985) (xy 229.910386 -208.17078) (xy 229.914196 -208.140046) (xy 229.915021 -208.130852)
			(xy 229.910858 -208.112884) (xy 229.906068 -208.104994) (xy 229.890678 -208.081217) (xy 229.866271 -208.030111)
			(xy 229.849693 -207.975957) (xy 229.841309 -207.919946) (xy 229.841305 -207.863311) (xy 229.84968 -207.807298)
			(xy 229.86625 -207.753141) (xy 229.89065 -207.702032) (xy 229.906068 -207.678274) (xy 229.910884 -207.670394)
			(xy 229.915051 -207.652418) (xy 229.914196 -207.643222) (xy 229.910386 -207.612488) (xy 229.908793 -207.603244)
			(xy 229.899792 -207.586803) (xy 229.89286 -207.580484) (xy 229.869225 -207.559707) (xy 229.826677 -207.51334)
			(xy 229.790178 -207.462077) (xy 229.760284 -207.406701) (xy 229.737453 -207.348059) (xy 229.722034 -207.287047)
			(xy 229.714263 -207.224599) (xy 229.71379 -207.193134) (xy 229.714292 -207.161173) (xy 229.722303 -207.097755)
			(xy 229.7382 -207.035841) (xy 229.761732 -206.976408) (xy 229.792526 -206.920393) (xy 229.830099 -206.868678)
			(xy 229.873856 -206.822081) (xy 229.923109 -206.781336) (xy 229.97708 -206.747085) (xy 230.034919 -206.719868)
			(xy 230.095712 -206.700115) (xy 230.158502 -206.688137) (xy 230.222298 -206.684124) (xy 230.286094 -206.688137)
			(xy 230.348884 -206.700115) (xy 230.409677 -206.719868) (xy 230.467516 -206.747085) (xy 230.521487 -206.781336)
			(xy 230.57074 -206.822081) (xy 230.614497 -206.868678) (xy 230.65207 -206.920393) (xy 230.682864 -206.976408)
			(xy 230.706396 -207.035841) (xy 230.722293 -207.097755) (xy 230.730304 -207.161173) (xy 230.730806 -207.193134)
			(xy 230.730349 -207.224601) (xy 230.722579 -207.287052) (xy 230.707162 -207.348068) (xy 230.684333 -207.406715)
			(xy 230.654442 -207.462096) (xy 230.617946 -207.513366) (xy 230.575402 -207.55974) (xy 230.551736 -207.580484)
			(xy 230.544882 -207.586865) (xy 230.535895 -207.603276) (xy 230.53421 -207.612488) (xy 230.5304 -207.643222)
			(xy 230.529592 -207.652416) (xy 230.533744 -207.670383) (xy 230.538528 -207.678274) (xy 230.553975 -207.702014)
			(xy 230.578372 -207.75313) (xy 230.594939 -207.807292) (xy 230.603313 -207.863309) (xy 230.603308 -207.919948)
			(xy 230.594926 -207.975963) (xy 230.578351 -208.030123) (xy 230.553947 -208.081235) (xy 230.538528 -208.104994)
			(xy 230.533727 -208.112882) (xy 230.529551 -208.130852) (xy 230.5304 -208.140046) (xy 230.53421 -208.17078)
			(xy 230.535818 -208.18002) (xy 230.544809 -208.196463) (xy 230.551736 -208.202784) (xy 230.575403 -208.223526)
			(xy 230.617949 -208.269899) (xy 230.654446 -208.321168) (xy 230.684336 -208.37655) (xy 230.707161 -208.435198)
			(xy 230.722573 -208.496215) (xy 230.730337 -208.558667) (xy 230.730806 -208.590134) (xy 230.730408 -208.620578)
			(xy 230.723139 -208.68103) (xy 230.708699 -208.740181) (xy 230.703826 -208.753159) (xy 243.736362 -208.753159)
			(xy 243.736362 -208.689237) (xy 243.744373 -208.625819) (xy 243.76027 -208.563905) (xy 243.783802 -208.504472)
			(xy 243.814596 -208.448457) (xy 243.852169 -208.396742) (xy 243.895926 -208.350145) (xy 243.945179 -208.3094)
			(xy 243.99915 -208.275149) (xy 244.056989 -208.247932) (xy 244.117782 -208.228179) (xy 244.180572 -208.216201)
			(xy 244.244368 -208.212188) (xy 244.308164 -208.216201) (xy 244.370954 -208.228179) (xy 244.431747 -208.247932)
			(xy 244.489586 -208.275149) (xy 244.543557 -208.3094) (xy 244.59281 -208.350145) (xy 244.636567 -208.396742)
			(xy 244.67414 -208.448457) (xy 244.704934 -208.504472) (xy 244.728466 -208.563905) (xy 244.744363 -208.625819)
			(xy 244.752374 -208.689237) (xy 244.752876 -208.721198) (xy 244.752374 -208.753159) (xy 244.744363 -208.816577)
			(xy 244.728466 -208.878491) (xy 244.704934 -208.937924) (xy 244.67414 -208.993939) (xy 244.636567 -209.045654)
			(xy 244.59281 -209.092251) (xy 244.543557 -209.132996) (xy 244.489586 -209.167247) (xy 244.431747 -209.194464)
			(xy 244.370954 -209.214217) (xy 244.308164 -209.226195) (xy 244.244368 -209.230209) (xy 244.180572 -209.226195)
			(xy 244.117782 -209.214217) (xy 244.056989 -209.194464) (xy 243.99915 -209.167247) (xy 243.945179 -209.132996)
			(xy 243.895926 -209.092251) (xy 243.852169 -209.045654) (xy 243.814596 -208.993939) (xy 243.783802 -208.937924)
			(xy 243.76027 -208.878491) (xy 243.744373 -208.816577) (xy 243.736362 -208.753159) (xy 230.703826 -208.753159)
			(xy 230.687294 -208.797183) (xy 230.659231 -208.851218) (xy 230.624912 -208.901512) (xy 230.584829 -208.947345)
			(xy 230.539556 -208.98806) (xy 230.514906 -209.005932) (xy 230.505 -209.013044) (xy 230.493824 -209.034126)
			(xy 230.491538 -209.140806) (xy 230.502206 -209.162396) (xy 230.511858 -209.169762) (xy 230.538079 -209.190464)
			(xy 230.585437 -209.237583) (xy 230.626219 -209.290498) (xy 230.659723 -209.348296) (xy 230.685371 -209.409983)
			(xy 230.702722 -209.474497) (xy 230.711478 -209.540727) (xy 230.71201 -209.57413) (xy 230.711572 -209.604862)
			(xy 230.70416 -209.665876) (xy 230.689448 -209.725553) (xy 230.667651 -209.783021) (xy 230.639085 -209.837442)
			(xy 230.604168 -209.888024) (xy 230.563409 -209.934029) (xy 230.517402 -209.974785) (xy 230.466818 -210.0097)
			(xy 230.412395 -210.038262) (xy 230.354926 -210.060057) (xy 230.295249 -210.074765) (xy 230.234234 -210.082174)
			(xy 230.203502 -210.082638) (xy 230.173012 -210.082203) (xy 230.11247 -210.0749) (xy 230.053236 -210.060411)
			(xy 229.996159 -210.038945) (xy 229.942058 -210.010808) (xy 229.891709 -209.976405) (xy 229.868476 -209.956654)
			(xy 229.861364 -209.950558) (xy 229.844346 -209.943954) (xy 229.758748 -209.943954) (xy 229.74173 -209.950304)
			(xy 229.734618 -209.956654) (xy 229.71138 -209.976353) (xy 229.66106 -210.010691) (xy 229.606998 -210.038773)
			(xy 229.549969 -210.060195) (xy 229.490789 -210.074651) (xy 229.430306 -210.081934) (xy 229.399846 -210.082384)
			(xy 229.368139 -210.08188) (xy 229.305217 -210.073986) (xy 229.27437 -210.066636) (xy 229.2604 -210.06308)
			(xy 229.23373 -210.071208) (xy 229.154228 -210.159346) (xy 229.148894 -210.186524) (xy 229.153974 -210.199986)
			(xy 229.163814 -210.2281) (xy 229.17762 -210.286046) (xy 229.184553 -210.345208) (xy 229.184962 -210.374992)
			(xy 229.184563 -210.404867) (xy 229.177551 -210.464204) (xy 229.163634 -210.522312) (xy 229.143005 -210.578388)
			(xy 229.115947 -210.63166) (xy 229.082833 -210.681395) (xy 229.063804 -210.70443) (xy 229.058241 -210.711533)
			(xy 229.05198 -210.728437) (xy 229.051612 -210.73745) (xy 229.051612 -210.767676) (xy 229.051978 -210.776692)
			(xy 229.058219 -210.793609) (xy 229.063804 -210.800696) (xy 229.082848 -210.823718) (xy 229.115957 -210.873456)
			(xy 229.143008 -210.926732) (xy 229.163629 -210.982811) (xy 229.177535 -211.04092) (xy 229.184534 -211.100259)
			(xy 229.184962 -211.130134) (xy 229.18446 -211.162095) (xy 229.176449 -211.225513) (xy 229.160552 -211.287427)
			(xy 229.13702 -211.34686) (xy 229.106226 -211.402875) (xy 229.068653 -211.45459) (xy 229.024896 -211.501187)
			(xy 228.975643 -211.541932) (xy 228.921672 -211.576183) (xy 228.863833 -211.6034) (xy 228.80304 -211.623153)
			(xy 228.74025 -211.635131) (xy 228.676454 -211.639145) (xy 228.612658 -211.635131) (xy 228.549868 -211.623153)
			(xy 228.489075 -211.6034) (xy 228.431236 -211.576183) (xy 228.377265 -211.541932) (xy 228.328012 -211.501187)
			(xy 228.284255 -211.45459) (xy 228.246682 -211.402875) (xy 228.215888 -211.34686) (xy 228.192356 -211.287427)
			(xy 228.176459 -211.225513) (xy 228.168448 -211.162095) (xy 228.167946 -211.130134) (xy 225.936556 -211.130134)
			(xy 225.936556 -217.65895) (xy 232.916982 -217.65895) (xy 232.921053 -217.603328) (xy 232.933179 -217.548891)
			(xy 232.953102 -217.4968) (xy 232.980398 -217.448165) (xy 233.014484 -217.404022) (xy 233.054633 -217.365313)
			(xy 233.099991 -217.332862) (xy 233.149591 -217.307361) (xy 233.202375 -217.289354) (xy 233.257218 -217.279224)
			(xy 233.312952 -217.277187) (xy 233.368389 -217.283287) (xy 233.422346 -217.297393) (xy 233.473675 -217.319205)
			(xy 233.521281 -217.348259) (xy 233.564149 -217.383934) (xy 233.601366 -217.425471) (xy 233.632139 -217.471984)
			(xy 233.655811 -217.522481) (xy 233.671879 -217.575888) (xy 233.679999 -217.631064) (xy 233.680508 -217.65895)
			(xy 233.679999 -217.686836) (xy 233.671879 -217.742012) (xy 233.655811 -217.795419) (xy 233.632139 -217.845916)
			(xy 233.601366 -217.892429) (xy 233.564149 -217.933966) (xy 233.521281 -217.969641) (xy 233.473675 -217.998695)
			(xy 233.422346 -218.020507) (xy 233.368389 -218.034613) (xy 233.312952 -218.040713) (xy 233.257218 -218.038676)
			(xy 233.202375 -218.028546) (xy 233.149591 -218.010539) (xy 233.099991 -217.985038) (xy 233.054633 -217.952587)
			(xy 233.014484 -217.913878) (xy 232.980398 -217.869735) (xy 232.953102 -217.8211) (xy 232.933179 -217.769009)
			(xy 232.921053 -217.714572) (xy 232.916982 -217.65895) (xy 225.936556 -217.65895) (xy 225.936556 -221.996)
			(xy 229.218996 -221.996) (xy 229.223067 -221.940378) (xy 229.235193 -221.885941) (xy 229.255116 -221.83385)
			(xy 229.282412 -221.785215) (xy 229.316498 -221.741072) (xy 229.356647 -221.702363) (xy 229.402005 -221.669912)
			(xy 229.451605 -221.644411) (xy 229.504389 -221.626404) (xy 229.559232 -221.616274) (xy 229.614966 -221.614237)
			(xy 229.670403 -221.620337) (xy 229.72436 -221.634443) (xy 229.775689 -221.656255) (xy 229.823295 -221.685309)
			(xy 229.866163 -221.720984) (xy 229.90338 -221.762521) (xy 229.934153 -221.809034) (xy 229.957825 -221.859531)
			(xy 229.973893 -221.912938) (xy 229.982013 -221.968114) (xy 229.982522 -221.996) (xy 229.982013 -222.023886)
			(xy 229.973893 -222.079062) (xy 229.957825 -222.132469) (xy 229.934153 -222.182966) (xy 229.90338 -222.229479)
			(xy 229.866163 -222.271016) (xy 229.823295 -222.306691) (xy 229.775689 -222.335745) (xy 229.72436 -222.357557)
			(xy 229.670403 -222.371663) (xy 229.614966 -222.377763) (xy 229.559232 -222.375726) (xy 229.504389 -222.365596)
			(xy 229.451605 -222.347589) (xy 229.402005 -222.322088) (xy 229.356647 -222.289637) (xy 229.316498 -222.250928)
			(xy 229.282412 -222.206785) (xy 229.255116 -222.15815) (xy 229.235193 -222.106059) (xy 229.223067 -222.051622)
			(xy 229.218996 -221.996) (xy 225.936556 -221.996) (xy 225.936556 -224.029227) (xy 233.399832 -224.029227)
			(xy 233.399832 -223.965305) (xy 233.407843 -223.901887) (xy 233.42374 -223.839973) (xy 233.447272 -223.78054)
			(xy 233.478066 -223.724525) (xy 233.515639 -223.67281) (xy 233.559396 -223.626213) (xy 233.608649 -223.585468)
			(xy 233.66262 -223.551217) (xy 233.720459 -223.524) (xy 233.781252 -223.504247) (xy 233.844042 -223.492269)
			(xy 233.907838 -223.488256) (xy 233.971634 -223.492269) (xy 234.034424 -223.504247) (xy 234.095217 -223.524)
			(xy 234.153056 -223.551217) (xy 234.207027 -223.585468) (xy 234.25628 -223.626213) (xy 234.300037 -223.67281)
			(xy 234.33761 -223.724525) (xy 234.368404 -223.78054) (xy 234.391936 -223.839973) (xy 234.407833 -223.901887)
			(xy 234.415844 -223.965305) (xy 234.416346 -223.997266) (xy 234.415844 -224.029227) (xy 234.407833 -224.092645)
			(xy 234.391936 -224.154559) (xy 234.368404 -224.213992) (xy 234.33761 -224.270007) (xy 234.300037 -224.321722)
			(xy 234.25628 -224.368319) (xy 234.207027 -224.409064) (xy 234.153056 -224.443315) (xy 234.095217 -224.470532)
			(xy 234.034424 -224.490285) (xy 233.971634 -224.502263) (xy 233.907838 -224.506277) (xy 233.844042 -224.502263)
			(xy 233.781252 -224.490285) (xy 233.720459 -224.470532) (xy 233.66262 -224.443315) (xy 233.608649 -224.409064)
			(xy 233.559396 -224.368319) (xy 233.515639 -224.321722) (xy 233.478066 -224.270007) (xy 233.447272 -224.213992)
			(xy 233.42374 -224.154559) (xy 233.407843 -224.092645) (xy 233.399832 -224.029227) (xy 225.936556 -224.029227)
			(xy 225.936556 -225.43643) (xy 232.69397 -225.43643) (xy 232.698041 -225.380808) (xy 232.710167 -225.326371)
			(xy 232.73009 -225.27428) (xy 232.757386 -225.225645) (xy 232.791472 -225.181502) (xy 232.831621 -225.142793)
			(xy 232.876979 -225.110342) (xy 232.926579 -225.084841) (xy 232.979363 -225.066834) (xy 233.034206 -225.056704)
			(xy 233.08994 -225.054667) (xy 233.145377 -225.060767) (xy 233.199334 -225.074873) (xy 233.250663 -225.096685)
			(xy 233.298269 -225.125739) (xy 233.341137 -225.161414) (xy 233.378354 -225.202951) (xy 233.409127 -225.249464)
			(xy 233.432799 -225.299961) (xy 233.448867 -225.353368) (xy 233.456987 -225.408544) (xy 233.457496 -225.43643)
			(xy 233.456987 -225.464316) (xy 233.448867 -225.519492) (xy 233.432799 -225.572899) (xy 233.409127 -225.623396)
			(xy 233.378354 -225.669909) (xy 233.341137 -225.711446) (xy 233.298269 -225.747121) (xy 233.250663 -225.776175)
			(xy 233.199334 -225.797987) (xy 233.145377 -225.812093) (xy 233.08994 -225.818193) (xy 233.034206 -225.816156)
			(xy 232.979363 -225.806026) (xy 232.926579 -225.788019) (xy 232.876979 -225.762518) (xy 232.831621 -225.730067)
			(xy 232.791472 -225.691358) (xy 232.757386 -225.647215) (xy 232.73009 -225.59858) (xy 232.710167 -225.546489)
			(xy 232.698041 -225.492052) (xy 232.69397 -225.43643) (xy 225.936556 -225.43643) (xy 225.936556 -225.833223)
			(xy 235.738214 -225.833223) (xy 235.738218 -225.778727) (xy 235.745977 -225.724786) (xy 235.761333 -225.672499)
			(xy 235.783975 -225.622929) (xy 235.81344 -225.577086) (xy 235.849129 -225.535902) (xy 235.890316 -225.500217)
			(xy 235.936162 -225.470756) (xy 235.985734 -225.44812) (xy 236.038023 -225.432769) (xy 236.091965 -225.425015)
			(xy 236.146461 -225.425017) (xy 236.200402 -225.432774) (xy 236.252689 -225.448129) (xy 236.30226 -225.470769)
			(xy 236.348104 -225.500232) (xy 236.389289 -225.53592) (xy 236.424975 -225.577106) (xy 236.454438 -225.622951)
			(xy 236.477076 -225.672522) (xy 236.492428 -225.724811) (xy 236.500184 -225.778752) (xy 236.50067 -225.806)
			(xy 236.500007 -225.838115) (xy 236.489289 -225.901444) (xy 236.479334 -225.931984) (xy 236.474508 -225.9457)
			(xy 236.480604 -225.97364) (xy 236.563662 -226.06) (xy 236.591348 -226.066858) (xy 236.605318 -226.06254)
			(xy 236.632021 -226.0548) (xy 236.686994 -226.046515) (xy 236.714792 -226.04603) (xy 236.74442 -226.046612)
			(xy 236.802917 -226.056074) (xy 236.859152 -226.074756) (xy 236.911682 -226.102178) (xy 236.935772 -226.119436)
			(xy 236.9439 -226.125532) (xy 236.962442 -226.130612) (xy 237.052358 -226.119436) (xy 237.069376 -226.110038)
			(xy 237.075726 -226.102164) (xy 237.096443 -226.077306) (xy 237.143182 -226.032553) (xy 237.195226 -225.994096)
			(xy 237.25173 -225.962557) (xy 237.311781 -225.938446) (xy 237.374407 -225.922155) (xy 237.438595 -225.913946)
			(xy 237.47095 -225.913442) (xy 237.502918 -225.91382) (xy 237.566349 -225.921827) (xy 237.628277 -225.937722)
			(xy 237.687724 -225.961254) (xy 237.743752 -225.992051) (xy 237.795479 -226.029628) (xy 237.842088 -226.073392)
			(xy 237.882844 -226.122653) (xy 237.917104 -226.176634) (xy 237.944328 -226.234483) (xy 237.964086 -226.295289)
			(xy 237.976067 -226.358091) (xy 237.980082 -226.4219) (xy 237.976067 -226.485709) (xy 237.964086 -226.548511)
			(xy 237.944328 -226.609317) (xy 237.917104 -226.667166) (xy 237.882844 -226.721147) (xy 237.842088 -226.770408)
			(xy 237.795479 -226.814172) (xy 237.743752 -226.851749) (xy 237.687724 -226.882546) (xy 237.628277 -226.906078)
			(xy 237.566349 -226.921973) (xy 237.502918 -226.92998) (xy 237.47095 -226.930458) (xy 237.437909 -226.929915)
			(xy 237.372384 -226.921354) (xy 237.308518 -226.904382) (xy 237.247387 -226.879285) (xy 237.190019 -226.846486)
			(xy 237.137379 -226.806537) (xy 237.090355 -226.760109) (xy 237.06963 -226.73437) (xy 237.063534 -226.726242)
			(xy 237.04677 -226.71659) (xy 236.957108 -226.703636) (xy 236.938312 -226.708462) (xy 236.930184 -226.714304)
			(xy 236.906505 -226.73064) (xy 236.85514 -226.756538) (xy 236.800382 -226.774163) (xy 236.743554 -226.783091)
			(xy 236.714792 -226.783646) (xy 236.688449 -226.783146) (xy 236.636301 -226.775647) (xy 236.58575 -226.760804)
			(xy 236.537825 -226.738919) (xy 236.493503 -226.710436) (xy 236.453685 -226.675936) (xy 236.419182 -226.636121)
			(xy 236.390696 -226.591801) (xy 236.368806 -226.543878) (xy 236.353959 -226.493329) (xy 236.346456 -226.44118)
			(xy 236.345984 -226.414838) (xy 236.346532 -226.38503) (xy 236.35611 -226.32619) (xy 236.365034 -226.297744)
			(xy 236.369606 -226.283774) (xy 236.363256 -226.256088) (xy 236.278928 -226.170998) (xy 236.251242 -226.16414)
			(xy 236.237272 -226.168712) (xy 236.208527 -226.177447) (xy 236.149199 -226.186892) (xy 236.119162 -226.187508)
			(xy 236.091914 -226.186981) (xy 236.037974 -226.17922) (xy 235.985687 -226.163862) (xy 235.936118 -226.141219)
			(xy 235.890275 -226.111753) (xy 235.849093 -226.076062) (xy 235.813409 -226.034874) (xy 235.78395 -225.989027)
			(xy 235.761316 -225.939454) (xy 235.745966 -225.887164) (xy 235.738214 -225.833223) (xy 225.936556 -225.833223)
			(xy 225.936556 -227.457) (xy 233.17099 -227.457) (xy 233.175003 -227.393204) (xy 233.186981 -227.330414)
			(xy 233.206734 -227.269621) (xy 233.233951 -227.211782) (xy 233.268202 -227.157811) (xy 233.308947 -227.108558)
			(xy 233.355544 -227.064801) (xy 233.407259 -227.027228) (xy 233.463274 -226.996434) (xy 233.522707 -226.972902)
			(xy 233.584621 -226.957005) (xy 233.648039 -226.948994) (xy 233.68 -226.948492) (xy 233.710215 -226.94893)
			(xy 233.770218 -226.956117) (xy 233.828945 -226.970367) (xy 233.885569 -226.991478) (xy 233.939291 -227.019152)
			(xy 233.989354 -227.053) (xy 234.012486 -227.072444) (xy 234.019623 -227.078069) (xy 234.036678 -227.084313)
			(xy 234.04576 -227.084636) (xy 234.07624 -227.084636) (xy 234.08532 -227.084302) (xy 234.102371 -227.078059)
			(xy 234.109514 -227.072444) (xy 234.132649 -227.053005) (xy 234.182716 -227.019167) (xy 234.236439 -226.991498)
			(xy 234.293061 -226.970389) (xy 234.351786 -226.956137) (xy 234.411786 -226.948942) (xy 234.442 -226.948492)
			(xy 234.473961 -226.948994) (xy 234.537379 -226.957005) (xy 234.599293 -226.972902) (xy 234.658726 -226.996434)
			(xy 234.714741 -227.027228) (xy 234.766456 -227.064801) (xy 234.813053 -227.108558) (xy 234.853798 -227.157811)
			(xy 234.888049 -227.211782) (xy 234.915266 -227.269621) (xy 234.935019 -227.330414) (xy 234.946997 -227.393204)
			(xy 234.951011 -227.457) (xy 234.946997 -227.520796) (xy 234.935019 -227.583586) (xy 234.915266 -227.644379)
			(xy 234.888049 -227.702218) (xy 234.853798 -227.756189) (xy 234.813053 -227.805442) (xy 234.766456 -227.849199)
			(xy 234.714741 -227.886772) (xy 234.658726 -227.917566) (xy 234.599293 -227.941098) (xy 234.537379 -227.956995)
			(xy 234.473961 -227.965006) (xy 234.442 -227.965508) (xy 234.411785 -227.96507) (xy 234.351782 -227.957883)
			(xy 234.293055 -227.943633) (xy 234.236431 -227.922522) (xy 234.182709 -227.894848) (xy 234.132646 -227.861)
			(xy 234.109514 -227.841556) (xy 234.102377 -227.835931) (xy 234.085322 -227.829687) (xy 234.07624 -227.829364)
			(xy 234.04576 -227.829364) (xy 234.03668 -227.829698) (xy 234.019629 -227.835941) (xy 234.012486 -227.841556)
			(xy 233.989351 -227.860995) (xy 233.939284 -227.894833) (xy 233.885561 -227.922502) (xy 233.828939 -227.943611)
			(xy 233.770214 -227.957863) (xy 233.710214 -227.965058) (xy 233.68 -227.965508) (xy 233.648039 -227.965006)
			(xy 233.584621 -227.956995) (xy 233.522707 -227.941098) (xy 233.463274 -227.917566) (xy 233.407259 -227.886772)
			(xy 233.355544 -227.849199) (xy 233.308947 -227.805442) (xy 233.268202 -227.756189) (xy 233.233951 -227.702218)
			(xy 233.206734 -227.644379) (xy 233.186981 -227.583586) (xy 233.175003 -227.520796) (xy 233.17099 -227.457)
			(xy 225.936556 -227.457) (xy 225.936556 -228.575319) (xy 229.869994 -228.575319) (xy 229.869994 -228.511397)
			(xy 229.878005 -228.447979) (xy 229.893902 -228.386065) (xy 229.917434 -228.326632) (xy 229.948228 -228.270617)
			(xy 229.985801 -228.218902) (xy 230.029558 -228.172305) (xy 230.078811 -228.13156) (xy 230.132782 -228.097309)
			(xy 230.190621 -228.070092) (xy 230.251414 -228.050339) (xy 230.314204 -228.038361) (xy 230.378 -228.034348)
			(xy 230.441796 -228.038361) (xy 230.504586 -228.050339) (xy 230.565379 -228.070092) (xy 230.623218 -228.097309)
			(xy 230.677189 -228.13156) (xy 230.726442 -228.172305) (xy 230.770199 -228.218902) (xy 230.807772 -228.270617)
			(xy 230.838566 -228.326632) (xy 230.862098 -228.386065) (xy 230.877995 -228.447979) (xy 230.886006 -228.511397)
			(xy 230.886508 -228.543358) (xy 230.886006 -228.575319) (xy 230.877995 -228.638737) (xy 230.862098 -228.700651)
			(xy 230.846235 -228.740716) (xy 233.380803 -228.740716) (xy 233.384738 -228.686945) (xy 233.396461 -228.634321)
			(xy 233.415721 -228.583964) (xy 233.442107 -228.536947) (xy 233.475059 -228.494274) (xy 233.513872 -228.456853)
			(xy 233.55772 -228.425483) (xy 233.605668 -228.400831) (xy 233.656695 -228.383423) (xy 233.709713 -228.37363)
			(xy 233.763592 -228.371661) (xy 233.817183 -228.377558) (xy 233.869344 -228.391194) (xy 233.918964 -228.412281)
			(xy 233.964985 -228.440367) (xy 234.006427 -228.474855) (xy 234.042405 -228.515009) (xy 234.072153 -228.559973)
			(xy 234.095038 -228.60879) (xy 234.11057 -228.660419) (xy 234.11842 -228.713759) (xy 234.118912 -228.740716)
			(xy 234.11842 -228.767673) (xy 234.11057 -228.821013) (xy 234.095038 -228.872642) (xy 234.072153 -228.921459)
			(xy 234.042405 -228.966423) (xy 234.006427 -229.006577) (xy 233.964985 -229.041065) (xy 233.918964 -229.069151)
			(xy 233.869344 -229.090238) (xy 233.817183 -229.103874) (xy 233.763592 -229.109771) (xy 233.709713 -229.107802)
			(xy 233.656695 -229.098009) (xy 233.605668 -229.080601) (xy 233.55772 -229.055949) (xy 233.513872 -229.024579)
			(xy 233.475059 -228.987158) (xy 233.442107 -228.944485) (xy 233.415721 -228.897468) (xy 233.396461 -228.847111)
			(xy 233.384738 -228.794487) (xy 233.380803 -228.740716) (xy 230.846235 -228.740716) (xy 230.838566 -228.760084)
			(xy 230.807772 -228.816099) (xy 230.770199 -228.867814) (xy 230.726442 -228.914411) (xy 230.677189 -228.955156)
			(xy 230.623218 -228.989407) (xy 230.565379 -229.016624) (xy 230.504586 -229.036377) (xy 230.441796 -229.048355)
			(xy 230.378 -229.052369) (xy 230.314204 -229.048355) (xy 230.251414 -229.036377) (xy 230.190621 -229.016624)
			(xy 230.132782 -228.989407) (xy 230.078811 -228.955156) (xy 230.029558 -228.914411) (xy 229.985801 -228.867814)
			(xy 229.948228 -228.816099) (xy 229.917434 -228.760084) (xy 229.893902 -228.700651) (xy 229.878005 -228.638737)
			(xy 229.869994 -228.575319) (xy 225.936556 -228.575319) (xy 225.936556 -230.9096) (xy 227.677997 -230.9096)
			(xy 227.682122 -230.854559) (xy 227.694404 -230.800747) (xy 227.714569 -230.749366) (xy 227.742167 -230.701565)
			(xy 227.77658 -230.658412) (xy 227.817042 -230.620869) (xy 227.862646 -230.589776) (xy 227.912376 -230.565827)
			(xy 227.965119 -230.549557) (xy 228.019698 -230.54133) (xy 228.047296 -230.540814) (xy 228.072772 -230.541226)
			(xy 228.123244 -230.548211) (xy 228.172273 -230.562075) (xy 228.218928 -230.582555) (xy 228.262321 -230.609261)
			(xy 228.282246 -230.625142) (xy 228.290628 -230.632254) (xy 228.311202 -230.637842) (xy 228.407214 -230.623872)
			(xy 228.425248 -230.612442) (xy 228.431344 -230.603298) (xy 228.449097 -230.577641) (xy 228.489862 -230.53041)
			(xy 228.536101 -230.488521) (xy 228.587118 -230.452606) (xy 228.642146 -230.423203) (xy 228.70036 -230.400756)
			(xy 228.760882 -230.385601) (xy 228.822804 -230.377966) (xy 228.854 -230.377492) (xy 228.885961 -230.377994)
			(xy 228.949379 -230.386005) (xy 229.011293 -230.401902) (xy 229.070726 -230.425434) (xy 229.126741 -230.456228)
			(xy 229.178456 -230.493801) (xy 229.225053 -230.537558) (xy 229.265798 -230.586811) (xy 229.300049 -230.640782)
			(xy 229.327266 -230.698621) (xy 229.347019 -230.759414) (xy 229.358997 -230.822204) (xy 229.363011 -230.886)
			(xy 229.487982 -230.886) (xy 229.492053 -230.830378) (xy 229.504179 -230.775941) (xy 229.524102 -230.72385)
			(xy 229.551398 -230.675215) (xy 229.585484 -230.631072) (xy 229.625633 -230.592363) (xy 229.670991 -230.559912)
			(xy 229.720591 -230.534411) (xy 229.773375 -230.516404) (xy 229.828218 -230.506274) (xy 229.883952 -230.504237)
			(xy 229.939389 -230.510337) (xy 229.993346 -230.524443) (xy 230.044675 -230.546255) (xy 230.092281 -230.575309)
			(xy 230.135149 -230.610984) (xy 230.172366 -230.652521) (xy 230.203139 -230.699034) (xy 230.226811 -230.749531)
			(xy 230.242879 -230.802938) (xy 230.250999 -230.858114) (xy 230.251508 -230.886) (xy 230.503982 -230.886)
			(xy 230.508053 -230.830378) (xy 230.520179 -230.775941) (xy 230.540102 -230.72385) (xy 230.567398 -230.675215)
			(xy 230.601484 -230.631072) (xy 230.641633 -230.592363) (xy 230.686991 -230.559912) (xy 230.736591 -230.534411)
			(xy 230.789375 -230.516404) (xy 230.844218 -230.506274) (xy 230.899952 -230.504237) (xy 230.955389 -230.510337)
			(xy 231.009346 -230.524443) (xy 231.060675 -230.546255) (xy 231.108281 -230.575309) (xy 231.151149 -230.610984)
			(xy 231.188366 -230.652521) (xy 231.219139 -230.699034) (xy 231.242811 -230.749531) (xy 231.258879 -230.802938)
			(xy 231.266999 -230.858114) (xy 231.267508 -230.886) (xy 231.39299 -230.886) (xy 231.397003 -230.822204)
			(xy 231.408981 -230.759414) (xy 231.428734 -230.698621) (xy 231.455951 -230.640782) (xy 231.490202 -230.586811)
			(xy 231.530947 -230.537558) (xy 231.577544 -230.493801) (xy 231.629259 -230.456228) (xy 231.685274 -230.425434)
			(xy 231.744707 -230.401902) (xy 231.806621 -230.386005) (xy 231.870039 -230.377994) (xy 231.902 -230.377492)
			(xy 231.93328 -230.377911) (xy 231.995369 -230.385575) (xy 232.056047 -230.400801) (xy 232.114399 -230.423358)
			(xy 232.169542 -230.452904) (xy 232.220642 -230.488995) (xy 232.266928 -230.531083) (xy 232.307699 -230.578532)
			(xy 232.325418 -230.604314) (xy 232.33287 -230.614474) (xy 232.355001 -230.62646) (xy 232.367582 -230.627174)
			(xy 232.452418 -230.627174) (xy 232.465001 -230.626494) (xy 232.48712 -230.614472) (xy 232.494582 -230.604314)
			(xy 232.512344 -230.578567) (xy 232.553124 -230.531139) (xy 232.599411 -230.489068) (xy 232.650508 -230.45299)
			(xy 232.705642 -230.42345) (xy 232.763983 -230.400892) (xy 232.824649 -230.385657) (xy 232.886725 -230.377976)
			(xy 232.918 -230.377492) (xy 232.949131 -230.377969) (xy 233.010926 -230.385571) (xy 233.071331 -230.400661)
			(xy 233.129441 -230.423013) (xy 233.184388 -230.452293) (xy 233.235349 -230.488063) (xy 233.281561 -230.529787)
			(xy 233.302302 -230.553006) (xy 233.308652 -230.560372) (xy 233.325416 -230.569008) (xy 233.4133 -230.578914)
			(xy 233.431588 -230.573834) (xy 233.439462 -230.567992) (xy 233.463424 -230.551028) (xy 233.51558 -230.524078)
			(xy 233.571344 -230.505723) (xy 233.62931 -230.496425) (xy 233.658664 -230.495856) (xy 233.686265 -230.496416)
			(xy 233.74085 -230.504638) (xy 233.7936 -230.520905) (xy 233.826947 -230.536961) (xy 234.568994 -230.536961)
			(xy 234.568994 -230.473039) (xy 234.577005 -230.409621) (xy 234.592902 -230.347707) (xy 234.616434 -230.288274)
			(xy 234.647228 -230.232259) (xy 234.684801 -230.180544) (xy 234.728558 -230.133947) (xy 234.777811 -230.093202)
			(xy 234.831782 -230.058951) (xy 234.889621 -230.031734) (xy 234.950414 -230.011981) (xy 235.013204 -230.000003)
			(xy 235.077 -229.99599) (xy 235.140796 -230.000003) (xy 235.203586 -230.011981) (xy 235.264379 -230.031734)
			(xy 235.322218 -230.058951) (xy 235.376189 -230.093202) (xy 235.425442 -230.133947) (xy 235.469199 -230.180544)
			(xy 235.506772 -230.232259) (xy 235.537566 -230.288274) (xy 235.561098 -230.347707) (xy 235.576995 -230.409621)
			(xy 235.585006 -230.473039) (xy 235.585508 -230.505) (xy 235.585006 -230.536961) (xy 237.870994 -230.536961)
			(xy 237.870994 -230.473039) (xy 237.879005 -230.409621) (xy 237.894902 -230.347707) (xy 237.918434 -230.288274)
			(xy 237.949228 -230.232259) (xy 237.986801 -230.180544) (xy 238.030558 -230.133947) (xy 238.079811 -230.093202)
			(xy 238.133782 -230.058951) (xy 238.191621 -230.031734) (xy 238.252414 -230.011981) (xy 238.315204 -230.000003)
			(xy 238.379 -229.99599) (xy 238.442796 -230.000003) (xy 238.505586 -230.011981) (xy 238.566379 -230.031734)
			(xy 238.624218 -230.058951) (xy 238.678189 -230.093202) (xy 238.727442 -230.133947) (xy 238.771199 -230.180544)
			(xy 238.808772 -230.232259) (xy 238.839566 -230.288274) (xy 238.863098 -230.347707) (xy 238.878995 -230.409621)
			(xy 238.887006 -230.473039) (xy 238.887508 -230.505) (xy 238.887006 -230.536961) (xy 238.878995 -230.600379)
			(xy 238.863098 -230.662293) (xy 238.839566 -230.721726) (xy 238.808772 -230.777741) (xy 238.771199 -230.829456)
			(xy 238.727442 -230.876053) (xy 238.678189 -230.916798) (xy 238.624218 -230.951049) (xy 238.566379 -230.978266)
			(xy 238.505586 -230.998019) (xy 238.442796 -231.009997) (xy 238.379 -231.014011) (xy 238.315204 -231.009997)
			(xy 238.252414 -230.998019) (xy 238.191621 -230.978266) (xy 238.133782 -230.951049) (xy 238.079811 -230.916798)
			(xy 238.030558 -230.876053) (xy 237.986801 -230.829456) (xy 237.949228 -230.777741) (xy 237.918434 -230.721726)
			(xy 237.894902 -230.662293) (xy 237.879005 -230.600379) (xy 237.870994 -230.536961) (xy 235.585006 -230.536961)
			(xy 235.576995 -230.600379) (xy 235.561098 -230.662293) (xy 235.537566 -230.721726) (xy 235.506772 -230.777741)
			(xy 235.469199 -230.829456) (xy 235.425442 -230.876053) (xy 235.376189 -230.916798) (xy 235.322218 -230.951049)
			(xy 235.264379 -230.978266) (xy 235.203586 -230.998019) (xy 235.140796 -231.009997) (xy 235.077 -231.014011)
			(xy 235.013204 -231.009997) (xy 234.950414 -230.998019) (xy 234.889621 -230.978266) (xy 234.831782 -230.951049)
			(xy 234.777811 -230.916798) (xy 234.728558 -230.876053) (xy 234.684801 -230.829456) (xy 234.647228 -230.777741)
			(xy 234.616434 -230.721726) (xy 234.592902 -230.662293) (xy 234.577005 -230.600379) (xy 234.568994 -230.536961)
			(xy 233.826947 -230.536961) (xy 233.843336 -230.544852) (xy 233.888948 -230.575945) (xy 233.929415 -230.61349)
			(xy 233.963834 -230.656646) (xy 233.991436 -230.704451) (xy 234.011605 -230.755836) (xy 234.023889 -230.809653)
			(xy 234.028015 -230.8647) (xy 234.023889 -230.919747) (xy 234.011605 -230.973564) (xy 233.991436 -231.024949)
			(xy 233.963834 -231.072754) (xy 233.929415 -231.11591) (xy 233.888948 -231.153455) (xy 233.843336 -231.184548)
			(xy 233.7936 -231.208495) (xy 233.74085 -231.224762) (xy 233.686265 -231.232984) (xy 233.658664 -231.233472)
			(xy 233.631941 -231.232999) (xy 233.579054 -231.225281) (xy 233.527835 -231.210011) (xy 233.479356 -231.187508)
			(xy 233.456734 -231.173274) (xy 233.448606 -231.16794) (xy 233.430064 -231.16413) (xy 233.342942 -231.178862)
			(xy 233.326686 -231.188768) (xy 233.320844 -231.196388) (xy 233.300159 -231.222392) (xy 233.253082 -231.269284)
			(xy 233.2003 -231.309647) (xy 233.142712 -231.342795) (xy 233.081298 -231.368162) (xy 233.017104 -231.385318)
			(xy 232.951223 -231.393969) (xy 232.918 -231.394508) (xy 232.88672 -231.394089) (xy 232.824631 -231.386425)
			(xy 232.763953 -231.371199) (xy 232.705601 -231.348642) (xy 232.650458 -231.319096) (xy 232.599358 -231.283005)
			(xy 232.553072 -231.240917) (xy 232.512301 -231.193468) (xy 232.494582 -231.167686) (xy 232.48713 -231.157526)
			(xy 232.464999 -231.14554) (xy 232.452418 -231.144826) (xy 232.367582 -231.144826) (xy 232.354999 -231.145506)
			(xy 232.33288 -231.157528) (xy 232.325418 -231.167686) (xy 232.307656 -231.193433) (xy 232.266876 -231.240861)
			(xy 232.220589 -231.282932) (xy 232.169492 -231.31901) (xy 232.114358 -231.34855) (xy 232.056017 -231.371108)
			(xy 231.995351 -231.386343) (xy 231.933275 -231.394024) (xy 231.902 -231.394508) (xy 231.870039 -231.394006)
			(xy 231.806621 -231.385995) (xy 231.744707 -231.370098) (xy 231.685274 -231.346566) (xy 231.629259 -231.315772)
			(xy 231.577544 -231.278199) (xy 231.530947 -231.234442) (xy 231.490202 -231.185189) (xy 231.455951 -231.131218)
			(xy 231.428734 -231.073379) (xy 231.408981 -231.012586) (xy 231.397003 -230.949796) (xy 231.39299 -230.886)
			(xy 231.267508 -230.886) (xy 231.266999 -230.913886) (xy 231.258879 -230.969062) (xy 231.242811 -231.022469)
			(xy 231.219139 -231.072966) (xy 231.188366 -231.119479) (xy 231.151149 -231.161016) (xy 231.108281 -231.196691)
			(xy 231.060675 -231.225745) (xy 231.009346 -231.247557) (xy 230.955389 -231.261663) (xy 230.899952 -231.267763)
			(xy 230.844218 -231.265726) (xy 230.789375 -231.255596) (xy 230.736591 -231.237589) (xy 230.686991 -231.212088)
			(xy 230.641633 -231.179637) (xy 230.601484 -231.140928) (xy 230.567398 -231.096785) (xy 230.540102 -231.04815)
			(xy 230.520179 -230.996059) (xy 230.508053 -230.941622) (xy 230.503982 -230.886) (xy 230.251508 -230.886)
			(xy 230.250999 -230.913886) (xy 230.242879 -230.969062) (xy 230.226811 -231.022469) (xy 230.203139 -231.072966)
			(xy 230.172366 -231.119479) (xy 230.135149 -231.161016) (xy 230.092281 -231.196691) (xy 230.044675 -231.225745)
			(xy 229.993346 -231.247557) (xy 229.939389 -231.261663) (xy 229.883952 -231.267763) (xy 229.828218 -231.265726)
			(xy 229.773375 -231.255596) (xy 229.720591 -231.237589) (xy 229.670991 -231.212088) (xy 229.625633 -231.179637)
			(xy 229.585484 -231.140928) (xy 229.551398 -231.096785) (xy 229.524102 -231.04815) (xy 229.504179 -230.996059)
			(xy 229.492053 -230.941622) (xy 229.487982 -230.886) (xy 229.363011 -230.886) (xy 229.358997 -230.949796)
			(xy 229.347019 -231.012586) (xy 229.327266 -231.073379) (xy 229.300049 -231.131218) (xy 229.265798 -231.185189)
			(xy 229.225053 -231.234442) (xy 229.178456 -231.278199) (xy 229.126741 -231.315772) (xy 229.070726 -231.346566)
			(xy 229.011293 -231.370098) (xy 228.949379 -231.385995) (xy 228.885961 -231.394006) (xy 228.854 -231.394508)
			(xy 228.820467 -231.393993) (xy 228.753982 -231.385171) (xy 228.689236 -231.367682) (xy 228.627352 -231.341829)
			(xy 228.569406 -231.308061) (xy 228.516405 -231.266965) (xy 228.46927 -231.219255) (xy 228.448616 -231.192832)
			(xy 228.442012 -231.184196) (xy 228.423216 -231.173782) (xy 228.326442 -231.1654) (xy 228.306376 -231.172258)
			(xy 228.298248 -231.179878) (xy 228.277671 -231.198302) (xy 228.232051 -231.229433) (xy 228.182297 -231.253412)
			(xy 228.129524 -231.269702) (xy 228.074911 -231.277939) (xy 228.047296 -231.27843) (xy 228.019698 -231.27787)
			(xy 227.965119 -231.269643) (xy 227.912376 -231.253373) (xy 227.862646 -231.229424) (xy 227.817042 -231.198331)
			(xy 227.77658 -231.160788) (xy 227.742167 -231.117635) (xy 227.714569 -231.069834) (xy 227.694404 -231.018453)
			(xy 227.682122 -230.964641) (xy 227.677997 -230.9096) (xy 225.936556 -230.9096) (xy 225.936556 -233.299)
			(xy 229.361492 -233.299) (xy 229.361994 -233.267039) (xy 229.370005 -233.203621) (xy 229.385902 -233.141707)
			(xy 229.409434 -233.082274) (xy 229.440228 -233.026259) (xy 229.477801 -232.974544) (xy 229.521558 -232.927947)
			(xy 229.570811 -232.887202) (xy 229.624782 -232.852951) (xy 229.682621 -232.825734) (xy 229.743414 -232.805981)
			(xy 229.806204 -232.794003) (xy 229.87 -232.78999) (xy 229.933796 -232.794003) (xy 229.996586 -232.805981)
			(xy 230.057379 -232.825734) (xy 230.115218 -232.852951) (xy 230.169189 -232.887202) (xy 230.218442 -232.927947)
			(xy 230.262199 -232.974544) (xy 230.299772 -233.026259) (xy 230.330566 -233.082274) (xy 230.354098 -233.141707)
			(xy 230.369995 -233.203621) (xy 230.378006 -233.267039) (xy 230.378508 -233.299) (xy 232.40899 -233.299)
			(xy 232.413003 -233.235204) (xy 232.424981 -233.172414) (xy 232.444734 -233.111621) (xy 232.471951 -233.053782)
			(xy 232.506202 -232.999811) (xy 232.546947 -232.950558) (xy 232.593544 -232.906801) (xy 232.645259 -232.869228)
			(xy 232.701274 -232.838434) (xy 232.760707 -232.814902) (xy 232.822621 -232.799005) (xy 232.886039 -232.790994)
			(xy 232.918 -232.790492) (xy 232.948418 -232.79091) (xy 232.949165 -232.791) (xy 234.56799 -232.791)
			(xy 234.572003 -232.727204) (xy 234.583981 -232.664414) (xy 234.603734 -232.603621) (xy 234.630951 -232.545782)
			(xy 234.665202 -232.491811) (xy 234.705947 -232.442558) (xy 234.752544 -232.398801) (xy 234.804259 -232.361228)
			(xy 234.860274 -232.330434) (xy 234.919707 -232.306902) (xy 234.981621 -232.291005) (xy 235.045039 -232.282994)
			(xy 235.077 -232.282492) (xy 235.10828 -232.282911) (xy 235.170369 -232.290575) (xy 235.231047 -232.305801)
			(xy 235.289399 -232.328358) (xy 235.344542 -232.357904) (xy 235.395642 -232.393995) (xy 235.441928 -232.436083)
			(xy 235.482699 -232.483532) (xy 235.500418 -232.509314) (xy 235.50787 -232.519474) (xy 235.530001 -232.53146)
			(xy 235.542582 -232.532174) (xy 235.627418 -232.532174) (xy 235.640001 -232.531494) (xy 235.66212 -232.519472)
			(xy 235.669582 -232.509314) (xy 235.688378 -232.483152) (xy 235.694982 -232.474262) (xy 235.699808 -232.453434)
			(xy 235.681266 -232.357422) (xy 235.66882 -232.339896) (xy 235.659422 -232.334308) (xy 235.636256 -232.319928)
			(xy 235.593997 -232.285477) (xy 235.557273 -232.245178) (xy 235.526883 -232.199911) (xy 235.50349 -232.150662)
			(xy 235.487605 -232.098505) (xy 235.479574 -232.044577) (xy 235.479082 -232.017316) (xy 235.479598 -231.989716)
			(xy 235.487825 -231.935133) (xy 235.504095 -231.882386) (xy 235.528045 -231.832654) (xy 235.55914 -231.787046)
			(xy 235.596685 -231.746582) (xy 235.639842 -231.712165) (xy 235.687646 -231.684566) (xy 235.73903 -231.664399)
			(xy 235.792845 -231.652116) (xy 235.84789 -231.647991) (xy 235.902935 -231.652116) (xy 235.95675 -231.664399)
			(xy 236.008134 -231.684566) (xy 236.055938 -231.712165) (xy 236.099095 -231.746582) (xy 236.13664 -231.787046)
			(xy 236.167735 -231.832654) (xy 236.191685 -231.882386) (xy 236.207955 -231.935133) (xy 236.216182 -231.989716)
			(xy 236.216698 -232.017316) (xy 236.216236 -232.043191) (xy 236.20898 -232.094429) (xy 236.194625 -232.144148)
			(xy 236.18444 -232.167938) (xy 236.180122 -232.178098) (xy 236.180122 -232.199434) (xy 236.22 -232.288588)
			(xy 236.236002 -232.302812) (xy 236.24667 -232.306368) (xy 236.278494 -232.317004) (xy 236.339241 -232.345507)
			(xy 236.395709 -232.381755) (xy 236.446917 -232.425119) (xy 236.491973 -232.474843) (xy 236.530094 -232.530064)
			(xy 236.560617 -232.589822) (xy 236.583012 -232.653075) (xy 236.596889 -232.718726) (xy 236.599984 -232.752138)
			(xy 236.600746 -232.761536) (xy 236.608874 -232.778808) (xy 236.673136 -232.838752) (xy 236.690662 -232.845864)
			(xy 236.700314 -232.845864) (xy 236.710756 -232.846045) (xy 236.731597 -232.847443) (xy 236.74197 -232.848658)
			(xy 236.752638 -232.849928) (xy 236.772196 -232.84434) (xy 236.845602 -232.783888) (xy 236.855 -232.7656)
			(xy 236.855762 -232.754932) (xy 236.858517 -232.723259) (xy 236.870897 -232.660899) (xy 236.890954 -232.600569)
			(xy 236.918375 -232.54321) (xy 236.952732 -232.489716) (xy 236.99349 -232.440923) (xy 237.040013 -232.397591)
			(xy 237.091574 -232.360396) (xy 237.14737 -232.329919) (xy 237.20653 -232.306636) (xy 237.268131 -232.290909)
			(xy 237.331212 -232.282983) (xy 237.363 -232.282492) (xy 237.39428 -232.282911) (xy 237.456369 -232.290575)
			(xy 237.517047 -232.305801) (xy 237.575399 -232.328358) (xy 237.630542 -232.357904) (xy 237.681642 -232.393995)
			(xy 237.727928 -232.436083) (xy 237.768699 -232.483532) (xy 237.786418 -232.509314) (xy 237.79387 -232.519474)
			(xy 237.816001 -232.53146) (xy 237.828582 -232.532174) (xy 237.913418 -232.532174) (xy 237.926001 -232.531494)
			(xy 237.94812 -232.519472) (xy 237.955582 -232.509314) (xy 237.973344 -232.483567) (xy 238.014124 -232.436139)
			(xy 238.060411 -232.394068) (xy 238.111508 -232.35799) (xy 238.166642 -232.32845) (xy 238.224983 -232.305892)
			(xy 238.285649 -232.290657) (xy 238.347725 -232.282976) (xy 238.379 -232.282492) (xy 238.409054 -232.282917)
			(xy 238.468742 -232.290014) (xy 238.527178 -232.304096) (xy 238.583546 -232.324968) (xy 238.637062 -232.352338)
			(xy 238.686978 -232.385826) (xy 238.732599 -232.424963) (xy 238.773289 -232.469205) (xy 238.791242 -232.493312)
			(xy 238.798608 -232.503472) (xy 238.821722 -232.514648) (xy 238.931704 -232.51033) (xy 238.953802 -232.497376)
			(xy 238.960406 -232.486454) (xy 238.97774 -232.458852) (xy 239.018399 -232.407909) (xy 239.065237 -232.362582)
			(xy 239.117487 -232.323615) (xy 239.174289 -232.291648) (xy 239.234712 -232.267205) (xy 239.297764 -232.250688)
			(xy 239.36241 -232.242367) (xy 239.395 -232.241852) (xy 239.427784 -232.242333) (xy 239.492809 -232.250762)
			(xy 239.55621 -232.267479) (xy 239.616937 -232.292207) (xy 239.673981 -232.324536) (xy 239.726397 -232.36393)
			(xy 239.773313 -232.409735) (xy 239.794034 -232.435146) (xy 239.801908 -232.445306) (xy 239.825276 -232.455212)
			(xy 239.935766 -232.44556) (xy 239.957102 -232.43159) (xy 239.963198 -232.42016) (xy 239.978043 -232.393576)
			(xy 240.013068 -232.343771) (xy 240.053791 -232.298505) (xy 240.099628 -232.258426) (xy 240.149924 -232.224108)
			(xy 240.203958 -232.196043) (xy 240.260957 -232.174631) (xy 240.320105 -232.16018) (xy 240.380556 -232.152897)
			(xy 240.411 -232.152444) (xy 240.443613 -232.152974) (xy 240.508305 -232.161303) (xy 240.5714 -232.177837)
			(xy 240.631863 -232.202305) (xy 240.6887 -232.234304) (xy 240.740978 -232.27331) (xy 240.787838 -232.318681)
			(xy 240.828511 -232.369672) (xy 240.845848 -232.3973) (xy 240.852452 -232.408222) (xy 240.874296 -232.421176)
			(xy 240.984532 -232.425494) (xy 241.007392 -232.414572) (xy 241.015012 -232.404158) (xy 241.03237 -232.380874)
			(xy 241.071536 -232.33799) (xy 241.115326 -232.29984) (xy 241.163172 -232.266919) (xy 241.214452 -232.239654)
			(xy 241.241326 -232.228644) (xy 241.249512 -232.224949) (xy 241.262899 -232.212996) (xy 241.267488 -232.205276)
			(xy 241.281712 -232.178352) (xy 241.285615 -232.17031) (xy 241.288082 -232.152614) (xy 241.286538 -232.143808)
			(xy 241.282719 -232.124733) (xy 241.278647 -232.086044) (xy 241.27841 -232.066592) (xy 241.278863 -232.041469)
			(xy 241.285678 -231.991687) (xy 241.299196 -231.943293) (xy 241.319164 -231.897185) (xy 241.345214 -231.854218)
			(xy 241.360706 -231.834436) (xy 241.367818 -231.825546) (xy 241.373152 -231.804718) (xy 241.356134 -231.707182)
			(xy 241.343942 -231.689148) (xy 241.33429 -231.683306) (xy 241.306559 -231.666004) (xy 241.255376 -231.625352)
			(xy 241.209823 -231.578476) (xy 241.170653 -231.526149) (xy 241.138512 -231.469235) (xy 241.113928 -231.40867)
			(xy 241.097308 -231.345455) (xy 241.088926 -231.280632) (xy 241.088418 -231.24795) (xy 241.08892 -231.215989)
			(xy 241.096931 -231.152571) (xy 241.112828 -231.090657) (xy 241.13636 -231.031224) (xy 241.167154 -230.975209)
			(xy 241.204727 -230.923494) (xy 241.248484 -230.876897) (xy 241.297737 -230.836152) (xy 241.351708 -230.801901)
			(xy 241.409547 -230.774684) (xy 241.47034 -230.754931) (xy 241.53313 -230.742953) (xy 241.596926 -230.73894)
			(xy 241.660722 -230.742953) (xy 241.723512 -230.754931) (xy 241.784305 -230.774684) (xy 241.842144 -230.801901)
			(xy 241.896115 -230.836152) (xy 241.945368 -230.876897) (xy 241.989125 -230.923494) (xy 242.026698 -230.975209)
			(xy 242.057492 -231.031224) (xy 242.081024 -231.090657) (xy 242.096921 -231.152571) (xy 242.104932 -231.215989)
			(xy 242.105434 -231.24795) (xy 242.104927 -231.28085) (xy 242.096445 -231.346102) (xy 242.079616 -231.409713)
			(xy 242.054721 -231.470623) (xy 242.022176 -231.527811) (xy 241.982526 -231.580324) (xy 241.936433 -231.627282)
			(xy 241.91087 -231.648) (xy 241.90198 -231.654858) (xy 241.892074 -231.674162) (xy 241.886994 -231.772968)
			(xy 241.895122 -231.793288) (xy 241.90325 -231.800908) (xy 241.924211 -231.821919) (xy 241.959778 -231.869426)
			(xy 241.987276 -231.922016) (xy 242.005997 -231.978332) (xy 242.015456 -232.036919) (xy 242.016026 -232.066592)
			(xy 242.015572 -232.09359) (xy 242.007682 -232.147007) (xy 241.992084 -232.198701) (xy 241.969112 -232.247568)
			(xy 241.939258 -232.29256) (xy 241.90316 -232.332716) (xy 241.882676 -232.35031) (xy 241.876057 -232.35633)
			(xy 241.867098 -232.371803) (xy 241.86515 -232.380536) (xy 241.859816 -232.410508) (xy 241.858562 -232.419416)
			(xy 241.861671 -232.43712) (xy 241.865912 -232.445052) (xy 241.865912 -232.445306) (xy 241.87091 -232.453042)
			(xy 241.885213 -232.46462) (xy 241.902677 -232.470422) (xy 241.911886 -232.470452) (xy 241.941096 -232.469182)
			(xy 241.950245 -232.468383) (xy 241.967134 -232.46121) (xy 241.980432 -232.448566) (xy 241.984784 -232.44048)
			(xy 241.998989 -232.412117) (xy 242.033384 -232.358818) (xy 242.074142 -232.310212) (xy 242.120629 -232.267053)
			(xy 242.172124 -232.230011) (xy 242.227827 -232.199663) (xy 242.286872 -232.17648) (xy 242.348342 -232.160821)
			(xy 242.411283 -232.152931) (xy 242.443 -232.152444) (xy 242.474958 -232.153042) (xy 242.53837 -232.161053)
			(xy 242.600278 -232.176948) (xy 242.659706 -232.200477) (xy 242.715716 -232.231269) (xy 242.767425 -232.268838)
			(xy 242.814018 -232.312591) (xy 242.854759 -232.361839) (xy 242.889007 -232.415805) (xy 242.916221 -232.473638)
			(xy 242.935973 -232.534426) (xy 242.947949 -232.59721) (xy 242.951963 -232.661) (xy 242.947949 -232.72479)
			(xy 242.935973 -232.787574) (xy 242.916221 -232.848362) (xy 242.889007 -232.906195) (xy 242.854759 -232.960161)
			(xy 242.814018 -233.009409) (xy 242.767425 -233.053162) (xy 242.715716 -233.090731) (xy 242.659706 -233.121523)
			(xy 242.600278 -233.145052) (xy 242.53837 -233.160947) (xy 242.474958 -233.168958) (xy 242.443 -233.16946)
			(xy 242.412968 -233.169013) (xy 242.353323 -233.161944) (xy 242.294927 -233.147893) (xy 242.238594 -233.127055)
			(xy 242.185111 -233.099721) (xy 242.135223 -233.066273) (xy 242.089627 -233.027177) (xy 242.048957 -232.982979)
			(xy 242.031012 -232.958894) (xy 242.023392 -232.94848) (xy 242.000532 -232.937558) (xy 241.890296 -232.941876)
			(xy 241.868452 -232.95483) (xy 241.861848 -232.965752) (xy 241.844493 -232.993369) (xy 241.803822 -233.044362)
			(xy 241.756964 -233.089735) (xy 241.70469 -233.128745) (xy 241.647856 -233.16075) (xy 241.587396 -233.185226)
			(xy 241.524303 -233.201769) (xy 241.459613 -233.21011) (xy 241.394387 -233.21011) (xy 241.329697 -233.201769)
			(xy 241.266604 -233.185226) (xy 241.206144 -233.16075) (xy 241.14931 -233.128745) (xy 241.097036 -233.089735)
			(xy 241.050178 -233.044362) (xy 241.009507 -232.993369) (xy 240.992152 -232.965752) (xy 240.985548 -232.95483)
			(xy 240.963704 -232.941876) (xy 240.853468 -232.937558) (xy 240.830608 -232.94848) (xy 240.822988 -232.958894)
			(xy 240.80505 -232.982983) (xy 240.764374 -233.027176) (xy 240.718773 -233.066267) (xy 240.668884 -233.099712)
			(xy 240.615401 -233.127045) (xy 240.55907 -233.147885) (xy 240.500675 -233.161942) (xy 240.441031 -233.16902)
			(xy 240.411 -233.16946) (xy 240.378216 -233.168974) (xy 240.313192 -233.160546) (xy 240.24979 -233.143829)
			(xy 240.189064 -233.119102) (xy 240.13202 -233.086773) (xy 240.079604 -233.04738) (xy 240.032687 -233.001576)
			(xy 240.011966 -232.976166) (xy 240.004092 -232.966006) (xy 239.980724 -232.9561) (xy 239.870234 -232.965752)
			(xy 239.848898 -232.979722) (xy 239.842802 -232.991152) (xy 239.827962 -233.017739) (xy 239.792935 -233.067544)
			(xy 239.752212 -233.112809) (xy 239.706374 -233.152888) (xy 239.656078 -233.187205) (xy 239.602043 -233.21527)
			(xy 239.545044 -233.236681) (xy 239.485895 -233.251132) (xy 239.425444 -233.258415) (xy 239.395 -233.258868)
			(xy 239.377802 -233.258745) (xy 239.343482 -233.256457) (xy 239.32642 -233.254296) (xy 239.317309 -233.253391)
			(xy 239.299467 -233.257447) (xy 239.291622 -233.26217) (xy 239.265968 -233.279188) (xy 239.25866 -233.284415)
			(xy 239.247992 -233.298861) (xy 239.24514 -233.307382) (xy 239.237442 -233.332736) (xy 239.215744 -233.381078)
			(xy 239.187351 -233.425815) (xy 239.152846 -233.466029) (xy 239.112941 -233.500889) (xy 239.068457 -233.529678)
			(xy 239.02031 -233.551804) (xy 238.969492 -233.56681) (xy 238.91705 -233.574388) (xy 238.890556 -233.574844)
			(xy 238.862848 -233.574324) (xy 238.808056 -233.566027) (xy 238.755121 -233.549626) (xy 238.705237 -233.52549)
			(xy 238.659525 -233.494162) (xy 238.619014 -233.456348) (xy 238.584616 -233.412899) (xy 238.557106 -233.364792)
			(xy 238.54664 -233.339132) (xy 238.543173 -233.331143) (xy 238.531891 -233.317894) (xy 238.524542 -233.313224)
			(xy 238.49838 -233.298238) (xy 238.490595 -233.294166) (xy 238.473316 -233.291052) (xy 238.464598 -233.292142)
			(xy 238.443363 -233.295559) (xy 238.400507 -233.299248) (xy 238.379 -233.299508) (xy 238.34772 -233.299089)
			(xy 238.285631 -233.291425) (xy 238.224953 -233.276199) (xy 238.166601 -233.253642) (xy 238.111458 -233.224096)
			(xy 238.060358 -233.188005) (xy 238.014072 -233.145917) (xy 237.973301 -233.098468) (xy 237.955582 -233.072686)
			(xy 237.94813 -233.062526) (xy 237.925999 -233.05054) (xy 237.913418 -233.049826) (xy 237.828582 -233.049826)
			(xy 237.815999 -233.050506) (xy 237.79388 -233.062528) (xy 237.786418 -233.072686) (xy 237.768656 -233.098433)
			(xy 237.727876 -233.145861) (xy 237.681589 -233.187932) (xy 237.630492 -233.22401) (xy 237.575358 -233.25355)
			(xy 237.517017 -233.276108) (xy 237.456351 -233.291343) (xy 237.394275 -233.299024) (xy 237.363 -233.299508)
			(xy 237.33186 -233.299076) (xy 237.27004 -233.291524) (xy 237.20961 -233.276459) (xy 237.180374 -233.265726)
			(xy 237.170468 -233.261916) (xy 237.149894 -233.262678) (xy 237.064296 -233.303318) (xy 237.050834 -233.318812)
			(xy 237.047532 -233.328972) (xy 237.039097 -233.353299) (xy 237.016482 -233.399555) (xy 236.987655 -233.442215)
			(xy 236.953174 -233.480452) (xy 236.913711 -233.513522) (xy 236.870033 -233.540783) (xy 236.822987 -233.561705)
			(xy 236.77349 -233.575881) (xy 236.722502 -233.583035) (xy 236.696758 -233.58348) (xy 236.668756 -233.582935)
			(xy 236.613399 -233.574454) (xy 236.559957 -233.55771) (xy 236.509658 -233.533085) (xy 236.463655 -233.501145)
			(xy 236.423004 -233.462624) (xy 236.388639 -233.418404) (xy 236.361346 -233.369501) (xy 236.351064 -233.34345)
			(xy 236.347762 -233.33456) (xy 236.335316 -233.320336) (xy 236.25683 -233.280458) (xy 236.238034 -233.278426)
			(xy 236.22889 -233.280966) (xy 236.195586 -233.289622) (xy 236.127406 -233.298922) (xy 236.093 -233.299508)
			(xy 236.06172 -233.299089) (xy 235.999631 -233.291425) (xy 235.938953 -233.276199) (xy 235.880601 -233.253642)
			(xy 235.825458 -233.224096) (xy 235.774358 -233.188005) (xy 235.728072 -233.145917) (xy 235.687301 -233.098468)
			(xy 235.669582 -233.072686) (xy 235.66213 -233.062526) (xy 235.639999 -233.05054) (xy 235.627418 -233.049826)
			(xy 235.542582 -233.049826) (xy 235.529999 -233.050506) (xy 235.50788 -233.062528) (xy 235.500418 -233.072686)
			(xy 235.482656 -233.098433) (xy 235.441876 -233.145861) (xy 235.395589 -233.187932) (xy 235.344492 -233.22401)
			(xy 235.289358 -233.25355) (xy 235.231017 -233.276108) (xy 235.170351 -233.291343) (xy 235.108275 -233.299024)
			(xy 235.077 -233.299508) (xy 235.045039 -233.299006) (xy 234.981621 -233.290995) (xy 234.919707 -233.275098)
			(xy 234.860274 -233.251566) (xy 234.804259 -233.220772) (xy 234.752544 -233.183199) (xy 234.705947 -233.139442)
			(xy 234.665202 -233.090189) (xy 234.630951 -233.036218) (xy 234.603734 -232.978379) (xy 234.583981 -232.917586)
			(xy 234.572003 -232.854796) (xy 234.56799 -232.791) (xy 232.949165 -232.791) (xy 233.008819 -232.798183)
			(xy 233.06792 -232.812613) (xy 233.124876 -232.833994) (xy 233.178873 -232.86202) (xy 233.229139 -232.896291)
			(xy 233.274955 -232.936316) (xy 233.315667 -232.981523) (xy 233.333544 -233.006138) (xy 233.340656 -233.016044)
			(xy 233.361484 -233.02722) (xy 233.466894 -233.030522) (xy 233.488484 -233.020616) (xy 233.496104 -233.010964)
			(xy 233.513737 -232.989822) (xy 233.554158 -232.952452) (xy 233.599686 -232.921507) (xy 233.64931 -232.897675)
			(xy 233.701924 -232.881486) (xy 233.756361 -232.873299) (xy 233.783886 -232.872788) (xy 233.810231 -232.873253)
			(xy 233.862385 -232.88075) (xy 233.912942 -232.895593) (xy 233.960871 -232.917479) (xy 234.005198 -232.945965)
			(xy 234.045019 -232.980468) (xy 234.079525 -233.020288) (xy 234.108012 -233.064613) (xy 234.129901 -233.112542)
			(xy 234.144746 -233.163097) (xy 234.152246 -233.215251) (xy 234.152694 -233.241596) (xy 234.152273 -233.26664)
			(xy 234.145479 -233.316265) (xy 234.13203 -233.364513) (xy 234.112173 -233.410496) (xy 234.086273 -233.453368)
			(xy 234.054808 -233.492339) (xy 234.03687 -233.50982) (xy 234.026964 -233.519218) (xy 234.019344 -233.54538)
			(xy 234.046014 -233.657648) (xy 234.06481 -233.67746) (xy 234.078018 -233.68127) (xy 234.109206 -233.690948)
			(xy 234.168951 -233.71731) (xy 234.22483 -233.751104) (xy 234.275923 -233.791774) (xy 234.321389 -233.83865)
			(xy 234.36048 -233.89096) (xy 234.392552 -233.947845) (xy 234.417078 -234.008367) (xy 234.433655 -234.071532)
			(xy 234.442008 -234.136298) (xy 234.442508 -234.16895) (xy 234.442006 -234.200911) (xy 234.433995 -234.264329)
			(xy 234.418098 -234.326243) (xy 234.394566 -234.385676) (xy 234.363772 -234.441691) (xy 234.326199 -234.493406)
			(xy 234.282442 -234.540003) (xy 234.233189 -234.580748) (xy 234.179218 -234.614999) (xy 234.121379 -234.642216)
			(xy 234.060586 -234.661969) (xy 233.997796 -234.673947) (xy 233.934 -234.677961) (xy 233.870204 -234.673947)
			(xy 233.807414 -234.661969) (xy 233.746621 -234.642216) (xy 233.688782 -234.614999) (xy 233.634811 -234.580748)
			(xy 233.585558 -234.540003) (xy 233.541801 -234.493406) (xy 233.504228 -234.441691) (xy 233.473434 -234.385676)
			(xy 233.449902 -234.326243) (xy 233.434005 -234.264329) (xy 233.425994 -234.200911) (xy 233.425492 -234.16895)
			(xy 233.425959 -234.138339) (xy 233.433319 -234.077561) (xy 233.447926 -234.018107) (xy 233.469568 -233.960838)
			(xy 233.497933 -233.906583) (xy 233.532609 -233.856128) (xy 233.573095 -233.810204) (xy 233.618804 -233.769475)
			(xy 233.643678 -233.751628) (xy 233.654854 -233.743754) (xy 233.666284 -233.719116) (xy 233.656378 -233.604054)
			(xy 233.640884 -233.581702) (xy 233.628438 -233.576114) (xy 233.601217 -233.562775) (xy 233.551178 -233.528567)
			(xy 233.52887 -233.508042) (xy 233.520234 -233.49966) (xy 233.497628 -233.492802) (xy 233.393488 -233.50982)
			(xy 233.374438 -233.52379) (xy 233.368596 -233.534458) (xy 233.353989 -233.561556) (xy 233.319106 -233.612283)
			(xy 233.278353 -233.658427) (xy 233.232326 -233.699312) (xy 233.181698 -233.734339) (xy 233.127211 -233.762997)
			(xy 233.069663 -233.784866) (xy 233.009895 -233.799625) (xy 232.948782 -233.807059) (xy 232.918 -233.807508)
			(xy 232.886039 -233.807006) (xy 232.822621 -233.798995) (xy 232.760707 -233.783098) (xy 232.701274 -233.759566)
			(xy 232.645259 -233.728772) (xy 232.593544 -233.691199) (xy 232.546947 -233.647442) (xy 232.506202 -233.598189)
			(xy 232.471951 -233.544218) (xy 232.444734 -233.486379) (xy 232.424981 -233.425586) (xy 232.413003 -233.362796)
			(xy 232.40899 -233.299) (xy 230.378508 -233.299) (xy 230.378096 -233.329343) (xy 230.370866 -233.389597)
			(xy 230.356521 -233.448563) (xy 230.335264 -233.505404) (xy 230.307397 -233.559313) (xy 230.273316 -233.609525)
			(xy 230.233504 -233.655327) (xy 230.188527 -233.696068) (xy 230.139024 -233.731171) (xy 230.11257 -233.74604)
			(xy 230.10241 -233.751374) (xy 230.089202 -233.769662) (xy 230.069898 -233.86923) (xy 230.075486 -233.891074)
			(xy 230.082852 -233.899964) (xy 230.098806 -233.919877) (xy 230.125596 -233.963305) (xy 230.146137 -234.010013)
			(xy 230.160035 -234.05911) (xy 230.167026 -234.109655) (xy 230.167434 -234.135168) (xy 230.166918 -234.162768)
			(xy 230.158691 -234.217351) (xy 230.142421 -234.270098) (xy 230.118471 -234.319831) (xy 230.087376 -234.365438)
			(xy 230.049831 -234.405902) (xy 230.006674 -234.440319) (xy 229.95887 -234.467918) (xy 229.907486 -234.488085)
			(xy 229.853671 -234.500368) (xy 229.798626 -234.504493) (xy 229.743581 -234.500368) (xy 229.689766 -234.488085)
			(xy 229.638382 -234.467918) (xy 229.590578 -234.440319) (xy 229.547421 -234.405902) (xy 229.509876 -234.365438)
			(xy 229.478781 -234.319831) (xy 229.454831 -234.270098) (xy 229.438561 -234.217351) (xy 229.430334 -234.162768)
			(xy 229.429818 -234.135168) (xy 229.430287 -234.108666) (xy 229.437872 -234.056208) (xy 229.452896 -234.005378)
			(xy 229.475047 -233.957225) (xy 229.503869 -233.912743) (xy 229.538768 -233.87285) (xy 229.558596 -233.85526)
			(xy 229.567232 -233.84764) (xy 229.576376 -233.827066) (xy 229.574344 -233.72572) (xy 229.564184 -233.7054)
			(xy 229.555294 -233.698288) (xy 229.529831 -233.677574) (xy 229.483917 -233.630665) (xy 229.444426 -233.578234)
			(xy 229.412013 -233.521154) (xy 229.38722 -233.460377) (xy 229.370458 -233.396913) (xy 229.362007 -233.33182)
			(xy 229.361492 -233.299) (xy 225.936556 -233.299) (xy 225.936556 -235.585) (xy 230.376982 -235.585)
			(xy 230.381053 -235.529378) (xy 230.393179 -235.474941) (xy 230.413102 -235.42285) (xy 230.440398 -235.374215)
			(xy 230.474484 -235.330072) (xy 230.514633 -235.291363) (xy 230.559991 -235.258912) (xy 230.609591 -235.233411)
			(xy 230.662375 -235.215404) (xy 230.717218 -235.205274) (xy 230.772952 -235.203237) (xy 230.828389 -235.209337)
			(xy 230.882346 -235.223443) (xy 230.933675 -235.245255) (xy 230.981281 -235.274309) (xy 231.024149 -235.309984)
			(xy 231.061366 -235.351521) (xy 231.092139 -235.398034) (xy 231.115811 -235.448531) (xy 231.131879 -235.501938)
			(xy 231.139999 -235.557114) (xy 231.140508 -235.585) (xy 231.139999 -235.612886) (xy 231.131879 -235.668062)
			(xy 231.11866 -235.712) (xy 232.789982 -235.712) (xy 232.794053 -235.656378) (xy 232.806179 -235.601941)
			(xy 232.826102 -235.54985) (xy 232.853398 -235.501215) (xy 232.887484 -235.457072) (xy 232.927633 -235.418363)
			(xy 232.972991 -235.385912) (xy 233.022591 -235.360411) (xy 233.075375 -235.342404) (xy 233.130218 -235.332274)
			(xy 233.185952 -235.330237) (xy 233.241389 -235.336337) (xy 233.295346 -235.350443) (xy 233.346675 -235.372255)
			(xy 233.394281 -235.401309) (xy 233.437149 -235.436984) (xy 233.474366 -235.478521) (xy 233.505139 -235.525034)
			(xy 233.528811 -235.575531) (xy 233.544879 -235.628938) (xy 233.552999 -235.684114) (xy 233.553508 -235.712)
			(xy 233.552999 -235.739886) (xy 233.544879 -235.795062) (xy 233.528811 -235.848469) (xy 233.505139 -235.898966)
			(xy 233.474366 -235.945479) (xy 233.437149 -235.987016) (xy 233.394281 -236.022691) (xy 233.346675 -236.051745)
			(xy 233.295346 -236.073557) (xy 233.241389 -236.087663) (xy 233.185952 -236.093763) (xy 233.130218 -236.091726)
			(xy 233.075375 -236.081596) (xy 233.022591 -236.063589) (xy 232.972991 -236.038088) (xy 232.927633 -236.005637)
			(xy 232.887484 -235.966928) (xy 232.853398 -235.922785) (xy 232.826102 -235.87415) (xy 232.806179 -235.822059)
			(xy 232.794053 -235.767622) (xy 232.789982 -235.712) (xy 231.11866 -235.712) (xy 231.115811 -235.721469)
			(xy 231.092139 -235.771966) (xy 231.061366 -235.818479) (xy 231.024149 -235.860016) (xy 230.981281 -235.895691)
			(xy 230.933675 -235.924745) (xy 230.882346 -235.946557) (xy 230.828389 -235.960663) (xy 230.772952 -235.966763)
			(xy 230.717218 -235.964726) (xy 230.662375 -235.954596) (xy 230.609591 -235.936589) (xy 230.559991 -235.911088)
			(xy 230.514633 -235.878637) (xy 230.474484 -235.839928) (xy 230.440398 -235.795785) (xy 230.413102 -235.74715)
			(xy 230.393179 -235.695059) (xy 230.381053 -235.640622) (xy 230.376982 -235.585) (xy 225.936556 -235.585)
			(xy 225.936556 -236.474) (xy 231.138982 -236.474) (xy 231.143053 -236.418378) (xy 231.155179 -236.363941)
			(xy 231.175102 -236.31185) (xy 231.202398 -236.263215) (xy 231.236484 -236.219072) (xy 231.276633 -236.180363)
			(xy 231.321991 -236.147912) (xy 231.371591 -236.122411) (xy 231.424375 -236.104404) (xy 231.479218 -236.094274)
			(xy 231.534952 -236.092237) (xy 231.590389 -236.098337) (xy 231.644346 -236.112443) (xy 231.695675 -236.134255)
			(xy 231.743281 -236.163309) (xy 231.786149 -236.198984) (xy 231.823366 -236.240521) (xy 231.854139 -236.287034)
			(xy 231.877811 -236.337531) (xy 231.893879 -236.390938) (xy 231.901999 -236.446114) (xy 231.90216 -236.45495)
			(xy 241.298982 -236.45495) (xy 241.303053 -236.399328) (xy 241.315179 -236.344891) (xy 241.335102 -236.2928)
			(xy 241.362398 -236.244165) (xy 241.396484 -236.200022) (xy 241.436633 -236.161313) (xy 241.481991 -236.128862)
			(xy 241.531591 -236.103361) (xy 241.584375 -236.085354) (xy 241.639218 -236.075224) (xy 241.694952 -236.073187)
			(xy 241.750389 -236.079287) (xy 241.804346 -236.093393) (xy 241.855675 -236.115205) (xy 241.903281 -236.144259)
			(xy 241.946149 -236.179934) (xy 241.983366 -236.221471) (xy 242.014139 -236.267984) (xy 242.037811 -236.318481)
			(xy 242.053879 -236.371888) (xy 242.061999 -236.427064) (xy 242.062508 -236.45495) (xy 242.061999 -236.482836)
			(xy 242.053879 -236.538012) (xy 242.037811 -236.591419) (xy 242.014139 -236.641916) (xy 241.983366 -236.688429)
			(xy 241.946149 -236.729966) (xy 241.903281 -236.765641) (xy 241.855675 -236.794695) (xy 241.804346 -236.816507)
			(xy 241.750389 -236.830613) (xy 241.694952 -236.836713) (xy 241.639218 -236.834676) (xy 241.584375 -236.824546)
			(xy 241.531591 -236.806539) (xy 241.481991 -236.781038) (xy 241.436633 -236.748587) (xy 241.396484 -236.709878)
			(xy 241.362398 -236.665735) (xy 241.335102 -236.6171) (xy 241.315179 -236.565009) (xy 241.303053 -236.510572)
			(xy 241.298982 -236.45495) (xy 231.90216 -236.45495) (xy 231.902508 -236.474) (xy 231.901999 -236.501886)
			(xy 231.893879 -236.557062) (xy 231.877811 -236.610469) (xy 231.854139 -236.660966) (xy 231.823366 -236.707479)
			(xy 231.786149 -236.749016) (xy 231.743281 -236.784691) (xy 231.695675 -236.813745) (xy 231.644346 -236.835557)
			(xy 231.590389 -236.849663) (xy 231.534952 -236.855763) (xy 231.479218 -236.853726) (xy 231.424375 -236.843596)
			(xy 231.371591 -236.825589) (xy 231.321991 -236.800088) (xy 231.276633 -236.767637) (xy 231.236484 -236.728928)
			(xy 231.202398 -236.684785) (xy 231.175102 -236.63615) (xy 231.155179 -236.584059) (xy 231.143053 -236.529622)
			(xy 231.138982 -236.474) (xy 225.936556 -236.474) (xy 225.936556 -237.230666) (xy 236.605316 -237.230666)
			(xy 236.609387 -237.175044) (xy 236.621513 -237.120607) (xy 236.641436 -237.068516) (xy 236.668732 -237.019881)
			(xy 236.702818 -236.975738) (xy 236.742967 -236.937029) (xy 236.788325 -236.904578) (xy 236.837925 -236.879077)
			(xy 236.890709 -236.86107) (xy 236.945552 -236.85094) (xy 237.001286 -236.848903) (xy 237.056723 -236.855003)
			(xy 237.11068 -236.869109) (xy 237.162009 -236.890921) (xy 237.209615 -236.919975) (xy 237.252483 -236.95565)
			(xy 237.2897 -236.997187) (xy 237.320473 -237.0437) (xy 237.344145 -237.094197) (xy 237.360213 -237.147604)
			(xy 237.368333 -237.20278) (xy 237.368842 -237.230666) (xy 237.368333 -237.258552) (xy 237.360213 -237.313728)
			(xy 237.344145 -237.367135) (xy 237.320473 -237.417632) (xy 237.2897 -237.464145) (xy 237.252483 -237.505682)
			(xy 237.209615 -237.541357) (xy 237.162009 -237.570411) (xy 237.11068 -237.592223) (xy 237.056723 -237.606329)
			(xy 237.001286 -237.612429) (xy 236.945552 -237.610392) (xy 236.890709 -237.600262) (xy 236.837925 -237.582255)
			(xy 236.788325 -237.556754) (xy 236.742967 -237.524303) (xy 236.702818 -237.485594) (xy 236.668732 -237.441451)
			(xy 236.641436 -237.392816) (xy 236.621513 -237.340725) (xy 236.609387 -237.286288) (xy 236.605316 -237.230666)
			(xy 225.936556 -237.230666) (xy 225.936556 -237.995163) (xy 228.559862 -237.995163) (xy 228.559862 -237.931241)
			(xy 228.567873 -237.867823) (xy 228.58377 -237.805909) (xy 228.607302 -237.746476) (xy 228.638096 -237.690461)
			(xy 228.675669 -237.638746) (xy 228.719426 -237.592149) (xy 228.768679 -237.551404) (xy 228.82265 -237.517153)
			(xy 228.880489 -237.489936) (xy 228.941282 -237.470183) (xy 229.004072 -237.458205) (xy 229.067868 -237.454192)
			(xy 229.131664 -237.458205) (xy 229.194454 -237.470183) (xy 229.255247 -237.489936) (xy 229.313086 -237.517153)
			(xy 229.367057 -237.551404) (xy 229.41631 -237.592149) (xy 229.460067 -237.638746) (xy 229.49764 -237.690461)
			(xy 229.528434 -237.746476) (xy 229.551966 -237.805909) (xy 229.567863 -237.867823) (xy 229.575874 -237.931241)
			(xy 229.576376 -237.963202) (xy 229.575874 -237.995163) (xy 229.571478 -238.029961) (xy 240.410994 -238.029961)
			(xy 240.410994 -237.966039) (xy 240.419005 -237.902621) (xy 240.434902 -237.840707) (xy 240.458434 -237.781274)
			(xy 240.489228 -237.725259) (xy 240.526801 -237.673544) (xy 240.570558 -237.626947) (xy 240.619811 -237.586202)
			(xy 240.673782 -237.551951) (xy 240.731621 -237.524734) (xy 240.792414 -237.504981) (xy 240.855204 -237.493003)
			(xy 240.919 -237.48899) (xy 240.982796 -237.493003) (xy 241.045586 -237.504981) (xy 241.106379 -237.524734)
			(xy 241.164218 -237.551951) (xy 241.218189 -237.586202) (xy 241.267442 -237.626947) (xy 241.311199 -237.673544)
			(xy 241.348772 -237.725259) (xy 241.379566 -237.781274) (xy 241.403098 -237.840707) (xy 241.418995 -237.902621)
			(xy 241.427006 -237.966039) (xy 241.427508 -237.998) (xy 241.427006 -238.029961) (xy 241.418995 -238.093379)
			(xy 241.403098 -238.155293) (xy 241.379566 -238.214726) (xy 241.348772 -238.270741) (xy 241.311199 -238.322456)
			(xy 241.267442 -238.369053) (xy 241.218189 -238.409798) (xy 241.164218 -238.444049) (xy 241.106379 -238.471266)
			(xy 241.045586 -238.491019) (xy 240.982796 -238.502997) (xy 240.919 -238.507011) (xy 240.855204 -238.502997)
			(xy 240.792414 -238.491019) (xy 240.731621 -238.471266) (xy 240.673782 -238.444049) (xy 240.619811 -238.409798)
			(xy 240.570558 -238.369053) (xy 240.526801 -238.322456) (xy 240.489228 -238.270741) (xy 240.458434 -238.214726)
			(xy 240.434902 -238.155293) (xy 240.419005 -238.093379) (xy 240.410994 -238.029961) (xy 229.571478 -238.029961)
			(xy 229.567863 -238.058581) (xy 229.551966 -238.120495) (xy 229.528434 -238.179928) (xy 229.49764 -238.235943)
			(xy 229.460067 -238.287658) (xy 229.41631 -238.334255) (xy 229.367057 -238.375) (xy 229.313086 -238.409251)
			(xy 229.255247 -238.436468) (xy 229.194454 -238.456221) (xy 229.131664 -238.468199) (xy 229.067868 -238.472213)
			(xy 229.004072 -238.468199) (xy 228.941282 -238.456221) (xy 228.880489 -238.436468) (xy 228.82265 -238.409251)
			(xy 228.768679 -238.375) (xy 228.719426 -238.334255) (xy 228.675669 -238.287658) (xy 228.638096 -238.235943)
			(xy 228.607302 -238.179928) (xy 228.58377 -238.120495) (xy 228.567873 -238.058581) (xy 228.559862 -237.995163)
			(xy 225.936556 -237.995163) (xy 225.936556 -239.141) (xy 233.04399 -239.141) (xy 233.048003 -239.077204)
			(xy 233.059981 -239.014414) (xy 233.079734 -238.953621) (xy 233.106951 -238.895782) (xy 233.141202 -238.841811)
			(xy 233.181947 -238.792558) (xy 233.228544 -238.748801) (xy 233.280259 -238.711228) (xy 233.336274 -238.680434)
			(xy 233.395707 -238.656902) (xy 233.457621 -238.641005) (xy 233.521039 -238.632994) (xy 233.553 -238.632492)
			(xy 233.58428 -238.632911) (xy 233.646369 -238.640575) (xy 233.707047 -238.655801) (xy 233.765399 -238.678358)
			(xy 233.820542 -238.707904) (xy 233.871642 -238.743995) (xy 233.917928 -238.786083) (xy 233.958699 -238.833532)
			(xy 233.976418 -238.859314) (xy 233.98387 -238.869474) (xy 234.006001 -238.88146) (xy 234.018582 -238.882174)
			(xy 234.103418 -238.882174) (xy 234.116001 -238.881494) (xy 234.13812 -238.869472) (xy 234.145582 -238.859314)
			(xy 234.163344 -238.833567) (xy 234.204124 -238.786139) (xy 234.250411 -238.744068) (xy 234.301508 -238.70799)
			(xy 234.356642 -238.67845) (xy 234.414983 -238.655892) (xy 234.475649 -238.640657) (xy 234.537725 -238.632976)
			(xy 234.569 -238.632492) (xy 234.596987 -238.632863) (xy 234.652625 -238.63899) (xy 234.70725 -238.651201)
			(xy 234.733846 -238.659924) (xy 234.747308 -238.664496) (xy 234.774994 -238.658654) (xy 234.8611 -238.577374)
			(xy 234.868466 -238.550196) (xy 234.864656 -238.53648) (xy 234.858216 -238.51203) (xy 234.851336 -238.461939)
			(xy 234.85094 -238.436658) (xy 234.851456 -238.409058) (xy 234.859683 -238.354475) (xy 234.875953 -238.301728)
			(xy 234.899903 -238.251996) (xy 234.930998 -238.206388) (xy 234.968543 -238.165924) (xy 235.0117 -238.131507)
			(xy 235.059504 -238.103908) (xy 235.110888 -238.083741) (xy 235.164703 -238.071458) (xy 235.219748 -238.067333)
			(xy 235.274793 -238.071458) (xy 235.328608 -238.083741) (xy 235.379992 -238.103908) (xy 235.427796 -238.131507)
			(xy 235.470953 -238.165924) (xy 235.508498 -238.206388) (xy 235.539593 -238.251996) (xy 235.563543 -238.301728)
			(xy 235.579813 -238.354475) (xy 235.58804 -238.409058) (xy 235.588556 -238.436658) (xy 235.588248 -238.459766)
			(xy 235.58251 -238.505624) (xy 235.577126 -238.528098) (xy 235.57357 -238.541306) (xy 235.580936 -238.567214)
			(xy 235.663486 -238.647986) (xy 235.689394 -238.654844) (xy 235.702602 -238.651034) (xy 235.73603 -238.642352)
			(xy 235.804467 -238.633053) (xy 235.839 -238.632492) (xy 235.87028 -238.632911) (xy 235.932369 -238.640575)
			(xy 235.993047 -238.655801) (xy 236.051399 -238.678358) (xy 236.106542 -238.707904) (xy 236.157642 -238.743995)
			(xy 236.203928 -238.786083) (xy 236.244699 -238.833532) (xy 236.262418 -238.859314) (xy 236.26987 -238.869474)
			(xy 236.292001 -238.88146) (xy 236.304582 -238.882174) (xy 236.389418 -238.882174) (xy 236.402001 -238.881494)
			(xy 236.42412 -238.869472) (xy 236.431582 -238.859314) (xy 236.449344 -238.833567) (xy 236.490124 -238.786139)
			(xy 236.536411 -238.744068) (xy 236.587508 -238.70799) (xy 236.642642 -238.67845) (xy 236.700983 -238.655892)
			(xy 236.761649 -238.640657) (xy 236.823725 -238.632976) (xy 236.855 -238.632492) (xy 236.879864 -238.632786)
			(xy 236.929355 -238.637621) (xy 236.953806 -238.642144) (xy 236.964728 -238.64443) (xy 236.986826 -238.638842)
			(xy 237.065058 -238.575596) (xy 237.074964 -238.55553) (xy 237.074964 -238.5441) (xy 237.07604 -238.511157)
			(xy 237.085607 -238.445943) (xy 237.10352 -238.382512) (xy 237.129477 -238.321927) (xy 237.163043 -238.265202)
			(xy 237.203657 -238.21329) (xy 237.250637 -238.167059) (xy 237.303195 -238.127285) (xy 237.360452 -238.094634)
			(xy 237.421446 -238.069654) (xy 237.485157 -238.052763) (xy 237.550516 -238.044244) (xy 237.583472 -238.04372)
			(xy 237.614205 -238.044164) (xy 237.675222 -238.05157) (xy 237.734902 -238.066277) (xy 237.792373 -238.088071)
			(xy 237.846798 -238.116635) (xy 237.897384 -238.15155) (xy 237.943391 -238.192309) (xy 237.98415 -238.238316)
			(xy 238.019065 -238.288902) (xy 238.047629 -238.343327) (xy 238.069423 -238.400798) (xy 238.08413 -238.460478)
			(xy 238.091536 -238.521495) (xy 238.09198 -238.552228) (xy 238.091577 -238.582516) (xy 238.084402 -238.642666)
			(xy 238.070133 -238.701538) (xy 238.048972 -238.758297) (xy 238.021219 -238.812142) (xy 238.004604 -238.83747)
			(xy 237.997238 -238.848138) (xy 237.994698 -238.873792) (xy 238.03864 -238.976408) (xy 238.05896 -238.99241)
			(xy 238.071914 -238.994442) (xy 238.103879 -239.00026) (xy 238.166063 -239.019091) (xy 238.225344 -239.045688)
			(xy 238.280755 -239.079617) (xy 238.331394 -239.120327) (xy 238.376436 -239.167153) (xy 238.415148 -239.219335)
			(xy 238.4469 -239.276021) (xy 238.471175 -239.33629) (xy 238.487577 -239.399159) (xy 238.49584 -239.463605)
			(xy 238.496348 -239.496092) (xy 238.49605 -239.520181) (xy 238.491473 -239.568141) (xy 238.487204 -239.59185)
			(xy 238.484918 -239.604296) (xy 238.492284 -239.628426) (xy 238.569754 -239.705896) (xy 238.593884 -239.713262)
			(xy 238.60633 -239.710722) (xy 238.623625 -239.707619) (xy 238.65861 -239.704315) (xy 238.67618 -239.704118)
			(xy 238.705115 -239.704704) (xy 238.762273 -239.713763) (xy 238.789972 -239.722152) (xy 238.802418 -239.726216)
			(xy 238.827564 -239.721644) (xy 238.913924 -239.65154) (xy 238.92383 -239.628172) (xy 238.922306 -239.615218)
			(xy 238.921088 -239.602235) (xy 238.919816 -239.576188) (xy 238.919766 -239.563148) (xy 238.92028 -239.530014)
			(xy 238.928894 -239.464307) (xy 238.945971 -239.400276) (xy 238.971219 -239.339006) (xy 239.004213 -239.281534)
			(xy 239.044391 -239.228835) (xy 239.091075 -239.181801) (xy 239.143472 -239.14123) (xy 239.200696 -239.107808)
			(xy 239.261776 -239.082102) (xy 239.325677 -239.064548) (xy 239.358424 -239.059466) (xy 239.370616 -239.057688)
			(xy 239.389666 -239.044734) (xy 239.441482 -238.953802) (xy 239.443006 -238.930434) (xy 239.43818 -238.919258)
			(xy 239.42557 -238.8879) (xy 239.407814 -238.822686) (xy 239.398856 -238.755694) (xy 239.398302 -238.7219)
			(xy 239.398804 -238.689939) (xy 239.406815 -238.626521) (xy 239.422712 -238.564607) (xy 239.446244 -238.505174)
			(xy 239.477038 -238.449159) (xy 239.514611 -238.397444) (xy 239.558368 -238.350847) (xy 239.607621 -238.310102)
			(xy 239.661592 -238.275851) (xy 239.719431 -238.248634) (xy 239.780224 -238.228881) (xy 239.843014 -238.216903)
			(xy 239.90681 -238.21289) (xy 239.970606 -238.216903) (xy 240.033396 -238.228881) (xy 240.094189 -238.248634)
			(xy 240.152028 -238.275851) (xy 240.205999 -238.310102) (xy 240.255252 -238.350847) (xy 240.299009 -238.397444)
			(xy 240.336582 -238.449159) (xy 240.367376 -238.505174) (xy 240.390908 -238.564607) (xy 240.406805 -238.626521)
			(xy 240.414816 -238.689939) (xy 240.415318 -238.7219) (xy 240.41477 -238.755034) (xy 240.406161 -238.820739)
			(xy 240.389091 -238.88477) (xy 240.363847 -238.946041) (xy 240.330858 -239.003513) (xy 240.290682 -239.056213)
			(xy 240.244002 -239.103248) (xy 240.191606 -239.14382) (xy 240.134385 -239.177242) (xy 240.073306 -239.202948)
			(xy 240.009406 -239.220501) (xy 239.97666 -239.225582) (xy 239.964468 -239.22736) (xy 239.945418 -239.240314)
			(xy 239.893602 -239.331246) (xy 239.892078 -239.354614) (xy 239.896904 -239.36579) (xy 239.909502 -239.397153)
			(xy 239.927262 -239.462364) (xy 239.936224 -239.529355) (xy 239.936782 -239.563148) (xy 239.936389 -239.593881)
			(xy 239.928975 -239.654898) (xy 239.91426 -239.714577) (xy 239.892459 -239.772047) (xy 239.86389 -239.82647)
			(xy 239.828969 -239.877053) (xy 239.788206 -239.923058) (xy 239.742195 -239.963815) (xy 239.691607 -239.998728)
			(xy 239.63718 -240.027289) (xy 239.579706 -240.049082) (xy 239.520026 -240.063788) (xy 239.459007 -240.071194)
			(xy 239.428274 -240.071656) (xy 239.397629 -240.071214) (xy 239.336783 -240.063839) (xy 239.277263 -240.04921)
			(xy 239.219931 -240.027538) (xy 239.192562 -240.013744) (xy 239.181132 -240.007648) (xy 239.155732 -240.008156)
			(xy 239.058704 -240.062512) (xy 239.044988 -240.084102) (xy 239.044226 -240.097056) (xy 239.041921 -240.124739)
			(xy 239.030011 -240.178998) (xy 239.010099 -240.230857) (xy 238.982636 -240.279143) (xy 238.948242 -240.322765)
			(xy 238.907695 -240.360735) (xy 238.861912 -240.392196) (xy 238.81193 -240.416435) (xy 238.758877 -240.432905)
			(xy 238.703955 -240.441232) (xy 238.67618 -240.441734) (xy 238.649837 -240.441257) (xy 238.597686 -240.433756)
			(xy 238.547134 -240.418911) (xy 238.499209 -240.397023) (xy 238.454886 -240.368538) (xy 238.415068 -240.334036)
			(xy 238.380565 -240.294218) (xy 238.352079 -240.249896) (xy 238.330191 -240.201971) (xy 238.315345 -240.151419)
			(xy 238.307844 -240.099269) (xy 238.307372 -240.072926) (xy 238.307372 -240.067338) (xy 238.307626 -240.054638)
			(xy 238.296196 -240.032286) (xy 238.20628 -239.969548) (xy 238.181388 -239.9665) (xy 238.16945 -239.971072)
			(xy 238.140363 -239.981691) (xy 238.080266 -239.996617) (xy 238.018801 -240.004139) (xy 237.98784 -240.0046)
			(xy 237.957108 -240.004125) (xy 237.896093 -239.996721) (xy 237.836415 -239.982015) (xy 237.778945 -239.960223)
			(xy 237.72452 -239.931663) (xy 237.673936 -239.89675) (xy 237.627929 -239.855994) (xy 237.58717 -239.809989)
			(xy 237.552254 -239.759407) (xy 237.52369 -239.704985) (xy 237.501894 -239.647516) (xy 237.487185 -239.587839)
			(xy 237.479777 -239.526824) (xy 237.479332 -239.496092) (xy 237.47976 -239.465805) (xy 237.486931 -239.405656)
			(xy 237.501196 -239.346785) (xy 237.522351 -239.290025) (xy 237.550097 -239.236179) (xy 237.566708 -239.21085)
			(xy 237.574074 -239.200182) (xy 237.576614 -239.174528) (xy 237.532672 -239.071912) (xy 237.512352 -239.05591)
			(xy 237.499398 -239.053878) (xy 237.484666 -239.051084) (xy 237.473744 -239.048798) (xy 237.451646 -239.054386)
			(xy 237.373414 -239.117632) (xy 237.363508 -239.137698) (xy 237.363508 -239.149128) (xy 237.362486 -239.182073)
			(xy 237.352914 -239.24729) (xy 237.334997 -239.310724) (xy 237.309035 -239.371311) (xy 237.275464 -239.428037)
			(xy 237.234845 -239.47995) (xy 237.18786 -239.526181) (xy 237.135297 -239.565954) (xy 237.078035 -239.598603)
			(xy 237.017036 -239.623582) (xy 236.953321 -239.64047) (xy 236.887958 -239.648986) (xy 236.855 -239.649508)
			(xy 236.82372 -239.649089) (xy 236.761631 -239.641425) (xy 236.700953 -239.626199) (xy 236.642601 -239.603642)
			(xy 236.587458 -239.574096) (xy 236.536358 -239.538005) (xy 236.490072 -239.495917) (xy 236.449301 -239.448468)
			(xy 236.431582 -239.422686) (xy 236.42413 -239.412526) (xy 236.401999 -239.40054) (xy 236.389418 -239.399826)
			(xy 236.304582 -239.399826) (xy 236.291999 -239.400506) (xy 236.26988 -239.412528) (xy 236.262418 -239.422686)
			(xy 236.244656 -239.448433) (xy 236.203876 -239.495861) (xy 236.157589 -239.537932) (xy 236.106492 -239.57401)
			(xy 236.051358 -239.60355) (xy 235.993017 -239.626108) (xy 235.932351 -239.641343) (xy 235.870275 -239.649024)
			(xy 235.839 -239.649508) (xy 235.808269 -239.649044) (xy 235.747255 -239.641635) (xy 235.687579 -239.626927)
			(xy 235.630111 -239.605132) (xy 235.575689 -239.576569) (xy 235.525107 -239.541655) (xy 235.479102 -239.500898)
			(xy 235.438345 -239.454893) (xy 235.403431 -239.404311) (xy 235.374868 -239.349889) (xy 235.353073 -239.292421)
			(xy 235.338365 -239.232745) (xy 235.330956 -239.171731) (xy 235.330492 -239.141) (xy 235.331054 -239.107112)
			(xy 235.340063 -239.039938) (xy 235.357935 -238.974561) (xy 235.370624 -238.943134) (xy 235.375958 -238.930434)
			(xy 235.372656 -238.903764) (xy 235.30306 -238.811562) (xy 235.278422 -238.801148) (xy 235.264706 -238.802672)
			(xy 235.253512 -238.803979) (xy 235.231017 -238.805376) (xy 235.219748 -238.805466) (xy 235.20179 -238.805281)
			(xy 235.166039 -238.801848) (xy 235.148374 -238.798608) (xy 235.134404 -238.795814) (xy 235.107988 -238.805466)
			(xy 235.033566 -238.897668) (xy 235.029756 -238.925608) (xy 235.035598 -238.938562) (xy 235.048846 -238.97065)
			(xy 235.067521 -239.037511) (xy 235.076932 -239.10629) (xy 235.077508 -239.141) (xy 235.077044 -239.171731)
			(xy 235.069635 -239.232745) (xy 235.054927 -239.292421) (xy 235.033132 -239.349889) (xy 235.004569 -239.404311)
			(xy 234.969655 -239.454893) (xy 234.928898 -239.500898) (xy 234.882893 -239.541655) (xy 234.832311 -239.576569)
			(xy 234.777889 -239.605132) (xy 234.720421 -239.626927) (xy 234.660745 -239.641635) (xy 234.599731 -239.649044)
			(xy 234.569 -239.649508) (xy 234.53772 -239.649089) (xy 234.475631 -239.641425) (xy 234.414953 -239.626199)
			(xy 234.356601 -239.603642) (xy 234.301458 -239.574096) (xy 234.250358 -239.538005) (xy 234.204072 -239.495917)
			(xy 234.163301 -239.448468) (xy 234.145582 -239.422686) (xy 234.13813 -239.412526) (xy 234.115999 -239.40054)
			(xy 234.103418 -239.399826) (xy 234.018582 -239.399826) (xy 234.005999 -239.400506) (xy 233.98388 -239.412528)
			(xy 233.976418 -239.422686) (xy 233.958656 -239.448433) (xy 233.917876 -239.495861) (xy 233.871589 -239.537932)
			(xy 233.820492 -239.57401) (xy 233.765358 -239.60355) (xy 233.707017 -239.626108) (xy 233.646351 -239.641343)
			(xy 233.584275 -239.649024) (xy 233.553 -239.649508) (xy 233.521039 -239.649006) (xy 233.457621 -239.640995)
			(xy 233.395707 -239.625098) (xy 233.336274 -239.601566) (xy 233.280259 -239.570772) (xy 233.228544 -239.533199)
			(xy 233.181947 -239.489442) (xy 233.141202 -239.440189) (xy 233.106951 -239.386218) (xy 233.079734 -239.328379)
			(xy 233.059981 -239.267586) (xy 233.048003 -239.204796) (xy 233.04399 -239.141) (xy 225.936556 -239.141)
			(xy 225.936556 -240.919) (xy 229.087989 -240.919) (xy 229.092003 -240.855208) (xy 229.103979 -240.792422)
			(xy 229.12373 -240.731632) (xy 229.150943 -240.673796) (xy 229.18519 -240.619827) (xy 229.225931 -240.570576)
			(xy 229.272523 -240.526819) (xy 229.324231 -240.489245) (xy 229.380241 -240.458449) (xy 229.439669 -240.434915)
			(xy 229.501578 -240.419014) (xy 229.564991 -240.410997) (xy 229.59695 -240.410492) (xy 229.627265 -240.410935)
			(xy 229.687466 -240.418124) (xy 229.746387 -240.432418) (xy 229.80319 -240.453614) (xy 229.857071 -240.481412)
			(xy 229.907266 -240.515418) (xy 229.930452 -240.534952) (xy 229.93731 -240.541302) (xy 229.954328 -240.547398)
			(xy 230.039672 -240.547398) (xy 230.05669 -240.541302) (xy 230.063548 -240.534952) (xy 230.086715 -240.515392)
			(xy 230.136906 -240.481373) (xy 230.190789 -240.453567) (xy 230.247597 -240.432371) (xy 230.306524 -240.418084)
			(xy 230.366733 -240.410911) (xy 230.39705 -240.410492) (xy 230.429576 -240.410969) (xy 230.4941 -240.419247)
			(xy 230.55704 -240.435688) (xy 230.61737 -240.460023) (xy 230.674102 -240.491855) (xy 230.726311 -240.530662)
			(xy 230.773143 -240.575813) (xy 230.813834 -240.626568) (xy 230.847719 -240.682098) (xy 230.874244 -240.741497)
			(xy 230.892975 -240.803794) (xy 230.903608 -240.867972) (xy 230.905304 -240.900458) (xy 230.905558 -240.911888)
			(xy 230.915972 -240.931954) (xy 230.996236 -240.993422) (xy 231.018334 -240.998248) (xy 231.02951 -240.995708)
			(xy 231.049866 -240.991323) (xy 231.09124 -240.986612) (xy 231.11206 -240.98631) (xy 231.139238 -240.987326)
			(xy 231.149652 -240.988088) (xy 231.168702 -240.981738) (xy 231.238806 -240.920016) (xy 231.247696 -240.901982)
			(xy 231.248204 -240.891568) (xy 231.25036 -240.859486) (xy 231.261896 -240.796226) (xy 231.281317 -240.734925)
			(xy 231.30831 -240.676561) (xy 231.342447 -240.622066) (xy 231.383181 -240.57231) (xy 231.429863 -240.528087)
			(xy 231.481748 -240.490101) (xy 231.538009 -240.45896) (xy 231.597746 -240.435161) (xy 231.660007 -240.419082)
			(xy 231.723798 -240.410982) (xy 231.75595 -240.410492) (xy 231.786265 -240.410935) (xy 231.846466 -240.418124)
			(xy 231.905387 -240.432418) (xy 231.96219 -240.453614) (xy 232.016071 -240.481412) (xy 232.066266 -240.515418)
			(xy 232.089452 -240.534952) (xy 232.09631 -240.541302) (xy 232.113328 -240.547398) (xy 232.198672 -240.547398)
			(xy 232.21569 -240.541302) (xy 232.222548 -240.534952) (xy 232.245715 -240.515392) (xy 232.295906 -240.481373)
			(xy 232.349789 -240.453567) (xy 232.406597 -240.432371) (xy 232.465524 -240.418084) (xy 232.525733 -240.410911)
			(xy 232.55605 -240.410492) (xy 232.588014 -240.41097) (xy 232.65144 -240.418977) (xy 232.713361 -240.43487)
			(xy 232.772802 -240.458399) (xy 232.828826 -240.489193) (xy 232.880547 -240.526767) (xy 232.927152 -240.570526)
			(xy 232.967903 -240.619783) (xy 233.00216 -240.673758) (xy 233.029381 -240.731602) (xy 233.049137 -240.792401)
			(xy 233.061117 -240.855197) (xy 233.065132 -240.919) (xy 233.061117 -240.982803) (xy 233.049137 -241.045599)
			(xy 233.029381 -241.106398) (xy 233.00216 -241.164242) (xy 232.996601 -241.173) (xy 234.695492 -241.173)
			(xy 234.69593 -241.142785) (xy 234.703117 -241.082782) (xy 234.717367 -241.024055) (xy 234.738478 -240.967431)
			(xy 234.766152 -240.913709) (xy 234.8 -240.863646) (xy 234.819444 -240.840514) (xy 234.825069 -240.833377)
			(xy 234.831313 -240.816322) (xy 234.831636 -240.80724) (xy 234.831636 -240.77676) (xy 234.831302 -240.76768)
			(xy 234.825059 -240.750629) (xy 234.819444 -240.743486) (xy 234.800005 -240.720351) (xy 234.766167 -240.670284)
			(xy 234.738498 -240.616561) (xy 234.717389 -240.559939) (xy 234.703137 -240.501214) (xy 234.695942 -240.441214)
			(xy 234.695492 -240.411) (xy 234.695994 -240.379039) (xy 234.704005 -240.315621) (xy 234.719902 -240.253707)
			(xy 234.743434 -240.194274) (xy 234.774228 -240.138259) (xy 234.811801 -240.086544) (xy 234.855558 -240.039947)
			(xy 234.904811 -239.999202) (xy 234.958782 -239.964951) (xy 235.016621 -239.937734) (xy 235.077414 -239.917981)
			(xy 235.140204 -239.906003) (xy 235.204 -239.90199) (xy 235.267796 -239.906003) (xy 235.330586 -239.917981)
			(xy 235.391379 -239.937734) (xy 235.449218 -239.964951) (xy 235.503189 -239.999202) (xy 235.552442 -240.039947)
			(xy 235.596199 -240.086544) (xy 235.633772 -240.138259) (xy 235.664566 -240.194274) (xy 235.688098 -240.253707)
			(xy 235.703995 -240.315621) (xy 235.712006 -240.379039) (xy 235.712508 -240.411) (xy 235.71207 -240.441215)
			(xy 235.704883 -240.501218) (xy 235.690633 -240.559945) (xy 235.669522 -240.616569) (xy 235.641848 -240.670291)
			(xy 235.608 -240.720354) (xy 235.588556 -240.743486) (xy 235.582931 -240.750623) (xy 235.576687 -240.767678)
			(xy 235.576364 -240.77676) (xy 235.576364 -240.80724) (xy 235.576698 -240.81632) (xy 235.582941 -240.833371)
			(xy 235.588556 -240.840514) (xy 235.607995 -240.863649) (xy 235.641833 -240.913716) (xy 235.669502 -240.967439)
			(xy 235.690611 -241.024061) (xy 235.704863 -241.082786) (xy 235.712058 -241.142786) (xy 235.712508 -241.173)
			(xy 235.712069 -241.203577) (xy 235.704713 -241.264288) (xy 235.690133 -241.32368) (xy 235.668537 -241.380895)
			(xy 235.640239 -241.435109) (xy 235.605644 -241.485539) (xy 235.565254 -241.531458) (xy 235.51965 -241.572203)
			(xy 235.49483 -241.590068) (xy 235.48594 -241.596418) (xy 235.474764 -241.61496) (xy 235.463842 -241.71275)
			(xy 235.470446 -241.733578) (xy 235.477812 -241.741706) (xy 235.495798 -241.762165) (xy 235.526135 -241.80741)
			(xy 235.549482 -241.856627) (xy 235.565332 -241.908745) (xy 235.57334 -241.962627) (xy 235.573824 -241.989864)
			(xy 235.573308 -242.017464) (xy 235.565081 -242.072047) (xy 235.548811 -242.124794) (xy 235.524861 -242.174527)
			(xy 235.493766 -242.220134) (xy 235.456221 -242.260598) (xy 235.413064 -242.295015) (xy 235.36526 -242.322614)
			(xy 235.313876 -242.342781) (xy 235.260061 -242.355064) (xy 235.205016 -242.359189) (xy 235.149971 -242.355064)
			(xy 235.096156 -242.342781) (xy 235.044772 -242.322614) (xy 234.996968 -242.295015) (xy 234.953811 -242.260598)
			(xy 234.916266 -242.220134) (xy 234.885171 -242.174527) (xy 234.861221 -242.124794) (xy 234.844951 -242.072047)
			(xy 234.836724 -242.017464) (xy 234.836208 -241.989864) (xy 234.836646 -241.962732) (xy 234.844591 -241.909052)
			(xy 234.860321 -241.857117) (xy 234.883494 -241.80805) (xy 234.913611 -241.76291) (xy 234.931458 -241.742468)
			(xy 234.938824 -241.73434) (xy 234.945682 -241.713512) (xy 234.934252 -241.615722) (xy 234.923076 -241.59718)
			(xy 234.914186 -241.59083) (xy 234.889253 -241.572984) (xy 234.843437 -241.532232) (xy 234.802854 -241.486265)
			(xy 234.768094 -241.435753) (xy 234.73966 -241.381426) (xy 234.717966 -241.324075) (xy 234.703325 -241.264531)
			(xy 234.695952 -241.203659) (xy 234.695492 -241.173) (xy 232.996601 -241.173) (xy 232.967903 -241.218217)
			(xy 232.927152 -241.267474) (xy 232.880547 -241.311233) (xy 232.828826 -241.348807) (xy 232.772802 -241.379601)
			(xy 232.713361 -241.40313) (xy 232.65144 -241.419023) (xy 232.588014 -241.42703) (xy 232.55605 -241.427508)
			(xy 232.525735 -241.427065) (xy 232.465534 -241.419876) (xy 232.406613 -241.405582) (xy 232.34981 -241.384386)
			(xy 232.295929 -241.356588) (xy 232.245734 -241.322582) (xy 232.222548 -241.303048) (xy 232.21569 -241.296698)
			(xy 232.198672 -241.290602) (xy 232.113328 -241.290602) (xy 232.09631 -241.296698) (xy 232.089452 -241.303048)
			(xy 232.066285 -241.322608) (xy 232.016094 -241.356627) (xy 231.962211 -241.384433) (xy 231.905403 -241.405629)
			(xy 231.846476 -241.419916) (xy 231.786267 -241.427089) (xy 231.75595 -241.427508) (xy 231.728323 -241.427166)
			(xy 231.673391 -241.421208) (xy 231.619429 -241.409326) (xy 231.593136 -241.400838) (xy 231.58323 -241.397282)
			(xy 231.563164 -241.398806) (xy 231.479852 -241.44097) (xy 231.466898 -241.456464) (xy 231.463596 -241.46637)
			(xy 231.455367 -241.490948) (xy 231.432982 -241.537694) (xy 231.404269 -241.580843) (xy 231.369796 -241.619545)
			(xy 231.330241 -241.653037) (xy 231.286384 -241.680658) (xy 231.239091 -241.701863) (xy 231.189294 -241.716234)
			(xy 231.137975 -241.723489) (xy 231.11206 -241.723926) (xy 231.084981 -241.723401) (xy 231.031405 -241.715489)
			(xy 230.979563 -241.699826) (xy 230.930568 -241.67675) (xy 230.885476 -241.646755) (xy 230.845255 -241.610488)
			(xy 230.810771 -241.568729) (xy 230.782766 -241.522375) (xy 230.761841 -241.472423) (xy 230.754682 -241.446304)
			(xy 230.751888 -241.435128) (xy 230.73741 -241.417602) (xy 230.64597 -241.374422) (xy 230.623364 -241.374422)
			(xy 230.61295 -241.379248) (xy 230.579025 -241.394495) (xy 230.507817 -241.415979) (xy 230.434239 -241.426848)
			(xy 230.39705 -241.427508) (xy 230.366735 -241.427065) (xy 230.306534 -241.419876) (xy 230.247613 -241.405582)
			(xy 230.19081 -241.384386) (xy 230.136929 -241.356588) (xy 230.086734 -241.322582) (xy 230.063548 -241.303048)
			(xy 230.05669 -241.296698) (xy 230.039672 -241.290602) (xy 229.954328 -241.290602) (xy 229.93731 -241.296698)
			(xy 229.930452 -241.303048) (xy 229.907285 -241.322608) (xy 229.857094 -241.356627) (xy 229.803211 -241.384433)
			(xy 229.746403 -241.405629) (xy 229.687476 -241.419916) (xy 229.627267 -241.427089) (xy 229.59695 -241.427508)
			(xy 229.564991 -241.427003) (xy 229.501578 -241.418986) (xy 229.439669 -241.403085) (xy 229.380241 -241.379551)
			(xy 229.324231 -241.348755) (xy 229.272523 -241.311181) (xy 229.225931 -241.267424) (xy 229.18519 -241.218173)
			(xy 229.150943 -241.164204) (xy 229.12373 -241.106368) (xy 229.103979 -241.045578) (xy 229.092003 -240.982792)
			(xy 229.087989 -240.919) (xy 225.936556 -240.919) (xy 225.936556 -243.205) (xy 230.631492 -243.205)
			(xy 230.63193 -243.174785) (xy 230.639117 -243.114782) (xy 230.653367 -243.056055) (xy 230.674478 -242.999431)
			(xy 230.702152 -242.945709) (xy 230.736 -242.895646) (xy 230.755444 -242.872514) (xy 230.761069 -242.865377)
			(xy 230.767313 -242.848322) (xy 230.767636 -242.83924) (xy 230.767636 -242.80876) (xy 230.767302 -242.79968)
			(xy 230.761059 -242.782629) (xy 230.755444 -242.775486) (xy 230.736005 -242.752351) (xy 230.702167 -242.702284)
			(xy 230.674498 -242.648561) (xy 230.653389 -242.591939) (xy 230.639137 -242.533214) (xy 230.631942 -242.473214)
			(xy 230.631492 -242.443) (xy 230.631994 -242.411039) (xy 230.640005 -242.347621) (xy 230.655902 -242.285707)
			(xy 230.679434 -242.226274) (xy 230.710228 -242.170259) (xy 230.747801 -242.118544) (xy 230.791558 -242.071947)
			(xy 230.840811 -242.031202) (xy 230.894782 -241.996951) (xy 230.952621 -241.969734) (xy 231.013414 -241.949981)
			(xy 231.076204 -241.938003) (xy 231.14 -241.93399) (xy 231.203796 -241.938003) (xy 231.266586 -241.949981)
			(xy 231.327379 -241.969734) (xy 231.385218 -241.996951) (xy 231.439189 -242.031202) (xy 231.488442 -242.071947)
			(xy 231.532199 -242.118544) (xy 231.569772 -242.170259) (xy 231.600566 -242.226274) (xy 231.624098 -242.285707)
			(xy 231.639995 -242.347621) (xy 231.648006 -242.411039) (xy 231.648508 -242.443) (xy 231.64807 -242.473215)
			(xy 231.640883 -242.533218) (xy 231.626633 -242.591945) (xy 231.605522 -242.648569) (xy 231.577848 -242.702291)
			(xy 231.544 -242.752354) (xy 231.524556 -242.775486) (xy 231.518931 -242.782623) (xy 231.512687 -242.799678)
			(xy 231.512364 -242.80876) (xy 231.512364 -242.83924) (xy 231.512698 -242.84832) (xy 231.518941 -242.865371)
			(xy 231.524556 -242.872514) (xy 231.543995 -242.895649) (xy 231.577833 -242.945716) (xy 231.605502 -242.999439)
			(xy 231.626611 -243.056061) (xy 231.640863 -243.114786) (xy 231.648058 -243.174786) (xy 231.648508 -243.205)
			(xy 231.648046 -243.235603) (xy 231.640693 -243.296367) (xy 231.626104 -243.35581) (xy 231.604491 -243.413074)
			(xy 231.576166 -243.467332) (xy 231.541537 -243.517801) (xy 231.501105 -243.563752) (xy 231.478582 -243.584476)
			(xy 231.47147 -243.590826) (xy 231.463088 -243.606828) (xy 231.45242 -243.691918) (xy 231.456738 -243.709444)
			(xy 231.462072 -243.717318) (xy 231.477078 -243.740348) (xy 231.500798 -243.789934) (xy 231.516911 -243.842486)
			(xy 231.525063 -243.896845) (xy 231.525572 -243.924328) (xy 231.525237 -243.947573) (xy 231.519452 -243.993701)
			(xy 231.5079 -244.038732) (xy 231.499664 -244.060472) (xy 231.494076 -244.074188) (xy 231.49941 -244.10289)
			(xy 231.581706 -244.19179) (xy 231.610154 -244.199156) (xy 231.624124 -244.194838) (xy 231.660923 -244.18415)
			(xy 231.736686 -244.172674) (xy 231.775 -244.171978) (xy 231.806541 -244.172468) (xy 231.869139 -244.180271)
			(xy 231.930291 -244.195756) (xy 231.989058 -244.218688) (xy 232.044538 -244.248712) (xy 232.095877 -244.285368)
			(xy 232.142288 -244.328092) (xy 232.183058 -244.37623) (xy 232.217561 -244.42904) (xy 232.245266 -244.485713)
			(xy 232.265748 -244.545378) (xy 232.278693 -244.607118) (xy 232.283902 -244.669985) (xy 232.281294 -244.733013)
			(xy 232.270911 -244.795235) (xy 232.25291 -244.855695) (xy 232.22757 -244.913464) (xy 232.195278 -244.967655)
			(xy 232.156531 -245.017435) (xy 232.111925 -245.062041) (xy 232.062143 -245.100786) (xy 232.007952 -245.133076)
			(xy 231.950182 -245.158415) (xy 231.889722 -245.176414) (xy 231.8275 -245.186796) (xy 231.764471 -245.189402)
			(xy 231.701604 -245.184191) (xy 231.639864 -245.171244) (xy 231.5802 -245.15076) (xy 231.523528 -245.123054)
			(xy 231.470719 -245.08855) (xy 231.422582 -245.047778) (xy 231.379859 -245.001366) (xy 231.343204 -244.950026)
			(xy 231.313182 -244.894546) (xy 231.290252 -244.835778) (xy 231.274768 -244.774625) (xy 231.266967 -244.712027)
			(xy 231.266492 -244.680486) (xy 231.266979 -244.648615) (xy 231.274912 -244.585371) (xy 231.2907 -244.523617)
			(xy 231.314096 -244.464325) (xy 231.328976 -244.436138) (xy 231.336088 -244.423184) (xy 231.33431 -244.393974)
			(xy 231.263698 -244.295676) (xy 231.23652 -244.284754) (xy 231.222042 -244.287294) (xy 231.205862 -244.290037)
			(xy 231.173174 -244.292959) (xy 231.156764 -244.293136) (xy 231.13042 -244.292672) (xy 231.07827 -244.285169)
			(xy 231.027718 -244.270322) (xy 230.979792 -244.248433) (xy 230.93547 -244.219946) (xy 230.895652 -244.185442)
			(xy 230.861149 -244.145624) (xy 230.832664 -244.101301) (xy 230.810775 -244.053375) (xy 230.795929 -244.002822)
			(xy 230.788428 -243.950672) (xy 230.787956 -243.924328) (xy 230.788373 -243.898992) (xy 230.795328 -243.848798)
			(xy 230.809099 -243.800032) (xy 230.829424 -243.753614) (xy 230.842312 -243.731796) (xy 230.847138 -243.723668)
			(xy 230.85044 -243.705888) (xy 230.835962 -243.621306) (xy 230.826818 -243.605812) (xy 230.819452 -243.59997)
			(xy 230.794669 -243.579234) (xy 230.750068 -243.532473) (xy 230.711752 -243.480438) (xy 230.680339 -243.423966)
			(xy 230.656335 -243.36397) (xy 230.640127 -243.301415) (xy 230.631976 -243.237311) (xy 230.631492 -243.205)
			(xy 225.936556 -243.205) (xy 225.936556 -244.168422) (xy 225.936985 -244.178489) (xy 225.944711 -244.197083)
			(xy 225.951542 -244.20449) (xy 226.459499 -244.712447) (xy 229.996994 -244.712447) (xy 229.996994 -244.648525)
			(xy 230.005005 -244.585107) (xy 230.020902 -244.523193) (xy 230.044434 -244.46376) (xy 230.075228 -244.407745)
			(xy 230.112801 -244.35603) (xy 230.156558 -244.309433) (xy 230.205811 -244.268688) (xy 230.259782 -244.234437)
			(xy 230.317621 -244.20722) (xy 230.378414 -244.187467) (xy 230.441204 -244.175489) (xy 230.505 -244.171476)
			(xy 230.568796 -244.175489) (xy 230.631586 -244.187467) (xy 230.692379 -244.20722) (xy 230.750218 -244.234437)
			(xy 230.804189 -244.268688) (xy 230.853442 -244.309433) (xy 230.897199 -244.35603) (xy 230.934772 -244.407745)
			(xy 230.965566 -244.46376) (xy 230.989098 -244.523193) (xy 231.004995 -244.585107) (xy 231.013006 -244.648525)
			(xy 231.013508 -244.680486) (xy 231.013006 -244.712447) (xy 231.004995 -244.775865) (xy 230.989098 -244.837779)
			(xy 230.965566 -244.897212) (xy 230.934772 -244.953227) (xy 230.897199 -245.004942) (xy 230.853442 -245.051539)
			(xy 230.804189 -245.092284) (xy 230.750218 -245.126535) (xy 230.692379 -245.153752) (xy 230.631586 -245.173505)
			(xy 230.568796 -245.185483) (xy 230.505 -245.189497) (xy 230.441204 -245.185483) (xy 230.378414 -245.173505)
			(xy 230.317621 -245.153752) (xy 230.259782 -245.126535) (xy 230.205811 -245.092284) (xy 230.156558 -245.051539)
			(xy 230.112801 -245.004942) (xy 230.075228 -244.953227) (xy 230.044434 -244.897212) (xy 230.020902 -244.837779)
			(xy 230.005005 -244.775865) (xy 229.996994 -244.712447) (xy 226.459499 -244.712447) (xy 230.214678 -248.467626)
			(xy 230.222708 -248.474898) (xy 230.242972 -248.482507) (xy 230.264575 -248.481147) (xy 230.274368 -248.476516)
			(xy 230.374952 -248.42343) (xy 230.38943 -248.393458) (xy 230.386382 -248.376948) (xy 230.382232 -248.35361)
			(xy 230.377778 -248.306416) (xy 230.377492 -248.282714) (xy 230.378067 -248.248221) (xy 230.387393 -248.179869)
			(xy 230.405877 -248.113405) (xy 230.433177 -248.050052) (xy 230.468794 -247.990971) (xy 230.512072 -247.93725)
			(xy 230.53675 -247.913144) (xy 230.54437 -247.905778) (xy 230.552498 -247.886982) (xy 230.552498 -247.791732)
			(xy 230.54437 -247.772936) (xy 230.53675 -247.76557) (xy 230.512076 -247.74146) (xy 230.468802 -247.687736)
			(xy 230.433186 -247.628656) (xy 230.405883 -247.565304) (xy 230.387393 -247.498843) (xy 230.378055 -247.430492)
			(xy 230.377492 -247.396) (xy 230.378014 -247.362678) (xy 230.386714 -247.296604) (xy 230.403967 -247.232232)
			(xy 230.429475 -247.170663) (xy 230.462804 -247.112951) (xy 230.503382 -247.060085) (xy 230.550514 -247.012968)
			(xy 230.603395 -246.972408) (xy 230.632 -246.95531) (xy 230.64216 -246.949722) (xy 230.65486 -246.93118)
			(xy 230.671878 -246.831358) (xy 230.665782 -246.809768) (xy 230.658416 -246.801132) (xy 230.64159 -246.780937)
			(xy 230.613229 -246.73668) (xy 230.591441 -246.688845) (xy 230.576666 -246.6384) (xy 230.569204 -246.586368)
			(xy 230.568754 -246.560086) (xy 230.56927 -246.532486) (xy 230.577497 -246.477903) (xy 230.593767 -246.425156)
			(xy 230.617717 -246.375424) (xy 230.648812 -246.329816) (xy 230.686357 -246.289352) (xy 230.729514 -246.254935)
			(xy 230.777318 -246.227336) (xy 230.828702 -246.207169) (xy 230.882517 -246.194886) (xy 230.937562 -246.190761)
			(xy 230.992607 -246.194886) (xy 231.046422 -246.207169) (xy 231.097806 -246.227336) (xy 231.14561 -246.254935)
			(xy 231.188767 -246.289352) (xy 231.226312 -246.329816) (xy 231.257407 -246.375424) (xy 231.281357 -246.425156)
			(xy 231.297627 -246.477903) (xy 231.305854 -246.532486) (xy 231.30637 -246.560086) (xy 231.305908 -246.585756)
			(xy 231.29875 -246.636596) (xy 231.284614 -246.685952) (xy 231.263771 -246.732872) (xy 231.236624 -246.776448)
			(xy 231.203698 -246.815841) (xy 231.184958 -246.83339) (xy 231.176576 -246.841264) (xy 231.16794 -246.862092)
			(xy 231.172512 -246.963184) (xy 231.178787 -246.975122) (xy 232.475784 -246.975122) (xy 232.479855 -246.9195)
			(xy 232.491981 -246.865063) (xy 232.511904 -246.812972) (xy 232.5392 -246.764337) (xy 232.573286 -246.720194)
			(xy 232.613435 -246.681485) (xy 232.658793 -246.649034) (xy 232.708393 -246.623533) (xy 232.761177 -246.605526)
			(xy 232.81602 -246.595396) (xy 232.871754 -246.593359) (xy 232.927191 -246.599459) (xy 232.981148 -246.613565)
			(xy 233.032477 -246.635377) (xy 233.080083 -246.664431) (xy 233.122951 -246.700106) (xy 233.160168 -246.741643)
			(xy 233.190941 -246.788156) (xy 233.214613 -246.838653) (xy 233.230681 -246.89206) (xy 233.238801 -246.947236)
			(xy 233.23931 -246.975122) (xy 233.238801 -247.003008) (xy 233.230681 -247.058184) (xy 233.214613 -247.111591)
			(xy 233.190941 -247.162088) (xy 233.160168 -247.208601) (xy 233.122951 -247.250138) (xy 233.080083 -247.285813)
			(xy 233.032477 -247.314867) (xy 232.981148 -247.336679) (xy 232.927191 -247.350785) (xy 232.871754 -247.356885)
			(xy 232.81602 -247.354848) (xy 232.761177 -247.344718) (xy 232.708393 -247.326711) (xy 232.658793 -247.30121)
			(xy 232.613435 -247.268759) (xy 232.573286 -247.23005) (xy 232.5392 -247.185907) (xy 232.511904 -247.137272)
			(xy 232.491981 -247.085181) (xy 232.479855 -247.030744) (xy 232.475784 -246.975122) (xy 231.178787 -246.975122)
			(xy 231.182926 -246.982996) (xy 231.19207 -246.989854) (xy 231.21858 -247.010525) (xy 231.266455 -247.057718)
			(xy 231.307701 -247.110802) (xy 231.341599 -247.168854) (xy 231.36756 -247.230864) (xy 231.385131 -247.295752)
			(xy 231.394007 -247.362388) (xy 231.394508 -247.396) (xy 231.393932 -247.430492) (xy 231.384604 -247.498844)
			(xy 231.366119 -247.565306) (xy 231.338817 -247.628658) (xy 231.3032 -247.687737) (xy 231.259921 -247.741458)
			(xy 231.23525 -247.76557) (xy 231.22763 -247.772936) (xy 231.219502 -247.791732) (xy 231.219502 -247.886982)
			(xy 231.22763 -247.905778) (xy 231.23525 -247.913144) (xy 231.256804 -247.934123) (xy 231.29534 -247.980308)
			(xy 231.328156 -248.030718) (xy 231.354793 -248.084648) (xy 231.374879 -248.141346) (xy 231.388134 -248.200017)
			(xy 231.391714 -248.229882) (xy 231.392996 -248.238731) (xy 231.400852 -248.254782) (xy 231.413727 -248.267174)
			(xy 231.430066 -248.274411) (xy 231.438958 -248.275348) (xy 231.470697 -248.278011) (xy 231.506388 -248.285)
			(xy 238.25099 -248.285) (xy 238.255003 -248.221204) (xy 238.266981 -248.158414) (xy 238.286734 -248.097621)
			(xy 238.313951 -248.039782) (xy 238.348202 -247.985811) (xy 238.388947 -247.936558) (xy 238.435544 -247.892801)
			(xy 238.487259 -247.855228) (xy 238.543274 -247.824434) (xy 238.602707 -247.800902) (xy 238.664621 -247.785005)
			(xy 238.728039 -247.776994) (xy 238.76 -247.776492) (xy 238.790115 -247.776958) (xy 238.849924 -247.784069)
			(xy 238.908474 -247.798192) (xy 238.964948 -247.81913) (xy 239.018555 -247.846588) (xy 239.068545 -247.880184)
			(xy 239.114218 -247.919447) (xy 239.134904 -247.941338) (xy 239.14227 -247.949466) (xy 239.16132 -247.957848)
			(xy 239.258094 -247.957848) (xy 239.277144 -247.949466) (xy 239.28451 -247.941338) (xy 239.302063 -247.92288)
			(xy 239.341352 -247.890463) (xy 239.384727 -247.863758) (xy 239.431361 -247.843272) (xy 239.48037 -247.829393)
			(xy 239.530822 -247.822387) (xy 239.55629 -247.821958) (xy 239.58389 -247.822515) (xy 239.638472 -247.830741)
			(xy 239.691219 -247.84701) (xy 239.740952 -247.870959) (xy 239.786561 -247.902053) (xy 239.827025 -247.939597)
			(xy 239.861441 -247.982753) (xy 239.889041 -248.030557) (xy 239.909208 -248.08194) (xy 239.921491 -248.135755)
			(xy 239.925617 -248.1908) (xy 239.921491 -248.245845) (xy 239.909208 -248.29966) (xy 239.889041 -248.351043)
			(xy 239.861441 -248.398847) (xy 239.827025 -248.442003) (xy 239.786561 -248.479547) (xy 239.740952 -248.510641)
			(xy 239.691219 -248.53459) (xy 239.638472 -248.550859) (xy 239.58389 -248.559085) (xy 239.55629 -248.559574)
			(xy 239.52895 -248.559104) (xy 239.474871 -248.551015) (xy 239.422583 -248.535019) (xy 239.373236 -248.511465)
			(xy 239.350296 -248.496582) (xy 239.341152 -248.490486) (xy 239.320578 -248.48693) (xy 239.226598 -248.509536)
			(xy 239.210088 -248.522236) (xy 239.204754 -248.531634) (xy 239.187815 -248.560939) (xy 239.147416 -248.615246)
			(xy 239.100173 -248.663717) (xy 239.046918 -248.705495) (xy 238.988594 -248.739841) (xy 238.926231 -248.76615)
			(xy 238.860929 -248.783956) (xy 238.793843 -248.792945) (xy 238.76 -248.793508) (xy 238.728039 -248.793006)
			(xy 238.664621 -248.784995) (xy 238.602707 -248.769098) (xy 238.543274 -248.745566) (xy 238.487259 -248.714772)
			(xy 238.435544 -248.677199) (xy 238.388947 -248.633442) (xy 238.348202 -248.584189) (xy 238.313951 -248.530218)
			(xy 238.286734 -248.472379) (xy 238.266981 -248.411586) (xy 238.255003 -248.348796) (xy 238.25099 -248.285)
			(xy 231.506388 -248.285) (xy 231.533203 -248.290251) (xy 231.593692 -248.310199) (xy 231.651216 -248.337544)
			(xy 231.704877 -248.371857) (xy 231.753833 -248.412601) (xy 231.797319 -248.459139) (xy 231.834655 -248.510742)
			(xy 231.865255 -248.566603) (xy 231.888641 -248.625847) (xy 231.904448 -248.687548) (xy 231.912427 -248.75074)
			(xy 231.912922 -248.782586) (xy 231.912405 -248.815477) (xy 231.903924 -248.880709) (xy 231.887103 -248.944303)
			(xy 231.862222 -249.005196) (xy 231.829696 -249.062374) (xy 231.790069 -249.114879) (xy 231.744002 -249.161837)
			(xy 231.692265 -249.202462) (xy 231.635721 -249.236076) (xy 231.575314 -249.262119) (xy 231.512054 -249.280154)
			(xy 231.479598 -249.285506) (xy 231.469946 -249.28703) (xy 231.45369 -249.296428) (xy 231.398318 -249.365262)
			(xy 231.39273 -249.383296) (xy 231.393238 -249.392948) (xy 231.394508 -249.428) (xy 231.393764 -249.467643)
			(xy 231.381509 -249.545976) (xy 231.378804 -249.555) (xy 238.25099 -249.555) (xy 238.255003 -249.491204)
			(xy 238.266981 -249.428414) (xy 238.286734 -249.367621) (xy 238.313951 -249.309782) (xy 238.348202 -249.255811)
			(xy 238.388947 -249.206558) (xy 238.435544 -249.162801) (xy 238.487259 -249.125228) (xy 238.543274 -249.094434)
			(xy 238.602707 -249.070902) (xy 238.664621 -249.055005) (xy 238.728039 -249.046994) (xy 238.76 -249.046492)
			(xy 238.792819 -249.047038) (xy 238.85791 -249.055487) (xy 238.921372 -249.072246) (xy 238.982149 -249.097034)
			(xy 239.039229 -249.12944) (xy 239.091663 -249.168925) (xy 239.138577 -249.214831) (xy 239.159288 -249.240294)
			(xy 239.165384 -249.247914) (xy 239.18164 -249.257566) (xy 239.269524 -249.271028) (xy 239.287812 -249.266964)
			(xy 239.29594 -249.261376) (xy 239.318952 -249.246416) (xy 239.368479 -249.222759) (xy 239.420966 -249.206706)
			(xy 239.475252 -249.198612) (xy 239.502696 -249.19813) (xy 239.530301 -249.198544) (xy 239.584893 -249.206772)
			(xy 239.63765 -249.223045) (xy 239.687392 -249.246999) (xy 239.733008 -249.278099) (xy 239.77348 -249.315651)
			(xy 239.807902 -249.358815) (xy 239.835507 -249.406627) (xy 239.855677 -249.45802) (xy 239.867963 -249.511845)
			(xy 239.872089 -249.5669) (xy 239.867963 -249.621955) (xy 239.855677 -249.67578) (xy 239.835507 -249.727173)
			(xy 239.807902 -249.774985) (xy 239.77348 -249.818149) (xy 239.733008 -249.855701) (xy 239.687392 -249.886801)
			(xy 239.63765 -249.910755) (xy 239.584893 -249.927028) (xy 239.530301 -249.935256) (xy 239.502696 -249.935746)
			(xy 239.473775 -249.93519) (xy 239.416642 -249.926166) (xy 239.361616 -249.908339) (xy 239.310045 -249.882145)
			(xy 239.286288 -249.865642) (xy 239.278414 -249.8598) (xy 239.260126 -249.855228) (xy 239.171988 -249.865896)
			(xy 239.155224 -249.87504) (xy 239.149128 -249.882406) (xy 239.128397 -249.906339) (xy 239.081918 -249.949343)
			(xy 239.030462 -249.986247) (xy 238.974823 -250.016478) (xy 238.915863 -250.039571) (xy 238.854492 -250.055167)
			(xy 238.791661 -250.063026) (xy 238.76 -250.063508) (xy 238.728039 -250.063006) (xy 238.664621 -250.054995)
			(xy 238.602707 -250.039098) (xy 238.543274 -250.015566) (xy 238.487259 -249.984772) (xy 238.435544 -249.947199)
			(xy 238.388947 -249.903442) (xy 238.348202 -249.854189) (xy 238.313951 -249.800218) (xy 238.286734 -249.742379)
			(xy 238.266981 -249.681586) (xy 238.255003 -249.618796) (xy 238.25099 -249.555) (xy 231.378804 -249.555)
			(xy 231.370124 -249.583956) (xy 231.365552 -249.597672) (xy 231.372156 -249.625104) (xy 233.010456 -251.263404)
			(xy 233.019069 -251.27121) (xy 233.041029 -251.278756) (xy 233.05262 -251.277882) (xy 233.143552 -251.26696)
			(xy 233.16311 -251.254514) (xy 233.169206 -251.244354) (xy 233.177235 -251.231496) (xy 233.195036 -251.206956)
			(xy 233.204766 -251.195332) (xy 233.211624 -251.187204) (xy 233.21772 -251.167646) (xy 233.207306 -251.07265)
			(xy 233.197146 -251.05487) (xy 233.18851 -251.048266) (xy 233.162067 -251.0276) (xy 233.114321 -250.980436)
			(xy 233.073191 -250.927403) (xy 233.039392 -250.869422) (xy 233.013511 -250.8075) (xy 232.995997 -250.742712)
			(xy 232.987155 -250.676184) (xy 232.98658 -250.642628) (xy 232.987082 -250.610667) (xy 232.995093 -250.547249)
			(xy 233.01099 -250.485335) (xy 233.034522 -250.425902) (xy 233.065316 -250.369887) (xy 233.102889 -250.318172)
			(xy 233.146646 -250.271575) (xy 233.195899 -250.23083) (xy 233.24987 -250.196579) (xy 233.307709 -250.169362)
			(xy 233.368502 -250.149609) (xy 233.431292 -250.137631) (xy 233.495088 -250.133618) (xy 233.558884 -250.137631)
			(xy 233.621674 -250.149609) (xy 233.682467 -250.169362) (xy 233.740306 -250.196579) (xy 233.794277 -250.23083)
			(xy 233.84353 -250.271575) (xy 233.887287 -250.318172) (xy 233.92486 -250.369887) (xy 233.955654 -250.425902)
			(xy 233.979186 -250.485335) (xy 233.995083 -250.547249) (xy 234.003094 -250.610667) (xy 234.003596 -250.642628)
			(xy 234.003062 -250.676188) (xy 233.994237 -250.742726) (xy 233.976732 -250.807524) (xy 233.950851 -250.869454)
			(xy 233.917043 -250.927439) (xy 233.875899 -250.98047) (xy 233.828132 -251.027624) (xy 233.801666 -251.048266)
			(xy 233.79303 -251.05487) (xy 233.78287 -251.07265) (xy 233.772456 -251.167646) (xy 233.778552 -251.187204)
			(xy 233.78541 -251.195332) (xy 233.802533 -251.216128) (xy 233.83137 -251.261627) (xy 233.853518 -251.310731)
			(xy 233.868536 -251.362463) (xy 233.876126 -251.415794) (xy 233.876596 -251.442728) (xy 233.876108 -251.470645)
			(xy 233.867965 -251.525883) (xy 233.851858 -251.579343) (xy 233.82813 -251.629885) (xy 233.797289 -251.676429)
			(xy 233.759993 -251.71798) (xy 233.717039 -251.753651) (xy 233.693462 -251.76861) (xy 233.683302 -251.774706)
			(xy 233.670856 -251.794264) (xy 233.659934 -251.885196) (xy 233.659034 -251.896793) (xy 233.66657 -251.918771)
			(xy 233.674412 -251.92736) (xy 234.168696 -252.421644) (xy 234.176092 -252.428497) (xy 234.19469 -252.436242)
			(xy 234.204764 -252.43663)
		)
		(stroke
			(width 0)
			(type solid)
		)
		(fill yes)
		(layer "In6.Cu")
		(net "PVDD11_S3_P0")
	)
	(gr_poly
		(pts
			(xy 303.673256 -409.201112) (xy 304.65268 -409.06446) (xy 304.665126 -409.060904) (xy 311.174892 -406.364694)
			(xy 311.175654 -406.36444) (xy 318.544194 -403.201124) (xy 318.548994 -403.199234) (xy 318.559103 -403.197185)
			(xy 318.56426 -403.19706) (xy 321.240658 -403.19706) (xy 321.250723 -403.196625) (xy 321.269308 -403.188891)
			(xy 321.276726 -403.182074) (xy 321.592194 -402.866606) (xy 321.599042 -402.859208) (xy 321.60678 -402.84061)
			(xy 321.60718 -402.830538) (xy 321.60718 -402.563838) (xy 321.606659 -402.553324) (xy 321.598269 -402.534041)
			(xy 321.590924 -402.5265) (xy 321.571409 -402.507583) (xy 321.538219 -402.464548) (xy 321.512511 -402.416666)
			(xy 321.494976 -402.365226) (xy 321.486085 -402.311611) (xy 321.485514 -402.284438) (xy 321.486063 -402.256949)
			(xy 321.49516 -402.20273) (xy 321.513093 -402.150759) (xy 321.53937 -402.102468) (xy 321.555872 -402.080476)
			(xy 321.561714 -402.07311) (xy 321.567048 -402.05533) (xy 321.561714 -401.969224) (xy 321.554094 -401.95246)
			(xy 321.54749 -401.945856) (xy 321.526471 -401.924222) (xy 321.49084 -401.875555) (xy 321.463309 -401.821889)
			(xy 321.444563 -401.76456) (xy 321.435069 -401.704996) (xy 321.43446 -401.674838) (xy 321.43446 -400.811238)
			(xy 321.435006 -400.78176) (xy 321.444068 -400.723506) (xy 321.461984 -400.667339) (xy 321.488326 -400.614596)
			(xy 321.522467 -400.566533) (xy 321.563596 -400.524293) (xy 321.58686 -400.506184) (xy 321.596512 -400.498818)
			(xy 321.60718 -400.477736) (xy 321.60718 -400.446494) (xy 321.600322 -400.428714) (xy 321.593464 -400.421602)
			(xy 321.576359 -400.402598) (xy 321.548095 -400.359995) (xy 321.527322 -400.31328) (xy 321.51462 -400.263757)
			(xy 321.510346 -400.21281) (xy 321.514617 -400.161863) (xy 321.527315 -400.112339) (xy 321.548085 -400.065622)
			(xy 321.576346 -400.023018) (xy 321.593464 -400.004026) (xy 321.599752 -399.996737) (xy 321.606815 -399.978846)
			(xy 321.60718 -399.969228) (xy 321.60718 -399.314162) (xy 321.606749 -399.304095) (xy 321.599023 -399.285503)
			(xy 321.592194 -399.278094) (xy 321.185286 -398.871186) (xy 321.178432 -398.863791) (xy 321.17069 -398.845192)
			(xy 321.1703 -398.835118) (xy 321.1703 -398.77238) (xy 321.169913 -398.763426) (xy 321.163675 -398.746636)
			(xy 321.158108 -398.739614) (xy 321.14117 -398.718741) (xy 321.114142 -398.672279) (xy 321.095659 -398.621806)
			(xy 321.08629 -398.568878) (xy 321.085718 -398.542002) (xy 321.086258 -398.515123) (xy 321.095619 -398.462187)
			(xy 321.114105 -398.411709) (xy 321.141145 -398.365247) (xy 321.158108 -398.34439) (xy 321.164204 -398.337532)
			(xy 321.1703 -398.320768) (xy 321.1703 -398.2593) (xy 321.16971 -398.248106) (xy 321.160213 -398.227829)
			(xy 321.152012 -398.220184) (xy 321.082924 -398.16278) (xy 321.06108 -398.157192) (xy 321.049904 -398.159478)
			(xy 321.035308 -398.162032) (xy 321.005794 -398.164701) (xy 320.990976 -398.164812) (xy 320.965583 -398.164302)
			(xy 320.915454 -398.156169) (xy 320.867272 -398.140115) (xy 320.822282 -398.116556) (xy 320.781643 -398.086099)
			(xy 320.746405 -398.049529) (xy 320.717474 -398.007789) (xy 320.695599 -397.961957) (xy 320.687954 -397.937736)
			(xy 320.68643 -397.931894) (xy 320.365882 -397.377412) (xy 320.361818 -397.373094) (xy 320.345741 -397.355415)
			(xy 320.318557 -397.316116) (xy 320.297602 -397.273171) (xy 320.283354 -397.22756) (xy 320.276138 -397.180324)
			(xy 320.275712 -397.156432) (xy 320.275798 -397.144384) (xy 320.277581 -397.120355) (xy 320.279268 -397.108426)
			(xy 320.280538 -397.099536) (xy 320.27749 -397.082518) (xy 320.235326 -397.011652) (xy 320.222118 -397.000476)
			(xy 320.213736 -396.997428) (xy 320.191998 -396.98902) (xy 320.151159 -396.966564) (xy 320.114206 -396.938162)
			(xy 320.081999 -396.904475) (xy 320.055284 -396.866285) (xy 320.034683 -396.824479) (xy 320.020674 -396.780029)
			(xy 320.013583 -396.733965) (xy 320.013076 -396.710662) (xy 320.013575 -396.685264) (xy 320.021975 -396.635167)
			(xy 320.038551 -396.587151) (xy 320.062848 -396.542542) (xy 320.094195 -396.502572) (xy 320.112644 -396.48511)
			(xy 320.121026 -396.47749) (xy 320.129662 -396.457424) (xy 320.126868 -396.35811) (xy 320.11747 -396.338552)
			(xy 320.10858 -396.33144) (xy 320.09002 -396.315637) (xy 320.057295 -396.27951) (xy 320.030224 -396.238972)
			(xy 320.009392 -396.194903) (xy 319.995251 -396.148254) (xy 319.988106 -396.100035) (xy 319.987676 -396.075662)
			(xy 319.988115 -396.051546) (xy 319.99512 -396.003825) (xy 320.008976 -395.957627) (xy 320.029391 -395.913928)
			(xy 320.042286 -395.893544) (xy 320.048128 -395.884654) (xy 320.051684 -395.864588) (xy 320.030602 -395.772386)
			(xy 320.01841 -395.755622) (xy 320.00952 -395.750288) (xy 319.988714 -395.737435) (xy 319.95079 -395.706561)
			(xy 319.917833 -395.670432) (xy 319.890563 -395.629838) (xy 319.869576 -395.585667) (xy 319.855332 -395.538885)
			(xy 319.848142 -395.490514) (xy 319.847722 -395.466062) (xy 319.848283 -395.43878) (xy 319.857244 -395.384956)
			(xy 319.874918 -395.333332) (xy 319.900823 -395.285309) (xy 319.934259 -395.242189) (xy 319.953894 -395.223238)
			(xy 319.961343 -395.215746) (xy 319.969887 -395.196451) (xy 319.970404 -395.1859) (xy 319.970404 -395.111224)
			(xy 319.969818 -395.100689) (xy 319.96129 -395.081412) (xy 319.953894 -395.073886) (xy 319.935606 -395.056356)
			(xy 319.904097 -395.01669) (xy 319.879025 -394.972673) (xy 319.869566 -394.949172) (xy 319.863978 -394.93444)
			(xy 319.83807 -394.91666) (xy 319.31864 -394.91666) (xy 319.292732 -394.93444) (xy 319.287144 -394.949172)
			(xy 319.277643 -394.972652) (xy 319.252554 -395.01665) (xy 319.221067 -395.056323) (xy 319.202816 -395.073886)
			(xy 319.195369 -395.081379) (xy 319.186833 -395.100674) (xy 319.186306 -395.111224) (xy 319.186306 -395.1859)
			(xy 319.186897 -395.196433) (xy 319.195431 -395.215702) (xy 319.202816 -395.223238) (xy 319.222472 -395.24217)
			(xy 319.255915 -395.28529) (xy 319.281824 -395.333317) (xy 319.299494 -395.384947) (xy 319.308445 -395.438777)
			(xy 319.308988 -395.466062) (xy 319.308555 -395.49018) (xy 319.301559 -395.537904) (xy 319.28771 -395.584108)
			(xy 319.267301 -395.627813) (xy 319.254378 -395.64818) (xy 319.248536 -395.65707) (xy 319.24498 -395.677136)
			(xy 319.266062 -395.769338) (xy 319.278254 -395.786102) (xy 319.287144 -395.791436) (xy 319.307945 -395.804292)
			(xy 319.34586 -395.835171) (xy 319.378809 -395.871302) (xy 319.40607 -395.911896) (xy 319.427049 -395.956065)
			(xy 319.441287 -396.002845) (xy 319.448472 -396.051213) (xy 319.448942 -396.075662) (xy 319.448504 -396.100033)
			(xy 319.441348 -396.148246) (xy 319.4272 -396.194888) (xy 319.406365 -396.238952) (xy 319.379295 -396.279485)
			(xy 319.346573 -396.31561) (xy 319.328038 -396.33144) (xy 319.319148 -396.338552) (xy 319.30975 -396.35811)
			(xy 319.306956 -396.457424) (xy 319.315592 -396.47749) (xy 319.323974 -396.48511) (xy 319.342397 -396.502597)
			(xy 319.373742 -396.542564) (xy 319.398041 -396.587167) (xy 319.414624 -396.635175) (xy 319.423035 -396.685266)
			(xy 319.423542 -396.710662) (xy 319.42347 -396.72002) (xy 319.422324 -396.738702) (xy 319.421256 -396.748)
			(xy 319.42024 -396.75689) (xy 319.42405 -396.773654) (xy 319.467992 -396.843504) (xy 319.481708 -396.853918)
			(xy 319.49009 -396.856712) (xy 319.514127 -396.865164) (xy 319.559311 -396.888708) (xy 319.600126 -396.919204)
			(xy 319.635512 -396.95586) (xy 319.664552 -396.997724) (xy 319.686489 -397.04371) (xy 319.694052 -397.06804)
			(xy 319.695576 -397.073882) (xy 320.01587 -397.627602) (xy 320.019934 -397.63192) (xy 320.036123 -397.649629)
			(xy 320.063498 -397.689032) (xy 320.084588 -397.732128) (xy 320.098907 -397.777921) (xy 320.106123 -397.825354)
			(xy 320.106548 -397.849344) (xy 320.106058 -397.874131) (xy 320.098297 -397.923093) (xy 320.082972 -397.970238)
			(xy 320.060461 -398.014406) (xy 320.031318 -398.054509) (xy 319.99626 -398.089559) (xy 319.956152 -398.118694)
			(xy 319.911979 -398.141196) (xy 319.864831 -398.156512) (xy 319.815867 -398.164263) (xy 319.79108 -398.164812)
			(xy 319.765687 -398.164303) (xy 319.715557 -398.15617) (xy 319.667375 -398.140117) (xy 319.622384 -398.116558)
			(xy 319.581745 -398.0861) (xy 319.546506 -398.04953) (xy 319.517575 -398.00779) (xy 319.495699 -397.961958)
			(xy 319.488058 -397.937736) (xy 319.486534 -397.931894) (xy 319.16624 -397.378174) (xy 319.162176 -397.373856)
			(xy 319.145962 -397.356157) (xy 319.118534 -397.316767) (xy 319.097392 -397.273675) (xy 319.083023 -397.227877)
			(xy 319.07576 -397.180431) (xy 319.075308 -397.156432) (xy 319.075466 -397.14438) (xy 319.077375 -397.120352)
			(xy 319.079118 -397.108426) (xy 319.080388 -397.099536) (xy 319.07734 -397.082518) (xy 319.035176 -397.011652)
			(xy 319.021968 -397.000476) (xy 319.013586 -396.997428) (xy 318.991845 -396.989023) (xy 318.951 -396.96657)
			(xy 318.914042 -396.938171) (xy 318.881829 -396.904485) (xy 318.855109 -396.866294) (xy 318.834505 -396.824487)
			(xy 318.820493 -396.780033) (xy 318.8134 -396.733967) (xy 318.812926 -396.710662) (xy 318.813426 -396.685264)
			(xy 318.821826 -396.635168) (xy 318.838405 -396.587155) (xy 318.862705 -396.542549) (xy 318.894054 -396.502582)
			(xy 318.912494 -396.48511) (xy 318.920876 -396.47749) (xy 318.929512 -396.457424) (xy 318.926718 -396.35811)
			(xy 318.91732 -396.338552) (xy 318.90843 -396.33144) (xy 318.889867 -396.315638) (xy 318.857138 -396.279513)
			(xy 318.830063 -396.238976) (xy 318.809228 -396.194906) (xy 318.795084 -396.148256) (xy 318.787938 -396.100036)
			(xy 318.787526 -396.075662) (xy 318.787965 -396.051546) (xy 318.794971 -396.003826) (xy 318.808829 -395.957628)
			(xy 318.829246 -395.913931) (xy 318.842136 -395.893544) (xy 318.847978 -395.884654) (xy 318.851534 -395.864588)
			(xy 318.830452 -395.772386) (xy 318.81826 -395.755622) (xy 318.80937 -395.750288) (xy 318.788567 -395.737433)
			(xy 318.750648 -395.706556) (xy 318.717696 -395.670426) (xy 318.69043 -395.629832) (xy 318.669447 -395.585662)
			(xy 318.655205 -395.538882) (xy 318.648016 -395.490512) (xy 318.647572 -395.466062) (xy 318.648133 -395.438779)
			(xy 318.657093 -395.384954) (xy 318.674764 -395.333329) (xy 318.700667 -395.285304) (xy 318.7341 -395.24218)
			(xy 318.753744 -395.223238) (xy 318.761199 -395.215749) (xy 318.769752 -395.196453) (xy 318.770254 -395.1859)
			(xy 318.770254 -395.111224) (xy 318.769667 -395.10069) (xy 318.761133 -395.081418) (xy 318.753744 -395.073886)
			(xy 318.735458 -395.056354) (xy 318.703954 -395.016687) (xy 318.678886 -394.972668) (xy 318.669416 -394.949172)
			(xy 318.663828 -394.93444) (xy 318.63792 -394.91666) (xy 318.118744 -394.91666) (xy 318.092836 -394.93444)
			(xy 318.087248 -394.949172) (xy 318.077747 -394.972652) (xy 318.052659 -395.016651) (xy 318.021172 -395.056324)
			(xy 318.00292 -395.073886) (xy 317.995473 -395.081378) (xy 317.986936 -395.100674) (xy 317.98641 -395.111224)
			(xy 317.98641 -395.1859) (xy 317.987001 -395.196433) (xy 317.995536 -395.215702) (xy 318.00292 -395.223238)
			(xy 318.022575 -395.24217) (xy 318.056019 -395.285291) (xy 318.081927 -395.333317) (xy 318.099597 -395.384947)
			(xy 318.108548 -395.438777) (xy 318.109092 -395.466062) (xy 318.108659 -395.49018) (xy 318.101663 -395.537904)
			(xy 318.087814 -395.584109) (xy 318.067405 -395.627813) (xy 318.054482 -395.64818) (xy 318.04864 -395.65707)
			(xy 318.045084 -395.677136) (xy 318.066166 -395.769338) (xy 318.078358 -395.786102) (xy 318.087248 -395.791436)
			(xy 318.108049 -395.804292) (xy 318.145964 -395.835171) (xy 318.178912 -395.871302) (xy 318.206173 -395.911896)
			(xy 318.227151 -395.956066) (xy 318.241389 -396.002845) (xy 318.248574 -396.051213) (xy 318.249046 -396.075662)
			(xy 318.248608 -396.100033) (xy 318.241452 -396.148246) (xy 318.227304 -396.194889) (xy 318.20647 -396.238953)
			(xy 318.179399 -396.279485) (xy 318.146678 -396.315611) (xy 318.128142 -396.33144) (xy 318.119252 -396.338552)
			(xy 318.109854 -396.35811) (xy 318.10706 -396.457424) (xy 318.115696 -396.47749) (xy 318.124078 -396.48511)
			(xy 318.142501 -396.502597) (xy 318.173845 -396.542564) (xy 318.198144 -396.587167) (xy 318.214727 -396.635175)
			(xy 318.223138 -396.685266) (xy 318.223646 -396.710662) (xy 318.223574 -396.72002) (xy 318.222428 -396.738702)
			(xy 318.22136 -396.748) (xy 318.220344 -396.75689) (xy 318.224154 -396.773654) (xy 318.268096 -396.843504)
			(xy 318.281812 -396.853918) (xy 318.290194 -396.856712) (xy 318.31429 -396.865195) (xy 318.359577 -396.888825)
			(xy 318.40047 -396.919438) (xy 318.435901 -396.956234) (xy 318.464947 -396.998253) (xy 318.48685 -397.044401)
			(xy 318.49441 -397.068802) (xy 318.495934 -397.074644) (xy 318.81572 -397.627602) (xy 318.819784 -397.63192)
			(xy 318.836002 -397.649618) (xy 318.863436 -397.689006) (xy 318.884584 -397.732098) (xy 318.898958 -397.777896)
			(xy 318.906225 -397.825343) (xy 318.906652 -397.849344) (xy 318.906187 -397.874146) (xy 318.898417 -397.923136)
			(xy 318.883075 -397.970308) (xy 318.86054 -398.014496) (xy 318.831367 -398.054614) (xy 318.796275 -398.089671)
			(xy 318.756128 -398.118804) (xy 318.711917 -398.141295) (xy 318.664731 -398.15659) (xy 318.615732 -398.164311)
			(xy 318.59093 -398.164812) (xy 318.565535 -398.164307) (xy 318.515399 -398.15618) (xy 318.467211 -398.140132)
			(xy 318.422213 -398.116576) (xy 318.381568 -398.08612) (xy 318.346322 -398.04955) (xy 318.317385 -398.007808)
			(xy 318.295505 -397.961973) (xy 318.287908 -397.937736) (xy 318.286384 -397.931894) (xy 317.965836 -397.377412)
			(xy 317.961772 -397.373094) (xy 317.945666 -397.355426) (xy 317.918424 -397.316142) (xy 317.897411 -397.273201)
			(xy 317.883108 -397.227585) (xy 317.87584 -397.180334) (xy 317.875412 -397.156432) (xy 317.87557 -397.14438)
			(xy 317.877479 -397.120352) (xy 317.879222 -397.108426) (xy 317.880492 -397.099536) (xy 317.877444 -397.082518)
			(xy 317.83528 -397.011652) (xy 317.822072 -397.000476) (xy 317.81369 -396.997428) (xy 317.791949 -396.989023)
			(xy 317.751104 -396.966571) (xy 317.714145 -396.938172) (xy 317.681931 -396.904486) (xy 317.655211 -396.866295)
			(xy 317.634606 -396.824487) (xy 317.620594 -396.780034) (xy 317.613501 -396.733967) (xy 317.61303 -396.710662)
			(xy 317.61353 -396.685264) (xy 317.62193 -396.635168) (xy 317.638509 -396.587155) (xy 317.662809 -396.542549)
			(xy 317.694159 -396.502582) (xy 317.712598 -396.48511) (xy 317.72098 -396.47749) (xy 317.729616 -396.457424)
			(xy 317.726822 -396.35811) (xy 317.717424 -396.338552) (xy 317.708534 -396.33144) (xy 317.689971 -396.315639)
			(xy 317.657241 -396.279513) (xy 317.630166 -396.238977) (xy 317.609331 -396.194906) (xy 317.595187 -396.148256)
			(xy 317.58804 -396.100036) (xy 317.58763 -396.075662) (xy 317.588069 -396.051546) (xy 317.595075 -396.003826)
			(xy 317.608933 -395.957628) (xy 317.629351 -395.913931) (xy 317.64224 -395.893544) (xy 317.648082 -395.884654)
			(xy 317.651638 -395.864588) (xy 317.630556 -395.772386) (xy 317.618364 -395.755622) (xy 317.609474 -395.750288)
			(xy 317.588671 -395.737433) (xy 317.550751 -395.706556) (xy 317.517799 -395.670426) (xy 317.490533 -395.629833)
			(xy 317.469549 -395.585663) (xy 317.455308 -395.538882) (xy 317.448118 -395.490513) (xy 317.447676 -395.466062)
			(xy 317.448237 -395.438779) (xy 317.457197 -395.384954) (xy 317.474869 -395.333329) (xy 317.500772 -395.285304)
			(xy 317.534205 -395.242181) (xy 317.553848 -395.223238) (xy 317.561303 -395.215749) (xy 317.569855 -395.196453)
			(xy 317.570358 -395.1859) (xy 317.570358 -395.111224) (xy 317.569771 -395.10069) (xy 317.561238 -395.081418)
			(xy 317.553848 -395.073886) (xy 317.535562 -395.056355) (xy 317.504057 -395.016687) (xy 317.478989 -394.972668)
			(xy 317.46952 -394.949172) (xy 317.463932 -394.93444) (xy 317.438024 -394.91666) (xy 316.918594 -394.91666)
			(xy 316.892686 -394.93444) (xy 316.887098 -394.949172) (xy 316.877104 -394.973819) (xy 316.850403 -395.019813)
			(xy 316.816685 -395.06094) (xy 316.776819 -395.09614) (xy 316.731834 -395.124507) (xy 316.682888 -395.145307)
			(xy 316.631245 -395.158006) (xy 316.578234 -395.162276) (xy 316.525223 -395.158006) (xy 316.47358 -395.145307)
			(xy 316.424634 -395.124507) (xy 316.379649 -395.09614) (xy 316.339783 -395.06094) (xy 316.306065 -395.019813)
			(xy 316.279364 -394.973819) (xy 316.26937 -394.949172) (xy 316.263782 -394.93444) (xy 316.237874 -394.91666)
			(xy 315.718698 -394.91666) (xy 315.69279 -394.93444) (xy 315.687202 -394.949172) (xy 315.680469 -394.966072)
			(xy 315.663792 -394.998403) (xy 315.653928 -395.013688) (xy 315.649174 -395.021658) (xy 315.64515 -395.039757)
			(xy 315.646054 -395.048994) (xy 315.650372 -395.079982) (xy 315.652175 -395.089236) (xy 315.661429 -395.105644)
			(xy 315.668406 -395.111986) (xy 315.690502 -395.13066) (xy 315.730278 -395.172669) (xy 315.764442 -395.219357)
			(xy 315.792449 -395.269979) (xy 315.813853 -395.323726) (xy 315.828312 -395.379743) (xy 315.835595 -395.437136)
			(xy 315.836046 -395.466062) (xy 315.835442 -395.499382) (xy 315.825772 -395.565316) (xy 315.806645 -395.629152)
			(xy 315.79312 -395.65961) (xy 315.78886 -395.67008) (xy 315.788936 -395.692654) (xy 315.798684 -395.713016)
			(xy 315.80709 -395.72057) (xy 315.829339 -395.739243) (xy 315.869406 -395.781297) (xy 315.903831 -395.828083)
			(xy 315.93206 -395.878848) (xy 315.95364 -395.932776) (xy 315.968224 -395.989001) (xy 315.975577 -396.046619)
			(xy 315.976 -396.075662) (xy 315.975549 -396.104666) (xy 315.968218 -396.162209) (xy 315.953682 -396.218366)
			(xy 315.932172 -396.272238) (xy 315.904033 -396.322964) (xy 315.869715 -396.369732) (xy 315.829768 -396.411793)
			(xy 315.807598 -396.4305) (xy 315.800486 -396.436088) (xy 315.791342 -396.451328) (xy 315.776102 -396.534132)
			(xy 315.778896 -396.551404) (xy 315.783468 -396.559532) (xy 315.796063 -396.58271) (xy 315.813951 -396.632331)
			(xy 315.823034 -396.684289) (xy 315.8236 -396.710662) (xy 316.41288 -396.710662) (xy 316.413402 -396.685407)
			(xy 316.421715 -396.635585) (xy 316.438116 -396.587811) (xy 316.462157 -396.543388) (xy 316.493181 -396.503528)
			(xy 316.530343 -396.469318) (xy 316.572629 -396.441692) (xy 316.618885 -396.421402) (xy 316.66785 -396.409002)
			(xy 316.718188 -396.404831) (xy 316.768526 -396.409002) (xy 316.817491 -396.421402) (xy 316.863747 -396.441692)
			(xy 316.906033 -396.469318) (xy 316.943195 -396.503528) (xy 316.974219 -396.543388) (xy 316.99826 -396.587811)
			(xy 317.014661 -396.635585) (xy 317.022974 -396.685407) (xy 317.023496 -396.710662) (xy 317.023428 -396.720021)
			(xy 317.022284 -396.738703) (xy 317.02121 -396.748) (xy 317.020194 -396.75689) (xy 317.024004 -396.773654)
			(xy 317.067946 -396.843504) (xy 317.081662 -396.853918) (xy 317.090044 -396.856712) (xy 317.114073 -396.865178)
			(xy 317.159245 -396.888731) (xy 317.20005 -396.919231) (xy 317.235429 -396.955886) (xy 317.264465 -396.997746)
			(xy 317.286403 -397.043724) (xy 317.294006 -397.06804) (xy 317.29553 -397.073882) (xy 317.615824 -397.627602)
			(xy 317.619888 -397.63192) (xy 317.636078 -397.64964) (xy 317.663504 -397.689028) (xy 317.68465 -397.732114)
			(xy 317.699027 -397.777906) (xy 317.706304 -397.825346) (xy 317.706756 -397.849344) (xy 317.706347 -397.87415)
			(xy 317.698575 -397.92315) (xy 317.683231 -397.97033) (xy 317.660692 -398.014527) (xy 317.631514 -398.054651)
			(xy 317.596415 -398.089715) (xy 317.556262 -398.118854) (xy 317.512043 -398.14135) (xy 317.464848 -398.156648)
			(xy 317.415841 -398.164371) (xy 317.391034 -398.164812) (xy 317.365641 -398.164282) (xy 317.315508 -398.156156)
			(xy 317.267324 -398.14011) (xy 317.222329 -398.116556) (xy 317.181686 -398.086103) (xy 317.146443 -398.049535)
			(xy 317.117508 -398.007797) (xy 317.095629 -397.961965) (xy 317.088012 -397.937736) (xy 317.086488 -397.931894)
			(xy 316.766194 -397.378174) (xy 316.76213 -397.373856) (xy 316.745967 -397.356126) (xy 316.7186 -397.316722)
			(xy 316.69751 -397.273631) (xy 316.683184 -397.227846) (xy 316.67595 -397.18042) (xy 316.675516 -397.156432)
			(xy 316.675597 -397.144384) (xy 316.677379 -397.120355) (xy 316.679072 -397.108426) (xy 316.680342 -397.099536)
			(xy 316.677294 -397.082518) (xy 316.63513 -397.011652) (xy 316.621922 -397.000476) (xy 316.61354 -396.997428)
			(xy 316.591786 -396.989049) (xy 316.550928 -396.966604) (xy 316.513959 -396.938208) (xy 316.481737 -396.90452)
			(xy 316.455013 -396.866324) (xy 316.434408 -396.824508) (xy 316.420401 -396.780046) (xy 316.413318 -396.73397)
			(xy 316.41288 -396.710662) (xy 315.8236 -396.710662) (xy 315.823528 -396.72002) (xy 315.822382 -396.738702)
			(xy 315.821314 -396.748) (xy 315.820298 -396.75689) (xy 315.824108 -396.773654) (xy 315.86805 -396.843504)
			(xy 315.881766 -396.853918) (xy 315.890148 -396.856712) (xy 315.914182 -396.865168) (xy 315.959359 -396.888717)
			(xy 316.000167 -396.919216) (xy 316.035547 -396.955874) (xy 316.06458 -396.997738) (xy 316.086513 -397.043721)
			(xy 316.09411 -397.06804) (xy 316.095634 -397.073882) (xy 316.415928 -397.627602) (xy 316.419992 -397.63192)
			(xy 316.436209 -397.649618) (xy 316.463643 -397.689007) (xy 316.48479 -397.732098) (xy 316.499164 -397.777896)
			(xy 316.506431 -397.825344) (xy 316.50686 -397.849344) (xy 316.506395 -397.874146) (xy 316.498625 -397.923137)
			(xy 316.483283 -397.970309) (xy 316.460748 -398.014498) (xy 316.431575 -398.054616) (xy 316.396483 -398.089674)
			(xy 316.356337 -398.118808) (xy 316.312126 -398.1413) (xy 316.264939 -398.156596) (xy 316.21594 -398.164319)
			(xy 316.191138 -398.164812) (xy 316.165742 -398.164307) (xy 316.115606 -398.156182) (xy 316.067416 -398.140134)
			(xy 316.022418 -398.116579) (xy 315.981771 -398.086123) (xy 315.946524 -398.049553) (xy 315.917587 -398.007811)
			(xy 315.895706 -397.961975) (xy 315.888116 -397.937736) (xy 315.886592 -397.931894) (xy 315.566298 -397.378174)
			(xy 315.562234 -397.373856) (xy 315.546043 -397.356148) (xy 315.518666 -397.316746) (xy 315.497574 -397.27365)
			(xy 315.483255 -397.227857) (xy 315.476041 -397.180422) (xy 315.47562 -397.156432) (xy 315.475706 -397.144384)
			(xy 315.477489 -397.120355) (xy 315.479176 -397.108426) (xy 315.480446 -397.099536) (xy 315.477398 -397.082518)
			(xy 315.435234 -397.011652) (xy 315.422026 -397.000476) (xy 315.413644 -396.997428) (xy 315.391906 -396.989021)
			(xy 315.351065 -396.966565) (xy 315.314112 -396.938164) (xy 315.281903 -396.904477) (xy 315.255188 -396.866287)
			(xy 315.234587 -396.824481) (xy 315.220577 -396.780029) (xy 315.213485 -396.733965) (xy 315.212984 -396.710662)
			(xy 315.213566 -396.684292) (xy 315.222669 -396.632341) (xy 315.240545 -396.582721) (xy 315.253116 -396.559532)
			(xy 315.257688 -396.551404) (xy 315.260482 -396.534132) (xy 315.245242 -396.451328) (xy 315.236098 -396.436088)
			(xy 315.228986 -396.4305) (xy 315.206795 -396.411816) (xy 315.166841 -396.369757) (xy 315.132521 -396.322988)
			(xy 315.104384 -396.272258) (xy 315.082882 -396.218379) (xy 315.068359 -396.162216) (xy 315.061048 -396.104668)
			(xy 315.060584 -396.075662) (xy 315.061187 -396.042342) (xy 315.070852 -395.976405) (xy 315.089972 -395.912566)
			(xy 315.10351 -395.882114) (xy 315.107779 -395.871644) (xy 315.107714 -395.849064) (xy 315.097959 -395.828698)
			(xy 315.08954 -395.821154) (xy 315.067298 -395.802478) (xy 315.027243 -395.760419) (xy 314.992831 -395.713631)
			(xy 314.964615 -395.662866) (xy 314.943047 -395.608938) (xy 314.928475 -395.552716) (xy 314.921132 -395.495102)
			(xy 314.92063 -395.466062) (xy 314.921075 -395.437137) (xy 314.928369 -395.379747) (xy 314.942835 -395.323734)
			(xy 314.964243 -395.26999) (xy 314.992252 -395.219372) (xy 315.026416 -395.172686) (xy 315.066189 -395.130676)
			(xy 315.08827 -395.111986) (xy 315.095341 -395.105719) (xy 315.104621 -395.089278) (xy 315.106304 -395.079982)
			(xy 315.110622 -395.048994) (xy 315.11157 -395.039756) (xy 315.107537 -395.021644) (xy 315.102748 -395.013688)
			(xy 315.092896 -394.998396) (xy 315.076216 -394.966067) (xy 315.069474 -394.949172) (xy 315.063886 -394.93444)
			(xy 315.037978 -394.91666) (xy 314.518548 -394.91666) (xy 314.49264 -394.93444) (xy 314.487052 -394.949172)
			(xy 314.477551 -394.972652) (xy 314.452463 -395.016651) (xy 314.420976 -395.056324) (xy 314.402724 -395.073886)
			(xy 314.395276 -395.081378) (xy 314.386738 -395.100674) (xy 314.386214 -395.111224) (xy 314.386214 -395.1859)
			(xy 314.386805 -395.196433) (xy 314.395341 -395.215701) (xy 314.402724 -395.223238) (xy 314.422379 -395.24217)
			(xy 314.455822 -395.285291) (xy 314.48173 -395.333318) (xy 314.499399 -395.384947) (xy 314.508351 -395.438777)
			(xy 314.508896 -395.466062) (xy 314.508463 -395.49018) (xy 314.501467 -395.537905) (xy 314.487618 -395.584109)
			(xy 314.46721 -395.627813) (xy 314.454286 -395.64818) (xy 314.448444 -395.65707) (xy 314.444888 -395.677136)
			(xy 314.46597 -395.769338) (xy 314.478162 -395.786102) (xy 314.487052 -395.791436) (xy 314.507853 -395.804292)
			(xy 314.545767 -395.835171) (xy 314.578715 -395.871303) (xy 314.605975 -395.911897) (xy 314.626954 -395.956066)
			(xy 314.641191 -396.002845) (xy 314.648376 -396.051213) (xy 314.64885 -396.075662) (xy 314.648412 -396.100033)
			(xy 314.641257 -396.148246) (xy 314.627108 -396.194889) (xy 314.606274 -396.238953) (xy 314.579204 -396.279486)
			(xy 314.546483 -396.315612) (xy 314.527946 -396.33144) (xy 314.519056 -396.338552) (xy 314.509658 -396.35811)
			(xy 314.506864 -396.457424) (xy 314.5155 -396.47749) (xy 314.523882 -396.48511) (xy 314.542305 -396.502597)
			(xy 314.573648 -396.542565) (xy 314.597947 -396.587167) (xy 314.61453 -396.635176) (xy 314.62294 -396.685266)
			(xy 314.62345 -396.710662) (xy 314.623378 -396.72002) (xy 314.622232 -396.738702) (xy 314.621164 -396.748)
			(xy 314.620148 -396.75689) (xy 314.623958 -396.773654) (xy 314.6679 -396.843504) (xy 314.681616 -396.853918)
			(xy 314.689998 -396.856712) (xy 314.714034 -396.865165) (xy 314.759217 -396.888709) (xy 314.800031 -396.919206)
			(xy 314.835417 -396.955862) (xy 314.864456 -396.997726) (xy 314.886392 -397.043711) (xy 314.89396 -397.06804)
			(xy 314.895484 -397.073882) (xy 315.215778 -397.627602) (xy 315.219842 -397.63192) (xy 315.23603 -397.64963)
			(xy 315.263405 -397.689033) (xy 315.284495 -397.732128) (xy 315.298813 -397.777921) (xy 315.306029 -397.825354)
			(xy 315.306456 -397.849344) (xy 315.305966 -397.874131) (xy 315.298205 -397.923094) (xy 315.28288 -397.97024)
			(xy 315.260369 -398.014408) (xy 315.231226 -398.054511) (xy 315.196169 -398.089562) (xy 315.15606 -398.118698)
			(xy 315.111888 -398.141201) (xy 315.064739 -398.156518) (xy 315.015775 -398.164271) (xy 314.990988 -398.164812)
			(xy 314.965595 -398.164303) (xy 314.915464 -398.156171) (xy 314.867281 -398.140119) (xy 314.822289 -398.116561)
			(xy 314.781649 -398.086103) (xy 314.746408 -398.049533) (xy 314.717477 -398.007793) (xy 314.6956 -397.96196)
			(xy 314.687966 -397.937736) (xy 314.686442 -397.931894) (xy 314.366148 -397.378174) (xy 314.362084 -397.373856)
			(xy 314.345869 -397.356157) (xy 314.318441 -397.316767) (xy 314.297298 -397.273675) (xy 314.282929 -397.227878)
			(xy 314.275666 -397.180432) (xy 314.275216 -397.156432) (xy 314.275374 -397.14438) (xy 314.277283 -397.120352)
			(xy 314.279026 -397.108426) (xy 314.280296 -397.099536) (xy 314.277248 -397.082518) (xy 314.235084 -397.011652)
			(xy 314.221876 -397.000476) (xy 314.213494 -396.997428) (xy 314.191753 -396.989023) (xy 314.150907 -396.966571)
			(xy 314.113947 -396.938173) (xy 314.081734 -396.904486) (xy 314.055013 -396.866296) (xy 314.034408 -396.824488)
			(xy 314.020396 -396.780034) (xy 314.013303 -396.733967) (xy 314.012834 -396.710662) (xy 314.013334 -396.685264)
			(xy 314.021734 -396.635169) (xy 314.038313 -396.587155) (xy 314.062614 -396.54255) (xy 314.093964 -396.502583)
			(xy 314.112402 -396.48511) (xy 314.120784 -396.47749) (xy 314.12942 -396.457424) (xy 314.126626 -396.35811)
			(xy 314.117228 -396.338552) (xy 314.108338 -396.33144) (xy 314.089775 -396.315639) (xy 314.057045 -396.279513)
			(xy 314.029969 -396.238977) (xy 314.009133 -396.194907) (xy 313.994989 -396.148256) (xy 313.987843 -396.100036)
			(xy 313.987434 -396.075662) (xy 313.987873 -396.051546) (xy 313.994879 -396.003826) (xy 314.008738 -395.957629)
			(xy 314.029155 -395.913932) (xy 314.042044 -395.893544) (xy 314.047886 -395.884654) (xy 314.051442 -395.864588)
			(xy 314.03036 -395.772386) (xy 314.018168 -395.755622) (xy 314.009278 -395.750288) (xy 313.988475 -395.737434)
			(xy 313.950555 -395.706557) (xy 313.917602 -395.670427) (xy 313.890335 -395.629833) (xy 313.869352 -395.585663)
			(xy 313.85511 -395.538882) (xy 313.84792 -395.490513) (xy 313.84748 -395.466062) (xy 313.848041 -395.438779)
			(xy 313.857001 -395.384954) (xy 313.874673 -395.33333) (xy 313.900576 -395.285305) (xy 313.93401 -395.242181)
			(xy 313.953652 -395.223238) (xy 313.961106 -395.215749) (xy 313.969658 -395.196453) (xy 313.970162 -395.1859)
			(xy 313.970162 -395.111224) (xy 313.969575 -395.10069) (xy 313.961042 -395.081417) (xy 313.953652 -395.073886)
			(xy 313.935366 -395.056355) (xy 313.903861 -395.016687) (xy 313.878792 -394.972669) (xy 313.869324 -394.949172)
			(xy 313.863736 -394.93444) (xy 313.837828 -394.91666) (xy 313.318652 -394.91666) (xy 313.292744 -394.93444)
			(xy 313.287156 -394.949172) (xy 313.277655 -394.972652) (xy 313.252567 -395.016651) (xy 313.221081 -395.056325)
			(xy 313.202828 -395.073886) (xy 313.19538 -395.081378) (xy 313.186841 -395.100673) (xy 313.186318 -395.111224)
			(xy 313.186318 -395.1859) (xy 313.186909 -395.196433) (xy 313.195445 -395.215701) (xy 313.202828 -395.223238)
			(xy 313.222483 -395.24217) (xy 313.255926 -395.285291) (xy 313.281833 -395.333318) (xy 313.299502 -395.384947)
			(xy 313.308453 -395.438777) (xy 313.309 -395.466062) (xy 313.308567 -395.49018) (xy 313.301571 -395.537905)
			(xy 313.287723 -395.584109) (xy 313.267314 -395.627814) (xy 313.25439 -395.64818) (xy 313.248548 -395.65707)
			(xy 313.244992 -395.677136) (xy 313.266074 -395.769338) (xy 313.278266 -395.786102) (xy 313.287156 -395.791436)
			(xy 313.307957 -395.804292) (xy 313.34587 -395.835172) (xy 313.378818 -395.871303) (xy 313.406078 -395.911897)
			(xy 313.427056 -395.956066) (xy 313.441293 -396.002846) (xy 313.448478 -396.051213) (xy 313.448954 -396.075662)
			(xy 313.448516 -396.100033) (xy 313.441361 -396.148246) (xy 313.427213 -396.194889) (xy 313.406378 -396.238953)
			(xy 313.379308 -396.279487) (xy 313.346588 -396.315613) (xy 313.32805 -396.33144) (xy 313.31916 -396.338552)
			(xy 313.309762 -396.35811) (xy 313.306968 -396.457424) (xy 313.315604 -396.47749) (xy 313.323986 -396.48511)
			(xy 313.342409 -396.502597) (xy 313.373752 -396.542565) (xy 313.39805 -396.587167) (xy 313.414633 -396.635176)
			(xy 313.423043 -396.685266) (xy 313.423554 -396.710662) (xy 313.423482 -396.72002) (xy 313.422336 -396.738702)
			(xy 313.421268 -396.748) (xy 313.420252 -396.75689) (xy 313.424062 -396.773654) (xy 313.468004 -396.843504)
			(xy 313.48172 -396.853918) (xy 313.490102 -396.856712) (xy 313.514138 -396.865165) (xy 313.559321 -396.88871)
			(xy 313.600134 -396.919207) (xy 313.63552 -396.955863) (xy 313.664557 -396.997727) (xy 313.686494 -397.043712)
			(xy 313.694064 -397.06804) (xy 313.695588 -397.073882) (xy 314.015882 -397.627602) (xy 314.019946 -397.63192)
			(xy 314.036139 -397.649627) (xy 314.063521 -397.689028) (xy 314.084618 -397.732123) (xy 314.098941 -397.777917)
			(xy 314.106159 -397.825353) (xy 314.10656 -397.849344) (xy 314.10607 -397.874131) (xy 314.098309 -397.923094)
			(xy 314.082984 -397.97024) (xy 314.060473 -398.014409) (xy 314.03133 -398.054513) (xy 313.996273 -398.089564)
			(xy 313.956165 -398.1187) (xy 313.911992 -398.141204) (xy 313.864843 -398.156521) (xy 313.815879 -398.164274)
			(xy 313.791092 -398.164812) (xy 313.765699 -398.164304) (xy 313.715567 -398.156172) (xy 313.667384 -398.14012)
			(xy 313.622391 -398.116562) (xy 313.581751 -398.086105) (xy 313.54651 -398.049535) (xy 313.517578 -398.007795)
			(xy 313.495701 -397.961961) (xy 313.48807 -397.937736) (xy 313.486546 -397.931894) (xy 313.166252 -397.378174)
			(xy 313.162188 -397.373856) (xy 313.145973 -397.356157) (xy 313.118544 -397.316767) (xy 313.097401 -397.273676)
			(xy 313.083032 -397.227878) (xy 313.075769 -397.180432) (xy 313.07532 -397.156432) (xy 313.075478 -397.14438)
			(xy 313.077387 -397.120352) (xy 313.07913 -397.108426) (xy 313.0804 -397.099536) (xy 313.077352 -397.082518)
			(xy 313.035188 -397.011652) (xy 313.02198 -397.000476) (xy 313.013598 -396.997428) (xy 312.991857 -396.989023)
			(xy 312.95101 -396.966572) (xy 312.91405 -396.938173) (xy 312.881836 -396.904487) (xy 312.855115 -396.866297)
			(xy 312.83451 -396.824488) (xy 312.820497 -396.780034) (xy 312.813404 -396.733967) (xy 312.812938 -396.710662)
			(xy 312.813438 -396.685264) (xy 312.821839 -396.635169) (xy 312.838418 -396.587155) (xy 312.862718 -396.54255)
			(xy 312.894069 -396.502584) (xy 312.912506 -396.48511) (xy 312.920888 -396.47749) (xy 312.929524 -396.457424)
			(xy 312.92673 -396.35811) (xy 312.917332 -396.338552) (xy 312.908442 -396.33144) (xy 312.889879 -396.315639)
			(xy 312.857148 -396.279514) (xy 312.830072 -396.238977) (xy 312.809236 -396.194907) (xy 312.795092 -396.148257)
			(xy 312.787945 -396.100036) (xy 312.787538 -396.075662) (xy 312.787977 -396.051546) (xy 312.794983 -396.003826)
			(xy 312.808842 -395.957629) (xy 312.82926 -395.913932) (xy 312.842148 -395.893544) (xy 312.84799 -395.884654)
			(xy 312.851546 -395.864588) (xy 312.830464 -395.772386) (xy 312.818272 -395.755622) (xy 312.809382 -395.750288)
			(xy 312.788578 -395.737434) (xy 312.750658 -395.706557) (xy 312.717705 -395.670427) (xy 312.690438 -395.629833)
			(xy 312.669454 -395.585663) (xy 312.655212 -395.538882) (xy 312.648022 -395.490513) (xy 312.647584 -395.466062)
			(xy 312.648145 -395.438779) (xy 312.657106 -395.384955) (xy 312.674777 -395.33333) (xy 312.700681 -395.285305)
			(xy 312.734114 -395.242182) (xy 312.753756 -395.223238) (xy 312.76121 -395.215748) (xy 312.76976 -395.196453)
			(xy 312.770266 -395.1859) (xy 312.770266 -395.111224) (xy 312.769679 -395.10069) (xy 312.761147 -395.081417)
			(xy 312.753756 -395.073886) (xy 312.73547 -395.056355) (xy 312.703964 -395.016688) (xy 312.678895 -394.972669)
			(xy 312.669428 -394.949172) (xy 312.66384 -394.93444) (xy 312.637932 -394.91666) (xy 312.118756 -394.91666)
			(xy 312.092848 -394.93444) (xy 312.08726 -394.949172) (xy 312.077759 -394.972652) (xy 312.052671 -395.016652)
			(xy 312.021185 -395.056325) (xy 312.002932 -395.073886) (xy 311.995483 -395.081378) (xy 311.986944 -395.100673)
			(xy 311.986422 -395.111224) (xy 311.986422 -395.1859) (xy 311.987013 -395.196433) (xy 311.99555 -395.2157)
			(xy 312.002932 -395.223238) (xy 312.022587 -395.242171) (xy 312.056029 -395.285291) (xy 312.081936 -395.333318)
			(xy 312.099605 -395.384948) (xy 312.108556 -395.438777) (xy 312.109104 -395.466062) (xy 312.108671 -395.49018)
			(xy 312.101675 -395.537905) (xy 312.087827 -395.584109) (xy 312.067419 -395.627814) (xy 312.054494 -395.64818)
			(xy 312.048652 -395.65707) (xy 312.045096 -395.677136) (xy 312.066178 -395.769338) (xy 312.07837 -395.786102)
			(xy 312.08726 -395.791436) (xy 312.10806 -395.804292) (xy 312.145974 -395.835172) (xy 312.178921 -395.871304)
			(xy 312.206181 -395.911898) (xy 312.227158 -395.956067) (xy 312.241395 -396.002846) (xy 312.24858 -396.051213)
			(xy 312.249058 -396.075662) (xy 312.24862 -396.100033) (xy 312.241465 -396.148246) (xy 312.227317 -396.194889)
			(xy 312.206483 -396.238954) (xy 312.179413 -396.279487) (xy 312.146693 -396.315614) (xy 312.128154 -396.33144)
			(xy 312.119264 -396.338552) (xy 312.109866 -396.35811) (xy 312.107072 -396.457424) (xy 312.115708 -396.47749)
			(xy 312.12409 -396.48511) (xy 312.142512 -396.502598) (xy 312.173855 -396.542565) (xy 312.198153 -396.587168)
			(xy 312.214735 -396.635176) (xy 312.223146 -396.685266) (xy 312.223658 -396.710662) (xy 312.223586 -396.72002)
			(xy 312.22244 -396.738702) (xy 312.221372 -396.748) (xy 312.220356 -396.75689) (xy 312.224166 -396.773654)
			(xy 312.268108 -396.843504) (xy 312.281824 -396.853918) (xy 312.290206 -396.856712) (xy 312.314301 -396.865196)
			(xy 312.359587 -396.888827) (xy 312.400478 -396.91944) (xy 312.435909 -396.956236) (xy 312.464953 -396.998256)
			(xy 312.486855 -397.044403) (xy 312.494422 -397.068802) (xy 312.495946 -397.074644) (xy 312.815732 -397.627602)
			(xy 312.819796 -397.63192) (xy 312.836013 -397.649618) (xy 312.863446 -397.689007) (xy 312.884594 -397.732098)
			(xy 312.898967 -397.777896) (xy 312.906234 -397.825344) (xy 312.906664 -397.849344) (xy 312.906199 -397.874146)
			(xy 312.898429 -397.923137) (xy 312.883087 -397.970309) (xy 312.860552 -398.014499) (xy 312.83138 -398.054617)
			(xy 312.796287 -398.089676) (xy 312.756141 -398.11881) (xy 312.71193 -398.141303) (xy 312.664743 -398.156599)
			(xy 312.615744 -398.164322) (xy 312.590942 -398.164812) (xy 312.565546 -398.164307) (xy 312.515409 -398.156183)
			(xy 312.467219 -398.140136) (xy 312.42222 -398.11658) (xy 312.381573 -398.086125) (xy 312.346326 -398.049554)
			(xy 312.317388 -398.007813) (xy 312.295506 -397.961977) (xy 312.28792 -397.937736) (xy 312.286396 -397.931894)
			(xy 311.965848 -397.377412) (xy 311.961784 -397.373094) (xy 311.945682 -397.355424) (xy 311.918447 -397.316138)
			(xy 311.89744 -397.273197) (xy 311.883141 -397.227582) (xy 311.875876 -397.180333) (xy 311.875424 -397.156432)
			(xy 311.875582 -397.14438) (xy 311.877491 -397.120352) (xy 311.879234 -397.108426) (xy 311.880504 -397.099536)
			(xy 311.877456 -397.082518) (xy 311.835292 -397.011652) (xy 311.822084 -397.000476) (xy 311.813702 -396.997428)
			(xy 311.79196 -396.989024) (xy 311.751113 -396.966572) (xy 311.714153 -396.938174) (xy 311.681938 -396.904488)
			(xy 311.655217 -396.866297) (xy 311.634611 -396.824489) (xy 311.620599 -396.780035) (xy 311.613506 -396.733967)
			(xy 311.613042 -396.710662) (xy 311.613541 -396.685263) (xy 311.62194 -396.635165) (xy 311.638515 -396.587149)
			(xy 311.66281 -396.542539) (xy 311.694154 -396.502565) (xy 311.71261 -396.48511) (xy 311.720992 -396.47749)
			(xy 311.729628 -396.457424) (xy 311.726834 -396.35811) (xy 311.717436 -396.338552) (xy 311.708546 -396.33144)
			(xy 311.689983 -396.315639) (xy 311.657252 -396.279514) (xy 311.630175 -396.238978) (xy 311.609339 -396.194907)
			(xy 311.595195 -396.148257) (xy 311.588048 -396.100036) (xy 311.587642 -396.075662) (xy 311.588081 -396.051546)
			(xy 311.595087 -396.003826) (xy 311.608946 -395.957629) (xy 311.629364 -395.913932) (xy 311.642252 -395.893544)
			(xy 311.648094 -395.884654) (xy 311.65165 -395.864588) (xy 311.630568 -395.772386) (xy 311.618376 -395.755622)
			(xy 311.609486 -395.750288) (xy 311.588682 -395.737434) (xy 311.550761 -395.706557) (xy 311.517808 -395.670428)
			(xy 311.490541 -395.629834) (xy 311.469556 -395.585664) (xy 311.455314 -395.538883) (xy 311.448124 -395.490513)
			(xy 311.447688 -395.466062) (xy 311.448249 -395.438779) (xy 311.45721 -395.384955) (xy 311.474881 -395.33333)
			(xy 311.500785 -395.285306) (xy 311.534219 -395.242183) (xy 311.55386 -395.223238) (xy 311.561313 -395.215748)
			(xy 311.569863 -395.196453) (xy 311.57037 -395.1859) (xy 311.57037 -395.111224) (xy 311.569783 -395.10069)
			(xy 311.561251 -395.081416) (xy 311.55386 -395.073886) (xy 311.535574 -395.056355) (xy 311.504068 -395.016688)
			(xy 311.478998 -394.97267) (xy 311.469532 -394.949172) (xy 311.463944 -394.93444) (xy 311.438036 -394.91666)
			(xy 310.918606 -394.91666) (xy 310.892698 -394.93444) (xy 310.88711 -394.949172) (xy 310.877608 -394.972651)
			(xy 310.852517 -395.016648) (xy 310.821028 -395.056318) (xy 310.802782 -395.073886) (xy 310.795339 -395.08138)
			(xy 310.786809 -395.100675) (xy 310.786272 -395.111224) (xy 310.786272 -395.1859) (xy 310.786862 -395.196434)
			(xy 310.795392 -395.215707) (xy 310.802782 -395.223238) (xy 310.822434 -395.242172) (xy 310.855872 -395.285294)
			(xy 310.881775 -395.333321) (xy 310.899441 -395.38495) (xy 310.90839 -395.438778) (xy 310.908954 -395.466062)
			(xy 310.908521 -395.490179) (xy 310.901524 -395.537904) (xy 310.887674 -395.584107) (xy 310.867263 -395.627811)
			(xy 310.854344 -395.64818) (xy 310.848502 -395.65707) (xy 310.844946 -395.677136) (xy 310.866028 -395.769338)
			(xy 310.87822 -395.786102) (xy 310.88711 -395.791436) (xy 310.907913 -395.80429) (xy 310.945832 -395.835167)
			(xy 310.978783 -395.871298) (xy 311.006048 -395.911892) (xy 311.027029 -395.956062) (xy 311.041268 -396.002843)
			(xy 311.048455 -396.051212) (xy 311.048908 -396.075662) (xy 311.04847 -396.100032) (xy 311.041314 -396.148245)
			(xy 311.027164 -396.194886) (xy 311.006328 -396.238949) (xy 310.979256 -396.27948) (xy 310.946532 -396.315602)
			(xy 310.928004 -396.33144) (xy 310.919114 -396.338552) (xy 310.909716 -396.35811) (xy 310.906922 -396.457424)
			(xy 310.915558 -396.47749) (xy 310.92394 -396.48511) (xy 310.94236 -396.502599) (xy 310.973698 -396.542568)
			(xy 310.997991 -396.587171) (xy 311.014571 -396.635178) (xy 311.02298 -396.685267) (xy 311.023508 -396.710662)
			(xy 311.023436 -396.72002) (xy 311.02229 -396.738702) (xy 311.021222 -396.748) (xy 311.020206 -396.75689)
			(xy 311.024016 -396.773654) (xy 311.067958 -396.843504) (xy 311.081674 -396.853918) (xy 311.090056 -396.856712)
			(xy 311.114089 -396.865168) (xy 311.159265 -396.888718) (xy 311.200073 -396.919218) (xy 311.235452 -396.955876)
			(xy 311.264484 -396.99774) (xy 311.286416 -397.043723) (xy 311.294018 -397.06804) (xy 311.295542 -397.073882)
			(xy 311.615836 -397.627602) (xy 311.6199 -397.63192) (xy 311.636117 -397.649618) (xy 311.66355 -397.689007)
			(xy 311.684697 -397.732098) (xy 311.69907 -397.777896) (xy 311.706337 -397.825344) (xy 311.706768 -397.849344)
			(xy 311.706303 -397.874146) (xy 311.698533 -397.923138) (xy 311.683191 -397.97031) (xy 311.660657 -398.0145)
			(xy 311.631484 -398.054619) (xy 311.596392 -398.089678) (xy 311.556245 -398.118813) (xy 311.512034 -398.141306)
			(xy 311.464848 -398.156602) (xy 311.415848 -398.164326) (xy 311.391046 -398.164812) (xy 311.36565 -398.164308)
			(xy 311.315512 -398.156183) (xy 311.267322 -398.140137) (xy 311.222323 -398.116582) (xy 311.181675 -398.086126)
			(xy 311.146427 -398.049556) (xy 311.117489 -398.007814) (xy 311.095607 -397.961978) (xy 311.088024 -397.937736)
			(xy 311.0865 -397.931894) (xy 310.766206 -397.378174) (xy 310.762142 -397.373856) (xy 310.745951 -397.356148)
			(xy 310.718572 -397.316746) (xy 310.69748 -397.273651) (xy 310.683161 -397.227857) (xy 310.675947 -397.180423)
			(xy 310.675528 -397.156432) (xy 310.675614 -397.144384) (xy 310.677397 -397.120355) (xy 310.679084 -397.108426)
			(xy 310.680354 -397.099536) (xy 310.677306 -397.082518) (xy 310.635142 -397.011652) (xy 310.621934 -397.000476)
			(xy 310.613552 -396.997428) (xy 310.591813 -396.989021) (xy 310.550972 -396.966566) (xy 310.514018 -396.938165)
			(xy 310.481808 -396.904478) (xy 310.455092 -396.866288) (xy 310.43449 -396.824482) (xy 310.42048 -396.78003)
			(xy 310.413388 -396.733966) (xy 310.412892 -396.710662) (xy 310.413392 -396.685264) (xy 310.421791 -396.635167)
			(xy 310.438369 -396.587152) (xy 310.462667 -396.542545) (xy 310.494014 -396.502575) (xy 310.51246 -396.48511)
			(xy 310.520842 -396.47749) (xy 310.529478 -396.457424) (xy 310.526684 -396.35811) (xy 310.517286 -396.338552)
			(xy 310.508396 -396.33144) (xy 310.489835 -396.315637) (xy 310.457109 -396.279511) (xy 310.430036 -396.238974)
			(xy 310.409204 -396.194904) (xy 310.395061 -396.148254) (xy 310.387916 -396.100035) (xy 310.387492 -396.075662)
			(xy 310.387931 -396.051546) (xy 310.394936 -396.003826) (xy 310.408793 -395.957627) (xy 310.429209 -395.913929)
			(xy 310.442102 -395.893544) (xy 310.447944 -395.884654) (xy 310.4515 -395.864588) (xy 310.430418 -395.772386)
			(xy 310.418226 -395.755622) (xy 310.409336 -395.750288) (xy 310.388535 -395.737432) (xy 310.350619 -395.706553)
			(xy 310.31767 -395.670422) (xy 310.290408 -395.629828) (xy 310.269427 -395.585659) (xy 310.255187 -395.538879)
			(xy 310.247999 -395.490512) (xy 310.247538 -395.466062) (xy 310.248099 -395.438779) (xy 310.257058 -395.384953)
			(xy 310.274728 -395.333327) (xy 310.300629 -395.2853) (xy 310.33406 -395.242173) (xy 310.35371 -395.223238)
			(xy 310.361157 -395.215745) (xy 310.369699 -395.19645) (xy 310.37022 -395.1859) (xy 310.37022 -395.111224)
			(xy 310.369635 -395.100688) (xy 310.361109 -395.081409) (xy 310.35371 -395.073886) (xy 310.335421 -395.056356)
			(xy 310.303911 -395.016691) (xy 310.278838 -394.972674) (xy 310.269382 -394.949172) (xy 310.263794 -394.93444)
			(xy 310.237886 -394.91666) (xy 309.71871 -394.91666) (xy 309.692802 -394.93444) (xy 309.687214 -394.949172)
			(xy 309.680482 -394.966072) (xy 309.663805 -394.998404) (xy 309.65394 -395.013688) (xy 309.649185 -395.021657)
			(xy 309.64516 -395.039757) (xy 309.646066 -395.048994) (xy 309.650384 -395.079982) (xy 309.652187 -395.089236)
			(xy 309.661443 -395.105642) (xy 309.668418 -395.111986) (xy 309.690513 -395.13066) (xy 309.730288 -395.17267)
			(xy 309.764451 -395.219358) (xy 309.792458 -395.26998) (xy 309.813861 -395.323727) (xy 309.828319 -395.379744)
			(xy 309.835603 -395.437136) (xy 309.836058 -395.466062) (xy 309.835454 -395.499382) (xy 309.825784 -395.565316)
			(xy 309.806658 -395.629153) (xy 309.793132 -395.65961) (xy 309.788871 -395.67008) (xy 309.788947 -395.692654)
			(xy 309.798697 -395.713015) (xy 309.807102 -395.72057) (xy 309.82935 -395.739243) (xy 309.869417 -395.781298)
			(xy 309.903841 -395.828084) (xy 309.932069 -395.878848) (xy 309.953648 -395.932777) (xy 309.968232 -395.989001)
			(xy 309.975585 -396.046619) (xy 309.976012 -396.075662) (xy 309.975561 -396.104666) (xy 309.968231 -396.162209)
			(xy 309.953694 -396.218366) (xy 309.932185 -396.272239) (xy 309.904046 -396.322966) (xy 309.869729 -396.369734)
			(xy 309.829783 -396.411796) (xy 309.80761 -396.4305) (xy 309.800498 -396.436088) (xy 309.791354 -396.451328)
			(xy 309.776114 -396.534132) (xy 309.778908 -396.551404) (xy 309.78348 -396.559532) (xy 309.796074 -396.58271)
			(xy 309.813962 -396.632331) (xy 309.823045 -396.684289) (xy 309.823612 -396.710662) (xy 309.82354 -396.72002)
			(xy 309.822394 -396.738702) (xy 309.821326 -396.748) (xy 309.82031 -396.75689) (xy 309.82412 -396.773654)
			(xy 309.868062 -396.843504) (xy 309.881778 -396.853918) (xy 309.89016 -396.856712) (xy 309.914193 -396.865169)
			(xy 309.959369 -396.888719) (xy 310.000176 -396.919219) (xy 310.035554 -396.955876) (xy 310.064586 -396.99774)
			(xy 310.086518 -397.043724) (xy 310.094122 -397.06804) (xy 310.095646 -397.073882) (xy 310.41594 -397.627602)
			(xy 310.420004 -397.63192) (xy 310.436221 -397.649618) (xy 310.463653 -397.689007) (xy 310.4848 -397.732099)
			(xy 310.499173 -397.777897) (xy 310.50644 -397.825344) (xy 310.506872 -397.849344) (xy 310.506407 -397.874146)
			(xy 310.498637 -397.923138) (xy 310.483295 -397.970311) (xy 310.460761 -398.014501) (xy 310.431588 -398.05462)
			(xy 310.396496 -398.089679) (xy 310.35635 -398.118815) (xy 310.312139 -398.141308) (xy 310.264952 -398.156605)
			(xy 310.215953 -398.16433) (xy 310.19115 -398.164812) (xy 310.165754 -398.164308) (xy 310.115616 -398.156184)
			(xy 310.067425 -398.140138) (xy 310.022425 -398.116583) (xy 309.981777 -398.086128) (xy 309.946528 -398.049558)
			(xy 309.91759 -398.007816) (xy 309.895707 -397.961979) (xy 309.888128 -397.937736) (xy 309.886604 -397.931894)
			(xy 309.56631 -397.378174) (xy 309.562246 -397.373856) (xy 309.546055 -397.356148) (xy 309.518676 -397.316746)
			(xy 309.497583 -397.273651) (xy 309.483264 -397.227857) (xy 309.47605 -397.180423) (xy 309.475632 -397.156432)
			(xy 309.475718 -397.144384) (xy 309.477501 -397.120355) (xy 309.479188 -397.108426) (xy 309.480458 -397.099536)
			(xy 309.47741 -397.082518) (xy 309.435246 -397.011652) (xy 309.422038 -397.000476) (xy 309.413656 -396.997428)
			(xy 309.391917 -396.989021) (xy 309.351075 -396.966566) (xy 309.31412 -396.938166) (xy 309.281911 -396.904479)
			(xy 309.255194 -396.866289) (xy 309.234592 -396.824482) (xy 309.220582 -396.78003) (xy 309.21349 -396.733966)
			(xy 309.212996 -396.710662) (xy 309.213578 -396.684292) (xy 309.222681 -396.632341) (xy 309.240558 -396.582722)
			(xy 309.253128 -396.559532) (xy 309.2577 -396.551404) (xy 309.260494 -396.534132) (xy 309.245254 -396.451328)
			(xy 309.23611 -396.436088) (xy 309.228998 -396.4305) (xy 309.206807 -396.411817) (xy 309.166852 -396.369758)
			(xy 309.132531 -396.322989) (xy 309.104393 -396.272259) (xy 309.082891 -396.21838) (xy 309.068367 -396.162216)
			(xy 309.061055 -396.104668) (xy 309.060596 -396.075662) (xy 309.061199 -396.042342) (xy 309.070864 -395.976405)
			(xy 309.089985 -395.912567) (xy 309.103522 -395.882114) (xy 309.107791 -395.871644) (xy 309.107725 -395.849063)
			(xy 309.097972 -395.828697) (xy 309.089552 -395.821154) (xy 309.067309 -395.802478) (xy 309.027254 -395.76042)
			(xy 308.992841 -395.713632) (xy 308.964624 -395.662867) (xy 308.943055 -395.608939) (xy 308.928483 -395.552717)
			(xy 308.92114 -395.495102) (xy 308.920642 -395.466062) (xy 308.921087 -395.437137) (xy 308.928381 -395.379748)
			(xy 308.942847 -395.323735) (xy 308.964256 -395.269991) (xy 308.992266 -395.219373) (xy 309.02643 -395.172688)
			(xy 309.066203 -395.130679) (xy 309.088282 -395.111986) (xy 309.095351 -395.105719) (xy 309.104629 -395.089277)
			(xy 309.106316 -395.079982) (xy 309.110634 -395.048994) (xy 309.111582 -395.039756) (xy 309.10755 -395.021643)
			(xy 309.10276 -395.013688) (xy 309.092908 -394.998396) (xy 309.076227 -394.966068) (xy 309.069486 -394.949172)
			(xy 309.063898 -394.93444) (xy 309.03799 -394.91666) (xy 308.51856 -394.91666) (xy 308.492652 -394.93444)
			(xy 308.487064 -394.949172) (xy 308.47707 -394.973819) (xy 308.450369 -395.019813) (xy 308.416651 -395.06094)
			(xy 308.376785 -395.09614) (xy 308.3318 -395.124507) (xy 308.282854 -395.145307) (xy 308.231211 -395.158006)
			(xy 308.1782 -395.162276) (xy 308.125189 -395.158006) (xy 308.073546 -395.145307) (xy 308.0246 -395.124507)
			(xy 307.979615 -395.09614) (xy 307.939749 -395.06094) (xy 307.906031 -395.019813) (xy 307.87933 -394.973819)
			(xy 307.869336 -394.949172) (xy 307.863748 -394.93444) (xy 307.83784 -394.91666) (xy 307.318664 -394.91666)
			(xy 307.292756 -394.93444) (xy 307.287168 -394.949172) (xy 307.277668 -394.972652) (xy 307.25258 -395.016652)
			(xy 307.221095 -395.056326) (xy 307.20284 -395.073886) (xy 307.19539 -395.081377) (xy 307.18685 -395.100673)
			(xy 307.18633 -395.111224) (xy 307.18633 -395.1859) (xy 307.186922 -395.196432) (xy 307.195459 -395.215699)
			(xy 307.20284 -395.223238) (xy 307.222494 -395.242171) (xy 307.255936 -395.285292) (xy 307.281842 -395.333319)
			(xy 307.299511 -395.384948) (xy 307.308461 -395.438778) (xy 307.309012 -395.466062) (xy 307.308579 -395.49018)
			(xy 307.301583 -395.537905) (xy 307.287735 -395.584109) (xy 307.267328 -395.627815) (xy 307.254402 -395.64818)
			(xy 307.24856 -395.65707) (xy 307.245004 -395.677136) (xy 307.266086 -395.769338) (xy 307.278278 -395.786102)
			(xy 307.287168 -395.791436) (xy 307.307968 -395.804293) (xy 307.345881 -395.835173) (xy 307.378827 -395.871305)
			(xy 307.406086 -395.911899) (xy 307.427063 -395.956068) (xy 307.4413 -396.002847) (xy 307.448484 -396.051213)
			(xy 307.448966 -396.075662) (xy 307.448528 -396.100033) (xy 307.441373 -396.148246) (xy 307.427225 -396.19489)
			(xy 307.406392 -396.238955) (xy 307.379322 -396.279489) (xy 307.346602 -396.315616) (xy 307.328062 -396.33144)
			(xy 307.319172 -396.338552) (xy 307.309774 -396.35811) (xy 307.30698 -396.457424) (xy 307.315616 -396.47749)
			(xy 307.323998 -396.48511) (xy 307.34242 -396.502598) (xy 307.373762 -396.542566) (xy 307.398059 -396.587168)
			(xy 307.414641 -396.635176) (xy 307.423051 -396.685266) (xy 307.423566 -396.710662) (xy 308.012846 -396.710662)
			(xy 308.013368 -396.685407) (xy 308.021681 -396.635585) (xy 308.038082 -396.587811) (xy 308.062123 -396.543388)
			(xy 308.093147 -396.503528) (xy 308.130309 -396.469318) (xy 308.172595 -396.441692) (xy 308.218851 -396.421402)
			(xy 308.267816 -396.409002) (xy 308.318154 -396.404831) (xy 308.368492 -396.409002) (xy 308.417457 -396.421402)
			(xy 308.463713 -396.441692) (xy 308.505999 -396.469318) (xy 308.543161 -396.503528) (xy 308.574185 -396.543388)
			(xy 308.598226 -396.587811) (xy 308.614627 -396.635585) (xy 308.62294 -396.685407) (xy 308.623462 -396.710662)
			(xy 308.623393 -396.720021) (xy 308.62225 -396.738703) (xy 308.621176 -396.748) (xy 308.62016 -396.75689)
			(xy 308.62397 -396.773654) (xy 308.667912 -396.843504) (xy 308.681628 -396.853918) (xy 308.69001 -396.856712)
			(xy 308.714032 -396.865196) (xy 308.759205 -396.888744) (xy 308.800011 -396.91924) (xy 308.835392 -396.955892)
			(xy 308.864429 -396.997749) (xy 308.886368 -397.043725) (xy 308.893972 -397.06804) (xy 308.895496 -397.073882)
			(xy 309.21579 -397.627602) (xy 309.219854 -397.63192) (xy 309.236051 -397.649621) (xy 309.263414 -397.689032)
			(xy 309.284497 -397.73213) (xy 309.298816 -397.777923) (xy 309.30604 -397.825354) (xy 309.306468 -397.849344)
			(xy 309.306023 -397.874135) (xy 309.29826 -397.923105) (xy 309.282933 -397.970259) (xy 309.260419 -398.014434)
			(xy 309.231273 -398.054544) (xy 309.196211 -398.089601) (xy 309.156096 -398.118742) (xy 309.111918 -398.14125)
			(xy 309.064762 -398.15657) (xy 309.015791 -398.164326) (xy 308.991 -398.164812) (xy 308.965606 -398.164312)
			(xy 308.915472 -398.156181) (xy 308.867286 -398.140129) (xy 308.822292 -398.116571) (xy 308.781649 -398.086114)
			(xy 308.746407 -398.049543) (xy 308.717473 -398.007801) (xy 308.695595 -397.961967) (xy 308.687978 -397.937736)
			(xy 308.686454 -397.931894) (xy 308.36616 -397.378174) (xy 308.362096 -397.373856) (xy 308.345892 -397.356148)
			(xy 308.318468 -397.316757) (xy 308.297325 -397.273668) (xy 308.282952 -397.227873) (xy 308.275678 -397.18043)
			(xy 308.275228 -397.156432) (xy 308.27537 -397.14438) (xy 308.277276 -397.12035) (xy 308.279038 -397.108426)
			(xy 308.280308 -397.099536) (xy 308.27726 -397.082518) (xy 308.235096 -397.011652) (xy 308.221888 -397.000476)
			(xy 308.213506 -396.997428) (xy 308.191766 -396.989013) (xy 308.150906 -396.966577) (xy 308.113934 -396.938187)
			(xy 308.08171 -396.904505) (xy 308.054984 -396.866314) (xy 308.034376 -396.824502) (xy 308.020368 -396.780042)
			(xy 308.013284 -396.733969) (xy 308.012846 -396.710662) (xy 307.423566 -396.710662) (xy 307.423494 -396.72002)
			(xy 307.422348 -396.738702) (xy 307.42128 -396.748) (xy 307.420264 -396.75689) (xy 307.424074 -396.773654)
			(xy 307.468016 -396.843504) (xy 307.481732 -396.853918) (xy 307.490114 -396.856712) (xy 307.514149 -396.865166)
			(xy 307.55933 -396.888712) (xy 307.600143 -396.919209) (xy 307.635527 -396.955866) (xy 307.664563 -396.99773)
			(xy 307.686499 -397.043714) (xy 307.694076 -397.06804) (xy 307.6956 -397.073882) (xy 308.015894 -397.627602)
			(xy 308.019958 -397.63192) (xy 308.03615 -397.649628) (xy 308.063532 -397.689029) (xy 308.084627 -397.732124)
			(xy 308.09895 -397.777918) (xy 308.106168 -397.825353) (xy 308.106572 -397.849344) (xy 308.106083 -397.874131)
			(xy 308.098321 -397.923095) (xy 308.082997 -397.970242) (xy 308.060486 -398.014412) (xy 308.031343 -398.054517)
			(xy 307.996286 -398.089569) (xy 307.956178 -398.118707) (xy 307.912005 -398.141212) (xy 307.864856 -398.156531)
			(xy 307.815892 -398.164286) (xy 307.791104 -398.164812) (xy 307.76571 -398.164305) (xy 307.715577 -398.156175)
			(xy 307.667392 -398.140124) (xy 307.622398 -398.116566) (xy 307.581756 -398.08611) (xy 307.546514 -398.04954)
			(xy 307.51758 -398.007799) (xy 307.495702 -397.961965) (xy 307.488082 -397.937736) (xy 307.486558 -397.931894)
			(xy 307.166264 -397.378174) (xy 307.1622 -397.373856) (xy 307.145984 -397.356157) (xy 307.118555 -397.316768)
			(xy 307.097411 -397.273676) (xy 307.083041 -397.227878) (xy 307.075778 -397.180432) (xy 307.075332 -397.156432)
			(xy 307.07549 -397.14438) (xy 307.077399 -397.120352) (xy 307.079142 -397.108426) (xy 307.080412 -397.099536)
			(xy 307.077364 -397.082518) (xy 307.0352 -397.011652) (xy 307.021992 -397.000476) (xy 307.01361 -396.997428)
			(xy 306.991868 -396.989024) (xy 306.95102 -396.966573) (xy 306.914059 -396.938175) (xy 306.881843 -396.90449)
			(xy 306.855122 -396.866299) (xy 306.834515 -396.82449) (xy 306.820502 -396.780035) (xy 306.813408 -396.733967)
			(xy 306.81295 -396.710662) (xy 306.813449 -396.685263) (xy 306.821848 -396.635166) (xy 306.838424 -396.587149)
			(xy 306.862719 -396.542539) (xy 306.894064 -396.502567) (xy 306.912518 -396.48511) (xy 306.9209 -396.47749)
			(xy 306.929536 -396.457424) (xy 306.926742 -396.35811) (xy 306.917344 -396.338552) (xy 306.908454 -396.33144)
			(xy 306.88989 -396.315639) (xy 306.857158 -396.279515) (xy 306.830081 -396.238978) (xy 306.809245 -396.194908)
			(xy 306.7951 -396.148257) (xy 306.787953 -396.100036) (xy 306.78755 -396.075662) (xy 306.787989 -396.051546)
			(xy 306.794995 -396.003826) (xy 306.808855 -395.957629) (xy 306.829273 -395.913933) (xy 306.84216 -395.893544)
			(xy 306.848002 -395.884654) (xy 306.851558 -395.864588) (xy 306.830476 -395.772386) (xy 306.818284 -395.755622)
			(xy 306.809394 -395.750288) (xy 306.78859 -395.737434) (xy 306.750668 -395.706558) (xy 306.717713 -395.670429)
			(xy 306.690446 -395.629835) (xy 306.669461 -395.585665) (xy 306.655218 -395.538883) (xy 306.648028 -395.490513)
			(xy 306.647596 -395.466062) (xy 306.648157 -395.438779) (xy 306.657118 -395.384955) (xy 306.67479 -395.333331)
			(xy 306.700694 -395.285306) (xy 306.734129 -395.242184) (xy 306.753768 -395.223238) (xy 306.76122 -395.215748)
			(xy 306.769769 -395.196452) (xy 306.770278 -395.1859) (xy 306.770278 -395.111224) (xy 306.769691 -395.100689)
			(xy 306.761161 -395.081415) (xy 306.753768 -395.073886) (xy 306.735481 -395.056355) (xy 306.703975 -395.016688)
			(xy 306.678905 -394.97267) (xy 306.66944 -394.949172) (xy 306.663852 -394.93444) (xy 306.637944 -394.91666)
			(xy 306.238402 -394.91666) (xy 306.228333 -394.917084) (xy 306.209734 -394.924805) (xy 306.202334 -394.931646)
			(xy 306.028344 -395.105636) (xy 306.021834 -395.112778) (xy 306.014254 -395.130538) (xy 306.013612 -395.14018)
			(xy 306.011326 -395.219682) (xy 306.01793 -395.23797) (xy 306.024534 -395.245336) (xy 306.040384 -395.26361)
			(xy 306.067118 -395.303925) (xy 306.087687 -395.347707) (xy 306.101651 -395.39402) (xy 306.108711 -395.441876)
			(xy 306.109116 -395.466062) (xy 306.108683 -395.49018) (xy 306.101687 -395.537905) (xy 306.087839 -395.584109)
			(xy 306.067432 -395.627815) (xy 306.054506 -395.64818) (xy 306.048664 -395.65707) (xy 306.045108 -395.677136)
			(xy 306.06619 -395.769338) (xy 306.078382 -395.786102) (xy 306.087272 -395.791436) (xy 306.108072 -395.804293)
			(xy 306.145984 -395.835173) (xy 306.17893 -395.871305) (xy 306.206189 -395.911899) (xy 306.227166 -395.956068)
			(xy 306.241402 -396.002847) (xy 306.248587 -396.051213) (xy 306.24907 -396.075662) (xy 306.248632 -396.100033)
			(xy 306.241477 -396.148247) (xy 306.227329 -396.19489) (xy 306.206496 -396.238955) (xy 306.179427 -396.279489)
			(xy 306.146707 -396.315617) (xy 306.128166 -396.33144) (xy 306.119276 -396.338552) (xy 306.109878 -396.35811)
			(xy 306.107084 -396.457424) (xy 306.11572 -396.47749) (xy 306.124102 -396.48511) (xy 306.142524 -396.502598)
			(xy 306.173865 -396.542566) (xy 306.198162 -396.587169) (xy 306.214744 -396.635177) (xy 306.223154 -396.685267)
			(xy 306.22367 -396.710662) (xy 306.223598 -396.72002) (xy 306.222452 -396.738702) (xy 306.221384 -396.748)
			(xy 306.220368 -396.75689) (xy 306.224178 -396.773654) (xy 306.26812 -396.843504) (xy 306.281836 -396.853918)
			(xy 306.290218 -396.856712) (xy 306.314313 -396.865196) (xy 306.359597 -396.888829) (xy 306.400487 -396.919443)
			(xy 306.435916 -396.956239) (xy 306.464959 -396.998259) (xy 306.48686 -397.044406) (xy 306.494434 -397.068802)
			(xy 306.495958 -397.074644) (xy 306.815744 -397.627602) (xy 306.819808 -397.63192) (xy 306.836025 -397.649618)
			(xy 306.863457 -397.689008) (xy 306.884603 -397.732099) (xy 306.898976 -397.777897) (xy 306.906243 -397.825344)
			(xy 306.906676 -397.849344) (xy 306.906211 -397.874146) (xy 306.898441 -397.923139) (xy 306.8831 -397.970311)
			(xy 306.860565 -398.014502) (xy 306.831392 -398.054621) (xy 306.7963 -398.089681) (xy 306.756154 -398.118817)
			(xy 306.711943 -398.141311) (xy 306.664756 -398.156609) (xy 306.615757 -398.164333) (xy 306.590954 -398.164812)
			(xy 306.565562 -398.164301) (xy 306.515435 -398.156164) (xy 306.467256 -398.140109) (xy 306.422269 -398.116548)
			(xy 306.381634 -398.08609) (xy 306.346397 -398.04952) (xy 306.31747 -398.007781) (xy 306.295596 -397.96195)
			(xy 306.287932 -397.937736) (xy 306.286408 -397.931894) (xy 305.96586 -397.377412) (xy 305.961796 -397.373094)
			(xy 305.945693 -397.355425) (xy 305.918457 -397.316138) (xy 305.89745 -397.273197) (xy 305.88315 -397.227582)
			(xy 305.875885 -397.180333) (xy 305.875436 -397.156432) (xy 305.875594 -397.14438) (xy 305.877503 -397.120352)
			(xy 305.879246 -397.108426) (xy 305.880516 -397.099536) (xy 305.877468 -397.082518) (xy 305.835304 -397.011652)
			(xy 305.822096 -397.000476) (xy 305.813714 -396.997428) (xy 305.791972 -396.989024) (xy 305.751123 -396.966574)
			(xy 305.714162 -396.938176) (xy 305.681946 -396.90449) (xy 305.655224 -396.866299) (xy 305.634617 -396.824491)
			(xy 305.620603 -396.780036) (xy 305.61351 -396.733968) (xy 305.613054 -396.710662) (xy 305.613553 -396.685264)
			(xy 305.621952 -396.635166) (xy 305.638528 -396.58715) (xy 305.662824 -396.54254) (xy 305.694169 -396.502567)
			(xy 305.712622 -396.48511) (xy 305.721004 -396.47749) (xy 305.72964 -396.457424) (xy 305.726846 -396.35811)
			(xy 305.717448 -396.338552) (xy 305.708558 -396.33144) (xy 305.700757 -396.324861) (xy 305.685887 -396.310882)
			(xy 305.67884 -396.3035) (xy 305.667918 -396.292324) (xy 305.637692 -396.28572) (xy 305.535584 -396.32636)
			(xy 305.526319 -396.33052) (xy 305.511839 -396.344737) (xy 305.504007 -396.363457) (xy 305.50358 -396.373604)
			(xy 305.50358 -397.41983) (xy 305.503747 -397.426563) (xy 305.507217 -397.43957) (xy 305.510438 -397.445484)
			(xy 305.615848 -397.627602) (xy 305.619912 -397.63192) (xy 305.636128 -397.649618) (xy 305.66356 -397.689008)
			(xy 305.684706 -397.732099) (xy 305.699079 -397.777897) (xy 305.706346 -397.825344) (xy 305.70678 -397.849344)
			(xy 305.706306 -397.874356) (xy 305.698418 -397.923754) (xy 305.682831 -397.971287) (xy 305.659936 -398.015764)
			(xy 305.630306 -398.056069) (xy 305.594686 -398.091191) (xy 305.553968 -398.12025) (xy 305.531774 -398.131792)
			(xy 305.518566 -398.138396) (xy 305.50358 -398.162526) (xy 305.50358 -398.180052) (xy 305.503938 -398.188749)
			(xy 305.509766 -398.205138) (xy 305.520734 -398.218638) (xy 305.527964 -398.223486) (xy 305.613562 -398.275556)
			(xy 305.63947 -398.276572) (xy 305.651662 -398.270476) (xy 305.673348 -398.259827) (xy 305.719249 -398.244765)
			(xy 305.766953 -398.237138) (xy 305.791108 -398.236694) (xy 305.816363 -398.237216) (xy 305.866183 -398.245531)
			(xy 305.913956 -398.261932) (xy 305.958377 -398.285973) (xy 305.998235 -398.316997) (xy 306.032444 -398.354159)
			(xy 306.06007 -398.396444) (xy 306.080359 -398.442699) (xy 306.092758 -398.491663) (xy 306.096929 -398.542)
			(xy 306.096929 -398.542002) (xy 306.6852 -398.542002) (xy 306.68916 -398.492948) (xy 306.700937 -398.445164)
			(xy 306.720228 -398.399888) (xy 306.746531 -398.358292) (xy 306.779166 -398.321455) (xy 306.817287 -398.29033)
			(xy 306.859908 -398.265723) (xy 306.905924 -398.248271) (xy 306.954143 -398.238427) (xy 307.003318 -398.236446)
			(xy 307.052173 -398.242378) (xy 307.099444 -398.25607) (xy 307.143906 -398.277168) (xy 307.184409 -398.305124)
			(xy 307.219902 -398.339216) (xy 307.249467 -398.37856) (xy 307.272338 -398.422137) (xy 307.287922 -398.468818)
			(xy 307.295817 -398.517395) (xy 307.296312 -398.542002) (xy 307.88535 -398.542002) (xy 307.88931 -398.492948)
			(xy 307.901087 -398.445164) (xy 307.920378 -398.399888) (xy 307.946681 -398.358292) (xy 307.979316 -398.321455)
			(xy 308.017437 -398.29033) (xy 308.060058 -398.265723) (xy 308.106074 -398.248271) (xy 308.154293 -398.238427)
			(xy 308.203468 -398.236446) (xy 308.252323 -398.242378) (xy 308.299594 -398.25607) (xy 308.344056 -398.277168)
			(xy 308.384559 -398.305124) (xy 308.420052 -398.339216) (xy 308.449617 -398.37856) (xy 308.472488 -398.422137)
			(xy 308.488072 -398.468818) (xy 308.495967 -398.517395) (xy 308.496462 -398.542002) (xy 309.085246 -398.542002)
			(xy 309.089206 -398.492948) (xy 309.100983 -398.445164) (xy 309.120274 -398.399888) (xy 309.146577 -398.358292)
			(xy 309.179212 -398.321455) (xy 309.217333 -398.29033) (xy 309.259954 -398.265723) (xy 309.30597 -398.248271)
			(xy 309.354189 -398.238427) (xy 309.403364 -398.236446) (xy 309.452219 -398.242378) (xy 309.49949 -398.25607)
			(xy 309.543952 -398.277168) (xy 309.584455 -398.305124) (xy 309.619948 -398.339216) (xy 309.649513 -398.37856)
			(xy 309.672384 -398.422137) (xy 309.687968 -398.468818) (xy 309.695863 -398.517395) (xy 309.696358 -398.542002)
			(xy 310.285142 -398.542002) (xy 310.289102 -398.492948) (xy 310.300879 -398.445164) (xy 310.32017 -398.399888)
			(xy 310.346473 -398.358292) (xy 310.379108 -398.321455) (xy 310.417229 -398.29033) (xy 310.45985 -398.265723)
			(xy 310.505866 -398.248271) (xy 310.554085 -398.238427) (xy 310.60326 -398.236446) (xy 310.652115 -398.242378)
			(xy 310.699386 -398.25607) (xy 310.743848 -398.277168) (xy 310.784351 -398.305124) (xy 310.819844 -398.339216)
			(xy 310.849409 -398.37856) (xy 310.87228 -398.422137) (xy 310.887864 -398.468818) (xy 310.895759 -398.517395)
			(xy 310.896254 -398.542002) (xy 311.485292 -398.542002) (xy 311.489252 -398.492948) (xy 311.501029 -398.445164)
			(xy 311.52032 -398.399888) (xy 311.546623 -398.358292) (xy 311.579258 -398.321455) (xy 311.617379 -398.29033)
			(xy 311.66 -398.265723) (xy 311.706016 -398.248271) (xy 311.754235 -398.238427) (xy 311.80341 -398.236446)
			(xy 311.852265 -398.242378) (xy 311.899536 -398.25607) (xy 311.943998 -398.277168) (xy 311.984501 -398.305124)
			(xy 312.019994 -398.339216) (xy 312.049559 -398.37856) (xy 312.07243 -398.422137) (xy 312.088014 -398.468818)
			(xy 312.095909 -398.517395) (xy 312.096404 -398.542002) (xy 312.685188 -398.542002) (xy 312.689148 -398.492948)
			(xy 312.700925 -398.445164) (xy 312.720216 -398.399888) (xy 312.746519 -398.358292) (xy 312.779154 -398.321455)
			(xy 312.817275 -398.29033) (xy 312.859896 -398.265723) (xy 312.905912 -398.248271) (xy 312.954131 -398.238427)
			(xy 313.003306 -398.236446) (xy 313.052161 -398.242378) (xy 313.099432 -398.25607) (xy 313.143894 -398.277168)
			(xy 313.184397 -398.305124) (xy 313.21989 -398.339216) (xy 313.249455 -398.37856) (xy 313.272326 -398.422137)
			(xy 313.28791 -398.468818) (xy 313.295805 -398.517395) (xy 313.2963 -398.542002) (xy 313.885338 -398.542002)
			(xy 313.889298 -398.492948) (xy 313.901075 -398.445164) (xy 313.920366 -398.399888) (xy 313.946669 -398.358292)
			(xy 313.979304 -398.321455) (xy 314.017425 -398.29033) (xy 314.060046 -398.265723) (xy 314.106062 -398.248271)
			(xy 314.154281 -398.238427) (xy 314.203456 -398.236446) (xy 314.252311 -398.242378) (xy 314.299582 -398.25607)
			(xy 314.344044 -398.277168) (xy 314.384547 -398.305124) (xy 314.42004 -398.339216) (xy 314.449605 -398.37856)
			(xy 314.472476 -398.422137) (xy 314.48806 -398.468818) (xy 314.495955 -398.517395) (xy 314.49645 -398.542002)
			(xy 315.085234 -398.542002) (xy 315.089194 -398.492948) (xy 315.100971 -398.445164) (xy 315.120262 -398.399888)
			(xy 315.146565 -398.358292) (xy 315.1792 -398.321455) (xy 315.217321 -398.29033) (xy 315.259942 -398.265723)
			(xy 315.305958 -398.248271) (xy 315.354177 -398.238427) (xy 315.403352 -398.236446) (xy 315.452207 -398.242378)
			(xy 315.499478 -398.25607) (xy 315.54394 -398.277168) (xy 315.584443 -398.305124) (xy 315.619936 -398.339216)
			(xy 315.649501 -398.37856) (xy 315.672372 -398.422137) (xy 315.687956 -398.468818) (xy 315.695851 -398.517395)
			(xy 315.696346 -398.542002) (xy 316.28513 -398.542002) (xy 316.28909 -398.492948) (xy 316.300867 -398.445164)
			(xy 316.320158 -398.399888) (xy 316.346461 -398.358292) (xy 316.379096 -398.321455) (xy 316.417217 -398.29033)
			(xy 316.459838 -398.265723) (xy 316.505854 -398.248271) (xy 316.554073 -398.238427) (xy 316.603248 -398.236446)
			(xy 316.652103 -398.242378) (xy 316.699374 -398.25607) (xy 316.743836 -398.277168) (xy 316.784339 -398.305124)
			(xy 316.819832 -398.339216) (xy 316.849397 -398.37856) (xy 316.872268 -398.422137) (xy 316.887852 -398.468818)
			(xy 316.895747 -398.517395) (xy 316.896242 -398.542002) (xy 317.48528 -398.542002) (xy 317.48924 -398.492948)
			(xy 317.501017 -398.445164) (xy 317.520308 -398.399888) (xy 317.546611 -398.358292) (xy 317.579246 -398.321455)
			(xy 317.617367 -398.29033) (xy 317.659988 -398.265723) (xy 317.706004 -398.248271) (xy 317.754223 -398.238427)
			(xy 317.803398 -398.236446) (xy 317.852253 -398.242378) (xy 317.899524 -398.25607) (xy 317.943986 -398.277168)
			(xy 317.984489 -398.305124) (xy 318.019982 -398.339216) (xy 318.049547 -398.37856) (xy 318.072418 -398.422137)
			(xy 318.088002 -398.468818) (xy 318.095897 -398.517395) (xy 318.096392 -398.542002) (xy 318.685176 -398.542002)
			(xy 318.689136 -398.492948) (xy 318.700913 -398.445164) (xy 318.720204 -398.399888) (xy 318.746507 -398.358292)
			(xy 318.779142 -398.321455) (xy 318.817263 -398.29033) (xy 318.859884 -398.265723) (xy 318.9059 -398.248271)
			(xy 318.954119 -398.238427) (xy 319.003294 -398.236446) (xy 319.052149 -398.242378) (xy 319.09942 -398.25607)
			(xy 319.143882 -398.277168) (xy 319.184385 -398.305124) (xy 319.219878 -398.339216) (xy 319.249443 -398.37856)
			(xy 319.272314 -398.422137) (xy 319.287898 -398.468818) (xy 319.295793 -398.517395) (xy 319.296288 -398.542002)
			(xy 319.885326 -398.542002) (xy 319.889286 -398.492948) (xy 319.901063 -398.445164) (xy 319.920354 -398.399888)
			(xy 319.946657 -398.358292) (xy 319.979292 -398.321455) (xy 320.017413 -398.29033) (xy 320.060034 -398.265723)
			(xy 320.10605 -398.248271) (xy 320.154269 -398.238427) (xy 320.203444 -398.236446) (xy 320.252299 -398.242378)
			(xy 320.29957 -398.25607) (xy 320.344032 -398.277168) (xy 320.384535 -398.305124) (xy 320.420028 -398.339216)
			(xy 320.449593 -398.37856) (xy 320.472464 -398.422137) (xy 320.488048 -398.468818) (xy 320.495943 -398.517395)
			(xy 320.496438 -398.542002) (xy 320.495943 -398.566609) (xy 320.488048 -398.615186) (xy 320.472464 -398.661867)
			(xy 320.449593 -398.705444) (xy 320.420028 -398.744788) (xy 320.384535 -398.77888) (xy 320.344032 -398.806836)
			(xy 320.29957 -398.827934) (xy 320.252299 -398.841626) (xy 320.203444 -398.847558) (xy 320.154269 -398.845577)
			(xy 320.10605 -398.835733) (xy 320.060034 -398.818281) (xy 320.017413 -398.793674) (xy 319.979292 -398.762549)
			(xy 319.946657 -398.725712) (xy 319.920354 -398.684116) (xy 319.901063 -398.63884) (xy 319.889286 -398.591056)
			(xy 319.885326 -398.542002) (xy 319.296288 -398.542002) (xy 319.295793 -398.566609) (xy 319.287898 -398.615186)
			(xy 319.272314 -398.661867) (xy 319.249443 -398.705444) (xy 319.219878 -398.744788) (xy 319.184385 -398.77888)
			(xy 319.143882 -398.806836) (xy 319.09942 -398.827934) (xy 319.052149 -398.841626) (xy 319.003294 -398.847558)
			(xy 318.954119 -398.845577) (xy 318.9059 -398.835733) (xy 318.859884 -398.818281) (xy 318.817263 -398.793674)
			(xy 318.779142 -398.762549) (xy 318.746507 -398.725712) (xy 318.720204 -398.684116) (xy 318.700913 -398.63884)
			(xy 318.689136 -398.591056) (xy 318.685176 -398.542002) (xy 318.096392 -398.542002) (xy 318.095897 -398.566609)
			(xy 318.088002 -398.615186) (xy 318.072418 -398.661867) (xy 318.049547 -398.705444) (xy 318.019982 -398.744788)
			(xy 317.984489 -398.77888) (xy 317.943986 -398.806836) (xy 317.899524 -398.827934) (xy 317.852253 -398.841626)
			(xy 317.803398 -398.847558) (xy 317.754223 -398.845577) (xy 317.706004 -398.835733) (xy 317.659988 -398.818281)
			(xy 317.617367 -398.793674) (xy 317.579246 -398.762549) (xy 317.546611 -398.725712) (xy 317.520308 -398.684116)
			(xy 317.501017 -398.63884) (xy 317.48924 -398.591056) (xy 317.48528 -398.542002) (xy 316.896242 -398.542002)
			(xy 316.895747 -398.566609) (xy 316.887852 -398.615186) (xy 316.872268 -398.661867) (xy 316.849397 -398.705444)
			(xy 316.819832 -398.744788) (xy 316.784339 -398.77888) (xy 316.743836 -398.806836) (xy 316.699374 -398.827934)
			(xy 316.652103 -398.841626) (xy 316.603248 -398.847558) (xy 316.554073 -398.845577) (xy 316.505854 -398.835733)
			(xy 316.459838 -398.818281) (xy 316.417217 -398.793674) (xy 316.379096 -398.762549) (xy 316.346461 -398.725712)
			(xy 316.320158 -398.684116) (xy 316.300867 -398.63884) (xy 316.28909 -398.591056) (xy 316.28513 -398.542002)
			(xy 315.696346 -398.542002) (xy 315.695851 -398.566609) (xy 315.687956 -398.615186) (xy 315.672372 -398.661867)
			(xy 315.649501 -398.705444) (xy 315.619936 -398.744788) (xy 315.584443 -398.77888) (xy 315.54394 -398.806836)
			(xy 315.499478 -398.827934) (xy 315.452207 -398.841626) (xy 315.403352 -398.847558) (xy 315.354177 -398.845577)
			(xy 315.305958 -398.835733) (xy 315.259942 -398.818281) (xy 315.217321 -398.793674) (xy 315.1792 -398.762549)
			(xy 315.146565 -398.725712) (xy 315.120262 -398.684116) (xy 315.100971 -398.63884) (xy 315.089194 -398.591056)
			(xy 315.085234 -398.542002) (xy 314.49645 -398.542002) (xy 314.495955 -398.566609) (xy 314.48806 -398.615186)
			(xy 314.472476 -398.661867) (xy 314.449605 -398.705444) (xy 314.42004 -398.744788) (xy 314.384547 -398.77888)
			(xy 314.344044 -398.806836) (xy 314.299582 -398.827934) (xy 314.252311 -398.841626) (xy 314.203456 -398.847558)
			(xy 314.154281 -398.845577) (xy 314.106062 -398.835733) (xy 314.060046 -398.818281) (xy 314.017425 -398.793674)
			(xy 313.979304 -398.762549) (xy 313.946669 -398.725712) (xy 313.920366 -398.684116) (xy 313.901075 -398.63884)
			(xy 313.889298 -398.591056) (xy 313.885338 -398.542002) (xy 313.2963 -398.542002) (xy 313.295805 -398.566609)
			(xy 313.28791 -398.615186) (xy 313.272326 -398.661867) (xy 313.249455 -398.705444) (xy 313.21989 -398.744788)
			(xy 313.184397 -398.77888) (xy 313.143894 -398.806836) (xy 313.099432 -398.827934) (xy 313.052161 -398.841626)
			(xy 313.003306 -398.847558) (xy 312.954131 -398.845577) (xy 312.905912 -398.835733) (xy 312.859896 -398.818281)
			(xy 312.817275 -398.793674) (xy 312.779154 -398.762549) (xy 312.746519 -398.725712) (xy 312.720216 -398.684116)
			(xy 312.700925 -398.63884) (xy 312.689148 -398.591056) (xy 312.685188 -398.542002) (xy 312.096404 -398.542002)
			(xy 312.095909 -398.566609) (xy 312.088014 -398.615186) (xy 312.07243 -398.661867) (xy 312.049559 -398.705444)
			(xy 312.019994 -398.744788) (xy 311.984501 -398.77888) (xy 311.943998 -398.806836) (xy 311.899536 -398.827934)
			(xy 311.852265 -398.841626) (xy 311.80341 -398.847558) (xy 311.754235 -398.845577) (xy 311.706016 -398.835733)
			(xy 311.66 -398.818281) (xy 311.617379 -398.793674) (xy 311.579258 -398.762549) (xy 311.546623 -398.725712)
			(xy 311.52032 -398.684116) (xy 311.501029 -398.63884) (xy 311.489252 -398.591056) (xy 311.485292 -398.542002)
			(xy 310.896254 -398.542002) (xy 310.895759 -398.566609) (xy 310.887864 -398.615186) (xy 310.87228 -398.661867)
			(xy 310.849409 -398.705444) (xy 310.819844 -398.744788) (xy 310.784351 -398.77888) (xy 310.743848 -398.806836)
			(xy 310.699386 -398.827934) (xy 310.652115 -398.841626) (xy 310.60326 -398.847558) (xy 310.554085 -398.845577)
			(xy 310.505866 -398.835733) (xy 310.45985 -398.818281) (xy 310.417229 -398.793674) (xy 310.379108 -398.762549)
			(xy 310.346473 -398.725712) (xy 310.32017 -398.684116) (xy 310.300879 -398.63884) (xy 310.289102 -398.591056)
			(xy 310.285142 -398.542002) (xy 309.696358 -398.542002) (xy 309.695863 -398.566609) (xy 309.687968 -398.615186)
			(xy 309.672384 -398.661867) (xy 309.649513 -398.705444) (xy 309.619948 -398.744788) (xy 309.584455 -398.77888)
			(xy 309.543952 -398.806836) (xy 309.49949 -398.827934) (xy 309.452219 -398.841626) (xy 309.403364 -398.847558)
			(xy 309.354189 -398.845577) (xy 309.30597 -398.835733) (xy 309.259954 -398.818281) (xy 309.217333 -398.793674)
			(xy 309.179212 -398.762549) (xy 309.146577 -398.725712) (xy 309.120274 -398.684116) (xy 309.100983 -398.63884)
			(xy 309.089206 -398.591056) (xy 309.085246 -398.542002) (xy 308.496462 -398.542002) (xy 308.495967 -398.566609)
			(xy 308.488072 -398.615186) (xy 308.472488 -398.661867) (xy 308.449617 -398.705444) (xy 308.420052 -398.744788)
			(xy 308.384559 -398.77888) (xy 308.344056 -398.806836) (xy 308.299594 -398.827934) (xy 308.252323 -398.841626)
			(xy 308.203468 -398.847558) (xy 308.154293 -398.845577) (xy 308.106074 -398.835733) (xy 308.060058 -398.818281)
			(xy 308.017437 -398.793674) (xy 307.979316 -398.762549) (xy 307.946681 -398.725712) (xy 307.920378 -398.684116)
			(xy 307.901087 -398.63884) (xy 307.88931 -398.591056) (xy 307.88535 -398.542002) (xy 307.296312 -398.542002)
			(xy 307.295817 -398.566609) (xy 307.287922 -398.615186) (xy 307.272338 -398.661867) (xy 307.249467 -398.705444)
			(xy 307.219902 -398.744788) (xy 307.184409 -398.77888) (xy 307.143906 -398.806836) (xy 307.099444 -398.827934)
			(xy 307.052173 -398.841626) (xy 307.003318 -398.847558) (xy 306.954143 -398.845577) (xy 306.905924 -398.835733)
			(xy 306.859908 -398.818281) (xy 306.817287 -398.793674) (xy 306.779166 -398.762549) (xy 306.746531 -398.725712)
			(xy 306.720228 -398.684116) (xy 306.700937 -398.63884) (xy 306.68916 -398.591056) (xy 306.6852 -398.542002)
			(xy 306.096929 -398.542002) (xy 306.092758 -398.592337) (xy 306.080359 -398.641301) (xy 306.06007 -398.687556)
			(xy 306.032444 -398.729841) (xy 305.998235 -398.767003) (xy 305.958377 -398.798027) (xy 305.913956 -398.822068)
			(xy 305.866183 -398.838469) (xy 305.816363 -398.846784) (xy 305.791108 -398.84731) (xy 305.766957 -398.846825)
			(xy 305.719263 -398.83918) (xy 305.673361 -398.824143) (xy 305.651662 -398.813528) (xy 305.63947 -398.807432)
			(xy 305.613562 -398.808448) (xy 305.527964 -398.860518) (xy 305.520718 -398.865343) (xy 305.509756 -398.87885)
			(xy 305.503965 -398.895253) (xy 305.50358 -398.903952) (xy 305.50358 -398.913858) (xy 305.49596 -398.9324)
			(xy 305.330606 -399.097754) (xy 305.32321 -399.104606) (xy 305.304612 -399.11235) (xy 305.294538 -399.11274)
			(xy 303.370742 -399.11274) (xy 303.360677 -399.113175) (xy 303.342092 -399.120909) (xy 303.334674 -399.127726)
			(xy 302.704246 -399.758154) (xy 302.697226 -399.765959) (xy 302.689625 -399.785503) (xy 302.689514 -399.796)
			(xy 302.692816 -399.88109) (xy 302.70196 -399.899886) (xy 302.710088 -399.906998) (xy 302.727843 -399.922782)
			(xy 302.759089 -399.958564) (xy 302.784893 -399.99845) (xy 302.804724 -400.041618) (xy 302.818173 -400.08718)
			(xy 302.824964 -400.134197) (xy 302.825404 -400.15795) (xy 302.825007 -400.181183) (xy 302.818498 -400.22719)
			(xy 302.805615 -400.271833) (xy 302.786611 -400.314235) (xy 302.761861 -400.353559) (xy 302.747172 -400.371564)
			(xy 302.741076 -400.378676) (xy 302.73498 -400.395186) (xy 302.73498 -400.479514) (xy 302.741076 -400.496024)
			(xy 302.747172 -400.503136) (xy 302.76188 -400.521126) (xy 302.786634 -400.560452) (xy 302.805638 -400.602857)
			(xy 302.818517 -400.647504) (xy 302.825017 -400.693516) (xy 302.825404 -400.71675) (xy 302.824894 -400.742737)
			(xy 302.816764 -400.794072) (xy 302.800703 -400.843502) (xy 302.777107 -400.889812) (xy 302.746557 -400.93186)
			(xy 302.709806 -400.968611) (xy 302.667758 -400.999161) (xy 302.621448 -401.022757) (xy 302.572018 -401.038818)
			(xy 302.520683 -401.046948) (xy 302.468709 -401.046948) (xy 302.417374 -401.038818) (xy 302.367944 -401.022757)
			(xy 302.321634 -400.999161) (xy 302.279586 -400.968611) (xy 302.242835 -400.93186) (xy 302.212285 -400.889812)
			(xy 302.188689 -400.843502) (xy 302.172628 -400.794072) (xy 302.164498 -400.742737) (xy 302.163988 -400.71675)
			(xy 302.164385 -400.693517) (xy 302.170894 -400.64751) (xy 302.183777 -400.602867) (xy 302.20278 -400.560465)
			(xy 302.22753 -400.52114) (xy 302.24222 -400.503136) (xy 302.248316 -400.496024) (xy 302.254412 -400.479514)
			(xy 302.254412 -400.395186) (xy 302.248316 -400.378676) (xy 302.24222 -400.371564) (xy 302.234942 -400.362769)
			(xy 302.221469 -400.344337) (xy 302.215296 -400.334734) (xy 302.212248 -400.329908) (xy 302.208184 -400.326098)
			(xy 302.20075 -400.319382) (xy 302.18225 -400.311746) (xy 302.162236 -400.311746) (xy 302.143736 -400.319382)
			(xy 302.136302 -400.326098) (xy 300.787562 -401.674838) (xy 303.434496 -401.674838) (xy 303.434496 -400.811238)
			(xy 303.434958 -400.784882) (xy 303.442222 -400.732671) (xy 303.456603 -400.681958) (xy 303.477828 -400.633707)
			(xy 303.505492 -400.588837) (xy 303.539069 -400.548201) (xy 303.558194 -400.53006) (xy 303.565306 -400.52371)
			(xy 303.573434 -400.506946) (xy 303.581816 -400.420332) (xy 303.576736 -400.402552) (xy 303.571148 -400.394678)
			(xy 303.556997 -400.374832) (xy 303.53454 -400.331573) (xy 303.519228 -400.2853) (xy 303.511448 -400.237184)
			(xy 303.51095 -400.212814) (xy 303.511472 -400.187559) (xy 303.519785 -400.137737) (xy 303.536186 -400.089963)
			(xy 303.560227 -400.04554) (xy 303.591251 -400.00568) (xy 303.628413 -399.97147) (xy 303.670699 -399.943844)
			(xy 303.716955 -399.923554) (xy 303.76592 -399.911154) (xy 303.816258 -399.906983) (xy 303.866596 -399.911154)
			(xy 303.915561 -399.923554) (xy 303.961817 -399.943844) (xy 304.004103 -399.97147) (xy 304.041265 -400.00568)
			(xy 304.072289 -400.04554) (xy 304.09633 -400.089963) (xy 304.112731 -400.137737) (xy 304.121044 -400.187559)
			(xy 304.121566 -400.212814) (xy 304.121085 -400.237186) (xy 304.113326 -400.285309) (xy 304.098009 -400.331584)
			(xy 304.075524 -400.374833) (xy 304.061368 -400.394678) (xy 304.05578 -400.402552) (xy 304.0507 -400.420332)
			(xy 304.059082 -400.506946) (xy 304.06721 -400.52371) (xy 304.074322 -400.53006) (xy 304.093451 -400.548199)
			(xy 304.12704 -400.588828) (xy 304.154713 -400.633697) (xy 304.175941 -400.681949) (xy 304.190321 -400.732666)
			(xy 304.197577 -400.78488) (xy 304.19802 -400.811238) (xy 304.19802 -401.674838) (xy 304.634392 -401.674838)
			(xy 304.634392 -400.811238) (xy 304.634855 -400.784882) (xy 304.642119 -400.732672) (xy 304.6565 -400.681958)
			(xy 304.677725 -400.633707) (xy 304.705389 -400.588837) (xy 304.738965 -400.548201) (xy 304.75809 -400.53006)
			(xy 304.765202 -400.523456) (xy 304.773584 -400.506946) (xy 304.781712 -400.420078) (xy 304.776886 -400.402298)
			(xy 304.771044 -400.394678) (xy 304.756933 -400.374814) (xy 304.734513 -400.331557) (xy 304.719257 -400.285285)
			(xy 304.711554 -400.237175) (xy 304.7111 -400.212814) (xy 304.711622 -400.187559) (xy 304.719935 -400.137737)
			(xy 304.736336 -400.089963) (xy 304.760377 -400.04554) (xy 304.791401 -400.00568) (xy 304.828563 -399.97147)
			(xy 304.870849 -399.943844) (xy 304.917105 -399.923554) (xy 304.96607 -399.911154) (xy 305.016408 -399.906983)
			(xy 305.066746 -399.911154) (xy 305.115711 -399.923554) (xy 305.161967 -399.943844) (xy 305.204253 -399.97147)
			(xy 305.241415 -400.00568) (xy 305.272439 -400.04554) (xy 305.29648 -400.089963) (xy 305.312881 -400.137737)
			(xy 305.321194 -400.187559) (xy 305.321716 -400.212814) (xy 305.321259 -400.237217) (xy 305.313498 -400.285402)
			(xy 305.298175 -400.331741) (xy 305.275681 -400.375054) (xy 305.261518 -400.394932) (xy 305.25593 -400.402552)
			(xy 305.25085 -400.420332) (xy 305.258978 -400.5072) (xy 305.26736 -400.52371) (xy 305.274472 -400.530314)
			(xy 305.293532 -400.548476) (xy 305.327025 -400.589095) (xy 305.354624 -400.633928) (xy 305.375808 -400.682125)
			(xy 305.390174 -400.732773) (xy 305.397451 -400.784915) (xy 305.397916 -400.811238) (xy 305.397916 -401.674838)
			(xy 305.834796 -401.674838) (xy 305.834796 -400.811238) (xy 305.835245 -400.784893) (xy 305.842494 -400.732703)
			(xy 305.856844 -400.682004) (xy 305.878025 -400.633757) (xy 305.905634 -400.588879) (xy 305.939148 -400.548219)
			(xy 305.95824 -400.53006) (xy 305.965352 -400.52371) (xy 305.97348 -400.506946) (xy 305.981862 -400.420332)
			(xy 305.976782 -400.402552) (xy 305.971194 -400.394678) (xy 305.957049 -400.374828) (xy 305.934589 -400.331571)
			(xy 305.919275 -400.285299) (xy 305.911495 -400.237184) (xy 305.910996 -400.212814) (xy 305.911518 -400.187559)
			(xy 305.919831 -400.137737) (xy 305.936232 -400.089963) (xy 305.960273 -400.04554) (xy 305.991297 -400.00568)
			(xy 306.028459 -399.97147) (xy 306.070745 -399.943844) (xy 306.117001 -399.923554) (xy 306.165966 -399.911154)
			(xy 306.216304 -399.906983) (xy 306.266642 -399.911154) (xy 306.315607 -399.923554) (xy 306.361863 -399.943844)
			(xy 306.404149 -399.97147) (xy 306.441311 -400.00568) (xy 306.472335 -400.04554) (xy 306.496376 -400.089963)
			(xy 306.512777 -400.137737) (xy 306.52109 -400.187559) (xy 306.521612 -400.212814) (xy 306.521141 -400.237187)
			(xy 306.513381 -400.285311) (xy 306.498062 -400.331586) (xy 306.475573 -400.374834) (xy 306.461414 -400.394678)
			(xy 306.455826 -400.402552) (xy 306.450746 -400.420332) (xy 306.459128 -400.506946) (xy 306.467256 -400.52371)
			(xy 306.474368 -400.53006) (xy 306.493474 -400.548206) (xy 306.526995 -400.588864) (xy 306.554607 -400.633744)
			(xy 306.575787 -400.681993) (xy 306.590133 -400.732697) (xy 306.597372 -400.784891) (xy 306.597812 -400.811238)
			(xy 306.597812 -401.674838) (xy 307.034692 -401.674838) (xy 307.034692 -400.811238) (xy 307.035143 -400.784893)
			(xy 307.042391 -400.732703) (xy 307.056741 -400.682004) (xy 307.077922 -400.633757) (xy 307.105531 -400.588879)
			(xy 307.139044 -400.54822) (xy 307.158136 -400.53006) (xy 307.165248 -400.52371) (xy 307.173376 -400.506946)
			(xy 307.181758 -400.420332) (xy 307.176678 -400.402552) (xy 307.17109 -400.394678) (xy 307.156945 -400.374828)
			(xy 307.134485 -400.331571) (xy 307.119171 -400.285299) (xy 307.111391 -400.237184) (xy 307.110892 -400.212814)
			(xy 307.111414 -400.187559) (xy 307.119727 -400.137737) (xy 307.136128 -400.089963) (xy 307.160169 -400.04554)
			(xy 307.191193 -400.00568) (xy 307.228355 -399.97147) (xy 307.270641 -399.943844) (xy 307.316897 -399.923554)
			(xy 307.365862 -399.911154) (xy 307.4162 -399.906983) (xy 307.466538 -399.911154) (xy 307.515503 -399.923554)
			(xy 307.561759 -399.943844) (xy 307.604045 -399.97147) (xy 307.641207 -400.00568) (xy 307.672231 -400.04554)
			(xy 307.696272 -400.089963) (xy 307.712673 -400.137737) (xy 307.720986 -400.187559) (xy 307.721508 -400.212814)
			(xy 307.721038 -400.237187) (xy 307.713278 -400.285311) (xy 307.697958 -400.331586) (xy 307.675469 -400.374834)
			(xy 307.66131 -400.394678) (xy 307.655722 -400.402552) (xy 307.650642 -400.420332) (xy 307.659024 -400.506946)
			(xy 307.667152 -400.52371) (xy 307.674264 -400.53006) (xy 307.69337 -400.548207) (xy 307.72689 -400.588864)
			(xy 307.754503 -400.633744) (xy 307.775683 -400.681994) (xy 307.790029 -400.732697) (xy 307.797268 -400.784891)
			(xy 307.797708 -400.811238) (xy 307.797708 -401.674838) (xy 308.234588 -401.674838) (xy 308.234588 -400.811238)
			(xy 308.235052 -400.784882) (xy 308.242316 -400.732672) (xy 308.256697 -400.681959) (xy 308.277921 -400.633708)
			(xy 308.305585 -400.588837) (xy 308.339161 -400.548201) (xy 308.358286 -400.53006) (xy 308.365398 -400.52371)
			(xy 308.373526 -400.506946) (xy 308.381908 -400.420332) (xy 308.376828 -400.402552) (xy 308.37124 -400.394678)
			(xy 308.357088 -400.374832) (xy 308.334632 -400.331573) (xy 308.31932 -400.2853) (xy 308.31154 -400.237184)
			(xy 308.311042 -400.212814) (xy 308.311564 -400.187559) (xy 308.319877 -400.137737) (xy 308.336278 -400.089963)
			(xy 308.360319 -400.04554) (xy 308.391343 -400.00568) (xy 308.428505 -399.97147) (xy 308.470791 -399.943844)
			(xy 308.517047 -399.923554) (xy 308.566012 -399.911154) (xy 308.61635 -399.906983) (xy 308.666688 -399.911154)
			(xy 308.715653 -399.923554) (xy 308.761909 -399.943844) (xy 308.804195 -399.97147) (xy 308.841357 -400.00568)
			(xy 308.872381 -400.04554) (xy 308.896422 -400.089963) (xy 308.912823 -400.137737) (xy 308.921136 -400.187559)
			(xy 308.921658 -400.212814) (xy 308.921178 -400.237186) (xy 308.91342 -400.285309) (xy 308.898102 -400.331585)
			(xy 308.875617 -400.374833) (xy 308.86146 -400.394678) (xy 308.855872 -400.402552) (xy 308.850792 -400.420332)
			(xy 308.859174 -400.506946) (xy 308.867302 -400.52371) (xy 308.874414 -400.53006) (xy 308.893541 -400.548201)
			(xy 308.927131 -400.588829) (xy 308.954804 -400.633697) (xy 308.976033 -400.68195) (xy 308.990413 -400.732666)
			(xy 308.997669 -400.78488) (xy 308.998112 -400.811238) (xy 308.998112 -401.674838) (xy 309.434484 -401.674838)
			(xy 309.434484 -400.811238) (xy 309.43495 -400.784882) (xy 309.442213 -400.732672) (xy 309.456594 -400.681959)
			(xy 309.477818 -400.633708) (xy 309.505482 -400.588837) (xy 309.539057 -400.548201) (xy 309.558182 -400.53006)
			(xy 309.565294 -400.52371) (xy 309.573422 -400.506946) (xy 309.581804 -400.420332) (xy 309.576724 -400.402552)
			(xy 309.571136 -400.394678) (xy 309.556984 -400.374833) (xy 309.534527 -400.331573) (xy 309.519216 -400.2853)
			(xy 309.511436 -400.237184) (xy 309.510938 -400.212814) (xy 309.51146 -400.187559) (xy 309.519773 -400.137737)
			(xy 309.536174 -400.089963) (xy 309.560215 -400.04554) (xy 309.591239 -400.00568) (xy 309.628401 -399.97147)
			(xy 309.670687 -399.943844) (xy 309.716943 -399.923554) (xy 309.765908 -399.911154) (xy 309.816246 -399.906983)
			(xy 309.866584 -399.911154) (xy 309.915549 -399.923554) (xy 309.961805 -399.943844) (xy 310.004091 -399.97147)
			(xy 310.041253 -400.00568) (xy 310.072277 -400.04554) (xy 310.096318 -400.089963) (xy 310.112719 -400.137737)
			(xy 310.121032 -400.187559) (xy 310.121554 -400.212814) (xy 310.121075 -400.237186) (xy 310.113316 -400.285309)
			(xy 310.097999 -400.331585) (xy 310.075513 -400.374833) (xy 310.061356 -400.394678) (xy 310.055768 -400.402552)
			(xy 310.050688 -400.420332) (xy 310.05907 -400.506946) (xy 310.067198 -400.52371) (xy 310.07431 -400.53006)
			(xy 310.093436 -400.548202) (xy 310.127026 -400.58883) (xy 310.1547 -400.633698) (xy 310.175929 -400.68195)
			(xy 310.190309 -400.732666) (xy 310.197565 -400.78488) (xy 310.198008 -400.811238) (xy 310.198008 -401.674838)
			(xy 310.634888 -401.674838) (xy 310.634888 -400.811238) (xy 310.63534 -400.784893) (xy 310.642588 -400.732703)
			(xy 310.656938 -400.682004) (xy 310.678119 -400.633758) (xy 310.705727 -400.588879) (xy 310.73924 -400.54822)
			(xy 310.758332 -400.53006) (xy 310.765444 -400.52371) (xy 310.773572 -400.506946) (xy 310.781954 -400.420332)
			(xy 310.776874 -400.402552) (xy 310.771286 -400.394678) (xy 310.75714 -400.374828) (xy 310.734681 -400.331571)
			(xy 310.719367 -400.285299) (xy 310.711587 -400.237184) (xy 310.711088 -400.212814) (xy 310.71161 -400.187559)
			(xy 310.719923 -400.137737) (xy 310.736324 -400.089963) (xy 310.760365 -400.04554) (xy 310.791389 -400.00568)
			(xy 310.828551 -399.97147) (xy 310.870837 -399.943844) (xy 310.917093 -399.923554) (xy 310.966058 -399.911154)
			(xy 311.016396 -399.906983) (xy 311.066734 -399.911154) (xy 311.115699 -399.923554) (xy 311.161955 -399.943844)
			(xy 311.204241 -399.97147) (xy 311.241403 -400.00568) (xy 311.272427 -400.04554) (xy 311.296468 -400.089963)
			(xy 311.312869 -400.137737) (xy 311.321182 -400.187559) (xy 311.321704 -400.212814) (xy 311.321235 -400.237187)
			(xy 311.313475 -400.285311) (xy 311.298155 -400.331586) (xy 311.275665 -400.374834) (xy 311.261506 -400.394678)
			(xy 311.255918 -400.402552) (xy 311.250838 -400.420332) (xy 311.25922 -400.506946) (xy 311.267348 -400.52371)
			(xy 311.27446 -400.53006) (xy 311.293565 -400.548208) (xy 311.327086 -400.588865) (xy 311.354698 -400.633744)
			(xy 311.375879 -400.681994) (xy 311.390225 -400.732697) (xy 311.397464 -400.784891) (xy 311.397904 -400.811238)
			(xy 311.397904 -401.674838) (xy 311.834784 -401.674838) (xy 311.834784 -400.811238) (xy 311.835237 -400.784893)
			(xy 311.842485 -400.732703) (xy 311.856835 -400.682004) (xy 311.878016 -400.633758) (xy 311.905624 -400.588879)
			(xy 311.939136 -400.54822) (xy 311.958228 -400.53006) (xy 311.96534 -400.52371) (xy 311.973468 -400.506946)
			(xy 311.98185 -400.420332) (xy 311.97677 -400.402552) (xy 311.971182 -400.394678) (xy 311.957036 -400.374829)
			(xy 311.934576 -400.331571) (xy 311.919263 -400.285299) (xy 311.911482 -400.237184) (xy 311.910984 -400.212814)
			(xy 311.911506 -400.187559) (xy 311.919819 -400.137737) (xy 311.93622 -400.089963) (xy 311.960261 -400.04554)
			(xy 311.991285 -400.00568) (xy 312.028447 -399.97147) (xy 312.070733 -399.943844) (xy 312.116989 -399.923554)
			(xy 312.165954 -399.911154) (xy 312.216292 -399.906983) (xy 312.26663 -399.911154) (xy 312.315595 -399.923554)
			(xy 312.361851 -399.943844) (xy 312.404137 -399.97147) (xy 312.441299 -400.00568) (xy 312.472323 -400.04554)
			(xy 312.496364 -400.089963) (xy 312.512765 -400.137737) (xy 312.521078 -400.187559) (xy 312.5216 -400.212814)
			(xy 312.521131 -400.237187) (xy 312.513371 -400.285311) (xy 312.498051 -400.331586) (xy 312.475561 -400.374834)
			(xy 312.461402 -400.394678) (xy 312.455814 -400.402552) (xy 312.450734 -400.420332) (xy 312.459116 -400.506946)
			(xy 312.467244 -400.52371) (xy 312.474356 -400.53006) (xy 312.49346 -400.548209) (xy 312.526981 -400.588865)
			(xy 312.554594 -400.633745) (xy 312.575775 -400.681994) (xy 312.590121 -400.732697) (xy 312.59736 -400.784891)
			(xy 312.5978 -400.811238) (xy 312.5978 -401.674838) (xy 313.03468 -401.674838) (xy 313.03468 -400.811238)
			(xy 313.035097 -400.78491) (xy 313.042348 -400.732755) (xy 313.056704 -400.682093) (xy 313.077892 -400.633888)
			(xy 313.105509 -400.589055) (xy 313.13903 -400.548446) (xy 313.158124 -400.530314) (xy 313.165236 -400.52371)
			(xy 313.173618 -400.5072) (xy 313.181746 -400.420332) (xy 313.176666 -400.402552) (xy 313.171078 -400.394932)
			(xy 313.15692 -400.375052) (xy 313.134433 -400.331737) (xy 313.119116 -400.285399) (xy 313.111358 -400.237216)
			(xy 313.11088 -400.212814) (xy 313.111402 -400.187559) (xy 313.119715 -400.137737) (xy 313.136116 -400.089963)
			(xy 313.160157 -400.04554) (xy 313.191181 -400.00568) (xy 313.228343 -399.97147) (xy 313.270629 -399.943844)
			(xy 313.316885 -399.923554) (xy 313.36585 -399.911154) (xy 313.416188 -399.906983) (xy 313.466526 -399.911154)
			(xy 313.515491 -399.923554) (xy 313.561747 -399.943844) (xy 313.604033 -399.97147) (xy 313.641195 -400.00568)
			(xy 313.672219 -400.04554) (xy 313.69626 -400.089963) (xy 313.712661 -400.137737) (xy 313.720974 -400.187559)
			(xy 313.721496 -400.212814) (xy 313.721008 -400.237173) (xy 313.713295 -400.285276) (xy 313.698049 -400.331546)
			(xy 313.675657 -400.374813) (xy 313.661552 -400.394678) (xy 313.65571 -400.402298) (xy 313.650884 -400.420078)
			(xy 313.659012 -400.506946) (xy 313.667394 -400.523456) (xy 313.674506 -400.53006) (xy 313.693632 -400.548203)
			(xy 313.727222 -400.58883) (xy 313.754896 -400.633698) (xy 313.776125 -400.68195) (xy 313.790505 -400.732666)
			(xy 313.797761 -400.78488) (xy 313.798204 -400.811238) (xy 313.798204 -401.674838) (xy 314.234576 -401.674838)
			(xy 314.234576 -400.811238) (xy 314.235044 -400.784882) (xy 314.242308 -400.732672) (xy 314.256688 -400.681959)
			(xy 314.277912 -400.633708) (xy 314.305575 -400.588838) (xy 314.33915 -400.548201) (xy 314.358274 -400.53006)
			(xy 314.365386 -400.52371) (xy 314.373514 -400.506946) (xy 314.381896 -400.420332) (xy 314.376816 -400.402552)
			(xy 314.371228 -400.394678) (xy 314.357075 -400.374833) (xy 314.334619 -400.331574) (xy 314.319308 -400.2853)
			(xy 314.311528 -400.237184) (xy 314.31103 -400.212814) (xy 314.311552 -400.187559) (xy 314.319865 -400.137737)
			(xy 314.336266 -400.089963) (xy 314.360307 -400.04554) (xy 314.391331 -400.00568) (xy 314.428493 -399.97147)
			(xy 314.470779 -399.943844) (xy 314.517035 -399.923554) (xy 314.566 -399.911154) (xy 314.616338 -399.906983)
			(xy 314.666676 -399.911154) (xy 314.715641 -399.923554) (xy 314.761897 -399.943844) (xy 314.804183 -399.97147)
			(xy 314.841345 -400.00568) (xy 314.872369 -400.04554) (xy 314.89641 -400.089963) (xy 314.912811 -400.137737)
			(xy 314.921124 -400.187559) (xy 314.921646 -400.212814) (xy 314.921169 -400.237186) (xy 314.91341 -400.28531)
			(xy 314.898092 -400.331585) (xy 314.875605 -400.374833) (xy 314.861448 -400.394678) (xy 314.85586 -400.402552)
			(xy 314.85078 -400.420332) (xy 314.859162 -400.506946) (xy 314.86729 -400.52371) (xy 314.874402 -400.53006)
			(xy 314.893527 -400.548203) (xy 314.927117 -400.588831) (xy 314.954791 -400.633698) (xy 314.976021 -400.68195)
			(xy 314.990401 -400.732667) (xy 314.997657 -400.78488) (xy 314.9981 -400.811238) (xy 314.9981 -401.674838)
			(xy 315.43498 -401.674838) (xy 315.43498 -400.811238) (xy 315.435418 -400.784922) (xy 315.442642 -400.732787)
			(xy 315.456959 -400.682139) (xy 315.478096 -400.633937) (xy 315.505654 -400.589096) (xy 315.539109 -400.548464)
			(xy 315.55817 -400.530314) (xy 315.565282 -400.52371) (xy 315.573664 -400.5072) (xy 315.581792 -400.420332)
			(xy 315.576712 -400.402552) (xy 315.571124 -400.394932) (xy 315.556971 -400.375048) (xy 315.534482 -400.331735)
			(xy 315.519164 -400.285398) (xy 315.511404 -400.237216) (xy 315.510926 -400.212814) (xy 315.511448 -400.187559)
			(xy 315.519761 -400.137737) (xy 315.536162 -400.089963) (xy 315.560203 -400.04554) (xy 315.591227 -400.00568)
			(xy 315.628389 -399.97147) (xy 315.670675 -399.943844) (xy 315.716931 -399.923554) (xy 315.765896 -399.911154)
			(xy 315.816234 -399.906983) (xy 315.866572 -399.911154) (xy 315.915537 -399.923554) (xy 315.961793 -399.943844)
			(xy 316.004079 -399.97147) (xy 316.041241 -400.00568) (xy 316.072265 -400.04554) (xy 316.096306 -400.089963)
			(xy 316.112707 -400.137737) (xy 316.12102 -400.187559) (xy 316.121542 -400.212814) (xy 316.121046 -400.237172)
			(xy 316.113334 -400.285275) (xy 316.09809 -400.331545) (xy 316.075701 -400.374812) (xy 316.061598 -400.394678)
			(xy 316.055756 -400.402298) (xy 316.05093 -400.420078) (xy 316.059058 -400.506946) (xy 316.06744 -400.523456)
			(xy 316.074552 -400.53006) (xy 316.093655 -400.548209) (xy 316.127177 -400.588866) (xy 316.15479 -400.633745)
			(xy 316.175971 -400.681994) (xy 316.190317 -400.732697) (xy 316.197556 -400.784891) (xy 316.197996 -400.811238)
			(xy 316.197996 -401.674838) (xy 316.634876 -401.674838) (xy 316.634876 -400.811238) (xy 316.635332 -400.784893)
			(xy 316.64258 -400.732703) (xy 316.65693 -400.682005) (xy 316.678109 -400.633759) (xy 316.705717 -400.58888)
			(xy 316.739229 -400.54822) (xy 316.75832 -400.53006) (xy 316.765432 -400.52371) (xy 316.77356 -400.506946)
			(xy 316.781942 -400.420332) (xy 316.776862 -400.402552) (xy 316.771274 -400.394678) (xy 316.757127 -400.374829)
			(xy 316.734668 -400.331572) (xy 316.719355 -400.285299) (xy 316.711574 -400.237184) (xy 316.711076 -400.212814)
			(xy 316.711598 -400.187559) (xy 316.719911 -400.137737) (xy 316.736312 -400.089963) (xy 316.760353 -400.04554)
			(xy 316.791377 -400.00568) (xy 316.828539 -399.97147) (xy 316.870825 -399.943844) (xy 316.917081 -399.923554)
			(xy 316.966046 -399.911154) (xy 317.016384 -399.906983) (xy 317.066722 -399.911154) (xy 317.115687 -399.923554)
			(xy 317.161943 -399.943844) (xy 317.204229 -399.97147) (xy 317.241391 -400.00568) (xy 317.272415 -400.04554)
			(xy 317.296456 -400.089963) (xy 317.312857 -400.137737) (xy 317.32117 -400.187559) (xy 317.321692 -400.212814)
			(xy 317.321225 -400.237187) (xy 317.313465 -400.285311) (xy 317.298144 -400.331587) (xy 317.275653 -400.374834)
			(xy 317.261494 -400.394678) (xy 317.255906 -400.402552) (xy 317.250826 -400.420332) (xy 317.259208 -400.506946)
			(xy 317.267336 -400.52371) (xy 317.274448 -400.53006) (xy 317.293551 -400.54821) (xy 317.327072 -400.588866)
			(xy 317.354685 -400.633745) (xy 317.375867 -400.681994) (xy 317.390213 -400.732697) (xy 317.397452 -400.784891)
			(xy 317.397892 -400.811238) (xy 317.397892 -401.674838) (xy 317.834772 -401.674838) (xy 317.834772 -400.811238)
			(xy 317.835229 -400.784893) (xy 317.842477 -400.732704) (xy 317.856827 -400.682005) (xy 317.878006 -400.633759)
			(xy 317.905613 -400.58888) (xy 317.939125 -400.54822) (xy 317.958216 -400.53006) (xy 317.965328 -400.52371)
			(xy 317.973456 -400.506946) (xy 317.981838 -400.420332) (xy 317.976758 -400.402552) (xy 317.97117 -400.394678)
			(xy 317.957022 -400.37483) (xy 317.934564 -400.331572) (xy 317.919251 -400.285299) (xy 317.91147 -400.237184)
			(xy 317.910972 -400.212814) (xy 317.911494 -400.187559) (xy 317.919807 -400.137737) (xy 317.936208 -400.089963)
			(xy 317.960249 -400.04554) (xy 317.991273 -400.00568) (xy 318.028435 -399.97147) (xy 318.070721 -399.943844)
			(xy 318.116977 -399.923554) (xy 318.165942 -399.911154) (xy 318.21628 -399.906983) (xy 318.266618 -399.911154)
			(xy 318.315583 -399.923554) (xy 318.361839 -399.943844) (xy 318.404125 -399.97147) (xy 318.441287 -400.00568)
			(xy 318.472311 -400.04554) (xy 318.496352 -400.089963) (xy 318.512753 -400.137737) (xy 318.521066 -400.187559)
			(xy 318.521588 -400.212814) (xy 318.521122 -400.237187) (xy 318.513361 -400.285311) (xy 318.49804 -400.331587)
			(xy 318.47555 -400.374834) (xy 318.46139 -400.394678) (xy 318.455802 -400.402552) (xy 318.450722 -400.420332)
			(xy 318.459104 -400.506946) (xy 318.467232 -400.52371) (xy 318.474344 -400.53006) (xy 318.493446 -400.548211)
			(xy 318.526967 -400.588867) (xy 318.554581 -400.633746) (xy 318.575762 -400.681995) (xy 318.590109 -400.732697)
			(xy 318.597348 -400.784891) (xy 318.597788 -400.811238) (xy 318.597788 -401.674838) (xy 319.034668 -401.674838)
			(xy 319.034668 -400.811238) (xy 319.035126 -400.784893) (xy 319.042374 -400.732704) (xy 319.056724 -400.682005)
			(xy 319.077903 -400.633759) (xy 319.10551 -400.58888) (xy 319.139021 -400.54822) (xy 319.158112 -400.53006)
			(xy 319.165224 -400.52371) (xy 319.173352 -400.506946) (xy 319.181734 -400.420332) (xy 319.176654 -400.402552)
			(xy 319.171066 -400.394678) (xy 319.156918 -400.37483) (xy 319.134459 -400.331572) (xy 319.119146 -400.285299)
			(xy 319.111366 -400.237184) (xy 319.110868 -400.212814) (xy 319.11139 -400.187559) (xy 319.119703 -400.137737)
			(xy 319.136104 -400.089963) (xy 319.160145 -400.04554) (xy 319.191169 -400.00568) (xy 319.228331 -399.97147)
			(xy 319.270617 -399.943844) (xy 319.316873 -399.923554) (xy 319.365838 -399.911154) (xy 319.416176 -399.906983)
			(xy 319.466514 -399.911154) (xy 319.515479 -399.923554) (xy 319.561735 -399.943844) (xy 319.604021 -399.97147)
			(xy 319.641183 -400.00568) (xy 319.672207 -400.04554) (xy 319.696248 -400.089963) (xy 319.712649 -400.137737)
			(xy 319.720962 -400.187559) (xy 319.721484 -400.212814) (xy 319.721019 -400.237187) (xy 319.713258 -400.285311)
			(xy 319.697937 -400.331587) (xy 319.675446 -400.374834) (xy 319.661286 -400.394678) (xy 319.655698 -400.402552)
			(xy 319.650618 -400.420332) (xy 319.659 -400.506946) (xy 319.667128 -400.52371) (xy 319.67424 -400.53006)
			(xy 319.693341 -400.548212) (xy 319.726863 -400.588867) (xy 319.754477 -400.633746) (xy 319.775658 -400.681995)
			(xy 319.790005 -400.732697) (xy 319.797244 -400.784891) (xy 319.797684 -400.811238) (xy 319.797684 -401.674838)
			(xy 320.234564 -401.674838) (xy 320.234564 -400.811238) (xy 320.235036 -400.784882) (xy 320.242299 -400.732673)
			(xy 320.256679 -400.68196) (xy 320.277902 -400.633709) (xy 320.305564 -400.588838) (xy 320.339138 -400.548202)
			(xy 320.358262 -400.53006) (xy 320.365374 -400.52371) (xy 320.373502 -400.506946) (xy 320.381884 -400.420332)
			(xy 320.376804 -400.402552) (xy 320.371216 -400.394678) (xy 320.357061 -400.374834) (xy 320.334606 -400.331574)
			(xy 320.319295 -400.2853) (xy 320.311516 -400.237184) (xy 320.311018 -400.212814) (xy 320.31154 -400.187559)
			(xy 320.319853 -400.137737) (xy 320.336254 -400.089963) (xy 320.360295 -400.04554) (xy 320.391319 -400.00568)
			(xy 320.428481 -399.97147) (xy 320.470767 -399.943844) (xy 320.517023 -399.923554) (xy 320.565988 -399.911154)
			(xy 320.616326 -399.906983) (xy 320.666664 -399.911154) (xy 320.715629 -399.923554) (xy 320.761885 -399.943844)
			(xy 320.804171 -399.97147) (xy 320.841333 -400.00568) (xy 320.872357 -400.04554) (xy 320.896398 -400.089963)
			(xy 320.912799 -400.137737) (xy 320.921112 -400.187559) (xy 320.921634 -400.212814) (xy 320.921159 -400.237186)
			(xy 320.9134 -400.28531) (xy 320.898081 -400.331585) (xy 320.875594 -400.374833) (xy 320.861436 -400.394678)
			(xy 320.855848 -400.402552) (xy 320.850768 -400.420332) (xy 320.85915 -400.506946) (xy 320.867278 -400.52371)
			(xy 320.87439 -400.53006) (xy 320.893532 -400.548186) (xy 320.927117 -400.588819) (xy 320.954787 -400.633691)
			(xy 320.976013 -400.681946) (xy 320.99039 -400.732664) (xy 320.997645 -400.78488) (xy 320.998088 -400.811238)
			(xy 320.998088 -401.674838) (xy 320.997677 -401.701013) (xy 320.990479 -401.752866) (xy 320.976265 -401.803249)
			(xy 320.955301 -401.851219) (xy 320.92798 -401.895874) (xy 320.894815 -401.936379) (xy 320.875914 -401.954492)
			(xy 320.868548 -401.96135) (xy 320.86042 -401.978876) (xy 320.855086 -402.069046) (xy 320.861182 -402.087334)
			(xy 320.867786 -402.094954) (xy 320.882684 -402.113) (xy 320.907749 -402.152517) (xy 320.926997 -402.19517)
			(xy 320.940045 -402.24011) (xy 320.946632 -402.28644) (xy 320.947034 -402.309838) (xy 320.946524 -402.335825)
			(xy 320.938394 -402.38716) (xy 320.922333 -402.43659) (xy 320.898737 -402.4829) (xy 320.868187 -402.524948)
			(xy 320.831436 -402.561699) (xy 320.789388 -402.592249) (xy 320.743078 -402.615845) (xy 320.693648 -402.631906)
			(xy 320.642313 -402.640036) (xy 320.590339 -402.640036) (xy 320.539004 -402.631906) (xy 320.489574 -402.615845)
			(xy 320.443264 -402.592249) (xy 320.401216 -402.561699) (xy 320.364465 -402.524948) (xy 320.333915 -402.4829)
			(xy 320.310319 -402.43659) (xy 320.294258 -402.38716) (xy 320.286128 -402.335825) (xy 320.285618 -402.309838)
			(xy 320.28605 -402.286442) (xy 320.292636 -402.240116) (xy 320.305681 -402.195179) (xy 320.324925 -402.152528)
			(xy 320.349986 -402.113012) (xy 320.364866 -402.094954) (xy 320.37147 -402.087334) (xy 320.377566 -402.069046)
			(xy 320.372232 -401.978876) (xy 320.364104 -401.96135) (xy 320.356738 -401.954492) (xy 320.33783 -401.936388)
			(xy 320.30467 -401.895881) (xy 320.277356 -401.851222) (xy 320.256401 -401.803251) (xy 320.242197 -401.752866)
			(xy 320.235012 -401.701012) (xy 320.234564 -401.674838) (xy 319.797684 -401.674838) (xy 319.797216 -401.701001)
			(xy 319.790066 -401.752836) (xy 319.775906 -401.80321) (xy 319.754999 -401.851178) (xy 319.727738 -401.895842)
			(xy 319.694635 -401.936365) (xy 319.675764 -401.954492) (xy 319.668398 -401.96135) (xy 319.66027 -401.978876)
			(xy 319.654936 -402.069046) (xy 319.661032 -402.087334) (xy 319.667636 -402.094954) (xy 319.682541 -402.112994)
			(xy 319.707604 -402.152513) (xy 319.72685 -402.195168) (xy 319.739896 -402.240109) (xy 319.746482 -402.28644)
			(xy 319.746884 -402.309838) (xy 319.746374 -402.335825) (xy 319.738244 -402.38716) (xy 319.722183 -402.43659)
			(xy 319.698587 -402.4829) (xy 319.668037 -402.524948) (xy 319.631286 -402.561699) (xy 319.589238 -402.592249)
			(xy 319.542928 -402.615845) (xy 319.493498 -402.631906) (xy 319.442163 -402.640036) (xy 319.390189 -402.640036)
			(xy 319.338854 -402.631906) (xy 319.289424 -402.615845) (xy 319.243114 -402.592249) (xy 319.201066 -402.561699)
			(xy 319.164315 -402.524948) (xy 319.133765 -402.4829) (xy 319.110169 -402.43659) (xy 319.094108 -402.38716)
			(xy 319.085978 -402.335825) (xy 319.085468 -402.309838) (xy 319.085889 -402.286441) (xy 319.092475 -402.240114)
			(xy 319.105522 -402.195177) (xy 319.12477 -402.152526) (xy 319.149833 -402.113011) (xy 319.164716 -402.094954)
			(xy 319.17132 -402.087334) (xy 319.177416 -402.069046) (xy 319.172082 -401.978876) (xy 319.163954 -401.96135)
			(xy 319.156588 -401.954492) (xy 319.137691 -401.936388) (xy 319.104575 -401.895867) (xy 319.077306 -401.851201)
			(xy 319.056396 -401.803227) (xy 319.042237 -401.752847) (xy 319.035095 -401.701004) (xy 319.034668 -401.674838)
			(xy 318.597788 -401.674838) (xy 318.597267 -401.703743) (xy 318.588561 -401.760894) (xy 318.571338 -401.81608)
			(xy 318.545991 -401.868038) (xy 318.513102 -401.91558) (xy 318.493648 -401.936966) (xy 318.487552 -401.94357)
			(xy 318.48044 -401.959572) (xy 318.474852 -402.041868) (xy 318.479678 -402.058886) (xy 318.484758 -402.065998)
			(xy 318.499395 -402.087227) (xy 318.522648 -402.133248) (xy 318.538474 -402.182322) (xy 318.546489 -402.233257)
			(xy 318.546988 -402.259038) (xy 318.546478 -402.285025) (xy 318.538348 -402.33636) (xy 318.522287 -402.38579)
			(xy 318.498691 -402.4321) (xy 318.468141 -402.474148) (xy 318.43139 -402.510899) (xy 318.389342 -402.541449)
			(xy 318.343032 -402.565045) (xy 318.293602 -402.581106) (xy 318.242267 -402.589236) (xy 318.190293 -402.589236)
			(xy 318.138958 -402.581106) (xy 318.089528 -402.565045) (xy 318.043218 -402.541449) (xy 318.00117 -402.510899)
			(xy 317.964419 -402.474148) (xy 317.933869 -402.4321) (xy 317.910273 -402.38579) (xy 317.894212 -402.33636)
			(xy 317.886082 -402.285025) (xy 317.885572 -402.259038) (xy 317.88605 -402.233255) (xy 317.894057 -402.182314)
			(xy 317.909882 -402.133236) (xy 317.93314 -402.087213) (xy 317.947802 -402.065998) (xy 317.952882 -402.058886)
			(xy 317.957708 -402.041868) (xy 317.95212 -401.959572) (xy 317.945008 -401.94357) (xy 317.938912 -401.936966)
			(xy 317.919431 -401.915601) (xy 317.886522 -401.868065) (xy 317.861171 -401.816103) (xy 317.843958 -401.760908)
			(xy 317.83528 -401.703747) (xy 317.834772 -401.674838) (xy 317.397892 -401.674838) (xy 317.397422 -401.701001)
			(xy 317.390272 -401.752836) (xy 317.376111 -401.803209) (xy 317.355205 -401.851177) (xy 317.327945 -401.895841)
			(xy 317.294842 -401.936365) (xy 317.275972 -401.954492) (xy 317.268606 -401.96135) (xy 317.260478 -401.978876)
			(xy 317.255144 -402.069046) (xy 317.26124 -402.087334) (xy 317.267844 -402.094954) (xy 317.282751 -402.112993)
			(xy 317.307813 -402.152513) (xy 317.327058 -402.195168) (xy 317.340104 -402.240109) (xy 317.34669 -402.28644)
			(xy 317.347092 -402.309838) (xy 317.346582 -402.335825) (xy 317.338452 -402.38716) (xy 317.322391 -402.43659)
			(xy 317.298795 -402.4829) (xy 317.268245 -402.524948) (xy 317.231494 -402.561699) (xy 317.189446 -402.592249)
			(xy 317.143136 -402.615845) (xy 317.093706 -402.631906) (xy 317.042371 -402.640036) (xy 316.990397 -402.640036)
			(xy 316.939062 -402.631906) (xy 316.889632 -402.615845) (xy 316.843322 -402.592249) (xy 316.801274 -402.561699)
			(xy 316.764523 -402.524948) (xy 316.733973 -402.4829) (xy 316.710377 -402.43659) (xy 316.694316 -402.38716)
			(xy 316.686186 -402.335825) (xy 316.685676 -402.309838) (xy 316.686095 -402.286441) (xy 316.692681 -402.240114)
			(xy 316.705729 -402.195177) (xy 316.724977 -402.152526) (xy 316.750041 -402.113011) (xy 316.764924 -402.094954)
			(xy 316.771528 -402.087334) (xy 316.777624 -402.069046) (xy 316.77229 -401.978876) (xy 316.764162 -401.96135)
			(xy 316.756796 -401.954492) (xy 316.737901 -401.936387) (xy 316.704784 -401.895866) (xy 316.677515 -401.8512)
			(xy 316.656604 -401.803227) (xy 316.642445 -401.752847) (xy 316.635303 -401.701004) (xy 316.634876 -401.674838)
			(xy 316.197996 -401.674838) (xy 316.197525 -401.701001) (xy 316.190375 -401.752836) (xy 316.176214 -401.803209)
			(xy 316.155309 -401.851177) (xy 316.128049 -401.895841) (xy 316.094946 -401.936365) (xy 316.076076 -401.954492)
			(xy 316.06871 -401.96135) (xy 316.060582 -401.978876) (xy 316.055248 -402.069046) (xy 316.061344 -402.087334)
			(xy 316.067948 -402.094954) (xy 316.082855 -402.112992) (xy 316.107917 -402.152512) (xy 316.127163 -402.195168)
			(xy 316.140208 -402.240109) (xy 316.146794 -402.28644) (xy 316.147196 -402.309838) (xy 316.146686 -402.335825)
			(xy 316.138556 -402.38716) (xy 316.122495 -402.43659) (xy 316.098899 -402.4829) (xy 316.068349 -402.524948)
			(xy 316.031598 -402.561699) (xy 315.98955 -402.592249) (xy 315.94324 -402.615845) (xy 315.89381 -402.631906)
			(xy 315.842475 -402.640036) (xy 315.790501 -402.640036) (xy 315.739166 -402.631906) (xy 315.689736 -402.615845)
			(xy 315.643426 -402.592249) (xy 315.601378 -402.561699) (xy 315.564627 -402.524948) (xy 315.534077 -402.4829)
			(xy 315.510481 -402.43659) (xy 315.49442 -402.38716) (xy 315.48629 -402.335825) (xy 315.48578 -402.309838)
			(xy 315.486198 -402.286441) (xy 315.492785 -402.240114) (xy 315.505832 -402.195177) (xy 315.52508 -402.152525)
			(xy 315.550145 -402.113011) (xy 315.565028 -402.094954) (xy 315.571632 -402.087334) (xy 315.577728 -402.069046)
			(xy 315.572394 -401.978876) (xy 315.564266 -401.96135) (xy 315.5569 -401.954492) (xy 315.538006 -401.936386)
			(xy 315.504889 -401.895865) (xy 315.477619 -401.8512) (xy 315.456708 -401.803227) (xy 315.442549 -401.752847)
			(xy 315.435407 -401.701004) (xy 315.43498 -401.674838) (xy 314.9981 -401.674838) (xy 314.997685 -401.701013)
			(xy 314.990487 -401.752865) (xy 314.976274 -401.803249) (xy 314.95531 -401.851218) (xy 314.92799 -401.895874)
			(xy 314.894826 -401.936379) (xy 314.875926 -401.954492) (xy 314.86856 -401.96135) (xy 314.860432 -401.978876)
			(xy 314.855098 -402.069046) (xy 314.861194 -402.087334) (xy 314.867798 -402.094954) (xy 314.882698 -402.112999)
			(xy 314.907762 -402.152516) (xy 314.92701 -402.19517) (xy 314.940057 -402.24011) (xy 314.946644 -402.28644)
			(xy 314.947046 -402.309838) (xy 314.946536 -402.335825) (xy 314.938406 -402.38716) (xy 314.922345 -402.43659)
			(xy 314.898749 -402.4829) (xy 314.868199 -402.524948) (xy 314.831448 -402.561699) (xy 314.7894 -402.592249)
			(xy 314.74309 -402.615845) (xy 314.69366 -402.631906) (xy 314.642325 -402.640036) (xy 314.590351 -402.640036)
			(xy 314.539016 -402.631906) (xy 314.489586 -402.615845) (xy 314.443276 -402.592249) (xy 314.401228 -402.561699)
			(xy 314.364477 -402.524948) (xy 314.333927 -402.4829) (xy 314.310331 -402.43659) (xy 314.29427 -402.38716)
			(xy 314.28614 -402.335825) (xy 314.28563 -402.309838) (xy 314.28606 -402.286442) (xy 314.292645 -402.240115)
			(xy 314.305691 -402.195179) (xy 314.324936 -402.152527) (xy 314.349997 -402.113012) (xy 314.364878 -402.094954)
			(xy 314.371482 -402.087334) (xy 314.377578 -402.069046) (xy 314.372244 -401.978876) (xy 314.364116 -401.96135)
			(xy 314.35675 -401.954492) (xy 314.337844 -401.936385) (xy 314.304684 -401.895879) (xy 314.277369 -401.851221)
			(xy 314.256413 -401.80325) (xy 314.242209 -401.752865) (xy 314.235024 -401.701012) (xy 314.234576 -401.674838)
			(xy 313.798204 -401.674838) (xy 313.797788 -401.701013) (xy 313.79059 -401.752865) (xy 313.776377 -401.803248)
			(xy 313.755414 -401.851218) (xy 313.728094 -401.895874) (xy 313.69493 -401.936379) (xy 313.67603 -401.954492)
			(xy 313.668664 -401.96135) (xy 313.660536 -401.978876) (xy 313.655202 -402.069046) (xy 313.661298 -402.087334)
			(xy 313.667902 -402.094954) (xy 313.682802 -402.112998) (xy 313.707867 -402.152516) (xy 313.727114 -402.19517)
			(xy 313.740161 -402.24011) (xy 313.746748 -402.28644) (xy 313.74715 -402.309838) (xy 313.74664 -402.335825)
			(xy 313.73851 -402.38716) (xy 313.722449 -402.43659) (xy 313.698853 -402.4829) (xy 313.668303 -402.524948)
			(xy 313.631552 -402.561699) (xy 313.589504 -402.592249) (xy 313.543194 -402.615845) (xy 313.493764 -402.631906)
			(xy 313.442429 -402.640036) (xy 313.390455 -402.640036) (xy 313.33912 -402.631906) (xy 313.28969 -402.615845)
			(xy 313.24338 -402.592249) (xy 313.201332 -402.561699) (xy 313.164581 -402.524948) (xy 313.134031 -402.4829)
			(xy 313.110435 -402.43659) (xy 313.094374 -402.38716) (xy 313.086244 -402.335825) (xy 313.085734 -402.309838)
			(xy 313.086163 -402.286442) (xy 313.092748 -402.240115) (xy 313.105794 -402.195178) (xy 313.12504 -402.152527)
			(xy 313.150101 -402.113012) (xy 313.164982 -402.094954) (xy 313.171586 -402.087334) (xy 313.177682 -402.069046)
			(xy 313.172348 -401.978876) (xy 313.16422 -401.96135) (xy 313.156854 -401.954492) (xy 313.137949 -401.936385)
			(xy 313.104788 -401.895879) (xy 313.077473 -401.851221) (xy 313.056518 -401.80325) (xy 313.042313 -401.752865)
			(xy 313.035128 -401.701012) (xy 313.03468 -401.674838) (xy 312.5978 -401.674838) (xy 312.597256 -401.704988)
			(xy 312.587799 -401.76454) (xy 312.569094 -401.821864) (xy 312.541607 -401.875534) (xy 312.506021 -401.924213)
			(xy 312.485024 -401.945856) (xy 312.47842 -401.95246) (xy 312.4708 -401.969224) (xy 312.465466 -402.05533)
			(xy 312.4708 -402.07311) (xy 312.476642 -402.080476) (xy 312.493146 -402.102466) (xy 312.519422 -402.150758)
			(xy 312.537355 -402.202729) (xy 312.546451 -402.256949) (xy 312.547 -402.284438) (xy 312.54649 -402.310425)
			(xy 312.53836 -402.36176) (xy 312.522299 -402.41119) (xy 312.498703 -402.4575) (xy 312.468153 -402.499548)
			(xy 312.431402 -402.536299) (xy 312.389354 -402.566849) (xy 312.343044 -402.590445) (xy 312.293614 -402.606506)
			(xy 312.242279 -402.614636) (xy 312.190305 -402.614636) (xy 312.13897 -402.606506) (xy 312.08954 -402.590445)
			(xy 312.04323 -402.566849) (xy 312.001182 -402.536299) (xy 311.964431 -402.499548) (xy 311.933881 -402.4575)
			(xy 311.910285 -402.41119) (xy 311.894224 -402.36176) (xy 311.886094 -402.310425) (xy 311.885584 -402.284438)
			(xy 311.88614 -402.256948) (xy 311.895216 -402.202722) (xy 311.91314 -402.150746) (xy 311.939418 -402.102452)
			(xy 311.955942 -402.080476) (xy 311.961784 -402.07311) (xy 311.967118 -402.05533) (xy 311.961784 -401.969224)
			(xy 311.954164 -401.95246) (xy 311.94756 -401.945856) (xy 311.926575 -401.9242) (xy 311.89098 -401.87553)
			(xy 311.863487 -401.821864) (xy 311.844783 -401.76454) (xy 311.835335 -401.704987) (xy 311.834784 -401.674838)
			(xy 311.397904 -401.674838) (xy 311.397379 -401.703743) (xy 311.388673 -401.760894) (xy 311.37145 -401.816079)
			(xy 311.346105 -401.868037) (xy 311.313217 -401.91558) (xy 311.293764 -401.936966) (xy 311.287668 -401.94357)
			(xy 311.280556 -401.959572) (xy 311.274968 -402.041868) (xy 311.279794 -402.058886) (xy 311.284874 -402.065998)
			(xy 311.299513 -402.087226) (xy 311.322765 -402.133248) (xy 311.33859 -402.182321) (xy 311.346605 -402.233257)
			(xy 311.347104 -402.259038) (xy 311.346594 -402.285025) (xy 311.338464 -402.33636) (xy 311.322403 -402.38579)
			(xy 311.298807 -402.4321) (xy 311.268257 -402.474148) (xy 311.231506 -402.510899) (xy 311.189458 -402.541449)
			(xy 311.143148 -402.565045) (xy 311.093718 -402.581106) (xy 311.042383 -402.589236) (xy 310.990409 -402.589236)
			(xy 310.939074 -402.581106) (xy 310.889644 -402.565045) (xy 310.843334 -402.541449) (xy 310.801286 -402.510899)
			(xy 310.764535 -402.474148) (xy 310.733985 -402.4321) (xy 310.710389 -402.38579) (xy 310.694328 -402.33636)
			(xy 310.686198 -402.285025) (xy 310.685688 -402.259038) (xy 310.686163 -402.233255) (xy 310.69417 -402.182313)
			(xy 310.709996 -402.133235) (xy 310.733256 -402.087212) (xy 310.747918 -402.065998) (xy 310.752998 -402.058886)
			(xy 310.757824 -402.041868) (xy 310.752236 -401.959572) (xy 310.745124 -401.94357) (xy 310.739028 -401.936966)
			(xy 310.71955 -401.915599) (xy 310.68664 -401.868063) (xy 310.661287 -401.816102) (xy 310.644074 -401.760908)
			(xy 310.635396 -401.703747) (xy 310.634888 -401.674838) (xy 310.198008 -401.674838) (xy 310.19759 -401.701012)
			(xy 310.190393 -401.752865) (xy 310.17618 -401.803248) (xy 310.155217 -401.851217) (xy 310.127897 -401.895873)
			(xy 310.094734 -401.936378) (xy 310.075834 -401.954492) (xy 310.068468 -401.96135) (xy 310.06034 -401.978876)
			(xy 310.055006 -402.069046) (xy 310.061102 -402.087334) (xy 310.067706 -402.094954) (xy 310.082607 -402.112998)
			(xy 310.107671 -402.152515) (xy 310.126918 -402.19517) (xy 310.139966 -402.24011) (xy 310.146552 -402.28644)
			(xy 310.146954 -402.309838) (xy 310.146444 -402.335825) (xy 310.138314 -402.38716) (xy 310.122253 -402.43659)
			(xy 310.098657 -402.4829) (xy 310.068107 -402.524948) (xy 310.031356 -402.561699) (xy 309.989308 -402.592249)
			(xy 309.942998 -402.615845) (xy 309.893568 -402.631906) (xy 309.842233 -402.640036) (xy 309.790259 -402.640036)
			(xy 309.738924 -402.631906) (xy 309.689494 -402.615845) (xy 309.643184 -402.592249) (xy 309.601136 -402.561699)
			(xy 309.564385 -402.524948) (xy 309.533835 -402.4829) (xy 309.510239 -402.43659) (xy 309.494178 -402.38716)
			(xy 309.486048 -402.335825) (xy 309.485538 -402.309838) (xy 309.485966 -402.286442) (xy 309.492552 -402.240115)
			(xy 309.505597 -402.195178) (xy 309.524843 -402.152527) (xy 309.549905 -402.113012) (xy 309.564786 -402.094954)
			(xy 309.57139 -402.087334) (xy 309.577486 -402.069046) (xy 309.572152 -401.978876) (xy 309.564024 -401.96135)
			(xy 309.556658 -401.954492) (xy 309.537754 -401.936384) (xy 309.504593 -401.895878) (xy 309.477278 -401.851221)
			(xy 309.456322 -401.80325) (xy 309.442118 -401.752865) (xy 309.434932 -401.701012) (xy 309.434484 -401.674838)
			(xy 308.998112 -401.674838) (xy 308.997693 -401.701012) (xy 308.990496 -401.752865) (xy 308.976283 -401.803248)
			(xy 308.95532 -401.851217) (xy 308.928001 -401.895873) (xy 308.894838 -401.936378) (xy 308.875938 -401.954492)
			(xy 308.868572 -401.96135) (xy 308.860444 -401.978876) (xy 308.85511 -402.069046) (xy 308.861206 -402.087334)
			(xy 308.86781 -402.094954) (xy 308.882711 -402.112997) (xy 308.907775 -402.152515) (xy 308.927023 -402.19517)
			(xy 308.94007 -402.24011) (xy 308.946656 -402.28644) (xy 308.947058 -402.309838) (xy 308.946548 -402.335825)
			(xy 308.938418 -402.38716) (xy 308.922357 -402.43659) (xy 308.898761 -402.4829) (xy 308.868211 -402.524948)
			(xy 308.83146 -402.561699) (xy 308.789412 -402.592249) (xy 308.743102 -402.615845) (xy 308.693672 -402.631906)
			(xy 308.642337 -402.640036) (xy 308.590363 -402.640036) (xy 308.539028 -402.631906) (xy 308.489598 -402.615845)
			(xy 308.443288 -402.592249) (xy 308.40124 -402.561699) (xy 308.364489 -402.524948) (xy 308.333939 -402.4829)
			(xy 308.310343 -402.43659) (xy 308.294282 -402.38716) (xy 308.286152 -402.335825) (xy 308.285642 -402.309838)
			(xy 308.286069 -402.286442) (xy 308.292655 -402.240115) (xy 308.305701 -402.195178) (xy 308.324947 -402.152527)
			(xy 308.350009 -402.113012) (xy 308.36489 -402.094954) (xy 308.371494 -402.087334) (xy 308.37759 -402.069046)
			(xy 308.372256 -401.978876) (xy 308.364128 -401.96135) (xy 308.356762 -401.954492) (xy 308.337858 -401.936383)
			(xy 308.304697 -401.895878) (xy 308.277382 -401.85122) (xy 308.256426 -401.80325) (xy 308.242222 -401.752865)
			(xy 308.235036 -401.701012) (xy 308.234588 -401.674838) (xy 307.797708 -401.674838) (xy 307.797182 -401.703743)
			(xy 307.788476 -401.760894) (xy 307.771254 -401.816079) (xy 307.745909 -401.868037) (xy 307.713021 -401.91558)
			(xy 307.693568 -401.936966) (xy 307.687472 -401.94357) (xy 307.68036 -401.959572) (xy 307.674772 -402.041868)
			(xy 307.679598 -402.058886) (xy 307.684678 -402.065998) (xy 307.699318 -402.087226) (xy 307.722569 -402.133248)
			(xy 307.738394 -402.182321) (xy 307.746409 -402.233257) (xy 307.746908 -402.259038) (xy 307.746398 -402.285025)
			(xy 307.738268 -402.33636) (xy 307.722207 -402.38579) (xy 307.698611 -402.4321) (xy 307.668061 -402.474148)
			(xy 307.63131 -402.510899) (xy 307.589262 -402.541449) (xy 307.542952 -402.565045) (xy 307.493522 -402.581106)
			(xy 307.442187 -402.589236) (xy 307.390213 -402.589236) (xy 307.338878 -402.581106) (xy 307.289448 -402.565045)
			(xy 307.243138 -402.541449) (xy 307.20109 -402.510899) (xy 307.164339 -402.474148) (xy 307.133789 -402.4321)
			(xy 307.110193 -402.38579) (xy 307.094132 -402.33636) (xy 307.086002 -402.285025) (xy 307.085492 -402.259038)
			(xy 307.085966 -402.233255) (xy 307.093974 -402.182313) (xy 307.1098 -402.133235) (xy 307.13306 -402.087212)
			(xy 307.147722 -402.065998) (xy 307.152802 -402.058886) (xy 307.157628 -402.041868) (xy 307.15204 -401.959572)
			(xy 307.144928 -401.94357) (xy 307.138832 -401.936966) (xy 307.119338 -401.915613) (xy 307.086434 -401.868072)
			(xy 307.061086 -401.816107) (xy 307.043876 -401.76091) (xy 307.0352 -401.703747) (xy 307.034692 -401.674838)
			(xy 306.597812 -401.674838) (xy 306.597336 -401.701001) (xy 306.590186 -401.752835) (xy 306.576026 -401.803208)
			(xy 306.555121 -401.851176) (xy 306.527863 -401.89584) (xy 306.494761 -401.936364) (xy 306.475892 -401.954492)
			(xy 306.468526 -401.96135) (xy 306.460398 -401.978876) (xy 306.455064 -402.069046) (xy 306.46116 -402.087334)
			(xy 306.467764 -402.094954) (xy 306.482658 -402.113003) (xy 306.507725 -402.152518) (xy 306.526974 -402.195171)
			(xy 306.540023 -402.240111) (xy 306.54661 -402.28644) (xy 306.547012 -402.309838) (xy 306.546502 -402.335825)
			(xy 306.538372 -402.38716) (xy 306.522311 -402.43659) (xy 306.498715 -402.4829) (xy 306.468165 -402.524948)
			(xy 306.431414 -402.561699) (xy 306.389366 -402.592249) (xy 306.343056 -402.615845) (xy 306.293626 -402.631906)
			(xy 306.242291 -402.640036) (xy 306.190317 -402.640036) (xy 306.138982 -402.631906) (xy 306.089552 -402.615845)
			(xy 306.043242 -402.592249) (xy 306.001194 -402.561699) (xy 305.964443 -402.524948) (xy 305.933893 -402.4829)
			(xy 305.910297 -402.43659) (xy 305.894236 -402.38716) (xy 305.886106 -402.335825) (xy 305.885596 -402.309838)
			(xy 305.886034 -402.286442) (xy 305.892619 -402.240117) (xy 305.905663 -402.19518) (xy 305.924906 -402.152529)
			(xy 305.949964 -402.113013) (xy 305.964844 -402.094954) (xy 305.971448 -402.087334) (xy 305.977544 -402.069046)
			(xy 305.97221 -401.978876) (xy 305.964082 -401.96135) (xy 305.956716 -401.954492) (xy 305.937825 -401.936383)
			(xy 305.904707 -401.895863) (xy 305.877436 -401.851198) (xy 305.856525 -401.803226) (xy 305.842365 -401.752846)
			(xy 305.835223 -401.701004) (xy 305.834796 -401.674838) (xy 305.397916 -401.674838) (xy 305.397314 -401.704996)
			(xy 305.387819 -401.764561) (xy 305.369072 -401.82189) (xy 305.341539 -401.875556) (xy 305.305907 -401.924223)
			(xy 305.284886 -401.945856) (xy 305.278282 -401.95246) (xy 305.270662 -401.969224) (xy 305.265328 -402.05533)
			(xy 305.270662 -402.07311) (xy 305.276504 -402.080476) (xy 305.293017 -402.10246) (xy 305.319289 -402.150755)
			(xy 305.337219 -402.202728) (xy 305.346314 -402.256949) (xy 305.346862 -402.284438) (xy 305.346352 -402.310425)
			(xy 305.338222 -402.36176) (xy 305.322161 -402.41119) (xy 305.298565 -402.4575) (xy 305.268015 -402.499548)
			(xy 305.231264 -402.536299) (xy 305.189216 -402.566849) (xy 305.142906 -402.590445) (xy 305.093476 -402.606506)
			(xy 305.042141 -402.614636) (xy 304.990167 -402.614636) (xy 304.938832 -402.606506) (xy 304.889402 -402.590445)
			(xy 304.843092 -402.566849) (xy 304.801044 -402.536299) (xy 304.764293 -402.499548) (xy 304.733743 -402.4575)
			(xy 304.710147 -402.41119) (xy 304.694086 -402.36176) (xy 304.685956 -402.310425) (xy 304.685446 -402.284438)
			(xy 304.68601 -402.256948) (xy 304.695085 -402.202723) (xy 304.713006 -402.150747) (xy 304.739282 -402.102453)
			(xy 304.755804 -402.080476) (xy 304.761646 -402.07311) (xy 304.76698 -402.05533) (xy 304.761646 -401.969224)
			(xy 304.754026 -401.95246) (xy 304.747422 -401.945856) (xy 304.726369 -401.92425) (xy 304.690727 -401.875582)
			(xy 304.66319 -401.82191) (xy 304.644445 -401.764573) (xy 304.634959 -401.705) (xy 304.634392 -401.674838)
			(xy 304.19802 -401.674838) (xy 304.197417 -401.704996) (xy 304.187922 -401.764561) (xy 304.169175 -401.82189)
			(xy 304.141643 -401.875556) (xy 304.10601 -401.924223) (xy 304.08499 -401.945856) (xy 304.078386 -401.95246)
			(xy 304.070766 -401.969224) (xy 304.065432 -402.05533) (xy 304.070766 -402.07311) (xy 304.076608 -402.080476)
			(xy 304.093121 -402.102459) (xy 304.119393 -402.150755) (xy 304.137323 -402.202728) (xy 304.146418 -402.256949)
			(xy 304.146966 -402.284438) (xy 304.146456 -402.310425) (xy 304.138326 -402.36176) (xy 304.122265 -402.41119)
			(xy 304.098669 -402.4575) (xy 304.068119 -402.499548) (xy 304.031368 -402.536299) (xy 303.98932 -402.566849)
			(xy 303.94301 -402.590445) (xy 303.89358 -402.606506) (xy 303.842245 -402.614636) (xy 303.790271 -402.614636)
			(xy 303.738936 -402.606506) (xy 303.689506 -402.590445) (xy 303.643196 -402.566849) (xy 303.601148 -402.536299)
			(xy 303.564397 -402.499548) (xy 303.533847 -402.4575) (xy 303.510251 -402.41119) (xy 303.49419 -402.36176)
			(xy 303.48606 -402.310425) (xy 303.48555 -402.284438) (xy 303.486113 -402.256948) (xy 303.495188 -402.202723)
			(xy 303.51311 -402.150747) (xy 303.539385 -402.102453) (xy 303.555908 -402.080476) (xy 303.56175 -402.07311)
			(xy 303.567084 -402.05533) (xy 303.56175 -401.969224) (xy 303.55413 -401.95246) (xy 303.547526 -401.945856)
			(xy 303.526474 -401.92425) (xy 303.490832 -401.875582) (xy 303.463294 -401.82191) (xy 303.444549 -401.764573)
			(xy 303.435063 -401.705) (xy 303.434496 -401.674838) (xy 300.787562 -401.674838) (xy 300.071282 -402.391118)
			(xy 300.062841 -402.400416) (xy 300.055526 -402.424406) (xy 300.057312 -402.436838) (xy 300.075854 -402.532088)
			(xy 300.091602 -402.551646) (xy 300.103286 -402.556472) (xy 300.128798 -402.567807) (xy 300.176479 -402.596843)
			(xy 300.219419 -402.632518) (xy 300.256699 -402.674071) (xy 300.287525 -402.720615) (xy 300.311238 -402.771154)
			(xy 300.327331 -402.82461) (xy 300.33546 -402.879841) (xy 300.33595 -402.907754) (xy 300.335474 -402.935122)
			(xy 300.327643 -402.989296) (xy 300.312148 -403.041794) (xy 300.289309 -403.091538) (xy 300.259594 -403.137507)
			(xy 300.24197 -403.158452) (xy 300.235874 -403.165564) (xy 300.229524 -403.182582) (xy 300.229524 -403.267926)
			(xy 300.235874 -403.284944) (xy 300.24197 -403.292056) (xy 300.25961 -403.312988) (xy 300.289332 -403.358955)
			(xy 300.312169 -403.408702) (xy 300.327653 -403.461206) (xy 300.335464 -403.515384) (xy 300.33595 -403.542754)
			(xy 300.33549 -403.57001) (xy 300.327739 -403.623968) (xy 300.312387 -403.676274) (xy 300.289748 -403.725863)
			(xy 300.260282 -403.771725) (xy 300.224589 -403.812926) (xy 300.183395 -403.848629) (xy 300.13754 -403.878106)
			(xy 300.087957 -403.900756) (xy 300.035654 -403.91612) (xy 299.981698 -403.923884) (xy 299.954442 -403.924262)
			(xy 299.928698 -403.923843) (xy 299.877676 -403.916928) (xy 299.828046 -403.903218) (xy 299.780709 -403.882962)
			(xy 299.736524 -403.856527) (xy 299.696294 -403.824394) (xy 299.660747 -403.787145) (xy 299.645324 -403.766528)
			(xy 299.637716 -403.757136) (xy 299.616242 -403.746115) (xy 299.604176 -403.745446) (xy 299.572172 -403.745446)
			(xy 299.560097 -403.746109) (xy 299.538597 -403.757103) (xy 299.531024 -403.766528) (xy 299.52696 -403.771862)
			(xy 299.52696 -404.748492) (xy 304.627278 -404.748492) (xy 304.631349 -404.69287) (xy 304.643475 -404.638433)
			(xy 304.663398 -404.586342) (xy 304.690694 -404.537707) (xy 304.72478 -404.493564) (xy 304.764929 -404.454855)
			(xy 304.810287 -404.422404) (xy 304.859887 -404.396903) (xy 304.912671 -404.378896) (xy 304.967514 -404.368766)
			(xy 305.023248 -404.366729) (xy 305.078685 -404.372829) (xy 305.132642 -404.386935) (xy 305.183971 -404.408747)
			(xy 305.231577 -404.437801) (xy 305.274445 -404.473476) (xy 305.311662 -404.515013) (xy 305.342435 -404.561526)
			(xy 305.366107 -404.612023) (xy 305.382175 -404.66543) (xy 305.390295 -404.720606) (xy 305.390804 -404.748492)
			(xy 305.390295 -404.776378) (xy 305.382175 -404.831554) (xy 305.366107 -404.884961) (xy 305.342435 -404.935458)
			(xy 305.311662 -404.981971) (xy 305.274445 -405.023508) (xy 305.231577 -405.059183) (xy 305.183971 -405.088237)
			(xy 305.132642 -405.110049) (xy 305.078685 -405.124155) (xy 305.023248 -405.130255) (xy 304.967514 -405.128218)
			(xy 304.912671 -405.118088) (xy 304.859887 -405.100081) (xy 304.810287 -405.07458) (xy 304.764929 -405.042129)
			(xy 304.72478 -405.00342) (xy 304.690694 -404.959277) (xy 304.663398 -404.910642) (xy 304.643475 -404.858551)
			(xy 304.631349 -404.804114) (xy 304.627278 -404.748492) (xy 299.52696 -404.748492) (xy 299.52696 -404.856188)
			(xy 299.527545 -404.867426) (xy 299.537179 -404.887729) (xy 299.545502 -404.895304) (xy 299.56989 -404.916063)
			(xy 299.613776 -404.96271) (xy 299.651461 -405.014496) (xy 299.682348 -405.070602) (xy 299.705951 -405.13014)
			(xy 299.721895 -405.19217) (xy 299.729928 -405.255711) (xy 299.730414 -405.287734) (xy 299.729933 -405.318429)
			(xy 299.72251 -405.379368) (xy 299.70781 -405.438972) (xy 299.686048 -405.496376) (xy 299.65754 -405.550745)
			(xy 299.640498 -405.576278) (xy 299.635033 -405.58503) (xy 299.630917 -405.605228) (xy 299.635055 -405.625422)
			(xy 299.640498 -405.63419) (xy 299.657553 -405.659717) (xy 299.686082 -405.71408) (xy 299.707852 -405.771483)
			(xy 299.722547 -405.831092) (xy 299.729953 -405.892037) (xy 299.730414 -405.922734) (xy 299.729933 -405.953429)
			(xy 299.72251 -406.014368) (xy 299.70781 -406.073972) (xy 299.686048 -406.131376) (xy 299.65754 -406.185745)
			(xy 299.640498 -406.211278) (xy 299.635033 -406.22003) (xy 299.630917 -406.240228) (xy 299.635055 -406.260422)
			(xy 299.640498 -406.26919) (xy 299.657553 -406.294717) (xy 299.686082 -406.34908) (xy 299.707852 -406.406483)
			(xy 299.722547 -406.466092) (xy 299.729953 -406.527037) (xy 299.730414 -406.557734) (xy 299.729834 -406.59263)
			(xy 299.720282 -406.661764) (xy 299.70136 -406.728942) (xy 299.673426 -406.7929) (xy 299.637005 -406.852434)
			(xy 299.615352 -406.879806) (xy 299.609174 -406.888071) (xy 299.603428 -406.90787) (xy 299.605985 -406.928326)
			(xy 299.61078 -406.937464) (xy 299.62713 -406.966647) (xy 299.652873 -407.028389) (xy 299.670294 -407.092974)
			(xy 299.679092 -407.159287) (xy 299.679614 -407.192734) (xy 299.679198 -407.221987) (xy 299.67248 -407.280105)
			(xy 299.659148 -407.337071) (xy 299.639378 -407.392135) (xy 299.626782 -407.41854) (xy 299.619416 -407.433272)
			(xy 299.62475 -407.46553) (xy 300.005242 -407.846022) (xy 300.01464 -407.849832) (xy 300.033993 -407.857968)
			(xy 300.070511 -407.878678) (xy 300.103936 -407.904079) (xy 300.119034 -407.918666) (xy 301.387002 -409.186634)
			(xy 301.394344 -409.193452) (xy 301.412807 -409.201194) (xy 301.422816 -409.20162) (xy 303.666144 -409.20162)
		)
		(stroke
			(width 0)
			(type solid)
		)
		(fill yes)
		(layer "In6.Cu")
		(net "P0V9_CPU0_RT0_2A_2D")
	)
	(gr_poly
		(pts
			(xy 16.004794 -413.211264) (xy 16.01399 -413.210883) (xy 16.031194 -413.204384) (xy 16.038322 -413.198564)
			(xy 16.059302 -413.180834) (xy 16.10539 -413.150953) (xy 16.155286 -413.127985) (xy 16.207957 -413.112404)
			(xy 16.262318 -413.104532) (xy 16.317246 -413.104532) (xy 16.371607 -413.112404) (xy 16.424278 -413.127985)
			(xy 16.474174 -413.150953) (xy 16.520262 -413.180834) (xy 16.541242 -413.198564) (xy 16.5484 -413.204338)
			(xy 16.565583 -413.210854) (xy 16.57477 -413.211264) (xy 17.487392 -413.211264) (xy 17.495941 -413.21094)
			(xy 17.512087 -413.205319) (xy 17.525488 -413.194701) (xy 17.530318 -413.187642) (xy 17.58315 -413.104076)
			(xy 17.584674 -413.078168) (xy 17.579086 -413.06623) (xy 17.567537 -413.040614) (xy 17.551245 -412.986839)
			(xy 17.543012 -412.931257) (xy 17.54251 -412.903162) (xy 17.542996 -412.875911) (xy 17.550752 -412.821963)
			(xy 17.566107 -412.769668) (xy 17.588749 -412.720091) (xy 17.618215 -412.674241) (xy 17.653906 -412.63305)
			(xy 17.695097 -412.597359) (xy 17.740947 -412.567893) (xy 17.790524 -412.545251) (xy 17.842819 -412.529896)
			(xy 17.896767 -412.52214) (xy 17.951269 -412.52214) (xy 18.005217 -412.529896) (xy 18.057512 -412.545251)
			(xy 18.107089 -412.567893) (xy 18.152939 -412.597359) (xy 18.19413 -412.63305) (xy 18.229821 -412.674241)
			(xy 18.259287 -412.720091) (xy 18.281929 -412.769668) (xy 18.297284 -412.821963) (xy 18.30504 -412.875911)
			(xy 18.305526 -412.903162) (xy 18.305031 -412.931257) (xy 18.296801 -412.986842) (xy 18.280514 -413.04062)
			(xy 18.26895 -413.06623) (xy 18.263362 -413.078168) (xy 18.264886 -413.104076) (xy 18.317718 -413.187642)
			(xy 18.322565 -413.194688) (xy 18.335955 -413.205312) (xy 18.352098 -413.21093) (xy 18.360644 -413.211264)
			(xy 18.416016 -413.211264) (xy 18.426084 -413.210837) (xy 18.444681 -413.203115) (xy 18.452084 -413.196278)
			(xy 19.051524 -412.596838) (xy 19.058369 -412.58944) (xy 19.066093 -412.570841) (xy 19.06651 -412.56077)
			(xy 19.06651 -412.298388) (xy 19.065889 -412.286543) (xy 19.055292 -412.265354) (xy 19.04619 -412.257748)
			(xy 18.971514 -412.201868) (xy 18.948146 -412.19755) (xy 18.936462 -412.200852) (xy 18.910428 -412.207945)
			(xy 18.857014 -412.215589) (xy 18.830036 -412.216092) (xy 18.802785 -412.215606) (xy 18.748837 -412.207849)
			(xy 18.696542 -412.192493) (xy 18.646965 -412.169852) (xy 18.601114 -412.140385) (xy 18.559924 -412.104693)
			(xy 18.524233 -412.063502) (xy 18.494766 -412.017652) (xy 18.472125 -411.968074) (xy 18.45677 -411.915779)
			(xy 18.449014 -411.861831) (xy 18.449014 -411.807329) (xy 18.45677 -411.753381) (xy 18.472125 -411.701086)
			(xy 18.494766 -411.651508) (xy 18.524233 -411.605658) (xy 18.559924 -411.564467) (xy 18.601114 -411.528775)
			(xy 18.646965 -411.499308) (xy 18.696542 -411.476667) (xy 18.748837 -411.461311) (xy 18.802785 -411.453554)
			(xy 18.830036 -411.453076) (xy 18.857016 -411.453556) (xy 18.910433 -411.4612) (xy 18.936462 -411.468316)
			(xy 18.948146 -411.471618) (xy 18.971514 -411.4673) (xy 19.04619 -411.41142) (xy 19.055291 -411.403815)
			(xy 19.065876 -411.382624) (xy 19.06651 -411.37078) (xy 19.06651 -409.631388) (xy 19.065889 -409.619543)
			(xy 19.055292 -409.598354) (xy 19.04619 -409.590748) (xy 18.971514 -409.534614) (xy 18.948146 -409.53055)
			(xy 18.936462 -409.533852) (xy 18.910366 -409.540959) (xy 18.856824 -409.548603) (xy 18.829782 -409.549092)
			(xy 18.802533 -409.548605) (xy 18.748589 -409.540846) (xy 18.696299 -409.52549) (xy 18.646726 -409.502849)
			(xy 18.60088 -409.473384) (xy 18.559694 -409.437694) (xy 18.524006 -409.396506) (xy 18.494542 -409.350658)
			(xy 18.471903 -409.301084) (xy 18.45655 -409.248793) (xy 18.448794 -409.194849) (xy 18.448794 -409.140351)
			(xy 18.45655 -409.086407) (xy 18.471903 -409.034116) (xy 18.494542 -408.984542) (xy 18.524006 -408.938694)
			(xy 18.559694 -408.897506) (xy 18.60088 -408.861816) (xy 18.646726 -408.832351) (xy 18.696299 -408.80971)
			(xy 18.748589 -408.794354) (xy 18.802533 -408.786595) (xy 18.829782 -408.786076) (xy 18.856769 -408.786543)
			(xy 18.910204 -408.794151) (xy 18.962032 -408.809218) (xy 19.011218 -408.831443) (xy 19.034252 -408.845512)
			(xy 19.049238 -408.855164) (xy 19.084798 -408.8511) (xy 20.108672 -407.827226) (xy 20.116073 -407.820388)
			(xy 20.134672 -407.812676) (xy 20.14474 -407.81224) (xy 29.608272 -407.81224) (xy 29.618286 -407.811757)
			(xy 29.636795 -407.804104) (xy 29.650966 -407.789952) (xy 29.658644 -407.771454) (xy 29.659072 -407.76144)
			(xy 29.659072 -404.605744) (xy 29.658638 -404.595679) (xy 29.650906 -404.577092) (xy 29.644086 -404.569676)
			(xy 28.195016 -403.120606) (xy 28.187613 -403.113772) (xy 28.169015 -403.106067) (xy 28.158948 -403.10562)
			(xy 19.618198 -403.10562) (xy 19.593215 -403.105009) (xy 19.544208 -403.095266) (xy 19.498041 -403.076155)
			(xy 19.456486 -403.048409) (xy 19.438366 -403.031198) (xy 17.926558 -401.51939) (xy 17.909335 -401.50128)
			(xy 17.881594 -401.45972) (xy 17.862483 -401.41355) (xy 17.852735 -401.364542) (xy 17.852136 -401.339558)
			(xy 17.852136 -393.473432) (xy 17.851699 -393.463369) (xy 17.84396 -393.444788) (xy 17.83715 -393.437364)
			(xy 16.569944 -392.170158) (xy 16.562545 -392.163314) (xy 16.543946 -392.155591) (xy 16.533876 -392.155172)
			(xy 14.138402 -392.155172) (xy 14.113418 -392.154561) (xy 14.064409 -392.144821) (xy 14.018239 -392.125713)
			(xy 13.97668 -392.097972) (xy 13.95857 -392.08075) (xy 13.119354 -391.241534) (xy 13.102136 -391.223423)
			(xy 13.074404 -391.181861) (xy 13.055303 -391.135691) (xy 13.045566 -391.086684) (xy 13.044932 -391.061702)
			(xy 13.044932 -389.063484) (xy 13.044507 -389.053414) (xy 13.036792 -389.034811) (xy 13.029946 -389.027416)
			(xy 10.16381 -386.16128) (xy 10.146585 -386.143171) (xy 10.11884 -386.101612) (xy 10.099726 -386.055442)
			(xy 10.089978 -386.006433) (xy 10.089388 -385.981448) (xy 10.089388 -383.838704) (xy 10.088965 -383.828634)
			(xy 10.081251 -383.810029) (xy 10.074402 -383.802636) (xy 7.698486 -381.42672) (xy 7.691062 -381.419942)
			(xy 7.672465 -381.41235) (xy 7.662418 -381.411988) (xy 7.32028 -381.411988) (xy 7.291324 -381.437642)
			(xy 7.289038 -381.456946) (xy 7.285429 -381.484541) (xy 7.271239 -381.538352) (xy 7.249375 -381.589528)
			(xy 7.2203 -381.636979) (xy 7.184633 -381.679698) (xy 7.143132 -381.716775) (xy 7.096681 -381.747422)
			(xy 7.046266 -381.770987) (xy 6.99296 -381.78697) (xy 6.937896 -381.795031) (xy 6.91007 -381.795528)
			(xy 6.88282 -381.79504) (xy 6.828874 -381.78728) (xy 6.776582 -381.771923) (xy 6.727007 -381.74928)
			(xy 6.681159 -381.719813) (xy 6.639971 -381.684122) (xy 6.604281 -381.642933) (xy 6.574815 -381.597084)
			(xy 6.552174 -381.547509) (xy 6.536818 -381.495216) (xy 6.529059 -381.44127) (xy 6.528562 -381.41402)
			(xy 6.529009 -381.387641) (xy 6.536274 -381.335387) (xy 6.550665 -381.284631) (xy 6.571906 -381.236338)
			(xy 6.599593 -381.19143) (xy 6.633198 -381.150761) (xy 6.672083 -381.115106) (xy 6.715506 -381.085144)
			(xy 6.738874 -381.072898) (xy 6.752082 -381.066548) (xy 6.767068 -381.042164) (xy 6.767068 -380.922276)
			(xy 6.752082 -380.897892) (xy 6.738874 -380.891542) (xy 6.715506 -380.879297) (xy 6.672081 -380.849338)
			(xy 6.633196 -380.813684) (xy 6.599592 -380.773015) (xy 6.571909 -380.728106) (xy 6.550674 -380.679812)
			(xy 6.536292 -380.629053) (xy 6.529038 -380.576798) (xy 6.528562 -380.55042) (xy 6.529046 -380.523167)
			(xy 6.5368 -380.469216) (xy 6.552154 -380.416917) (xy 6.574793 -380.367335) (xy 6.604258 -380.32148)
			(xy 6.639949 -380.280285) (xy 6.68114 -380.244588) (xy 6.726991 -380.215117) (xy 6.77657 -380.192471)
			(xy 6.828867 -380.177111) (xy 6.882817 -380.16935) (xy 6.91007 -380.168912) (xy 6.936534 -380.169368)
			(xy 6.988953 -380.176691) (xy 7.039858 -380.191186) (xy 7.088271 -380.212575) (xy 7.133265 -380.240448)
			(xy 7.173977 -380.274271) (xy 7.209625 -380.313394) (xy 7.239525 -380.357067) (xy 7.263104 -380.404452)
			(xy 7.27991 -380.454641) (xy 7.285228 -380.48057) (xy 7.28853 -380.498858) (xy 7.31647 -380.521972)
			(xy 7.946898 -380.521972) (xy 7.971896 -380.522604) (xy 8.020925 -380.532396) (xy 8.067101 -380.551565)
			(xy 8.10865 -380.579374) (xy 8.12673 -380.596648) (xy 8.386133 -380.856051) (xy 9.436082 -380.856051)
			(xy 9.436082 -380.801549) (xy 9.443838 -380.747602) (xy 9.459193 -380.695308) (xy 9.481834 -380.645731)
			(xy 9.5113 -380.599881) (xy 9.546991 -380.558691) (xy 9.588181 -380.523) (xy 9.634031 -380.493534)
			(xy 9.683608 -380.470893) (xy 9.735902 -380.455538) (xy 9.789849 -380.447782) (xy 9.8171 -380.447296)
			(xy 9.842716 -380.447723) (xy 9.893486 -380.454584) (xy 9.942881 -380.46818) (xy 9.990009 -380.488269)
			(xy 10.034024 -380.514487) (xy 10.054336 -380.5301) (xy 10.062464 -380.53645) (xy 10.082276 -380.542038)
			(xy 10.17524 -380.529846) (xy 10.19302 -380.519432) (xy 10.199116 -380.51105) (xy 10.208935 -380.498203)
			(xy 10.230428 -380.474041) (xy 10.242042 -380.46279) (xy 10.249916 -380.45517) (xy 10.25779 -380.435866)
			(xy 10.256012 -380.3396) (xy 10.247376 -380.32055) (xy 10.239248 -380.313184) (xy 10.219468 -380.294997)
			(xy 10.184674 -380.254051) (xy 10.155972 -380.208626) (xy 10.133932 -380.159621) (xy 10.118989 -380.108008)
			(xy 10.11144 -380.054808) (xy 10.110978 -380.027942) (xy 10.111464 -380.000691) (xy 10.11922 -379.946743)
			(xy 10.134575 -379.894448) (xy 10.157217 -379.844871) (xy 10.186683 -379.799021) (xy 10.222374 -379.75783)
			(xy 10.263565 -379.722139) (xy 10.309415 -379.692673) (xy 10.358992 -379.670031) (xy 10.411287 -379.654676)
			(xy 10.465235 -379.64692) (xy 10.519737 -379.64692) (xy 10.573685 -379.654676) (xy 10.62598 -379.670031)
			(xy 10.675557 -379.692673) (xy 10.721407 -379.722139) (xy 10.762598 -379.75783) (xy 10.798289 -379.799021)
			(xy 10.827755 -379.844871) (xy 10.850397 -379.894448) (xy 10.865752 -379.946743) (xy 10.873508 -380.000691)
			(xy 10.873994 -380.027942) (xy 10.873606 -380.053088) (xy 12.10945 -380.053088) (xy 12.109966 -380.025484)
			(xy 12.117913 -379.97085) (xy 12.133654 -379.917933) (xy 12.15686 -379.867839) (xy 12.187045 -379.821613)
			(xy 12.22358 -379.780222) (xy 12.244324 -379.762004) (xy 12.252452 -379.755146) (xy 12.26185 -379.735842)
			(xy 12.264898 -379.63856) (xy 12.25677 -379.619002) (xy 12.248896 -379.611382) (xy 12.230736 -379.593319)
			(xy 12.198897 -379.553199) (xy 12.17271 -379.50918) (xy 12.152646 -379.462055) (xy 12.139067 -379.412668)
			(xy 12.132215 -379.36191) (xy 12.131802 -379.3363) (xy 12.132268 -379.30893) (xy 12.140085 -379.254751)
			(xy 12.155575 -379.202247) (xy 12.178416 -379.152501) (xy 12.208141 -379.106534) (xy 12.225782 -379.085602)
			(xy 12.231878 -379.07849) (xy 12.238228 -379.061472) (xy 12.238228 -378.976128) (xy 12.231878 -378.95911)
			(xy 12.225782 -378.951998) (xy 12.208126 -378.93108) (xy 12.178417 -378.885103) (xy 12.155585 -378.835352)
			(xy 12.140098 -378.782848) (xy 12.132274 -378.72867) (xy 12.131802 -378.7013) (xy 12.132288 -378.674049)
			(xy 12.140044 -378.620101) (xy 12.155399 -378.567806) (xy 12.178041 -378.518229) (xy 12.207507 -378.472379)
			(xy 12.243198 -378.431188) (xy 12.284389 -378.395497) (xy 12.330239 -378.366031) (xy 12.379816 -378.343389)
			(xy 12.432111 -378.328034) (xy 12.486059 -378.320278) (xy 12.540561 -378.320278) (xy 12.594509 -378.328034)
			(xy 12.646804 -378.343389) (xy 12.696381 -378.366031) (xy 12.742231 -378.395497) (xy 12.783422 -378.431188)
			(xy 12.819113 -378.472379) (xy 12.848579 -378.518229) (xy 12.871221 -378.567806) (xy 12.886576 -378.620101)
			(xy 12.894332 -378.674049) (xy 12.894818 -378.7013) (xy 12.894372 -378.728671) (xy 12.886552 -378.782852)
			(xy 12.87106 -378.835356) (xy 12.848213 -378.885103) (xy 12.818482 -378.931068) (xy 12.800838 -378.951998)
			(xy 12.794742 -378.95911) (xy 12.788392 -378.976128) (xy 12.788392 -379.061472) (xy 12.794742 -379.07849)
			(xy 12.800838 -379.085602) (xy 12.818498 -379.106517) (xy 12.848205 -379.152495) (xy 12.871037 -379.202247)
			(xy 12.886523 -379.254751) (xy 12.894347 -379.30893) (xy 12.894818 -379.3363) (xy 12.894374 -379.363907)
			(xy 12.886414 -379.418544) (xy 12.870659 -379.471463) (xy 12.84744 -379.521558) (xy 12.817241 -379.567781)
			(xy 12.780694 -379.609168) (xy 12.759944 -379.627384) (xy 12.751816 -379.634242) (xy 12.742418 -379.653546)
			(xy 12.73937 -379.750828) (xy 12.747498 -379.770386) (xy 12.755372 -379.778006) (xy 12.773568 -379.796033)
			(xy 12.805406 -379.836161) (xy 12.831589 -379.880187) (xy 12.851646 -379.927319) (xy 12.865217 -379.976712)
			(xy 12.872058 -380.027476) (xy 12.872466 -380.053088) (xy 12.872004 -380.080663) (xy 12.864052 -380.135236)
			(xy 12.848327 -380.188097) (xy 12.825157 -380.238143) (xy 12.795023 -380.284332) (xy 12.758554 -380.325703)
			(xy 12.737846 -380.343918) (xy 12.72921 -380.351284) (xy 12.719812 -380.37135) (xy 12.72032 -380.471934)
			(xy 12.729718 -380.492) (xy 12.738354 -380.499366) (xy 12.759369 -380.517586) (xy 12.796408 -380.559077)
			(xy 12.827037 -380.605502) (xy 12.850607 -380.655879) (xy 12.866619 -380.709142) (xy 12.874734 -380.764165)
			(xy 12.87526 -380.791974) (xy 12.874774 -380.819225) (xy 12.867018 -380.873173) (xy 12.851663 -380.925468)
			(xy 12.829021 -380.975045) (xy 12.799555 -381.020895) (xy 12.763864 -381.062086) (xy 12.722673 -381.097777)
			(xy 12.676823 -381.127243) (xy 12.627246 -381.149885) (xy 12.574951 -381.16524) (xy 12.521003 -381.172996)
			(xy 12.466501 -381.172996) (xy 12.412553 -381.16524) (xy 12.360258 -381.149885) (xy 12.310681 -381.127243)
			(xy 12.264831 -381.097777) (xy 12.22364 -381.062086) (xy 12.187949 -381.020895) (xy 12.158483 -380.975045)
			(xy 12.135841 -380.925468) (xy 12.120486 -380.873173) (xy 12.11273 -380.819225) (xy 12.112244 -380.791974)
			(xy 12.112745 -380.764401) (xy 12.120688 -380.709829) (xy 12.136405 -380.656969) (xy 12.159569 -380.606922)
			(xy 12.189696 -380.560732) (xy 12.226159 -380.51936) (xy 12.246864 -380.501144) (xy 12.2555 -380.493778)
			(xy 12.264898 -380.473712) (xy 12.26439 -380.373128) (xy 12.254992 -380.353062) (xy 12.246356 -380.345696)
			(xy 12.225325 -380.327494) (xy 12.188286 -380.286) (xy 12.157659 -380.239571) (xy 12.134092 -380.18919)
			(xy 12.118084 -380.135924) (xy 12.109973 -380.080898) (xy 12.10945 -380.053088) (xy 10.873606 -380.053088)
			(xy 10.873597 -380.053653) (xy 10.866669 -380.104608) (xy 10.852958 -380.154169) (xy 10.832712 -380.20144)
			(xy 10.806299 -380.245561) (xy 10.774197 -380.285734) (xy 10.755884 -380.303786) (xy 10.74801 -380.311406)
			(xy 10.740136 -380.33071) (xy 10.741914 -380.426976) (xy 10.75055 -380.446026) (xy 10.758678 -380.453392)
			(xy 10.7785 -380.471535) (xy 10.81329 -380.512491) (xy 10.841985 -380.557926) (xy 10.864018 -380.606939)
			(xy 10.878952 -380.658559) (xy 10.886491 -380.711765) (xy 10.886948 -380.738634) (xy 10.886454 -380.765884)
			(xy 10.878694 -380.81983) (xy 10.863336 -380.872122) (xy 10.840694 -380.921696) (xy 10.811228 -380.967545)
			(xy 10.775538 -381.008734) (xy 10.73435 -381.044425) (xy 10.688502 -381.073891) (xy 10.638927 -381.096534)
			(xy 10.586635 -381.111893) (xy 10.53269 -381.119654) (xy 10.50544 -381.120142) (xy 10.479824 -381.119706)
			(xy 10.429054 -381.11285) (xy 10.379659 -381.099256) (xy 10.33253 -381.079169) (xy 10.288516 -381.052951)
			(xy 10.268204 -381.037338) (xy 10.260076 -381.030988) (xy 10.240264 -381.0254) (xy 10.1473 -381.037592)
			(xy 10.12952 -381.048006) (xy 10.123424 -381.056388) (xy 10.105294 -381.079848) (xy 10.062978 -381.121375)
			(xy 10.014752 -381.155861) (xy 9.961775 -381.182479) (xy 9.90532 -381.200587) (xy 9.846744 -381.209752)
			(xy 9.8171 -381.210312) (xy 9.789849 -381.209818) (xy 9.735902 -381.202062) (xy 9.683608 -381.186707)
			(xy 9.634031 -381.164066) (xy 9.588181 -381.1346) (xy 9.546991 -381.098909) (xy 9.5113 -381.057719)
			(xy 9.481834 -381.011869) (xy 9.459193 -380.962292) (xy 9.443838 -380.909998) (xy 9.436082 -380.856051)
			(xy 8.386133 -380.856051) (xy 8.935212 -381.40513) (xy 15.882112 -381.40513) (xy 15.882593 -381.37776)
			(xy 15.890407 -381.323582) (xy 15.905892 -381.271079) (xy 15.928731 -381.221332) (xy 15.958452 -381.175364)
			(xy 15.976092 -381.154432) (xy 15.982188 -381.14732) (xy 15.988538 -381.130302) (xy 15.988538 -381.044958)
			(xy 15.982188 -381.02794) (xy 15.976092 -381.020828) (xy 15.958482 -380.999871) (xy 15.928759 -380.953906)
			(xy 15.905914 -380.904164) (xy 15.890417 -380.851666) (xy 15.882586 -380.797491) (xy 15.882583 -380.742754)
			(xy 15.890407 -380.688578) (xy 15.905898 -380.636078) (xy 15.928737 -380.586333) (xy 15.958455 -380.540365)
			(xy 15.976092 -380.519432) (xy 15.982188 -380.51232) (xy 15.988538 -380.495302) (xy 15.988538 -380.409958)
			(xy 15.982188 -380.39294) (xy 15.976092 -380.385828) (xy 15.958482 -380.364871) (xy 15.928759 -380.318906)
			(xy 15.905914 -380.269164) (xy 15.890417 -380.216666) (xy 15.882586 -380.162491) (xy 15.882583 -380.107754)
			(xy 15.890407 -380.053578) (xy 15.905898 -380.001078) (xy 15.928737 -379.951333) (xy 15.958455 -379.905365)
			(xy 15.976092 -379.884432) (xy 15.982188 -379.87732) (xy 15.988538 -379.860302) (xy 15.988538 -379.774958)
			(xy 15.982188 -379.75794) (xy 15.976092 -379.750828) (xy 15.958482 -379.729871) (xy 15.928759 -379.683906)
			(xy 15.905914 -379.634164) (xy 15.890417 -379.581666) (xy 15.882586 -379.527491) (xy 15.882583 -379.472754)
			(xy 15.890407 -379.418578) (xy 15.905898 -379.366078) (xy 15.928737 -379.316333) (xy 15.958455 -379.270365)
			(xy 15.976092 -379.249432) (xy 15.982188 -379.24232) (xy 15.988538 -379.225302) (xy 15.988538 -379.139958)
			(xy 15.982188 -379.12294) (xy 15.976092 -379.115828) (xy 15.958451 -379.094897) (xy 15.92874 -379.048924)
			(xy 15.905904 -378.999176) (xy 15.890414 -378.946675) (xy 15.882586 -378.892499) (xy 15.882112 -378.86513)
			(xy 15.882598 -378.837879) (xy 15.890354 -378.783931) (xy 15.905709 -378.731636) (xy 15.928351 -378.682059)
			(xy 15.957817 -378.636209) (xy 15.993508 -378.595018) (xy 16.034699 -378.559327) (xy 16.080549 -378.529861)
			(xy 16.130126 -378.507219) (xy 16.182421 -378.491864) (xy 16.236369 -378.484108) (xy 16.290871 -378.484108)
			(xy 16.344819 -378.491864) (xy 16.397114 -378.507219) (xy 16.446691 -378.529861) (xy 16.492541 -378.559327)
			(xy 16.533732 -378.595018) (xy 16.569423 -378.636209) (xy 16.598889 -378.682059) (xy 16.621531 -378.731636)
			(xy 16.636886 -378.783931) (xy 16.644642 -378.837879) (xy 16.645128 -378.86513) (xy 16.644697 -378.892502)
			(xy 16.636873 -378.946683) (xy 16.621377 -378.999187) (xy 16.598527 -379.048934) (xy 16.568794 -379.094898)
			(xy 16.551148 -379.115828) (xy 16.545052 -379.12294) (xy 16.538702 -379.139958) (xy 16.538702 -379.225302)
			(xy 16.545052 -379.24232) (xy 16.551148 -379.249432) (xy 16.568819 -379.27034) (xy 16.598545 -379.316312)
			(xy 16.62139 -379.366062) (xy 16.636885 -379.418568) (xy 16.644711 -379.47275) (xy 16.644708 -379.527495)
			(xy 16.636875 -379.581676) (xy 16.621374 -379.63418) (xy 16.598523 -379.683928) (xy 16.568792 -379.729896)
			(xy 16.551148 -379.750828) (xy 16.545052 -379.75794) (xy 16.538702 -379.774958) (xy 16.538702 -379.860302)
			(xy 16.545052 -379.87732) (xy 16.551148 -379.884432) (xy 16.568819 -379.90534) (xy 16.598545 -379.951312)
			(xy 16.62139 -380.001062) (xy 16.636885 -380.053568) (xy 16.644711 -380.10775) (xy 16.644708 -380.162495)
			(xy 16.636875 -380.216676) (xy 16.621374 -380.26918) (xy 16.598523 -380.318928) (xy 16.568792 -380.364896)
			(xy 16.551148 -380.385828) (xy 16.545052 -380.39294) (xy 16.538702 -380.409958) (xy 16.538702 -380.495302)
			(xy 16.545052 -380.51232) (xy 16.551148 -380.519432) (xy 16.568819 -380.54034) (xy 16.598545 -380.586312)
			(xy 16.62139 -380.636062) (xy 16.636885 -380.688568) (xy 16.644711 -380.74275) (xy 16.644708 -380.797495)
			(xy 16.644405 -380.799594) (xy 18.005552 -380.799594) (xy 18.005939 -380.774164) (xy 18.012698 -380.723755)
			(xy 18.026095 -380.674691) (xy 18.045893 -380.627843) (xy 18.071741 -380.584041) (xy 18.103179 -380.544061)
			(xy 18.121122 -380.526036) (xy 18.128488 -380.518924) (xy 18.136362 -380.500382) (xy 18.136616 -380.406656)
			(xy 18.128742 -380.388114) (xy 18.121376 -380.380748) (xy 18.10012 -380.35909) (xy 18.064082 -380.310269)
			(xy 18.036228 -380.256358) (xy 18.01726 -380.198718) (xy 18.007659 -380.138801) (xy 18.007076 -380.10846)
			(xy 18.007582 -380.079721) (xy 18.01621 -380.022893) (xy 18.033264 -379.968002) (xy 18.05836 -379.916291)
			(xy 18.090928 -379.868929) (xy 18.1102 -379.847602) (xy 18.116804 -379.84049) (xy 18.123916 -379.822964)
			(xy 18.123916 -379.733556) (xy 18.116804 -379.71603) (xy 18.1102 -379.708918) (xy 18.090929 -379.687591)
			(xy 18.058364 -379.640229) (xy 18.033273 -379.588517) (xy 18.016223 -379.533626) (xy 18.007601 -379.476799)
			(xy 18.007601 -379.419321) (xy 18.016223 -379.362494) (xy 18.033273 -379.307603) (xy 18.058364 -379.255891)
			(xy 18.090929 -379.208529) (xy 18.1102 -379.187202) (xy 18.116804 -379.18009) (xy 18.123916 -379.162564)
			(xy 18.123916 -379.073156) (xy 18.116804 -379.05563) (xy 18.1102 -379.048518) (xy 18.090921 -379.027198)
			(xy 18.058354 -378.979835) (xy 18.033262 -378.928122) (xy 18.016213 -378.873229) (xy 18.007595 -378.8164)
			(xy 18.007076 -378.78766) (xy 18.007541 -378.760408) (xy 18.015302 -378.706461) (xy 18.030661 -378.654167)
			(xy 18.053306 -378.60459) (xy 18.082775 -378.558741) (xy 18.118469 -378.517552) (xy 18.15966 -378.481861)
			(xy 18.205511 -378.452395) (xy 18.255089 -378.429753) (xy 18.307384 -378.414397) (xy 18.361332 -378.406639)
			(xy 18.388584 -378.406152) (xy 18.417229 -378.406637) (xy 18.473874 -378.415214) (xy 18.528601 -378.432164)
			(xy 18.580178 -378.457104) (xy 18.627447 -378.489474) (xy 18.669346 -378.528548) (xy 18.687542 -378.550678)
			(xy 18.6944 -378.559314) (xy 18.713704 -378.56922) (xy 18.811748 -378.574554) (xy 18.832068 -378.56668)
			(xy 18.839688 -378.558806) (xy 18.861356 -378.537509) (xy 18.910208 -378.501392) (xy 18.964166 -378.473475)
			(xy 19.021868 -378.454464) (xy 19.081854 -378.444839) (xy 19.11223 -378.444252) (xy 19.14149 -378.444813)
			(xy 19.199321 -378.453759) (xy 19.255112 -378.471422) (xy 19.307555 -378.497388) (xy 19.355424 -378.53105)
			(xy 19.376898 -378.550932) (xy 19.38401 -378.55779) (xy 19.402044 -378.565156) (xy 19.492468 -378.565156)
			(xy 19.510502 -378.55779) (xy 19.517614 -378.550932) (xy 19.539048 -378.531001) (xy 19.586919 -378.497327)
			(xy 19.639371 -378.471358) (xy 19.695174 -378.453703) (xy 19.753018 -378.444778) (xy 19.782282 -378.444252)
			(xy 19.811862 -378.444836) (xy 19.870315 -378.453966) (xy 19.926657 -378.472009) (xy 19.979539 -378.498533)
			(xy 20.027693 -378.532901) (xy 20.069964 -378.574291) (xy 20.088098 -378.597668) (xy 20.095686 -378.606789)
			(xy 20.116888 -378.617376) (xy 20.128738 -378.617988) (xy 20.210272 -378.617988) (xy 20.222117 -378.617357)
			(xy 20.243308 -378.60677) (xy 20.250912 -378.597668) (xy 20.260074 -378.585618) (xy 20.280037 -378.562857)
			(xy 20.29079 -378.552202) (xy 20.298664 -378.544582) (xy 20.306538 -378.525024) (xy 20.303744 -378.428504)
			(xy 20.294854 -378.409454) (xy 20.286726 -378.402342) (xy 20.266449 -378.384128) (xy 20.230747 -378.342943)
			(xy 20.201264 -378.297102) (xy 20.178597 -378.247534) (xy 20.163208 -378.195247) (xy 20.155409 -378.141304)
			(xy 20.1549 -378.114052) (xy 20.155347 -378.086223) (xy 20.163428 -378.031153) (xy 20.179427 -377.977844)
			(xy 20.203003 -377.927425) (xy 20.233657 -377.880968) (xy 20.270736 -377.839458) (xy 20.313455 -377.803779)
			(xy 20.360905 -377.774686) (xy 20.386294 -377.763278) (xy 20.395946 -377.759214) (xy 20.41017 -377.744482)
			(xy 20.443444 -377.656344) (xy 20.442428 -377.63577) (xy 20.43811 -377.626372) (xy 20.42649 -377.600731)
			(xy 20.410102 -377.546875) (xy 20.4018 -377.491197) (xy 20.40128 -377.46305) (xy 20.401804 -377.434133)
			(xy 20.410528 -377.376961) (xy 20.427783 -377.321761) (xy 20.453173 -377.269798) (xy 20.486117 -377.222265)
			(xy 20.52586 -377.180249) (xy 20.548346 -377.16206) (xy 20.557129 -377.154519) (xy 20.567299 -377.133744)
			(xy 20.567904 -377.122182) (xy 20.567904 -377.041918) (xy 20.567322 -377.030352) (xy 20.557135 -377.009581)
			(xy 20.548346 -377.00204) (xy 20.527563 -376.985287) (xy 20.490433 -376.946933) (xy 20.459012 -376.903779)
			(xy 20.433913 -376.856665) (xy 20.415627 -376.806513) (xy 20.40451 -376.754301) (xy 20.400781 -376.70105)
			(xy 20.40451 -376.647799) (xy 20.415627 -376.595587) (xy 20.433913 -376.545435) (xy 20.459012 -376.498321)
			(xy 20.490433 -376.455167) (xy 20.527563 -376.416813) (xy 20.548346 -376.40006) (xy 20.557129 -376.392519)
			(xy 20.567299 -376.371744) (xy 20.567904 -376.360182) (xy 20.567904 -376.279918) (xy 20.567322 -376.268352)
			(xy 20.557135 -376.247581) (xy 20.548346 -376.24004) (xy 20.527563 -376.223287) (xy 20.490433 -376.184933)
			(xy 20.459012 -376.141779) (xy 20.433913 -376.094665) (xy 20.415627 -376.044513) (xy 20.40451 -375.992301)
			(xy 20.400781 -375.93905) (xy 20.40451 -375.885799) (xy 20.415627 -375.833587) (xy 20.433913 -375.783435)
			(xy 20.459012 -375.736321) (xy 20.490433 -375.693167) (xy 20.527563 -375.654813) (xy 20.548346 -375.63806)
			(xy 20.557129 -375.630519) (xy 20.567299 -375.609744) (xy 20.567904 -375.598182) (xy 20.567904 -375.517918)
			(xy 20.567322 -375.506352) (xy 20.557135 -375.485581) (xy 20.548346 -375.47804) (xy 20.52587 -375.45984)
			(xy 20.486137 -375.417821) (xy 20.453199 -375.370287) (xy 20.42781 -375.318328) (xy 20.410551 -375.263133)
			(xy 20.401818 -375.205965) (xy 20.40128 -375.17705) (xy 20.401766 -375.149799) (xy 20.409522 -375.095851)
			(xy 20.424877 -375.043556) (xy 20.447519 -374.993979) (xy 20.476985 -374.948129) (xy 20.512676 -374.906938)
			(xy 20.553867 -374.871247) (xy 20.599717 -374.841781) (xy 20.649294 -374.819139) (xy 20.701589 -374.803784)
			(xy 20.755537 -374.796028) (xy 20.810039 -374.796028) (xy 20.863987 -374.803784) (xy 20.916282 -374.819139)
			(xy 20.965859 -374.841781) (xy 21.011709 -374.871247) (xy 21.0529 -374.906938) (xy 21.088591 -374.948129)
			(xy 21.118057 -374.993979) (xy 21.140699 -375.043556) (xy 21.156054 -375.095851) (xy 21.16381 -375.149799)
			(xy 21.164296 -375.17705) (xy 21.163743 -375.205966) (xy 21.155022 -375.263135) (xy 21.137771 -375.318334)
			(xy 21.112385 -375.370295) (xy 21.079448 -375.41783) (xy 21.039713 -375.459849) (xy 21.01723 -375.47804)
			(xy 21.008443 -375.485577) (xy 20.998276 -375.506355) (xy 20.997672 -375.517918) (xy 20.997672 -375.598182)
			(xy 20.998228 -375.609752) (xy 21.00843 -375.630525) (xy 21.01723 -375.63806) (xy 21.038013 -375.654813)
			(xy 21.075144 -375.693166) (xy 21.106565 -375.736321) (xy 21.131664 -375.783435) (xy 21.14995 -375.833587)
			(xy 21.161067 -375.885798) (xy 21.164797 -375.93905) (xy 21.161067 -375.992302) (xy 21.14995 -376.044513)
			(xy 21.131664 -376.094665) (xy 21.106565 -376.141779) (xy 21.075144 -376.184934) (xy 21.038013 -376.223287)
			(xy 21.01723 -376.24004) (xy 21.008443 -376.247577) (xy 20.998276 -376.268355) (xy 20.997672 -376.279918)
			(xy 20.997672 -376.360182) (xy 20.998228 -376.371752) (xy 21.00843 -376.392525) (xy 21.01723 -376.40006)
			(xy 21.038013 -376.416813) (xy 21.075144 -376.455166) (xy 21.106565 -376.498321) (xy 21.131664 -376.545435)
			(xy 21.14995 -376.595587) (xy 21.154341 -376.616209) (xy 22.153395 -376.616209) (xy 22.157124 -376.562959)
			(xy 22.168239 -376.510749) (xy 22.186523 -376.460598) (xy 22.211619 -376.413485) (xy 22.243037 -376.370331)
			(xy 22.280165 -376.331978) (xy 22.300946 -376.315224) (xy 22.3097 -376.307655) (xy 22.319886 -376.286901)
			(xy 22.320504 -376.275346) (xy 22.320504 -376.195082) (xy 22.319942 -376.183513) (xy 22.309741 -376.162742)
			(xy 22.300946 -376.155204) (xy 22.280177 -376.138434) (xy 22.243048 -376.100082) (xy 22.211628 -376.056929)
			(xy 22.18653 -376.009818) (xy 22.168243 -375.959668) (xy 22.157126 -375.907458) (xy 22.153395 -375.854209)
			(xy 22.157124 -375.800959) (xy 22.168239 -375.748749) (xy 22.186523 -375.698598) (xy 22.211619 -375.651485)
			(xy 22.243037 -375.608331) (xy 22.280165 -375.569978) (xy 22.300946 -375.553224) (xy 22.3097 -375.545655)
			(xy 22.319886 -375.524901) (xy 22.320504 -375.513346) (xy 22.320504 -375.433082) (xy 22.319942 -375.421513)
			(xy 22.309741 -375.400742) (xy 22.300946 -375.393204) (xy 22.278453 -375.375024) (xy 22.238721 -375.333001)
			(xy 22.205785 -375.285463) (xy 22.180398 -375.2335) (xy 22.163144 -375.178301) (xy 22.154415 -375.12113)
			(xy 22.15388 -375.092214) (xy 22.154366 -375.064963) (xy 22.162122 -375.011015) (xy 22.177477 -374.95872)
			(xy 22.200119 -374.909143) (xy 22.229585 -374.863293) (xy 22.265276 -374.822102) (xy 22.306467 -374.786411)
			(xy 22.352317 -374.756945) (xy 22.401894 -374.734303) (xy 22.454189 -374.718948) (xy 22.508137 -374.711192)
			(xy 22.562639 -374.711192) (xy 22.616587 -374.718948) (xy 22.668882 -374.734303) (xy 22.718459 -374.756945)
			(xy 22.764309 -374.786411) (xy 22.8055 -374.822102) (xy 22.841191 -374.863293) (xy 22.870657 -374.909143)
			(xy 22.893299 -374.95872) (xy 22.908654 -375.011015) (xy 22.91641 -375.064963) (xy 22.916896 -375.092214)
			(xy 22.916318 -375.121129) (xy 22.907601 -375.178297) (xy 22.890355 -375.233495) (xy 22.864975 -375.285457)
			(xy 22.832042 -375.332992) (xy 22.792311 -375.375012) (xy 22.76983 -375.393204) (xy 22.761059 -375.400757)
			(xy 22.750883 -375.421523) (xy 22.750272 -375.433082) (xy 22.750272 -375.513346) (xy 22.750848 -375.524914)
			(xy 22.761036 -375.545686) (xy 22.76983 -375.553224) (xy 22.790627 -375.569961) (xy 22.827759 -375.608315)
			(xy 22.859181 -375.651472) (xy 22.884281 -375.698587) (xy 22.902567 -375.748741) (xy 22.913683 -375.800955)
			(xy 22.917412 -375.854209) (xy 22.913681 -375.907462) (xy 22.902562 -375.959675) (xy 22.884274 -376.009829)
			(xy 22.859172 -376.056943) (xy 22.827748 -376.100098) (xy 22.790614 -376.138451) (xy 22.76983 -376.155204)
			(xy 22.761059 -376.162757) (xy 22.750883 -376.183523) (xy 22.750272 -376.195082) (xy 22.750272 -376.275346)
			(xy 22.750848 -376.286914) (xy 22.761036 -376.307686) (xy 22.76983 -376.315224) (xy 22.790627 -376.331961)
			(xy 22.827759 -376.370315) (xy 22.859181 -376.413472) (xy 22.884281 -376.460587) (xy 22.902567 -376.510741)
			(xy 22.913683 -376.562955) (xy 22.917412 -376.616209) (xy 22.913681 -376.669462) (xy 22.902562 -376.721675)
			(xy 22.884274 -376.771829) (xy 22.859172 -376.818943) (xy 22.827748 -376.862098) (xy 22.790614 -376.900451)
			(xy 22.76983 -376.917204) (xy 22.761059 -376.924757) (xy 22.750883 -376.945523) (xy 22.750272 -376.957082)
			(xy 22.750272 -377.037346) (xy 22.750848 -377.048914) (xy 22.761036 -377.069686) (xy 22.76983 -377.077224)
			(xy 22.792331 -377.095394) (xy 22.832064 -377.137419) (xy 22.865 -377.184958) (xy 22.890385 -377.236924)
			(xy 22.907638 -377.292125) (xy 22.916363 -377.349297) (xy 22.916896 -377.378214) (xy 22.916393 -377.405147)
			(xy 22.908811 -377.458476) (xy 22.8938 -377.510208) (xy 22.87166 -377.559313) (xy 22.84283 -377.604813)
			(xy 22.82571 -377.62561) (xy 22.818852 -377.633738) (xy 22.812756 -377.653804) (xy 22.823678 -377.7488)
			(xy 22.834346 -377.767088) (xy 22.842982 -377.773438) (xy 22.866608 -377.791547) (xy 22.908468 -377.833868)
			(xy 22.943245 -377.882178) (xy 22.970093 -377.935305) (xy 22.988361 -377.991958) (xy 22.997606 -378.050761)
			(xy 22.998176 -378.080524) (xy 22.997696 -378.10853) (xy 22.989523 -378.163942) (xy 22.973341 -378.217566)
			(xy 22.949498 -378.26825) (xy 22.918505 -378.314906) (xy 22.900132 -378.336048) (xy 22.893528 -378.343414)
			(xy 22.886924 -378.36094) (xy 22.888448 -378.450348) (xy 22.895814 -378.46762) (xy 22.902672 -378.474732)
			(xy 22.922864 -378.496215) (xy 22.957006 -378.544279) (xy 22.983348 -378.597023) (xy 23.001265 -378.653191)
			(xy 23.010329 -378.711446) (xy 23.010876 -378.740924) (xy 23.01039 -378.768175) (xy 23.002634 -378.822123)
			(xy 22.987279 -378.874418) (xy 22.964637 -378.923995) (xy 22.935171 -378.969845) (xy 22.89948 -379.011036)
			(xy 22.858289 -379.046727) (xy 22.812439 -379.076193) (xy 22.762862 -379.098835) (xy 22.710567 -379.11419)
			(xy 22.656619 -379.121946) (xy 22.602117 -379.121946) (xy 22.548169 -379.11419) (xy 22.495874 -379.098835)
			(xy 22.446297 -379.076193) (xy 22.400447 -379.046727) (xy 22.359256 -379.011036) (xy 22.323565 -378.969845)
			(xy 22.294099 -378.923995) (xy 22.271457 -378.874418) (xy 22.256102 -378.822123) (xy 22.248346 -378.768175)
			(xy 22.24786 -378.740924) (xy 22.248385 -378.71292) (xy 22.256549 -378.65751) (xy 22.272722 -378.603888)
			(xy 22.296554 -378.553203) (xy 22.327536 -378.506545) (xy 22.345904 -378.4854) (xy 22.352508 -378.478034)
			(xy 22.359112 -378.460508) (xy 22.357588 -378.3711) (xy 22.350222 -378.353828) (xy 22.343364 -378.346716)
			(xy 22.323201 -378.325207) (xy 22.289054 -378.277151) (xy 22.262705 -378.224414) (xy 22.244782 -378.168251)
			(xy 22.23571 -378.11) (xy 22.23516 -378.080524) (xy 22.235614 -378.053589) (xy 22.243206 -378.000258)
			(xy 22.258227 -377.948525) (xy 22.280379 -377.899421) (xy 22.30922 -377.853922) (xy 22.326346 -377.833128)
			(xy 22.333204 -377.825) (xy 22.3393 -377.804934) (xy 22.328378 -377.709938) (xy 22.31771 -377.69165)
			(xy 22.309074 -377.6853) (xy 22.28543 -377.667212) (xy 22.243569 -377.624889) (xy 22.208792 -377.576575)
			(xy 22.181946 -377.523443) (xy 22.163683 -377.466786) (xy 22.154445 -377.407978) (xy 22.15388 -377.378214)
			(xy 22.154378 -377.349296) (xy 22.163107 -377.292122) (xy 22.180367 -377.236922) (xy 22.205762 -377.18496)
			(xy 22.238711 -377.137426) (xy 22.278458 -377.095412) (xy 22.300946 -377.077224) (xy 22.3097 -377.069655)
			(xy 22.319886 -377.048901) (xy 22.320504 -377.037346) (xy 22.320504 -376.957082) (xy 22.319942 -376.945513)
			(xy 22.309741 -376.924742) (xy 22.300946 -376.917204) (xy 22.280177 -376.900434) (xy 22.243048 -376.862082)
			(xy 22.211628 -376.818929) (xy 22.18653 -376.771818) (xy 22.168243 -376.721668) (xy 22.157126 -376.669458)
			(xy 22.153395 -376.616209) (xy 21.154341 -376.616209) (xy 21.161067 -376.647798) (xy 21.164797 -376.70105)
			(xy 21.161067 -376.754302) (xy 21.14995 -376.806513) (xy 21.131664 -376.856665) (xy 21.106565 -376.903779)
			(xy 21.075144 -376.946934) (xy 21.038013 -376.985287) (xy 21.01723 -377.00204) (xy 21.008443 -377.009577)
			(xy 20.998276 -377.030355) (xy 20.997672 -377.041918) (xy 20.997672 -377.122182) (xy 20.998228 -377.133752)
			(xy 21.00843 -377.154525) (xy 21.01723 -377.16206) (xy 21.039701 -377.180266) (xy 21.079435 -377.222284)
			(xy 21.112375 -377.269816) (xy 21.137765 -377.321774) (xy 21.155025 -377.376968) (xy 21.163758 -377.434135)
			(xy 21.164296 -377.46305) (xy 21.163853 -377.49088) (xy 21.155772 -377.545949) (xy 21.139772 -377.599259)
			(xy 21.116195 -377.649678) (xy 21.085541 -377.696135) (xy 21.048461 -377.737644) (xy 21.005742 -377.773324)
			(xy 20.958291 -377.802416) (xy 20.932902 -377.813824) (xy 20.92325 -377.817888) (xy 20.909026 -377.83262)
			(xy 20.875752 -377.920758) (xy 20.876768 -377.941332) (xy 20.881086 -377.95073) (xy 20.888452 -377.966986)
			(xy 20.892425 -377.975526) (xy 20.905503 -377.989068) (xy 20.922589 -377.996973) (xy 20.941376 -377.998175)
			(xy 20.959329 -377.992513) (xy 20.974027 -377.980749) (xy 20.97913 -377.972828) (xy 20.993908 -377.94856)
			(xy 21.029543 -377.904305) (xy 21.071346 -377.865824) (xy 21.118394 -377.833968) (xy 21.169645 -377.809441)
			(xy 21.223967 -377.792785) (xy 21.280159 -377.78437) (xy 21.308568 -377.783852) (xy 21.335817 -377.784408)
			(xy 21.38976 -377.792159) (xy 21.442051 -377.807508) (xy 21.491625 -377.830143) (xy 21.537474 -377.859602)
			(xy 21.578663 -377.895286) (xy 21.614355 -377.936469) (xy 21.643823 -377.982312) (xy 21.666467 -378.031882)
			(xy 21.681826 -378.08417) (xy 21.689587 -378.138111) (xy 21.690076 -378.16536) (xy 21.689633 -378.19266)
			(xy 21.681852 -378.246704) (xy 21.666445 -378.299085) (xy 21.643725 -378.348734) (xy 21.614157 -378.394636)
			(xy 21.596604 -378.41555) (xy 21.59 -378.422916) (xy 21.583904 -378.44095) (xy 21.587206 -378.530104)
			(xy 21.594826 -378.547376) (xy 21.601938 -378.554488) (xy 21.623017 -378.576118) (xy 21.658744 -378.624811)
			(xy 21.686349 -378.678527) (xy 21.705141 -378.735923) (xy 21.714652 -378.795563) (xy 21.715222 -378.82576)
			(xy 21.714729 -378.8545) (xy 21.706098 -378.911328) (xy 21.68904 -378.966219) (xy 21.663942 -379.01793)
			(xy 21.631371 -379.065292) (xy 21.612098 -379.086618) (xy 21.605494 -379.09373) (xy 21.598382 -379.111256)
			(xy 21.598382 -379.200664) (xy 21.605494 -379.21819) (xy 21.612098 -379.225302) (xy 21.631339 -379.246655)
			(xy 21.663911 -379.294009) (xy 21.689011 -379.345714) (xy 21.706068 -379.400599) (xy 21.714697 -379.457423)
			(xy 21.715222 -379.48616) (xy 21.714752 -379.51353) (xy 21.706938 -379.56771) (xy 21.691451 -379.620214)
			(xy 21.668609 -379.669961) (xy 21.638884 -379.715927) (xy 21.621242 -379.736858) (xy 21.615146 -379.74397)
			(xy 21.608796 -379.760988) (xy 21.608796 -379.846332) (xy 21.615146 -379.86335) (xy 21.621242 -379.870462)
			(xy 21.638884 -379.891392) (xy 21.668594 -379.937366) (xy 21.691429 -379.987114) (xy 21.706919 -380.039615)
			(xy 21.714748 -380.093791) (xy 21.715222 -380.12116) (xy 21.714631 -380.151355) (xy 21.705111 -380.210989)
			(xy 21.686316 -380.26838) (xy 21.658718 -380.322094) (xy 21.623003 -380.370792) (xy 21.601938 -380.392432)
			(xy 21.594826 -380.399544) (xy 21.587206 -380.416816) (xy 21.583904 -380.50597) (xy 21.59 -380.524004)
			(xy 21.596604 -380.53137) (xy 21.614134 -380.552301) (xy 21.643695 -380.598202) (xy 21.666411 -380.647848)
			(xy 21.68182 -380.700224) (xy 21.689607 -380.754262) (xy 21.690076 -380.78156) (xy 21.689631 -380.807303)
			(xy 21.68954 -380.807976) (xy 25.408128 -380.807976) (xy 25.408547 -380.781076) (xy 25.416102 -380.727809)
			(xy 25.431074 -380.676133) (xy 25.453165 -380.627077) (xy 25.481935 -380.581616) (xy 25.516812 -380.540652)
			(xy 25.536652 -380.52248) (xy 25.544526 -380.515368) (xy 25.553416 -380.496826) (xy 25.556718 -380.402084)
			(xy 25.549352 -380.383034) (xy 25.541986 -380.375414) (xy 25.521744 -380.353929) (xy 25.487525 -380.305831)
			(xy 25.461121 -380.253037) (xy 25.443162 -380.196807) (xy 25.434077 -380.138482) (xy 25.433528 -380.108968)
			(xy 25.433968 -380.081597) (xy 25.441791 -380.027416) (xy 25.457286 -379.974913) (xy 25.480134 -379.925166)
			(xy 25.509864 -379.879201) (xy 25.527508 -379.85827) (xy 25.533604 -379.851158) (xy 25.539954 -379.83414)
			(xy 25.539954 -379.748796) (xy 25.533604 -379.731778) (xy 25.527508 -379.724666) (xy 25.509888 -379.703719)
			(xy 25.480173 -379.65775) (xy 25.457333 -379.608007) (xy 25.441838 -379.555509) (xy 25.434005 -379.501336)
			(xy 25.433528 -379.473968) (xy 25.434095 -379.444527) (xy 25.443132 -379.386344) (xy 25.461004 -379.33024)
			(xy 25.487284 -379.277549) (xy 25.521349 -379.229522) (xy 25.541478 -379.20803) (xy 25.54859 -379.200918)
			(xy 25.555956 -379.182122) (xy 25.554178 -379.089412) (xy 25.54605 -379.071124) (xy 25.538684 -379.064012)
			(xy 25.520399 -379.045947) (xy 25.488359 -379.005753) (xy 25.462003 -378.961624) (xy 25.441808 -378.914356)
			(xy 25.428139 -378.864805) (xy 25.421245 -378.813869) (xy 25.420828 -378.788168) (xy 25.421225 -378.760913)
			(xy 25.428987 -378.706957) (xy 25.444349 -378.654656) (xy 25.466998 -378.605073) (xy 25.496473 -378.559219)
			(xy 25.532174 -378.518025) (xy 25.573373 -378.482332) (xy 25.619233 -378.452866) (xy 25.66882 -378.430226)
			(xy 25.721124 -378.414873) (xy 25.775081 -378.40712) (xy 25.802336 -378.40666) (xy 25.831075 -378.407173)
			(xy 25.887903 -378.415799) (xy 25.942793 -378.432853) (xy 25.994505 -378.457947) (xy 26.041867 -378.490513)
			(xy 26.063194 -378.509784) (xy 26.070306 -378.516388) (xy 26.087832 -378.5235) (xy 26.17724 -378.5235)
			(xy 26.194766 -378.516388) (xy 26.201878 -378.509784) (xy 26.223205 -378.490514) (xy 26.270568 -378.457949)
			(xy 26.322279 -378.432858) (xy 26.37717 -378.415808) (xy 26.433997 -378.407186) (xy 26.491475 -378.407186)
			(xy 26.548302 -378.415808) (xy 26.603193 -378.432858) (xy 26.654904 -378.457949) (xy 26.702267 -378.490514)
			(xy 26.723594 -378.509784) (xy 26.730706 -378.516388) (xy 26.748232 -378.5235) (xy 26.83764 -378.5235)
			(xy 26.855166 -378.516388) (xy 26.862278 -378.509784) (xy 26.883597 -378.490504) (xy 26.93096 -378.457937)
			(xy 26.982674 -378.432846) (xy 27.037567 -378.415797) (xy 27.094396 -378.407178) (xy 27.123136 -378.40666)
			(xy 27.152189 -378.40722) (xy 27.209625 -378.416011) (xy 27.265063 -378.433414) (xy 27.317218 -378.459027)
			(xy 27.364884 -378.492256) (xy 27.406957 -378.532332) (xy 27.425142 -378.554996) (xy 27.432254 -378.56414)
			(xy 27.45232 -378.5743) (xy 27.554428 -378.57684) (xy 27.575002 -378.567696) (xy 27.582622 -378.558806)
			(xy 27.600825 -378.538308) (xy 27.642111 -378.502243) (xy 27.688133 -378.472457) (xy 27.737943 -378.449563)
			(xy 27.790517 -378.434032) (xy 27.844772 -378.426185) (xy 27.872182 -378.42571) (xy 27.899435 -378.426172)
			(xy 27.953387 -378.433927) (xy 28.005686 -378.449282) (xy 28.055267 -378.471923) (xy 28.101121 -378.501391)
			(xy 28.142315 -378.537085) (xy 28.178009 -378.578279) (xy 28.207477 -378.624133) (xy 28.230118 -378.673714)
			(xy 28.245473 -378.726013) (xy 28.253228 -378.779965) (xy 28.25369 -378.807218) (xy 28.25318 -378.835957)
			(xy 28.244554 -378.892786) (xy 28.227501 -378.947677) (xy 28.202407 -378.999388) (xy 28.169838 -379.04675)
			(xy 28.150566 -379.068076) (xy 28.143962 -379.075188) (xy 28.13685 -379.092714) (xy 28.13685 -379.182122)
			(xy 28.143962 -379.199648) (xy 28.150566 -379.20676) (xy 28.169855 -379.228071) (xy 28.202421 -379.275436)
			(xy 28.227512 -379.32715) (xy 28.244561 -379.382043) (xy 28.253182 -379.438873) (xy 28.25318 -379.496353)
			(xy 28.244555 -379.553182) (xy 28.227502 -379.608074) (xy 28.202407 -379.659787) (xy 28.169839 -379.707149)
			(xy 28.150566 -379.728476) (xy 28.143962 -379.735588) (xy 28.13685 -379.753114) (xy 28.13685 -379.842522)
			(xy 28.143962 -379.860048) (xy 28.150566 -379.86716) (xy 28.169846 -379.888479) (xy 28.202411 -379.935843)
			(xy 28.227501 -379.987557) (xy 28.24455 -380.04245) (xy 28.25317 -380.099278) (xy 28.25369 -380.128018)
			(xy 28.25311 -380.157458) (xy 28.244074 -380.215641) (xy 28.226206 -380.271744) (xy 28.199929 -380.324436)
			(xy 28.165867 -380.372464) (xy 28.14574 -380.393956) (xy 28.138882 -380.401068) (xy 28.131516 -380.418848)
			(xy 28.130754 -380.509018) (xy 28.137866 -380.527052) (xy 28.144724 -380.534418) (xy 28.164114 -380.555734)
			(xy 28.196836 -380.603167) (xy 28.222048 -380.654983) (xy 28.239178 -380.710002) (xy 28.247835 -380.766972)
			(xy 28.248356 -380.795784) (xy 28.247898 -380.823389) (xy 28.239929 -380.87802) (xy 28.224171 -380.930933)
			(xy 28.200952 -380.981023) (xy 28.170757 -381.027244) (xy 28.152852 -381.04826) (xy 28.146248 -381.05588)
			(xy 28.139644 -381.07493) (xy 28.145486 -381.166624) (xy 28.154122 -381.184912) (xy 28.161742 -381.191516)
			(xy 28.181621 -381.209687) (xy 28.216553 -381.250681) (xy 28.245368 -381.296182) (xy 28.267495 -381.345285)
			(xy 28.282492 -381.397013) (xy 28.290061 -381.450337) (xy 28.29052 -381.477266) (xy 28.290013 -381.504517)
			(xy 28.282261 -381.558466) (xy 28.26691 -381.610763) (xy 28.244272 -381.660342) (xy 28.214809 -381.706194)
			(xy 28.17912 -381.747387) (xy 28.137931 -381.783081) (xy 28.092082 -381.81255) (xy 28.042506 -381.835194)
			(xy 27.990211 -381.850551) (xy 27.936263 -381.85831) (xy 27.909012 -381.858774) (xy 27.882656 -381.858307)
			(xy 27.830447 -381.851041) (xy 27.779735 -381.836659) (xy 27.731484 -381.815435) (xy 27.686613 -381.787773)
			(xy 27.645976 -381.754199) (xy 27.627834 -381.735076) (xy 27.620722 -381.727456) (xy 27.602942 -381.719074)
			(xy 27.51074 -381.714756) (xy 27.492198 -381.721614) (xy 27.484578 -381.728472) (xy 27.463411 -381.747032)
			(xy 27.41662 -381.778333) (xy 27.365739 -381.802421) (xy 27.311871 -381.818773) (xy 27.256186 -381.827034)
			(xy 27.228038 -381.827532) (xy 27.200375 -381.827041) (xy 27.145625 -381.819074) (xy 27.0926 -381.803286)
			(xy 27.042409 -381.780008) (xy 26.996104 -381.749729) (xy 26.975054 -381.731774) (xy 26.967942 -381.72517)
			(xy 26.950162 -381.71882) (xy 26.86177 -381.720598) (xy 26.844244 -381.727964) (xy 26.837386 -381.734568)
			(xy 26.81591 -381.754503) (xy 26.768013 -381.788255) (xy 26.71552 -381.814291) (xy 26.659666 -381.831999)
			(xy 26.601761 -381.840963) (xy 26.572464 -381.841502) (xy 26.546974 -381.84109) (xy 26.496449 -381.834307)
			(xy 26.447277 -381.820855) (xy 26.400335 -381.800972) (xy 26.35646 -381.775012) (xy 26.316435 -381.74344)
			(xy 26.298398 -381.725424) (xy 26.291032 -381.717804) (xy 26.271728 -381.709676) (xy 26.17597 -381.711454)
			(xy 26.15692 -381.720344) (xy 26.149808 -381.728218) (xy 26.131629 -381.747742) (xy 26.090799 -381.782074)
			(xy 26.045582 -381.810379) (xy 25.996861 -381.832107) (xy 25.945588 -381.846831) (xy 25.892763 -381.854265)
			(xy 25.86609 -381.85471) (xy 25.838839 -381.854232) (xy 25.784891 -381.846474) (xy 25.732596 -381.831117)
			(xy 25.683019 -381.808475) (xy 25.637169 -381.779008) (xy 25.595978 -381.743316) (xy 25.560287 -381.702125)
			(xy 25.530821 -381.656274) (xy 25.50818 -381.606697) (xy 25.492825 -381.554401) (xy 25.485068 -381.500453)
			(xy 25.484582 -381.473202) (xy 25.485165 -381.442144) (xy 25.495229 -381.38085) (xy 25.515091 -381.321996)
			(xy 25.544226 -381.267138) (xy 25.56256 -381.242062) (xy 25.568656 -381.233934) (xy 25.57399 -381.215392)
			(xy 25.563576 -381.125476) (xy 25.554432 -381.108458) (xy 25.546558 -381.102108) (xy 25.52529 -381.083892)
			(xy 25.487817 -381.042282) (xy 25.456825 -380.995644) (xy 25.432982 -380.944977) (xy 25.416797 -380.891371)
			(xy 25.408618 -380.835974) (xy 25.408128 -380.807976) (xy 21.68954 -380.807976) (xy 21.682701 -380.85832)
			(xy 21.668976 -380.907942) (xy 21.648705 -380.955269) (xy 21.622254 -380.999441) (xy 21.60651 -381.019812)
			(xy 21.600668 -381.027178) (xy 21.59508 -381.044958) (xy 21.600414 -381.132334) (xy 21.608034 -381.149098)
			(xy 21.615146 -381.155956) (xy 21.633035 -381.17399) (xy 21.664398 -381.213947) (xy 21.690182 -381.257712)
			(xy 21.709931 -381.304511) (xy 21.723296 -381.353517) (xy 21.730041 -381.403862) (xy 21.730462 -381.42926)
			(xy 21.729976 -381.456511) (xy 21.72222 -381.510459) (xy 21.706865 -381.562754) (xy 21.684223 -381.612331)
			(xy 21.654757 -381.658181) (xy 21.619066 -381.699372) (xy 21.577875 -381.735063) (xy 21.532025 -381.764529)
			(xy 21.482448 -381.787171) (xy 21.430153 -381.802526) (xy 21.376205 -381.810282) (xy 21.321703 -381.810282)
			(xy 21.267755 -381.802526) (xy 21.21546 -381.787171) (xy 21.165883 -381.764529) (xy 21.120033 -381.735063)
			(xy 21.078842 -381.699372) (xy 21.043151 -381.658181) (xy 21.013685 -381.612331) (xy 20.991043 -381.562754)
			(xy 20.975688 -381.510459) (xy 20.967932 -381.456511) (xy 20.967446 -381.42926) (xy 20.967897 -381.403517)
			(xy 20.974825 -381.3525) (xy 20.988548 -381.302878) (xy 21.008819 -381.255551) (xy 21.035268 -381.211379)
			(xy 21.051012 -381.191008) (xy 21.056854 -381.183642) (xy 21.062442 -381.165862) (xy 21.057108 -381.078486)
			(xy 21.049488 -381.061722) (xy 21.042376 -381.054864) (xy 21.033534 -381.046143) (xy 21.016883 -381.027713)
			(xy 21.009102 -381.018034) (xy 21.001736 -381.008382) (xy 20.979892 -380.998222) (xy 20.87372 -381.001778)
			(xy 20.852638 -381.013208) (xy 20.84578 -381.023368) (xy 20.830474 -381.044859) (xy 20.794837 -381.083769)
			(xy 20.754179 -381.117397) (xy 20.709276 -381.145103) (xy 20.660984 -381.166358) (xy 20.610223 -381.180756)
			(xy 20.557963 -381.188023) (xy 20.531582 -381.188468) (xy 20.503346 -381.187942) (xy 20.447491 -381.179616)
			(xy 20.393474 -381.163148) (xy 20.342474 -381.138898) (xy 20.295605 -381.107396) (xy 20.253891 -381.06933)
			(xy 20.235672 -381.047752) (xy 20.228068 -381.039366) (xy 20.20761 -381.029744) (xy 20.196302 -381.02921)
			(xy 20.117562 -381.02921) (xy 20.106274 -381.02982) (xy 20.085845 -381.039433) (xy 20.078192 -381.047752)
			(xy 20.059979 -381.069337) (xy 20.018268 -381.107409) (xy 19.971399 -381.138916) (xy 19.920397 -381.163168)
			(xy 19.866377 -381.179636) (xy 19.810519 -381.187959) (xy 19.782282 -381.188468) (xy 19.753023 -381.187894)
			(xy 19.695192 -381.178951) (xy 19.639402 -381.161291) (xy 19.586959 -381.135327) (xy 19.539089 -381.101669)
			(xy 19.517614 -381.081788) (xy 19.510502 -381.07493) (xy 19.492468 -381.067564) (xy 19.402044 -381.067564)
			(xy 19.38401 -381.07493) (xy 19.376898 -381.081788) (xy 19.355462 -381.101717) (xy 19.307591 -381.135391)
			(xy 19.25514 -381.16136) (xy 19.199338 -381.179014) (xy 19.141494 -381.187941) (xy 19.11223 -381.188468)
			(xy 19.08491 -381.188023) (xy 19.03083 -381.180225) (xy 18.978417 -381.164786) (xy 18.928746 -381.142022)
			(xy 18.882833 -381.112399) (xy 18.841621 -381.076524) (xy 18.823432 -381.056134) (xy 18.816066 -381.047752)
			(xy 18.796508 -381.038608) (xy 18.69821 -381.037592) (xy 18.678144 -381.046482) (xy 18.670778 -381.05461)
			(xy 18.652632 -381.074166) (xy 18.611793 -381.108492) (xy 18.566569 -381.136791) (xy 18.517842 -381.158512)
			(xy 18.466563 -381.17323) (xy 18.413734 -381.180659) (xy 18.38706 -381.181102) (xy 18.359807 -381.180659)
			(xy 18.305858 -381.172897) (xy 18.253562 -381.157537) (xy 18.203984 -381.134891) (xy 18.158134 -381.10542)
			(xy 18.116944 -381.069724) (xy 18.081253 -381.028529) (xy 18.051787 -380.982675) (xy 18.029147 -380.933095)
			(xy 18.013793 -380.880797) (xy 18.006037 -380.826847) (xy 18.005552 -380.799594) (xy 16.644405 -380.799594)
			(xy 16.636875 -380.851676) (xy 16.621374 -380.90418) (xy 16.598523 -380.953928) (xy 16.568792 -380.999896)
			(xy 16.551148 -381.020828) (xy 16.545052 -381.02794) (xy 16.538702 -381.044958) (xy 16.538702 -381.130302)
			(xy 16.545052 -381.14732) (xy 16.551148 -381.154432) (xy 16.568761 -381.175386) (xy 16.598478 -381.221352)
			(xy 16.62132 -381.271094) (xy 16.636817 -381.32359) (xy 16.644651 -381.377762) (xy 16.645128 -381.40513)
			(xy 16.644642 -381.432381) (xy 16.636886 -381.486329) (xy 16.621531 -381.538624) (xy 16.598889 -381.588201)
			(xy 16.569423 -381.634051) (xy 16.533732 -381.675242) (xy 16.492541 -381.710933) (xy 16.446691 -381.740399)
			(xy 16.397114 -381.763041) (xy 16.344819 -381.778396) (xy 16.290871 -381.786152) (xy 16.236369 -381.786152)
			(xy 16.182421 -381.778396) (xy 16.130126 -381.763041) (xy 16.080549 -381.740399) (xy 16.034699 -381.710933)
			(xy 15.993508 -381.675242) (xy 15.957817 -381.634051) (xy 15.928351 -381.588201) (xy 15.905709 -381.538624)
			(xy 15.890354 -381.486329) (xy 15.882598 -381.432381) (xy 15.882112 -381.40513) (xy 8.935212 -381.40513)
			(xy 10.904474 -383.374392) (xy 10.921696 -383.392502) (xy 10.949437 -383.434063) (xy 10.968549 -383.480232)
			(xy 10.978299 -383.52924) (xy 10.978896 -383.554224) (xy 10.978896 -385.696968) (xy 10.979332 -385.707033)
			(xy 10.987063 -385.72562) (xy 10.993882 -385.733036) (xy 13.860018 -388.599172) (xy 13.877237 -388.617283)
			(xy 13.904971 -388.658844) (xy 13.924073 -388.705014) (xy 13.933811 -388.754021) (xy 13.93444 -388.779004)
			(xy 13.93444 -389.571484) (xy 20.902166 -389.571484) (xy 20.906237 -389.515862) (xy 20.918363 -389.461425)
			(xy 20.938286 -389.409334) (xy 20.965582 -389.360699) (xy 20.999668 -389.316556) (xy 21.039817 -389.277847)
			(xy 21.085175 -389.245396) (xy 21.134775 -389.219895) (xy 21.187559 -389.201888) (xy 21.242402 -389.191758)
			(xy 21.298136 -389.189721) (xy 21.353573 -389.195821) (xy 21.40753 -389.209927) (xy 21.458859 -389.231739)
			(xy 21.506465 -389.260793) (xy 21.549333 -389.296468) (xy 21.58655 -389.338005) (xy 21.617323 -389.384518)
			(xy 21.640995 -389.435015) (xy 21.657063 -389.488422) (xy 21.665183 -389.543598) (xy 21.665692 -389.571484)
			(xy 21.665183 -389.59937) (xy 21.657063 -389.654546) (xy 21.640995 -389.707953) (xy 21.617323 -389.75845)
			(xy 21.58655 -389.804963) (xy 21.549333 -389.8465) (xy 21.506465 -389.882175) (xy 21.458859 -389.911229)
			(xy 21.40753 -389.933041) (xy 21.353573 -389.947147) (xy 21.298136 -389.953247) (xy 21.242402 -389.95121)
			(xy 21.187559 -389.94108) (xy 21.134775 -389.923073) (xy 21.085175 -389.897572) (xy 21.039817 -389.865121)
			(xy 20.999668 -389.826412) (xy 20.965582 -389.782269) (xy 20.938286 -389.733634) (xy 20.918363 -389.681543)
			(xy 20.906237 -389.627106) (xy 20.902166 -389.571484) (xy 13.93444 -389.571484) (xy 13.93444 -390.777222)
			(xy 13.934868 -390.78729) (xy 13.942593 -390.805884) (xy 13.949426 -390.81329) (xy 14.028416 -390.89228)
			(xy 16.845547 -390.89228) (xy 16.849529 -390.839131) (xy 16.861389 -390.787169) (xy 16.880861 -390.737556)
			(xy 16.90751 -390.691398) (xy 16.940741 -390.649728) (xy 16.979811 -390.613476) (xy 17.023848 -390.583452)
			(xy 17.071868 -390.560327) (xy 17.122798 -390.544617) (xy 17.175501 -390.536674) (xy 17.20215 -390.536176)
			(xy 17.22851 -390.536672) (xy 17.280651 -390.544458) (xy 17.331072 -390.559853) (xy 17.37867 -390.582519)
			(xy 17.422403 -390.61196) (xy 17.44218 -390.629394) (xy 17.449292 -390.635744) (xy 17.467072 -390.642602)
			(xy 17.554448 -390.642602) (xy 17.572228 -390.635744) (xy 17.57934 -390.629394) (xy 17.599135 -390.611984)
			(xy 17.642872 -390.582557) (xy 17.690467 -390.559894) (xy 17.74088 -390.544488) (xy 17.793013 -390.536675)
			(xy 17.81937 -390.536176) (xy 17.84573 -390.53666) (xy 17.897872 -390.544449) (xy 17.948294 -390.559846)
			(xy 17.995891 -390.582515) (xy 18.039623 -390.611959) (xy 18.0594 -390.629394) (xy 18.066512 -390.635744)
			(xy 18.084292 -390.642602) (xy 18.171668 -390.642602) (xy 18.189448 -390.635744) (xy 18.19656 -390.629394)
			(xy 18.216347 -390.611974) (xy 18.260086 -390.582549) (xy 18.307683 -390.559888) (xy 18.358098 -390.544484)
			(xy 18.410232 -390.536674) (xy 18.43659 -390.536176) (xy 18.461586 -390.536601) (xy 18.511085 -390.543597)
			(xy 18.559123 -390.55744) (xy 18.604755 -390.577857) (xy 18.647087 -390.604449) (xy 18.66646 -390.62025)
			(xy 18.673572 -390.626346) (xy 18.690082 -390.632442) (xy 18.774156 -390.632442) (xy 18.790666 -390.626346)
			(xy 18.797778 -390.62025) (xy 18.817138 -390.604432) (xy 18.85947 -390.577833) (xy 18.905105 -390.557415)
			(xy 18.953146 -390.543578) (xy 19.002651 -390.536595) (xy 19.027648 -390.536176) (xy 19.053974 -390.536628)
			(xy 19.106051 -390.544396) (xy 19.156413 -390.559754) (xy 19.203962 -390.582368) (xy 19.247659 -390.611743)
			(xy 19.267424 -390.62914) (xy 19.277076 -390.637776) (xy 19.301714 -390.643872) (xy 19.408648 -390.616948)
			(xy 19.427444 -390.599676) (xy 19.431762 -390.587738) (xy 19.44086 -390.563228) (xy 19.464763 -390.516732)
			(xy 19.494791 -390.473936) (xy 19.530383 -390.435642) (xy 19.57087 -390.402567) (xy 19.615495 -390.37533)
			(xy 19.663421 -390.354442) (xy 19.71375 -390.340295) (xy 19.76554 -390.333153) (xy 19.79168 -390.332722)
			(xy 19.818936 -390.333124) (xy 19.872893 -390.340879) (xy 19.925198 -390.356234) (xy 19.974784 -390.378878)
			(xy 20.020644 -390.408347) (xy 20.061842 -390.444044) (xy 20.087094 -390.473184) (xy 20.905976 -390.473184)
			(xy 20.910047 -390.417562) (xy 20.922173 -390.363125) (xy 20.942096 -390.311034) (xy 20.969392 -390.262399)
			(xy 21.003478 -390.218256) (xy 21.043627 -390.179547) (xy 21.088985 -390.147096) (xy 21.138585 -390.121595)
			(xy 21.191369 -390.103588) (xy 21.246212 -390.093458) (xy 21.301946 -390.091421) (xy 21.357383 -390.097521)
			(xy 21.41134 -390.111627) (xy 21.462669 -390.133439) (xy 21.510275 -390.162493) (xy 21.553143 -390.198168)
			(xy 21.59036 -390.239705) (xy 21.621133 -390.286218) (xy 21.644805 -390.336715) (xy 21.660873 -390.390122)
			(xy 21.668993 -390.445298) (xy 21.669502 -390.473184) (xy 21.668993 -390.50107) (xy 21.660873 -390.556246)
			(xy 21.644805 -390.609653) (xy 21.621133 -390.66015) (xy 21.59036 -390.706663) (xy 21.553143 -390.7482)
			(xy 21.510275 -390.783875) (xy 21.462669 -390.812929) (xy 21.41134 -390.834741) (xy 21.357383 -390.848847)
			(xy 21.301946 -390.854947) (xy 21.246212 -390.85291) (xy 21.191369 -390.84278) (xy 21.138585 -390.824773)
			(xy 21.088985 -390.799272) (xy 21.043627 -390.766821) (xy 21.003478 -390.728112) (xy 20.969392 -390.683969)
			(xy 20.942096 -390.635334) (xy 20.922173 -390.583243) (xy 20.910047 -390.528806) (xy 20.905976 -390.473184)
			(xy 20.087094 -390.473184) (xy 20.097541 -390.48524) (xy 20.127013 -390.531098) (xy 20.149659 -390.580683)
			(xy 20.165017 -390.632987) (xy 20.172775 -390.686944) (xy 20.172775 -390.741456) (xy 20.165017 -390.795413)
			(xy 20.149659 -390.847717) (xy 20.129297 -390.8923) (xy 25.924276 -390.8923) (xy 25.928259 -390.839151)
			(xy 25.940119 -390.787188) (xy 25.95959 -390.737574) (xy 25.986238 -390.691416) (xy 26.019467 -390.649744)
			(xy 26.058536 -390.613491) (xy 26.102572 -390.583464) (xy 26.150591 -390.560336) (xy 26.20152 -390.544623)
			(xy 26.254223 -390.536676) (xy 26.280872 -390.536176) (xy 26.307232 -390.536658) (xy 26.359374 -390.544448)
			(xy 26.409796 -390.559846) (xy 26.457393 -390.582515) (xy 26.501125 -390.611959) (xy 26.520902 -390.629394)
			(xy 26.528014 -390.635744) (xy 26.545794 -390.642602) (xy 26.63317 -390.642602) (xy 26.65095 -390.635744)
			(xy 26.658062 -390.629394) (xy 26.677848 -390.611973) (xy 26.721588 -390.582548) (xy 26.769185 -390.559887)
			(xy 26.8196 -390.544484) (xy 26.871734 -390.536674) (xy 26.898092 -390.536176) (xy 26.924453 -390.536646)
			(xy 26.976595 -390.544439) (xy 27.027017 -390.55984) (xy 27.074614 -390.582511) (xy 27.118346 -390.611958)
			(xy 27.138122 -390.629394) (xy 27.145234 -390.635744) (xy 27.163014 -390.642602) (xy 27.25039 -390.642602)
			(xy 27.26817 -390.635744) (xy 27.275282 -390.629394) (xy 27.29506 -390.611964) (xy 27.338802 -390.58254)
			(xy 27.386401 -390.559881) (xy 27.436818 -390.54448) (xy 27.488954 -390.536672) (xy 27.515312 -390.536176)
			(xy 27.540308 -390.536589) (xy 27.589808 -390.543588) (xy 27.637846 -390.557433) (xy 27.683478 -390.577853)
			(xy 27.72581 -390.604448) (xy 27.745182 -390.62025) (xy 27.752294 -390.626346) (xy 27.768804 -390.632442)
			(xy 27.852878 -390.632442) (xy 27.869388 -390.626346) (xy 27.8765 -390.62025) (xy 27.895852 -390.604422)
			(xy 27.938186 -390.577825) (xy 27.983823 -390.557409) (xy 28.031866 -390.543574) (xy 28.081372 -390.536593)
			(xy 28.10637 -390.536176) (xy 28.133805 -390.53668) (xy 28.188024 -390.545101) (xy 28.21432 -390.55294)
			(xy 28.22575 -390.556496) (xy 28.24861 -390.553194) (xy 28.334462 -390.49452) (xy 28.345892 -390.4742)
			(xy 28.346654 -390.462516) (xy 28.348971 -390.433797) (xy 28.361097 -390.377473) (xy 28.381556 -390.323614)
			(xy 28.409882 -390.273444) (xy 28.445432 -390.228105) (xy 28.487397 -390.188628) (xy 28.534821 -390.155912)
			(xy 28.586626 -390.130701) (xy 28.641634 -390.113568) (xy 28.698593 -390.104903) (xy 28.7274 -390.104376)
			(xy 28.75465 -390.104894) (xy 28.808595 -390.11265) (xy 28.860888 -390.128005) (xy 28.910463 -390.150645)
			(xy 28.956311 -390.18011) (xy 28.9975 -390.2158) (xy 29.03319 -390.256989) (xy 29.062655 -390.302837)
			(xy 29.085295 -390.352412) (xy 29.10065 -390.404705) (xy 29.108406 -390.45865) (xy 29.108406 -390.51315)
			(xy 29.10065 -390.567095) (xy 29.085295 -390.619388) (xy 29.062655 -390.668963) (xy 29.03319 -390.714811)
			(xy 28.9975 -390.756) (xy 28.956311 -390.79169) (xy 28.910463 -390.821155) (xy 28.860888 -390.843795)
			(xy 28.808595 -390.85915) (xy 28.75465 -390.866906) (xy 28.7274 -390.867392) (xy 28.693996 -390.866697)
			(xy 28.628208 -390.855075) (xy 28.59659 -390.844278) (xy 28.585414 -390.840214) (xy 28.5623 -390.8425)
			(xy 28.474162 -390.897618) (xy 28.461716 -390.91743) (xy 28.460446 -390.929114) (xy 28.457324 -390.955063)
			(xy 28.444379 -391.0057) (xy 28.424171 -391.053902) (xy 28.397134 -391.098631) (xy 28.36385 -391.138928)
			(xy 28.325032 -391.173926) (xy 28.281516 -391.202875) (xy 28.234235 -391.225151) (xy 28.184206 -391.240277)
			(xy 28.132503 -391.247927) (xy 28.10637 -391.248392) (xy 28.081375 -391.24794) (xy 28.031876 -391.240951)
			(xy 27.983839 -391.227115) (xy 27.938206 -391.206704) (xy 27.895873 -391.180117) (xy 27.8765 -391.164318)
			(xy 27.869388 -391.158222) (xy 27.852878 -391.152126) (xy 27.768804 -391.152126) (xy 27.752294 -391.158222)
			(xy 27.745182 -391.164318) (xy 27.725796 -391.180103) (xy 27.683472 -391.206708) (xy 27.637844 -391.227133)
			(xy 27.589808 -391.240977) (xy 27.540308 -391.247969) (xy 27.515312 -391.248392) (xy 27.488951 -391.247927)
			(xy 27.436808 -391.240135) (xy 27.386386 -391.224733) (xy 27.338788 -391.20206) (xy 27.295058 -391.172611)
			(xy 27.275282 -391.155174) (xy 27.26817 -391.148824) (xy 27.25039 -391.141966) (xy 27.163014 -391.141966)
			(xy 27.145234 -391.148824) (xy 27.138122 -391.155174) (xy 27.118352 -391.172614) (xy 27.074607 -391.202033)
			(xy 27.027006 -391.22469) (xy 26.976587 -391.24009) (xy 26.924451 -391.247896) (xy 26.898092 -391.248392)
			(xy 26.871731 -391.247939) (xy 26.819587 -391.240144) (xy 26.769165 -391.22474) (xy 26.721567 -391.202064)
			(xy 26.677837 -391.172612) (xy 26.658062 -391.155174) (xy 26.65095 -391.148824) (xy 26.63317 -391.141966)
			(xy 26.545794 -391.141966) (xy 26.528014 -391.148824) (xy 26.520902 -391.155174) (xy 26.50114 -391.172623)
			(xy 26.457393 -391.202042) (xy 26.40979 -391.224696) (xy 26.359369 -391.240094) (xy 26.307231 -391.247897)
			(xy 26.280872 -391.248392) (xy 26.254223 -391.247924) (xy 26.20152 -391.239977) (xy 26.150591 -391.224264)
			(xy 26.102572 -391.201136) (xy 26.058536 -391.171109) (xy 26.019467 -391.134856) (xy 25.986238 -391.093184)
			(xy 25.95959 -391.047026) (xy 25.940119 -390.997412) (xy 25.928259 -390.945449) (xy 25.924276 -390.8923)
			(xy 20.129297 -390.8923) (xy 20.127013 -390.897302) (xy 20.097541 -390.94316) (xy 20.061842 -390.984356)
			(xy 20.020644 -391.020053) (xy 19.974784 -391.049522) (xy 19.925198 -391.072166) (xy 19.872893 -391.087521)
			(xy 19.818936 -391.095276) (xy 19.79168 -391.095738) (xy 19.762096 -391.095179) (xy 19.703637 -391.086042)
			(xy 19.64729 -391.06799) (xy 19.594405 -391.041455) (xy 19.546251 -391.007075) (xy 19.524726 -390.986772)
			(xy 19.515582 -390.977882) (xy 19.491198 -390.97077) (xy 19.383248 -390.993884) (xy 19.363944 -391.010394)
			(xy 19.359118 -391.022332) (xy 19.348961 -391.046979) (xy 19.322322 -391.093153) (xy 19.289095 -391.134839)
			(xy 19.250024 -391.171104) (xy 19.205982 -391.201138) (xy 19.157955 -391.22427) (xy 19.107015 -391.239981)
			(xy 19.054302 -391.247922) (xy 19.027648 -391.248392) (xy 19.002653 -391.247952) (xy 18.953153 -391.240961)
			(xy 18.905116 -391.227122) (xy 18.859484 -391.206708) (xy 18.817151 -391.180118) (xy 18.797778 -391.164318)
			(xy 18.790666 -391.158222) (xy 18.774156 -391.152126) (xy 18.690082 -391.152126) (xy 18.673572 -391.158222)
			(xy 18.66646 -391.164318) (xy 18.647082 -391.180114) (xy 18.604756 -391.206717) (xy 18.559125 -391.22714)
			(xy 18.511088 -391.240982) (xy 18.461586 -391.247971) (xy 18.43659 -391.248392) (xy 18.410229 -391.247941)
			(xy 18.358085 -391.240145) (xy 18.307663 -391.22474) (xy 18.260065 -391.202064) (xy 18.216335 -391.172613)
			(xy 18.19656 -391.155174) (xy 18.189448 -391.148824) (xy 18.171668 -391.141966) (xy 18.084292 -391.141966)
			(xy 18.066512 -391.148824) (xy 18.0594 -391.155174) (xy 18.039599 -391.172577) (xy 17.995862 -391.202002)
			(xy 17.948269 -391.224666) (xy 17.897857 -391.240074) (xy 17.845726 -391.24789) (xy 17.81937 -391.248392)
			(xy 17.79301 -391.247893) (xy 17.740869 -391.240108) (xy 17.690447 -391.224715) (xy 17.642849 -391.202049)
			(xy 17.599117 -391.172608) (xy 17.57934 -391.155174) (xy 17.572228 -391.148824) (xy 17.554448 -391.141966)
			(xy 17.467072 -391.141966) (xy 17.449292 -391.148824) (xy 17.44218 -391.155174) (xy 17.422387 -391.172586)
			(xy 17.378648 -391.20201) (xy 17.331053 -391.224672) (xy 17.280639 -391.240078) (xy 17.228507 -391.247892)
			(xy 17.20215 -391.248392) (xy 17.175501 -391.247886) (xy 17.122798 -391.239943) (xy 17.071868 -391.224233)
			(xy 17.023848 -391.201108) (xy 16.979811 -391.171084) (xy 16.940741 -391.134832) (xy 16.90751 -391.093162)
			(xy 16.880861 -391.047004) (xy 16.861389 -390.997391) (xy 16.849529 -390.945429) (xy 16.845547 -390.89228)
			(xy 14.028416 -390.89228) (xy 14.386814 -391.250678) (xy 14.394212 -391.257525) (xy 14.41281 -391.265257)
			(xy 14.422882 -391.265664) (xy 16.818356 -391.265664) (xy 16.843341 -391.266271) (xy 16.892354 -391.276006)
			(xy 16.938528 -391.29511) (xy 16.98009 -391.32285) (xy 16.998188 -391.340086) (xy 17.419828 -391.761726)
			(xy 18.769076 -391.761726) (xy 18.769579 -391.734475) (xy 18.777332 -391.680526) (xy 18.792684 -391.62823)
			(xy 18.815323 -391.578651) (xy 18.844787 -391.532798) (xy 18.880476 -391.491606) (xy 18.921665 -391.455912)
			(xy 18.967514 -391.426443) (xy 19.01709 -391.403799) (xy 19.069385 -391.388441) (xy 19.123333 -391.380682)
			(xy 19.150584 -391.380218) (xy 19.176567 -391.380641) (xy 19.22805 -391.387704) (xy 19.278098 -391.401688)
			(xy 19.325786 -391.422335) (xy 19.370231 -391.449262) (xy 19.410611 -391.481971) (xy 19.428714 -391.500614)
			(xy 19.435826 -391.508234) (xy 19.454114 -391.516362) (xy 19.546824 -391.519156) (xy 19.56562 -391.51179)
			(xy 19.572986 -391.504678) (xy 19.594416 -391.48501) (xy 19.642122 -391.451735) (xy 19.694323 -391.42608)
			(xy 19.749811 -391.408639) (xy 19.807302 -391.399815) (xy 19.836384 -391.399268) (xy 19.863634 -391.399793)
			(xy 19.917579 -391.407547) (xy 19.969871 -391.422899) (xy 20.019447 -391.445536) (xy 20.065296 -391.474998)
			(xy 20.106486 -391.510686) (xy 20.142178 -391.551872) (xy 20.171645 -391.597718) (xy 20.194287 -391.647291)
			(xy 20.209645 -391.699582) (xy 20.215843 -391.742676) (xy 20.730716 -391.742676) (xy 20.734787 -391.687054)
			(xy 20.746913 -391.632617) (xy 20.766836 -391.580526) (xy 20.794132 -391.531891) (xy 20.828218 -391.487748)
			(xy 20.868367 -391.449039) (xy 20.913725 -391.416588) (xy 20.963325 -391.391087) (xy 21.016109 -391.37308)
			(xy 21.070952 -391.36295) (xy 21.126686 -391.360913) (xy 21.182123 -391.367013) (xy 21.23608 -391.381119)
			(xy 21.287409 -391.402931) (xy 21.335015 -391.431985) (xy 21.377883 -391.46766) (xy 21.4151 -391.509197)
			(xy 21.445873 -391.55571) (xy 21.469545 -391.606207) (xy 21.485613 -391.659614) (xy 21.493733 -391.71479)
			(xy 21.494242 -391.742676) (xy 21.493733 -391.770562) (xy 21.487557 -391.812526) (xy 27.862276 -391.812526)
			(xy 27.862779 -391.785275) (xy 27.870532 -391.731326) (xy 27.885884 -391.67903) (xy 27.908523 -391.629451)
			(xy 27.937987 -391.583598) (xy 27.973676 -391.542406) (xy 28.014865 -391.506712) (xy 28.060714 -391.477243)
			(xy 28.11029 -391.454599) (xy 28.162585 -391.439241) (xy 28.216533 -391.431482) (xy 28.243784 -391.431018)
			(xy 28.273907 -391.431608) (xy 28.333402 -391.441086) (xy 28.390669 -391.459793) (xy 28.444286 -391.487264)
			(xy 28.492922 -391.522818) (xy 28.514548 -391.543794) (xy 28.522422 -391.551668) (xy 28.542234 -391.559288)
			(xy 28.640024 -391.554208) (xy 28.659074 -391.544302) (xy 28.665932 -391.535666) (xy 28.68415 -391.513789)
			(xy 28.725992 -391.475185) (xy 28.773102 -391.443223) (xy 28.824436 -391.41861) (xy 28.878856 -391.401893)
			(xy 28.935155 -391.393442) (xy 28.96362 -391.392918) (xy 28.990875 -391.393336) (xy 29.044828 -391.401097)
			(xy 29.097129 -391.416457) (xy 29.146711 -391.439103) (xy 29.192565 -391.468576) (xy 29.233758 -391.504274)
			(xy 29.269452 -391.545472) (xy 29.298919 -391.59133) (xy 29.321559 -391.640914) (xy 29.336913 -391.693217)
			(xy 29.344667 -391.747171) (xy 29.345128 -391.774426) (xy 29.344717 -391.800035) (xy 29.337855 -391.850792)
			(xy 29.324271 -391.900177) (xy 29.304209 -391.947303) (xy 29.278029 -391.991325) (xy 29.246201 -392.031453)
			(xy 29.228034 -392.049508) (xy 29.218636 -392.058398) (xy 29.211016 -392.082782) (xy 29.231082 -392.191494)
			(xy 29.247084 -392.211306) (xy 29.259022 -392.216386) (xy 29.284595 -392.227703) (xy 29.332418 -392.256689)
			(xy 29.375495 -392.292347) (xy 29.412903 -392.333914) (xy 29.443839 -392.380499) (xy 29.46764 -392.431103)
			(xy 29.483795 -392.484639) (xy 29.491959 -392.539961) (xy 29.492448 -392.567922) (xy 29.491943 -392.595172)
			(xy 29.484184 -392.649117) (xy 29.468828 -392.701409) (xy 29.446188 -392.750983) (xy 29.416723 -392.796832)
			(xy 29.381034 -392.838021) (xy 29.339846 -392.873712) (xy 29.293999 -392.903179) (xy 29.244426 -392.925822)
			(xy 29.192135 -392.94118) (xy 29.13819 -392.948942) (xy 29.11094 -392.94943) (xy 29.080673 -392.948837)
			(xy 29.0209 -392.939271) (xy 28.963386 -392.920389) (xy 28.909575 -392.892664) (xy 28.860815 -392.856792)
			(xy 28.83916 -392.835638) (xy 28.832048 -392.828272) (xy 28.813506 -392.820652) (xy 28.720288 -392.820652)
			(xy 28.701746 -392.828272) (xy 28.694634 -392.835638) (xy 28.672998 -392.856814) (xy 28.624238 -392.892693)
			(xy 28.570422 -392.92042) (xy 28.512903 -392.939298) (xy 28.453123 -392.948853) (xy 28.422854 -392.94943)
			(xy 28.395603 -392.948965) (xy 28.341655 -392.941203) (xy 28.289362 -392.925843) (xy 28.239786 -392.903198)
			(xy 28.193936 -392.873729) (xy 28.152747 -392.838036) (xy 28.117057 -392.796844) (xy 28.08759 -392.750993)
			(xy 28.064949 -392.701416) (xy 28.049592 -392.649121) (xy 28.041833 -392.595173) (xy 28.041346 -392.567922)
			(xy 28.041819 -392.541189) (xy 28.049324 -392.488253) (xy 28.064134 -392.436879) (xy 28.085961 -392.38807)
			(xy 28.114378 -392.342781) (xy 28.131262 -392.32205) (xy 28.138882 -392.312652) (xy 28.14447 -392.289284)
			(xy 28.120086 -392.186414) (xy 28.104592 -392.167872) (xy 28.093416 -392.1633) (xy 28.068068 -392.151839)
			(xy 28.020679 -392.122711) (xy 27.978019 -392.087013) (xy 27.940992 -392.045501) (xy 27.910382 -391.999054)
			(xy 27.886838 -391.948656) (xy 27.870858 -391.895375) (xy 27.862781 -391.840339) (xy 27.862276 -391.812526)
			(xy 21.487557 -391.812526) (xy 21.485613 -391.825738) (xy 21.469545 -391.879145) (xy 21.445873 -391.929642)
			(xy 21.4151 -391.976155) (xy 21.377883 -392.017692) (xy 21.335015 -392.053367) (xy 21.287409 -392.082421)
			(xy 21.23608 -392.104233) (xy 21.182123 -392.118339) (xy 21.126686 -392.124439) (xy 21.070952 -392.122402)
			(xy 21.016109 -392.112272) (xy 20.963325 -392.094265) (xy 20.913725 -392.068764) (xy 20.868367 -392.036313)
			(xy 20.828218 -391.997604) (xy 20.794132 -391.953461) (xy 20.766836 -391.904826) (xy 20.746913 -391.852735)
			(xy 20.734787 -391.798298) (xy 20.730716 -391.742676) (xy 20.215843 -391.742676) (xy 20.217404 -391.753526)
			(xy 20.217892 -391.780776) (xy 20.217454 -391.807389) (xy 20.210053 -391.860097) (xy 20.195392 -391.911264)
			(xy 20.173755 -391.959893) (xy 20.145564 -392.00504) (xy 20.111367 -392.045826) (xy 20.091908 -392.063986)
			(xy 20.081748 -392.07313) (xy 20.07362 -392.099038) (xy 20.098004 -392.212068) (xy 20.116292 -392.232134)
			(xy 20.1295 -392.236198) (xy 20.154903 -392.244743) (xy 20.203216 -392.267948) (xy 20.247807 -392.297683)
			(xy 20.2878 -392.333364) (xy 20.322409 -392.374289) (xy 20.350951 -392.419653) (xy 20.372867 -392.468564)
			(xy 20.387726 -392.52006) (xy 20.395234 -392.573128) (xy 20.395692 -392.599926) (xy 20.395246 -392.627179)
			(xy 20.387486 -392.681129) (xy 20.372127 -392.733425) (xy 20.349481 -392.783003) (xy 20.341544 -392.795352)
			(xy 24.261552 -392.795352) (xy 24.261552 -392.740848) (xy 24.269308 -392.686899) (xy 24.284663 -392.634603)
			(xy 24.307303 -392.585024) (xy 24.336769 -392.539172) (xy 24.37246 -392.49798) (xy 24.41365 -392.462286)
			(xy 24.4595 -392.432817) (xy 24.509077 -392.410173) (xy 24.561372 -392.394814) (xy 24.61532 -392.387054)
			(xy 24.642572 -392.386566) (xy 24.668493 -392.386996) (xy 24.719856 -392.394035) (xy 24.769793 -392.407961)
			(xy 24.817387 -392.428516) (xy 24.861761 -392.455323) (xy 24.902098 -392.487889) (xy 24.920194 -392.506454)
			(xy 24.92756 -392.514328) (xy 24.946864 -392.522456) (xy 25.043384 -392.521186) (xy 25.062434 -392.51255)
			(xy 25.0698 -392.504422) (xy 25.087992 -392.484869) (xy 25.128845 -392.450472) (xy 25.174096 -392.42211)
			(xy 25.222861 -392.400337) (xy 25.274187 -392.385579) (xy 25.327069 -392.378126) (xy 25.353772 -392.377676)
			(xy 25.381025 -392.378169) (xy 25.434977 -392.385923) (xy 25.487276 -392.401276) (xy 25.536857 -392.423916)
			(xy 25.582712 -392.453382) (xy 25.623906 -392.489074) (xy 25.659601 -392.530266) (xy 25.689071 -392.576118)
			(xy 25.711714 -392.625698) (xy 25.727071 -392.677996) (xy 25.734829 -392.731947) (xy 25.734829 -392.786453)
			(xy 25.727071 -392.840404) (xy 25.711714 -392.892702) (xy 25.689071 -392.942282) (xy 25.659601 -392.988134)
			(xy 25.623906 -393.029326) (xy 25.582712 -393.065018) (xy 25.536857 -393.094484) (xy 25.487276 -393.117124)
			(xy 25.434977 -393.132477) (xy 25.381025 -393.140231) (xy 25.353772 -393.140692) (xy 25.327851 -393.140246)
			(xy 25.276489 -393.133212) (xy 25.226551 -393.119291) (xy 25.178957 -393.098738) (xy 25.134583 -393.071933)
			(xy 25.094245 -393.039369) (xy 25.07615 -393.020804) (xy 25.068784 -393.01293) (xy 25.04948 -393.004802)
			(xy 24.95296 -393.006072) (xy 24.93391 -393.014708) (xy 24.926544 -393.022836) (xy 24.908391 -393.042427)
			(xy 24.867529 -393.076819) (xy 24.822269 -393.105175) (xy 24.773496 -393.126941) (xy 24.722164 -393.14169)
			(xy 24.669277 -393.149136) (xy 24.642572 -393.149582) (xy 24.61532 -393.149146) (xy 24.561372 -393.141386)
			(xy 24.509077 -393.126027) (xy 24.4595 -393.103383) (xy 24.41365 -393.073914) (xy 24.37246 -393.03822)
			(xy 24.336769 -392.997028) (xy 24.307303 -392.951176) (xy 24.284663 -392.901597) (xy 24.269308 -392.849301)
			(xy 24.261552 -392.795352) (xy 20.341544 -392.795352) (xy 20.320011 -392.828855) (xy 20.284315 -392.870045)
			(xy 20.243121 -392.905736) (xy 20.197267 -392.935201) (xy 20.147686 -392.957841) (xy 20.095388 -392.973195)
			(xy 20.041437 -392.980949) (xy 20.014184 -392.981434) (xy 19.985268 -392.98088) (xy 19.928097 -392.972162)
			(xy 19.872898 -392.954913) (xy 19.820936 -392.929528) (xy 19.773401 -392.896589) (xy 19.731384 -392.856852)
			(xy 19.713194 -392.834368) (xy 19.705636 -392.825602) (xy 19.684874 -392.815422) (xy 19.673316 -392.81481)
			(xy 19.593052 -392.81481) (xy 19.581488 -392.815407) (xy 19.560716 -392.825583) (xy 19.553174 -392.834368)
			(xy 19.53499 -392.856857) (xy 19.492969 -392.896594) (xy 19.445433 -392.929533) (xy 19.393471 -392.954921)
			(xy 19.338272 -392.972175) (xy 19.281101 -392.980901) (xy 19.252184 -392.981434) (xy 19.224934 -392.980937)
			(xy 19.170988 -392.973179) (xy 19.118695 -392.957823) (xy 19.069119 -392.935182) (xy 19.02327 -392.905717)
			(xy 18.982081 -392.870026) (xy 18.946389 -392.828838) (xy 18.916923 -392.78299) (xy 18.89428 -392.733415)
			(xy 18.878923 -392.681122) (xy 18.871164 -392.627176) (xy 18.870676 -392.599926) (xy 18.871129 -392.574237)
			(xy 18.878021 -392.523325) (xy 18.891684 -392.473798) (xy 18.91187 -392.426553) (xy 18.938215 -392.382444)
			(xy 18.970241 -392.342271) (xy 19.007369 -392.306759) (xy 19.027902 -392.291316) (xy 19.039078 -392.283188)
			(xy 19.050254 -392.257788) (xy 19.036284 -392.142218) (xy 19.01952 -392.12012) (xy 19.006566 -392.11504)
			(xy 18.980604 -392.103918) (xy 18.932023 -392.07511) (xy 18.888218 -392.039457) (xy 18.850147 -391.997737)
			(xy 18.81864 -391.950861) (xy 18.794387 -391.899854) (xy 18.777916 -391.845829) (xy 18.769588 -391.789966)
			(xy 18.769076 -391.761726) (xy 17.419828 -391.761726) (xy 18.667222 -393.00912) (xy 18.684445 -393.02723)
			(xy 18.712187 -393.06879) (xy 18.731298 -393.114959) (xy 18.741045 -393.163968) (xy 18.741644 -393.188952)
			(xy 18.741644 -393.482068) (xy 23.315166 -393.482068) (xy 23.319237 -393.426446) (xy 23.331363 -393.372009)
			(xy 23.351286 -393.319918) (xy 23.378582 -393.271283) (xy 23.412668 -393.22714) (xy 23.452817 -393.188431)
			(xy 23.498175 -393.15598) (xy 23.547775 -393.130479) (xy 23.600559 -393.112472) (xy 23.655402 -393.102342)
			(xy 23.711136 -393.100305) (xy 23.766573 -393.106405) (xy 23.82053 -393.120511) (xy 23.871859 -393.142323)
			(xy 23.919465 -393.171377) (xy 23.962333 -393.207052) (xy 23.99955 -393.248589) (xy 24.030323 -393.295102)
			(xy 24.053995 -393.345599) (xy 24.070063 -393.399006) (xy 24.078183 -393.454182) (xy 24.078692 -393.482068)
			(xy 24.078183 -393.509954) (xy 24.070063 -393.56513) (xy 24.053995 -393.618537) (xy 24.030323 -393.669034)
			(xy 23.99955 -393.715547) (xy 23.962333 -393.757084) (xy 23.957065 -393.761468) (xy 25.528776 -393.761468)
			(xy 25.532847 -393.705846) (xy 25.544973 -393.651409) (xy 25.564896 -393.599318) (xy 25.592192 -393.550683)
			(xy 25.626278 -393.50654) (xy 25.666427 -393.467831) (xy 25.711785 -393.43538) (xy 25.761385 -393.409879)
			(xy 25.814169 -393.391872) (xy 25.869012 -393.381742) (xy 25.924746 -393.379705) (xy 25.980183 -393.385805)
			(xy 26.03414 -393.399911) (xy 26.085469 -393.421723) (xy 26.133075 -393.450777) (xy 26.175943 -393.486452)
			(xy 26.21316 -393.527989) (xy 26.243933 -393.574502) (xy 26.267605 -393.624999) (xy 26.283673 -393.678406)
			(xy 26.291793 -393.733582) (xy 26.292302 -393.761468) (xy 26.291793 -393.789354) (xy 26.283673 -393.84453)
			(xy 26.267605 -393.897937) (xy 26.243933 -393.948434) (xy 26.21316 -393.994947) (xy 26.175943 -394.036484)
			(xy 26.133075 -394.072159) (xy 26.085469 -394.101213) (xy 26.03414 -394.123025) (xy 25.980183 -394.137131)
			(xy 25.924746 -394.143231) (xy 25.869012 -394.141194) (xy 25.814169 -394.131064) (xy 25.761385 -394.113057)
			(xy 25.711785 -394.087556) (xy 25.666427 -394.055105) (xy 25.626278 -394.016396) (xy 25.592192 -393.972253)
			(xy 25.564896 -393.923618) (xy 25.544973 -393.871527) (xy 25.532847 -393.81709) (xy 25.528776 -393.761468)
			(xy 23.957065 -393.761468) (xy 23.919465 -393.792759) (xy 23.871859 -393.821813) (xy 23.82053 -393.843625)
			(xy 23.766573 -393.857731) (xy 23.711136 -393.863831) (xy 23.655402 -393.861794) (xy 23.600559 -393.851664)
			(xy 23.547775 -393.833657) (xy 23.498175 -393.808156) (xy 23.452817 -393.775705) (xy 23.412668 -393.736996)
			(xy 23.378582 -393.692853) (xy 23.351286 -393.644218) (xy 23.331363 -393.592127) (xy 23.319237 -393.53769)
			(xy 23.315166 -393.482068) (xy 18.741644 -393.482068) (xy 18.741644 -394.310452) (xy 22.100762 -394.310452)
			(xy 22.100762 -394.255948) (xy 22.108518 -394.201998) (xy 22.123874 -394.149702) (xy 22.146516 -394.100123)
			(xy 22.175983 -394.054271) (xy 22.211675 -394.013079) (xy 22.252866 -393.977386) (xy 22.298718 -393.947918)
			(xy 22.348296 -393.925276) (xy 22.400593 -393.90992) (xy 22.454542 -393.902162) (xy 22.481794 -393.901676)
			(xy 22.510712 -393.90217) (xy 22.567886 -393.9109) (xy 22.623086 -393.928161) (xy 22.675049 -393.953557)
			(xy 22.722582 -393.986506) (xy 22.764596 -394.026253) (xy 22.782784 -394.048742) (xy 22.79035 -394.057499)
			(xy 22.811106 -394.067683) (xy 22.822662 -394.0683) (xy 22.902926 -394.0683) (xy 22.914488 -394.067687)
			(xy 22.93526 -394.057523) (xy 22.942804 -394.048742) (xy 22.961003 -394.026265) (xy 23.00302 -393.986528)
			(xy 23.050553 -393.953587) (xy 23.102513 -393.928197) (xy 23.157709 -393.91094) (xy 23.214878 -393.902211)
			(xy 23.243794 -393.901676) (xy 23.271046 -393.902171) (xy 23.324995 -393.909927) (xy 23.377292 -393.925282)
			(xy 23.42687 -393.947923) (xy 23.472722 -393.97739) (xy 23.513914 -394.013082) (xy 23.549607 -394.054273)
			(xy 23.579074 -394.100124) (xy 23.601716 -394.149703) (xy 23.617072 -394.201999) (xy 23.624829 -394.255948)
			(xy 23.624829 -394.310452) (xy 23.617072 -394.364401) (xy 23.601716 -394.416697) (xy 23.579074 -394.466276)
			(xy 23.549607 -394.512127) (xy 23.513914 -394.553318) (xy 23.472722 -394.58901) (xy 23.42687 -394.618477)
			(xy 23.377292 -394.641118) (xy 23.324995 -394.656473) (xy 23.271046 -394.664229) (xy 23.243794 -394.664692)
			(xy 23.214877 -394.664181) (xy 23.157705 -394.655451) (xy 23.102506 -394.638191) (xy 23.050544 -394.612799)
			(xy 23.003011 -394.579854) (xy 22.960994 -394.540112) (xy 22.942804 -394.517626) (xy 22.935249 -394.508858)
			(xy 22.914484 -394.498681) (xy 22.902926 -394.498068) (xy 22.822662 -394.498068) (xy 22.811095 -394.49865)
			(xy 22.790322 -394.508834) (xy 22.782784 -394.517626) (xy 22.764609 -394.540123) (xy 22.722585 -394.579856)
			(xy 22.675046 -394.612792) (xy 22.623082 -394.638178) (xy 22.567882 -394.655432) (xy 22.510711 -394.664158)
			(xy 22.481794 -394.664692) (xy 22.454542 -394.664238) (xy 22.400593 -394.65648) (xy 22.348296 -394.641124)
			(xy 22.298718 -394.618482) (xy 22.252866 -394.589014) (xy 22.211675 -394.553321) (xy 22.175983 -394.512129)
			(xy 22.146516 -394.466277) (xy 22.123874 -394.416698) (xy 22.108518 -394.364402) (xy 22.100762 -394.310452)
			(xy 18.741644 -394.310452) (xy 18.741644 -395.964664) (xy 19.52498 -395.964664) (xy 19.525405 -395.937292)
			(xy 19.53323 -395.88311) (xy 19.548728 -395.830606) (xy 19.571579 -395.78086) (xy 19.601314 -395.734896)
			(xy 19.61896 -395.713966) (xy 19.625056 -395.706854) (xy 19.631406 -395.689836) (xy 19.631406 -395.604492)
			(xy 19.625056 -395.587474) (xy 19.61896 -395.580362) (xy 19.60133 -395.559423) (xy 19.571618 -395.513451)
			(xy 19.548781 -395.463706) (xy 19.533287 -395.411207) (xy 19.525456 -395.357033) (xy 19.52498 -395.329664)
			(xy 19.525466 -395.302413) (xy 19.533222 -395.248465) (xy 19.548577 -395.19617) (xy 19.571219 -395.146593)
			(xy 19.600685 -395.100743) (xy 19.636376 -395.059552) (xy 19.677567 -395.023861) (xy 19.723417 -394.994395)
			(xy 19.772994 -394.971753) (xy 19.825289 -394.956398) (xy 19.879237 -394.948642) (xy 19.933739 -394.948642)
			(xy 19.987687 -394.956398) (xy 20.039982 -394.971753) (xy 20.089559 -394.994395) (xy 20.135409 -395.023861)
			(xy 20.1766 -395.059552) (xy 20.212291 -395.100743) (xy 20.241757 -395.146593) (xy 20.264399 -395.19617)
			(xy 20.279754 -395.248465) (xy 20.28751 -395.302413) (xy 20.287996 -395.329664) (xy 20.28751 -395.357034)
			(xy 20.279697 -395.411212) (xy 20.264213 -395.463715) (xy 20.241375 -395.513462) (xy 20.211655 -395.55943)
			(xy 20.194016 -395.580362) (xy 20.18792 -395.587474) (xy 20.18157 -395.604492) (xy 20.18157 -395.689836)
			(xy 20.18792 -395.706854) (xy 20.194016 -395.713966) (xy 20.211655 -395.734898) (xy 20.23933 -395.77772)
			(xy 28.172664 -395.77772) (xy 28.173126 -395.750349) (xy 28.180943 -395.69617) (xy 28.196432 -395.643666)
			(xy 28.219275 -395.593919) (xy 28.249001 -395.547953) (xy 28.266644 -395.527022) (xy 28.27274 -395.51991)
			(xy 28.27909 -395.502892) (xy 28.27909 -395.417548) (xy 28.27274 -395.40053) (xy 28.266644 -395.393418)
			(xy 28.249007 -395.372484) (xy 28.219293 -395.326513) (xy 28.196456 -395.276766) (xy 28.180965 -395.224265)
			(xy 28.173137 -395.170089) (xy 28.172664 -395.14272) (xy 28.17315 -395.115469) (xy 28.180906 -395.061521)
			(xy 28.196261 -395.009226) (xy 28.218903 -394.959649) (xy 28.248369 -394.913799) (xy 28.28406 -394.872608)
			(xy 28.325251 -394.836917) (xy 28.371101 -394.807451) (xy 28.420678 -394.784809) (xy 28.472973 -394.769454)
			(xy 28.526921 -394.761698) (xy 28.581423 -394.761698) (xy 28.635371 -394.769454) (xy 28.687666 -394.784809)
			(xy 28.737243 -394.807451) (xy 28.783093 -394.836917) (xy 28.824284 -394.872608) (xy 28.859975 -394.913799)
			(xy 28.889441 -394.959649) (xy 28.912083 -395.009226) (xy 28.927438 -395.061521) (xy 28.935194 -395.115469)
			(xy 28.93568 -395.14272) (xy 28.935231 -395.170091) (xy 28.927409 -395.224271) (xy 28.911917 -395.276774)
			(xy 28.889071 -395.326521) (xy 28.859343 -395.372487) (xy 28.8417 -395.393418) (xy 28.835604 -395.40053)
			(xy 28.829254 -395.417548) (xy 28.829254 -395.502892) (xy 28.835604 -395.51991) (xy 28.8417 -395.527022)
			(xy 28.859316 -395.547973) (xy 28.889031 -395.59394) (xy 28.911872 -395.643683) (xy 28.927368 -395.69618)
			(xy 28.935203 -395.750352) (xy 28.93568 -395.77772) (xy 28.935194 -395.804971) (xy 28.927438 -395.858919)
			(xy 28.912083 -395.911214) (xy 28.889441 -395.960791) (xy 28.859975 -396.006641) (xy 28.824284 -396.047832)
			(xy 28.783093 -396.083523) (xy 28.737243 -396.112989) (xy 28.687666 -396.135631) (xy 28.635371 -396.150986)
			(xy 28.581423 -396.158742) (xy 28.526921 -396.158742) (xy 28.472973 -396.150986) (xy 28.420678 -396.135631)
			(xy 28.371101 -396.112989) (xy 28.325251 -396.083523) (xy 28.28406 -396.047832) (xy 28.248369 -396.006641)
			(xy 28.218903 -395.960791) (xy 28.196261 -395.911214) (xy 28.180906 -395.858919) (xy 28.17315 -395.804971)
			(xy 28.172664 -395.77772) (xy 20.23933 -395.77772) (xy 20.241366 -395.780871) (xy 20.264202 -395.830619)
			(xy 20.279693 -395.883119) (xy 20.287522 -395.937295) (xy 20.287996 -395.964664) (xy 20.28751 -395.991915)
			(xy 20.279754 -396.045863) (xy 20.264399 -396.098158) (xy 20.241757 -396.147735) (xy 20.212291 -396.193585)
			(xy 20.1766 -396.234776) (xy 20.135409 -396.270467) (xy 20.089559 -396.299933) (xy 20.039982 -396.322575)
			(xy 19.987687 -396.33793) (xy 19.933739 -396.345686) (xy 19.879237 -396.345686) (xy 19.825289 -396.33793)
			(xy 19.772994 -396.322575) (xy 19.723417 -396.299933) (xy 19.677567 -396.270467) (xy 19.636376 -396.234776)
			(xy 19.600685 -396.193585) (xy 19.571219 -396.147735) (xy 19.548577 -396.098158) (xy 19.533222 -396.045863)
			(xy 19.525466 -395.991915) (xy 19.52498 -395.964664) (xy 18.741644 -395.964664) (xy 18.741644 -398.878552)
			(xy 19.56308 -398.878552) (xy 19.563557 -398.851182) (xy 19.571369 -398.797003) (xy 19.586855 -398.744499)
			(xy 19.609694 -398.694752) (xy 19.639419 -398.648785) (xy 19.65706 -398.627854) (xy 19.663156 -398.620742)
			(xy 19.669506 -398.603724) (xy 19.669506 -398.51838) (xy 19.663156 -398.501362) (xy 19.65706 -398.49425)
			(xy 19.639424 -398.473315) (xy 19.609713 -398.427343) (xy 19.586877 -398.377596) (xy 19.571385 -398.325096)
			(xy 19.563555 -398.270921) (xy 19.56308 -398.243552) (xy 19.563499 -398.217882) (xy 19.570385 -398.167007)
			(xy 19.584026 -398.117513) (xy 19.604176 -398.070293) (xy 19.630472 -398.026199) (xy 19.662439 -397.986026)
			(xy 19.680682 -397.967962) (xy 19.687787 -397.960528) (xy 19.69591 -397.941656) (xy 19.69643 -397.931386)
			(xy 19.69643 -397.85798) (xy 19.695957 -397.847701) (xy 19.687813 -397.828823) (xy 19.680682 -397.821404)
			(xy 19.662461 -397.803318) (xy 19.630484 -397.763154) (xy 19.604181 -397.719066) (xy 19.584026 -397.67185)
			(xy 19.570383 -397.622358) (xy 19.563498 -397.571483) (xy 19.56308 -397.545814) (xy 19.563535 -397.518443)
			(xy 19.571352 -397.464263) (xy 19.586843 -397.411759) (xy 19.609688 -397.362012) (xy 19.639416 -397.316046)
			(xy 19.65706 -397.295116) (xy 19.663156 -397.288004) (xy 19.669506 -397.270986) (xy 19.669506 -397.185642)
			(xy 19.663156 -397.168624) (xy 19.65706 -397.161512) (xy 19.639406 -397.140592) (xy 19.609698 -397.094615)
			(xy 19.586865 -397.044864) (xy 19.571378 -396.992361) (xy 19.563552 -396.938184) (xy 19.56308 -396.910814)
			(xy 19.563566 -396.883563) (xy 19.571322 -396.829615) (xy 19.586677 -396.77732) (xy 19.609319 -396.727743)
			(xy 19.638785 -396.681893) (xy 19.674476 -396.640702) (xy 19.715667 -396.605011) (xy 19.761517 -396.575545)
			(xy 19.811094 -396.552903) (xy 19.863389 -396.537548) (xy 19.917337 -396.529792) (xy 19.971839 -396.529792)
			(xy 20.025787 -396.537548) (xy 20.078082 -396.552903) (xy 20.127659 -396.575545) (xy 20.173509 -396.605011)
			(xy 20.2147 -396.640702) (xy 20.250391 -396.681893) (xy 20.279857 -396.727743) (xy 20.302499 -396.77732)
			(xy 20.317854 -396.829615) (xy 20.32561 -396.883563) (xy 20.326096 -396.910814) (xy 20.325639 -396.938185)
			(xy 20.317819 -396.992364) (xy 20.302328 -397.044867) (xy 20.279484 -397.094614) (xy 20.249758 -397.140581)
			(xy 20.232116 -397.161512) (xy 20.22602 -397.168624) (xy 20.21967 -397.185642) (xy 20.21967 -397.270986)
			(xy 20.22602 -397.288004) (xy 20.232116 -397.295116) (xy 20.249732 -397.316067) (xy 20.279446 -397.362035)
			(xy 20.302287 -397.411778) (xy 20.317783 -397.464274) (xy 20.324947 -397.51381) (xy 28.152598 -397.51381)
			(xy 28.15307 -397.48644) (xy 28.160887 -397.432261) (xy 28.176374 -397.379758) (xy 28.199215 -397.330011)
			(xy 28.228938 -397.284044) (xy 28.246578 -397.263112) (xy 28.252674 -397.256) (xy 28.259024 -397.238982)
			(xy 28.259024 -397.153638) (xy 28.252674 -397.13662) (xy 28.246578 -397.129508) (xy 28.228926 -397.108587)
			(xy 28.199217 -397.06261) (xy 28.176384 -397.01286) (xy 28.160896 -396.960357) (xy 28.15307 -396.90618)
			(xy 28.152598 -396.87881) (xy 28.153084 -396.851559) (xy 28.16084 -396.797611) (xy 28.176195 -396.745316)
			(xy 28.198837 -396.695739) (xy 28.228303 -396.649889) (xy 28.263994 -396.608698) (xy 28.305185 -396.573007)
			(xy 28.351035 -396.543541) (xy 28.400612 -396.520899) (xy 28.452907 -396.505544) (xy 28.506855 -396.497788)
			(xy 28.561357 -396.497788) (xy 28.615305 -396.505544) (xy 28.6676 -396.520899) (xy 28.717177 -396.543541)
			(xy 28.763027 -396.573007) (xy 28.804218 -396.608698) (xy 28.839909 -396.649889) (xy 28.869375 -396.695739)
			(xy 28.892017 -396.745316) (xy 28.907372 -396.797611) (xy 28.915128 -396.851559) (xy 28.915614 -396.87881)
			(xy 28.91515 -396.90618) (xy 28.907331 -396.960359) (xy 28.891842 -397.012862) (xy 28.868999 -397.062609)
			(xy 28.839275 -397.108576) (xy 28.821634 -397.129508) (xy 28.815538 -397.13662) (xy 28.809188 -397.153638)
			(xy 28.809188 -397.238982) (xy 28.815538 -397.256) (xy 28.821634 -397.263112) (xy 28.839251 -397.284062)
			(xy 28.868965 -397.33003) (xy 28.891804 -397.379773) (xy 28.907301 -397.43227) (xy 28.915136 -397.486442)
			(xy 28.915614 -397.51381) (xy 28.915128 -397.541061) (xy 28.907372 -397.595009) (xy 28.892017 -397.647304)
			(xy 28.869375 -397.696881) (xy 28.839909 -397.742731) (xy 28.804218 -397.783922) (xy 28.763027 -397.819613)
			(xy 28.717177 -397.849079) (xy 28.6676 -397.871721) (xy 28.615305 -397.887076) (xy 28.561357 -397.894832)
			(xy 28.506855 -397.894832) (xy 28.452907 -397.887076) (xy 28.400612 -397.871721) (xy 28.351035 -397.849079)
			(xy 28.305185 -397.819613) (xy 28.263994 -397.783922) (xy 28.228303 -397.742731) (xy 28.198837 -397.696881)
			(xy 28.176195 -397.647304) (xy 28.16084 -397.595009) (xy 28.153084 -397.541061) (xy 28.152598 -397.51381)
			(xy 20.324947 -397.51381) (xy 20.325618 -397.518446) (xy 20.326096 -397.545814) (xy 20.325662 -397.571483)
			(xy 20.31878 -397.622359) (xy 20.305143 -397.671853) (xy 20.284995 -397.719073) (xy 20.258702 -397.763167)
			(xy 20.226736 -397.80334) (xy 20.208494 -397.821404) (xy 20.201401 -397.828847) (xy 20.193272 -397.847712)
			(xy 20.192746 -397.85798) (xy 20.192746 -397.931386) (xy 20.193244 -397.941662) (xy 20.201371 -397.960539)
			(xy 20.208494 -397.967962) (xy 20.226761 -397.986003) (xy 20.258731 -398.026178) (xy 20.285026 -398.070276)
			(xy 20.305172 -398.117501) (xy 20.318807 -398.167) (xy 20.325682 -398.217881) (xy 20.326096 -398.243552)
			(xy 20.325527 -398.273028) (xy 20.316465 -398.33128) (xy 20.29855 -398.387445) (xy 20.272207 -398.440185)
			(xy 20.238064 -398.488244) (xy 20.217892 -398.509744) (xy 20.211344 -398.517069) (xy 20.203907 -398.535237)
			(xy 20.203414 -398.54505) (xy 20.203414 -398.577054) (xy 20.203878 -398.586871) (xy 20.211338 -398.605035)
			(xy 20.217892 -398.61236) (xy 20.231608 -398.627346) (xy 20.239228 -398.635982) (xy 20.260056 -398.644872)
			(xy 20.36191 -398.641316) (xy 20.381976 -398.631156) (xy 20.389088 -398.621758) (xy 20.407229 -398.598733)
			(xy 20.449382 -398.558002) (xy 20.497271 -398.524202) (xy 20.549769 -398.498128) (xy 20.605639 -398.480395)
			(xy 20.663564 -398.471421) (xy 20.692872 -398.470882) (xy 20.721929 -398.471455) (xy 20.77937 -398.480283)
			(xy 20.834807 -398.497722) (xy 20.886956 -398.52337) (xy 20.934611 -398.556633) (xy 20.956016 -398.576292)
			(xy 20.963382 -398.58315) (xy 20.981162 -398.590262) (xy 21.071332 -398.590262) (xy 21.089112 -398.58315)
			(xy 21.096478 -398.576292) (xy 21.117891 -398.556639) (xy 21.165535 -398.523356) (xy 21.217681 -398.497695)
			(xy 21.273119 -398.480251) (xy 21.330563 -398.471428) (xy 21.359622 -398.470882) (xy 21.386871 -398.47139)
			(xy 21.440815 -398.479149) (xy 21.493106 -398.494505) (xy 21.542679 -398.517147) (xy 21.588525 -398.546613)
			(xy 21.629712 -398.582304) (xy 21.6654 -398.623492) (xy 21.694864 -398.66934) (xy 21.717502 -398.718915)
			(xy 21.732856 -398.771206) (xy 21.740612 -398.825151) (xy 21.740612 -398.879649) (xy 21.732856 -398.933594)
			(xy 21.717502 -398.985885) (xy 21.694864 -399.03546) (xy 21.6654 -399.081308) (xy 21.629712 -399.122496)
			(xy 21.588526 -399.158187) (xy 21.542679 -399.187653) (xy 21.493106 -399.210295) (xy 21.440815 -399.225651)
			(xy 21.386871 -399.23341) (xy 21.359622 -399.233898) (xy 21.330564 -399.233334) (xy 21.273123 -399.224505)
			(xy 21.217686 -399.207064) (xy 21.165536 -399.181413) (xy 21.117882 -399.148148) (xy 21.096478 -399.128488)
			(xy 21.089112 -399.12163) (xy 21.071332 -399.114518) (xy 20.981162 -399.114518) (xy 20.963382 -399.12163)
			(xy 20.956016 -399.128488) (xy 20.934618 -399.148157) (xy 20.886969 -399.181435) (xy 20.834819 -399.207092)
			(xy 20.779378 -399.224533) (xy 20.721932 -399.233353) (xy 20.692872 -399.233898) (xy 20.665778 -399.233464)
			(xy 20.612138 -399.225788) (xy 20.560125 -399.210593) (xy 20.510787 -399.188187) (xy 20.465119 -399.159021)
			(xy 20.42404 -399.123682) (xy 20.405852 -399.103596) (xy 20.398232 -399.09496) (xy 20.377404 -399.08607)
			(xy 20.27555 -399.089626) (xy 20.255484 -399.099786) (xy 20.248372 -399.109184) (xy 20.230239 -399.132216)
			(xy 20.188086 -399.172949) (xy 20.140196 -399.20675) (xy 20.087696 -399.232823) (xy 20.031824 -399.250554)
			(xy 19.973897 -399.259524) (xy 19.944588 -399.26006) (xy 19.917333 -399.259656) (xy 19.863377 -399.251896)
			(xy 19.811075 -399.236536) (xy 19.761492 -399.213889) (xy 19.715636 -399.184415) (xy 19.674442 -399.148715)
			(xy 19.638749 -399.107516) (xy 19.609282 -399.061656) (xy 19.586643 -399.012069) (xy 19.571291 -398.959764)
			(xy 19.56354 -398.905807) (xy 19.56308 -398.878552) (xy 18.741644 -398.878552) (xy 18.741644 -400.48307)
			(xy 23.694136 -400.48307) (xy 23.694576 -400.455699) (xy 23.702399 -400.401518) (xy 23.717893 -400.349014)
			(xy 23.740741 -400.299268) (xy 23.770472 -400.253303) (xy 23.788116 -400.232372) (xy 23.794212 -400.22526)
			(xy 23.800562 -400.208242) (xy 23.800562 -400.122898) (xy 23.794212 -400.10588) (xy 23.788116 -400.098768)
			(xy 23.770498 -400.077819) (xy 23.740782 -400.031851) (xy 23.717942 -399.982108) (xy 23.702446 -399.929611)
			(xy 23.694613 -399.875438) (xy 23.694136 -399.84807) (xy 23.694527 -399.820814) (xy 23.702289 -399.766859)
			(xy 23.717651 -399.714557) (xy 23.740301 -399.664973) (xy 23.769776 -399.619118) (xy 23.805477 -399.577925)
			(xy 23.846678 -399.542231) (xy 23.892538 -399.512765) (xy 23.942126 -399.490125) (xy 23.994431 -399.474774)
			(xy 24.048388 -399.467022) (xy 24.075644 -399.466562) (xy 24.105766 -399.467165) (xy 24.165261 -399.476638)
			(xy 24.222529 -399.495341) (xy 24.276146 -399.52281) (xy 24.324782 -399.558362) (xy 24.346408 -399.579338)
			(xy 24.35352 -399.586704) (xy 24.372316 -399.594324) (xy 24.464772 -399.594324) (xy 24.483568 -399.586704)
			(xy 24.49068 -399.579338) (xy 24.512297 -399.558349) (xy 24.560927 -399.52278) (xy 24.614545 -399.495301)
			(xy 24.671818 -399.476595) (xy 24.731319 -399.467128) (xy 24.761444 -399.466562) (xy 24.788814 -399.467046)
			(xy 24.842993 -399.474857) (xy 24.895496 -399.490341) (xy 24.945243 -399.513179) (xy 24.99121 -399.542902)
			(xy 25.012142 -399.560542) (xy 25.019254 -399.566638) (xy 25.036272 -399.572988) (xy 25.121616 -399.572988)
			(xy 25.138634 -399.566638) (xy 25.145746 -399.560542) (xy 25.166693 -399.542921) (xy 25.212661 -399.513205)
			(xy 25.262405 -399.490365) (xy 25.314902 -399.47487) (xy 25.369076 -399.467038) (xy 25.396444 -399.466562)
			(xy 25.423695 -399.467037) (xy 25.477642 -399.474799) (xy 25.529935 -399.490158) (xy 25.57951 -399.512802)
			(xy 25.625359 -399.54227) (xy 25.666548 -399.577962) (xy 25.702239 -399.619152) (xy 25.731705 -399.665002)
			(xy 25.754347 -399.714579) (xy 25.769704 -399.766872) (xy 25.777464 -399.820819) (xy 25.777952 -399.84807)
			(xy 25.77748 -399.87544) (xy 25.769665 -399.929619) (xy 25.754178 -399.982123) (xy 25.731338 -400.03187)
			(xy 25.701613 -400.077837) (xy 25.683972 -400.098768) (xy 25.677876 -400.10588) (xy 25.671526 -400.122898)
			(xy 25.671526 -400.208242) (xy 25.677876 -400.22526) (xy 25.683972 -400.232372) (xy 25.701607 -400.253307)
			(xy 25.73132 -400.299279) (xy 25.754158 -400.349025) (xy 25.76965 -400.401526) (xy 25.777478 -400.455701)
			(xy 25.777952 -400.48307) (xy 25.777394 -400.510318) (xy 25.769643 -400.564261) (xy 25.754294 -400.616552)
			(xy 25.731659 -400.666126) (xy 25.725734 -400.675348) (xy 27.191462 -400.675348) (xy 27.191889 -400.64897)
			(xy 27.199135 -400.596713) (xy 27.21351 -400.545953) (xy 27.234739 -400.497656) (xy 27.262418 -400.452744)
			(xy 27.29602 -400.412072) (xy 27.31516 -400.393916) (xy 27.322678 -400.386475) (xy 27.33123 -400.367147)
			(xy 27.33167 -400.356578) (xy 27.33167 -400.281648) (xy 27.331059 -400.271115) (xy 27.322551 -400.251837)
			(xy 27.31516 -400.24431) (xy 27.295999 -400.226174) (xy 27.262389 -400.185504) (xy 27.234707 -400.140589)
			(xy 27.213481 -400.092288) (xy 27.199116 -400.041521) (xy 27.191887 -399.989258) (xy 27.191462 -399.962878)
			(xy 27.191948 -399.935627) (xy 27.199704 -399.881679) (xy 27.215059 -399.829384) (xy 27.237701 -399.779807)
			(xy 27.267167 -399.733957) (xy 27.302858 -399.692766) (xy 27.344049 -399.657075) (xy 27.389899 -399.627609)
			(xy 27.439476 -399.604967) (xy 27.491771 -399.589612) (xy 27.545719 -399.581856) (xy 27.600221 -399.581856)
			(xy 27.654169 -399.589612) (xy 27.706464 -399.604967) (xy 27.756041 -399.627609) (xy 27.801891 -399.657075)
			(xy 27.843082 -399.692766) (xy 27.878773 -399.733957) (xy 27.908239 -399.779807) (xy 27.930881 -399.829384)
			(xy 27.946236 -399.881679) (xy 27.953992 -399.935627) (xy 27.954478 -399.962878) (xy 27.954055 -399.989256)
			(xy 27.946806 -400.041512) (xy 27.93243 -400.092272) (xy 27.9112 -400.140569) (xy 27.883521 -400.185481)
			(xy 27.84992 -400.226153) (xy 27.83078 -400.24431) (xy 27.82331 -400.251783) (xy 27.814786 -400.271093)
			(xy 27.81427 -400.281648) (xy 27.81427 -400.356578) (xy 27.814855 -400.367114) (xy 27.82338 -400.386393)
			(xy 27.83078 -400.393916) (xy 27.849913 -400.412081) (xy 27.883524 -400.452745) (xy 27.911209 -400.497654)
			(xy 27.932439 -400.54595) (xy 27.946811 -400.596712) (xy 27.954048 -400.648969) (xy 27.954478 -400.675348)
			(xy 27.953992 -400.702599) (xy 27.946236 -400.756547) (xy 27.930881 -400.808842) (xy 27.908239 -400.858419)
			(xy 27.878773 -400.904269) (xy 27.843082 -400.94546) (xy 27.801891 -400.981151) (xy 27.756041 -401.010617)
			(xy 27.706464 -401.033259) (xy 27.654169 -401.048614) (xy 27.600221 -401.05637) (xy 27.545719 -401.05637)
			(xy 27.491771 -401.048614) (xy 27.439476 -401.033259) (xy 27.389899 -401.010617) (xy 27.344049 -400.981151)
			(xy 27.302858 -400.94546) (xy 27.267167 -400.904269) (xy 27.237701 -400.858419) (xy 27.215059 -400.808842)
			(xy 27.199704 -400.756547) (xy 27.191948 -400.702599) (xy 27.191462 -400.675348) (xy 25.725734 -400.675348)
			(xy 25.7022 -400.711974) (xy 25.666516 -400.753164) (xy 25.625334 -400.788856) (xy 25.579491 -400.818324)
			(xy 25.529921 -400.840968) (xy 25.477634 -400.856327) (xy 25.423692 -400.864089) (xy 25.396444 -400.864578)
			(xy 25.369074 -400.864092) (xy 25.314896 -400.856279) (xy 25.262393 -400.840795) (xy 25.212646 -400.817958)
			(xy 25.166678 -400.788237) (xy 25.145746 -400.770598) (xy 25.138634 -400.764502) (xy 25.121616 -400.758152)
			(xy 25.036272 -400.758152) (xy 25.019254 -400.764502) (xy 25.012142 -400.770598) (xy 24.991205 -400.788231)
			(xy 24.945233 -400.817943) (xy 24.895487 -400.840781) (xy 24.842988 -400.856273) (xy 24.788813 -400.864103)
			(xy 24.761444 -400.864578) (xy 24.731322 -400.863971) (xy 24.671828 -400.854498) (xy 24.614561 -400.835795)
			(xy 24.560943 -400.808327) (xy 24.512306 -400.772777) (xy 24.49068 -400.751802) (xy 24.483568 -400.744436)
			(xy 24.464772 -400.736816) (xy 24.372316 -400.736816) (xy 24.35352 -400.744436) (xy 24.346408 -400.751802)
			(xy 24.324803 -400.772804) (xy 24.276169 -400.808369) (xy 24.222547 -400.835845) (xy 24.165273 -400.854548)
			(xy 24.10577 -400.864013) (xy 24.075644 -400.864578) (xy 24.048391 -400.864104) (xy 23.994439 -400.856352)
			(xy 23.942139 -400.841) (xy 23.892557 -400.81836) (xy 23.846703 -400.788894) (xy 23.805509 -400.753201)
			(xy 23.769814 -400.712009) (xy 23.740346 -400.666155) (xy 23.717705 -400.616574) (xy 23.702351 -400.564275)
			(xy 23.694597 -400.510323) (xy 23.694136 -400.48307) (xy 18.741644 -400.48307) (xy 18.741644 -401.055078)
			(xy 18.742083 -401.065141) (xy 18.749822 -401.083721) (xy 18.75663 -401.091146) (xy 19.091727 -401.426243)
			(xy 19.533319 -401.426243) (xy 19.533319 -401.371737) (xy 19.541076 -401.317787) (xy 19.556432 -401.265489)
			(xy 19.579075 -401.21591) (xy 19.608543 -401.170057) (xy 19.644236 -401.128865) (xy 19.685428 -401.093171)
			(xy 19.731281 -401.063704) (xy 19.780861 -401.041062) (xy 19.833159 -401.025706) (xy 19.887109 -401.017949)
			(xy 19.914362 -401.017486) (xy 19.944485 -401.018071) (xy 20.003981 -401.027547) (xy 20.061249 -401.046254)
			(xy 20.114867 -401.073727) (xy 20.163501 -401.109284) (xy 20.185126 -401.130262) (xy 20.192238 -401.137628)
			(xy 20.211034 -401.145248) (xy 20.30349 -401.145248) (xy 20.322286 -401.137628) (xy 20.329398 -401.130262)
			(xy 20.351011 -401.109268) (xy 20.399642 -401.073699) (xy 20.453261 -401.046221) (xy 20.510534 -401.027516)
			(xy 20.570037 -401.018051) (xy 20.600162 -401.017486) (xy 20.627531 -401.017978) (xy 20.681709 -401.02579)
			(xy 20.734212 -401.041273) (xy 20.783959 -401.064109) (xy 20.829927 -401.093828) (xy 20.85086 -401.111466)
			(xy 20.857972 -401.117562) (xy 20.87499 -401.123912) (xy 20.960334 -401.123912) (xy 20.977352 -401.117562)
			(xy 20.984464 -401.111466) (xy 21.005394 -401.093825) (xy 21.051368 -401.064115) (xy 21.101116 -401.04128)
			(xy 21.153617 -401.025789) (xy 21.207793 -401.01796) (xy 21.235162 -401.017486) (xy 21.262416 -401.017959)
			(xy 21.31637 -401.025711) (xy 21.368672 -401.041064) (xy 21.418256 -401.063704) (xy 21.464113 -401.09317)
			(xy 21.50531 -401.128863) (xy 21.541007 -401.170056) (xy 21.570478 -401.215911) (xy 21.593123 -401.265492)
			(xy 21.608481 -401.317792) (xy 21.616239 -401.371746) (xy 21.616239 -401.426254) (xy 21.608481 -401.480208)
			(xy 21.593123 -401.532508) (xy 21.570478 -401.582089) (xy 21.541007 -401.627944) (xy 21.50531 -401.669137)
			(xy 21.464113 -401.70483) (xy 21.418256 -401.734296) (xy 21.368672 -401.756936) (xy 21.31637 -401.772289)
			(xy 21.262416 -401.780041) (xy 21.235162 -401.780502) (xy 21.207793 -401.779999) (xy 21.153616 -401.77219)
			(xy 21.101113 -401.75671) (xy 21.051365 -401.733876) (xy 21.005397 -401.704159) (xy 20.984464 -401.686522)
			(xy 20.977352 -401.680426) (xy 20.960334 -401.674076) (xy 20.87499 -401.674076) (xy 20.857972 -401.680426)
			(xy 20.85086 -401.686522) (xy 20.829919 -401.70415) (xy 20.783948 -401.733863) (xy 20.734203 -401.7567)
			(xy 20.681704 -401.772194) (xy 20.62753 -401.780026) (xy 20.600162 -401.780502) (xy 20.570039 -401.779906)
			(xy 20.510544 -401.770433) (xy 20.453275 -401.751729) (xy 20.399658 -401.724258) (xy 20.351023 -401.688703)
			(xy 20.329398 -401.667726) (xy 20.322286 -401.66036) (xy 20.30349 -401.65274) (xy 20.211034 -401.65274)
			(xy 20.192238 -401.66036) (xy 20.185126 -401.667726) (xy 20.1635 -401.688706) (xy 20.114873 -401.724277)
			(xy 20.061257 -401.751758) (xy 20.003986 -401.770466) (xy 19.944486 -401.779935) (xy 19.914362 -401.780502)
			(xy 19.887109 -401.780031) (xy 19.833159 -401.772274) (xy 19.780861 -401.756918) (xy 19.731281 -401.734276)
			(xy 19.685428 -401.704809) (xy 19.644236 -401.669115) (xy 19.608543 -401.627923) (xy 19.579075 -401.58207)
			(xy 19.556432 -401.532491) (xy 19.541076 -401.480193) (xy 19.533319 -401.426243) (xy 19.091727 -401.426243)
			(xy 19.86661 -402.201126) (xy 19.874006 -402.207979) (xy 19.892604 -402.215721) (xy 19.902678 -402.216112)
			(xy 28.443428 -402.216112) (xy 28.468411 -402.216726) (xy 28.517417 -402.22647) (xy 28.563584 -402.245581)
			(xy 28.60514 -402.273324) (xy 28.62326 -402.290534) (xy 30.474158 -404.141432) (xy 30.491378 -404.159543)
			(xy 30.519114 -404.201104) (xy 30.53822 -404.247274) (xy 30.547964 -404.296281) (xy 30.54858 -404.321264)
			(xy 30.54858 -407.76144) (xy 30.549074 -407.771444) (xy 30.55674 -407.789925) (xy 30.570891 -407.804071)
			(xy 30.589376 -407.811729) (xy 30.59938 -407.81224) (xy 32.637222 -407.81224) (xy 32.647289 -407.811811)
			(xy 32.665882 -407.804085) (xy 32.67329 -407.797254) (xy 33.532064 -406.93848) (xy 33.538807 -406.93111)
			(xy 33.546398 -406.912648) (xy 33.546796 -406.902666) (xy 33.546796 -395.611858) (xy 33.546314 -395.601894)
			(xy 33.538732 -395.583464) (xy 33.532064 -395.576044) (xy 30.251654 -392.295634) (xy 30.244812 -392.288235)
			(xy 30.237093 -392.269636) (xy 30.236668 -392.259566) (xy 30.236668 -382.132078) (xy 30.236548 -382.127124)
			(xy 30.234627 -382.117403) (xy 30.232858 -382.112774) (xy 28.59151 -378.151898) (xy 28.587645 -378.143513)
			(xy 28.575052 -378.130031) (xy 28.558494 -378.121897) (xy 28.549346 -378.120656) (xy 28.44546 -378.111004)
			(xy 28.420568 -378.122942) (xy 28.412694 -378.13488) (xy 28.397495 -378.157197) (xy 28.361809 -378.197716)
			(xy 28.320764 -378.232797) (xy 28.275182 -378.261738) (xy 28.225974 -378.283962) (xy 28.174124 -378.299022)
			(xy 28.120667 -378.306619) (xy 28.09367 -378.307092) (xy 28.06556 -378.30659) (xy 28.009947 -378.298341)
			(xy 27.956146 -378.282026) (xy 27.905319 -378.257997) (xy 27.858566 -378.226773) (xy 27.837384 -378.208286)
			(xy 27.830272 -378.201682) (xy 27.813 -378.195078) (xy 27.725624 -378.194824) (xy 27.708352 -378.201682)
			(xy 27.700986 -378.208032) (xy 27.679861 -378.226441) (xy 27.633224 -378.257502) (xy 27.582543 -378.281401)
			(xy 27.528909 -378.297624) (xy 27.473479 -378.305821) (xy 27.445462 -378.30633) (xy 27.416724 -378.305806)
			(xy 27.359901 -378.297177) (xy 27.305015 -378.28012) (xy 27.25331 -378.255021) (xy 27.205955 -378.222449)
			(xy 27.184604 -378.203206) (xy 27.177492 -378.196602) (xy 27.159966 -378.18949) (xy 27.070558 -378.18949)
			(xy 27.053032 -378.196602) (xy 27.04592 -378.203206) (xy 27.024594 -378.222479) (xy 26.977232 -378.25505)
			(xy 26.925521 -378.280147) (xy 26.87063 -378.297205) (xy 26.813802 -378.305836) (xy 26.785062 -378.30633)
			(xy 26.754196 -378.305716) (xy 26.693276 -378.29574) (xy 26.634756 -378.276085) (xy 26.580164 -378.247265)
			(xy 26.555192 -378.229114) (xy 26.547572 -378.223526) (xy 26.529792 -378.218446) (xy 26.443686 -378.225304)
			(xy 26.426922 -378.233178) (xy 26.420318 -378.240036) (xy 26.402266 -378.258348) (xy 26.362093 -378.290446)
			(xy 26.317971 -378.316855) (xy 26.2707 -378.337095) (xy 26.221138 -378.350799) (xy 26.170185 -378.357719)
			(xy 26.144474 -378.358146) (xy 26.117223 -378.357658) (xy 26.063276 -378.349899) (xy 26.010982 -378.334542)
			(xy 25.961406 -378.3119) (xy 25.915556 -378.282434) (xy 25.874366 -378.246743) (xy 25.838674 -378.205554)
			(xy 25.809206 -378.159705) (xy 25.786562 -378.110129) (xy 25.771203 -378.057836) (xy 25.763442 -378.003889)
			(xy 25.762966 -377.976638) (xy 25.763436 -377.949667) (xy 25.771041 -377.896262) (xy 25.78609 -377.844461)
			(xy 25.808283 -377.795295) (xy 25.837179 -377.749744) (xy 25.872201 -377.708716) (xy 25.912651 -377.673028)
			(xy 25.957724 -377.643392) (xy 25.981914 -377.631452) (xy 25.992836 -377.626372) (xy 26.007314 -377.60783)
			(xy 26.029158 -377.50496) (xy 26.023062 -377.4821) (xy 26.015188 -377.472956) (xy 25.997598 -377.452029)
			(xy 25.967965 -377.40609) (xy 25.945192 -377.356392) (xy 25.929745 -377.303953) (xy 25.921941 -377.249846)
			(xy 25.921462 -377.222512) (xy 25.921995 -377.193596) (xy 25.930722 -377.136425) (xy 25.947977 -377.081226)
			(xy 25.973364 -377.029263) (xy 26.006304 -376.981728) (xy 26.04604 -376.939708) (xy 26.068528 -376.921522)
			(xy 26.077313 -376.91398) (xy 26.087488 -376.893208) (xy 26.088086 -376.881644) (xy 26.088086 -376.80138)
			(xy 26.087473 -376.789822) (xy 26.077291 -376.769063) (xy 26.068528 -376.761502) (xy 26.047746 -376.744748)
			(xy 26.010616 -376.706393) (xy 25.979196 -376.663237) (xy 25.954098 -376.616123) (xy 25.935811 -376.565971)
			(xy 25.924695 -376.513759) (xy 25.920964 -376.460507) (xy 25.924692 -376.407256) (xy 25.935807 -376.355043)
			(xy 25.954092 -376.30489) (xy 25.979188 -376.257775) (xy 26.010607 -376.214618) (xy 26.047735 -376.176262)
			(xy 26.068528 -376.159522) (xy 26.077313 -376.15198) (xy 26.087488 -376.131208) (xy 26.088086 -376.119644)
			(xy 26.088086 -376.03938) (xy 26.087473 -376.027822) (xy 26.077291 -376.007063) (xy 26.068528 -375.999502)
			(xy 26.046045 -375.981312) (xy 26.006308 -375.939294) (xy 25.97337 -375.89176) (xy 25.947986 -375.839797)
			(xy 25.930738 -375.784598) (xy 25.92202 -375.727428) (xy 25.921462 -375.698512) (xy 25.922015 -375.668963)
			(xy 25.931126 -375.610571) (xy 25.949131 -375.554282) (xy 25.975601 -375.501443) (xy 26.009901 -375.453317)
			(xy 26.030174 -375.431812) (xy 26.037286 -375.424446) (xy 26.044652 -375.406666) (xy 26.04516 -375.315988)
			(xy 26.038048 -375.297954) (xy 26.030936 -375.290588) (xy 26.011263 -375.269161) (xy 25.977977 -375.221458)
			(xy 25.952315 -375.169258) (xy 25.93487 -375.113768) (xy 25.926046 -375.056274) (xy 25.925526 -375.02719)
			(xy 25.926003 -374.999749) (xy 25.933865 -374.945434) (xy 25.949425 -374.892805) (xy 25.972363 -374.842947)
			(xy 26.002206 -374.796889) (xy 26.038337 -374.755579) (xy 26.058876 -374.737376) (xy 26.067004 -374.730518)
			(xy 26.076148 -374.711722) (xy 26.07945 -374.626378) (xy 26.079298 -374.615855) (xy 26.071553 -374.596311)
			(xy 26.064464 -374.588532) (xy 22.767798 -371.291612) (xy 22.760374 -371.284833) (xy 22.741777 -371.277238)
			(xy 22.73173 -371.27688) (xy 18.657824 -371.27688) (xy 18.625303 -371.27643) (xy 18.560671 -371.269126)
			(xy 18.497264 -371.25463) (xy 18.43588 -371.233123) (xy 18.37729 -371.204877) (xy 18.322233 -371.170247)
			(xy 18.2714 -371.129669) (xy 18.248122 -371.106954) (xy 16.6116 -369.470686) (xy 16.604259 -369.463866)
			(xy 16.585796 -369.45612) (xy 16.575786 -369.4557) (xy 5.410708 -369.4557) (xy 5.400637 -369.456122)
			(xy 5.382031 -369.463834) (xy 5.37464 -369.470686) (xy 4.469384 -370.375942) (xy 4.462708 -370.383354)
			(xy 4.455143 -370.401791) (xy 4.454652 -370.411756) (xy 4.454652 -376.70105) (xy 8.208781 -376.70105)
			(xy 8.21251 -376.647799) (xy 8.223627 -376.595587) (xy 8.241913 -376.545435) (xy 8.267012 -376.498321)
			(xy 8.298433 -376.455167) (xy 8.335563 -376.416813) (xy 8.356346 -376.40006) (xy 8.365129 -376.392519)
			(xy 8.375299 -376.371744) (xy 8.375904 -376.360182) (xy 8.375904 -376.279918) (xy 8.375322 -376.268352)
			(xy 8.365135 -376.247581) (xy 8.356346 -376.24004) (xy 8.335563 -376.223287) (xy 8.298433 -376.184933)
			(xy 8.267012 -376.141779) (xy 8.241913 -376.094665) (xy 8.223627 -376.044513) (xy 8.21251 -375.992301)
			(xy 8.208781 -375.93905) (xy 8.21251 -375.885799) (xy 8.223627 -375.833587) (xy 8.241913 -375.783435)
			(xy 8.267012 -375.736321) (xy 8.298433 -375.693167) (xy 8.335563 -375.654813) (xy 8.356346 -375.63806)
			(xy 8.365129 -375.630519) (xy 8.375299 -375.609744) (xy 8.375904 -375.598182) (xy 8.375904 -375.517918)
			(xy 8.375322 -375.506352) (xy 8.365135 -375.485581) (xy 8.356346 -375.47804) (xy 8.33387 -375.45984)
			(xy 8.294137 -375.417821) (xy 8.261199 -375.370287) (xy 8.23581 -375.318328) (xy 8.218551 -375.263133)
			(xy 8.209818 -375.205965) (xy 8.20928 -375.17705) (xy 8.209766 -375.149799) (xy 8.217522 -375.095851)
			(xy 8.232877 -375.043556) (xy 8.255519 -374.993979) (xy 8.284985 -374.948129) (xy 8.320676 -374.906938)
			(xy 8.361867 -374.871247) (xy 8.407717 -374.841781) (xy 8.457294 -374.819139) (xy 8.509589 -374.803784)
			(xy 8.563537 -374.796028) (xy 8.618039 -374.796028) (xy 8.671987 -374.803784) (xy 8.724282 -374.819139)
			(xy 8.773859 -374.841781) (xy 8.819709 -374.871247) (xy 8.8609 -374.906938) (xy 8.896591 -374.948129)
			(xy 8.926057 -374.993979) (xy 8.948699 -375.043556) (xy 8.964054 -375.095851) (xy 8.97181 -375.149799)
			(xy 8.972296 -375.17705) (xy 8.971743 -375.205966) (xy 8.963022 -375.263135) (xy 8.945771 -375.318334)
			(xy 8.920385 -375.370295) (xy 8.887448 -375.41783) (xy 8.847713 -375.459849) (xy 8.82523 -375.47804)
			(xy 8.816443 -375.485577) (xy 8.806276 -375.506355) (xy 8.805672 -375.517918) (xy 8.805672 -375.598182)
			(xy 8.806228 -375.609752) (xy 8.81643 -375.630525) (xy 8.82523 -375.63806) (xy 8.846013 -375.654813)
			(xy 8.883144 -375.693166) (xy 8.914565 -375.736321) (xy 8.939664 -375.783435) (xy 8.95795 -375.833587)
			(xy 8.969067 -375.885798) (xy 8.972797 -375.93905) (xy 8.969067 -375.992302) (xy 8.95795 -376.044513)
			(xy 8.939664 -376.094665) (xy 8.914565 -376.141779) (xy 8.883144 -376.184934) (xy 8.846013 -376.223287)
			(xy 8.82523 -376.24004) (xy 8.816443 -376.247577) (xy 8.806276 -376.268355) (xy 8.805672 -376.279918)
			(xy 8.805672 -376.360182) (xy 8.806228 -376.371752) (xy 8.81643 -376.392525) (xy 8.82523 -376.40006)
			(xy 8.846013 -376.416813) (xy 8.883144 -376.455166) (xy 8.914565 -376.498321) (xy 8.939664 -376.545435)
			(xy 8.95795 -376.595587) (xy 8.969067 -376.647798) (xy 8.972797 -376.70105) (xy 10.494781 -376.70105)
			(xy 10.49851 -376.647799) (xy 10.509627 -376.595587) (xy 10.527913 -376.545435) (xy 10.553012 -376.498321)
			(xy 10.584433 -376.455167) (xy 10.621563 -376.416813) (xy 10.642346 -376.40006) (xy 10.651129 -376.392519)
			(xy 10.661299 -376.371744) (xy 10.661904 -376.360182) (xy 10.661904 -376.279918) (xy 10.661322 -376.268352)
			(xy 10.651135 -376.247581) (xy 10.642346 -376.24004) (xy 10.621563 -376.223287) (xy 10.584433 -376.184933)
			(xy 10.553012 -376.141779) (xy 10.527913 -376.094665) (xy 10.509627 -376.044513) (xy 10.49851 -375.992301)
			(xy 10.494781 -375.93905) (xy 10.49851 -375.885799) (xy 10.509627 -375.833587) (xy 10.527913 -375.783435)
			(xy 10.553012 -375.736321) (xy 10.584433 -375.693167) (xy 10.621563 -375.654813) (xy 10.642346 -375.63806)
			(xy 10.651129 -375.630519) (xy 10.661299 -375.609744) (xy 10.661904 -375.598182) (xy 10.661904 -375.517918)
			(xy 10.661322 -375.506352) (xy 10.651135 -375.485581) (xy 10.642346 -375.47804) (xy 10.61987 -375.45984)
			(xy 10.580137 -375.417821) (xy 10.547199 -375.370287) (xy 10.52181 -375.318328) (xy 10.504551 -375.263133)
			(xy 10.495818 -375.205965) (xy 10.49528 -375.17705) (xy 10.495766 -375.149799) (xy 10.503522 -375.095851)
			(xy 10.518877 -375.043556) (xy 10.541519 -374.993979) (xy 10.570985 -374.948129) (xy 10.606676 -374.906938)
			(xy 10.647867 -374.871247) (xy 10.693717 -374.841781) (xy 10.743294 -374.819139) (xy 10.795589 -374.803784)
			(xy 10.849537 -374.796028) (xy 10.904039 -374.796028) (xy 10.957987 -374.803784) (xy 11.010282 -374.819139)
			(xy 11.059859 -374.841781) (xy 11.105709 -374.871247) (xy 11.1469 -374.906938) (xy 11.182591 -374.948129)
			(xy 11.212057 -374.993979) (xy 11.234699 -375.043556) (xy 11.250054 -375.095851) (xy 11.25781 -375.149799)
			(xy 11.258296 -375.17705) (xy 11.257743 -375.205966) (xy 11.249022 -375.263135) (xy 11.231771 -375.318334)
			(xy 11.206385 -375.370295) (xy 11.173448 -375.41783) (xy 11.133713 -375.459849) (xy 11.11123 -375.47804)
			(xy 11.102443 -375.485577) (xy 11.092276 -375.506355) (xy 11.091672 -375.517918) (xy 11.091672 -375.598182)
			(xy 11.092228 -375.609752) (xy 11.10243 -375.630525) (xy 11.11123 -375.63806) (xy 11.132013 -375.654813)
			(xy 11.169144 -375.693166) (xy 11.200565 -375.736321) (xy 11.225664 -375.783435) (xy 11.24395 -375.833587)
			(xy 11.255067 -375.885798) (xy 11.258797 -375.93905) (xy 11.255067 -375.992302) (xy 11.24395 -376.044513)
			(xy 11.225664 -376.094665) (xy 11.200565 -376.141779) (xy 11.169144 -376.184934) (xy 11.132013 -376.223287)
			(xy 11.11123 -376.24004) (xy 11.102443 -376.247577) (xy 11.092276 -376.268355) (xy 11.091672 -376.279918)
			(xy 11.091672 -376.360182) (xy 11.092228 -376.371752) (xy 11.10243 -376.392525) (xy 11.11123 -376.40006)
			(xy 11.132013 -376.416813) (xy 11.169144 -376.455166) (xy 11.200565 -376.498321) (xy 11.225664 -376.545435)
			(xy 11.24395 -376.595587) (xy 11.255067 -376.647798) (xy 11.258797 -376.70105) (xy 11.255067 -376.754302)
			(xy 11.24395 -376.806513) (xy 11.225664 -376.856665) (xy 11.200565 -376.903779) (xy 11.169144 -376.946934)
			(xy 11.132013 -376.985287) (xy 11.11123 -377.00204) (xy 11.102443 -377.009577) (xy 11.092276 -377.030355)
			(xy 11.091672 -377.041918) (xy 11.091672 -377.122182) (xy 11.092228 -377.133752) (xy 11.10243 -377.154525)
			(xy 11.11123 -377.16206) (xy 11.133701 -377.180266) (xy 11.173435 -377.222284) (xy 11.206375 -377.269816)
			(xy 11.231765 -377.321774) (xy 11.249025 -377.376968) (xy 11.257758 -377.434135) (xy 11.258296 -377.46305)
			(xy 11.25781 -377.490301) (xy 11.250054 -377.544249) (xy 11.234699 -377.596544) (xy 11.212057 -377.646121)
			(xy 11.182591 -377.691971) (xy 11.1469 -377.733162) (xy 11.105709 -377.768853) (xy 11.059859 -377.798319)
			(xy 11.010282 -377.820961) (xy 10.957987 -377.836316) (xy 10.904039 -377.844072) (xy 10.849537 -377.844072)
			(xy 10.795589 -377.836316) (xy 10.743294 -377.820961) (xy 10.693717 -377.798319) (xy 10.647867 -377.768853)
			(xy 10.606676 -377.733162) (xy 10.570985 -377.691971) (xy 10.541519 -377.646121) (xy 10.518877 -377.596544)
			(xy 10.503522 -377.544249) (xy 10.495766 -377.490301) (xy 10.49528 -377.46305) (xy 10.495804 -377.434133)
			(xy 10.504528 -377.376961) (xy 10.521783 -377.321761) (xy 10.547173 -377.269798) (xy 10.580117 -377.222265)
			(xy 10.61986 -377.180249) (xy 10.642346 -377.16206) (xy 10.651129 -377.154519) (xy 10.661299 -377.133744)
			(xy 10.661904 -377.122182) (xy 10.661904 -377.041918) (xy 10.661322 -377.030352) (xy 10.651135 -377.009581)
			(xy 10.642346 -377.00204) (xy 10.621563 -376.985287) (xy 10.584433 -376.946933) (xy 10.553012 -376.903779)
			(xy 10.527913 -376.856665) (xy 10.509627 -376.806513) (xy 10.49851 -376.754301) (xy 10.494781 -376.70105)
			(xy 8.972797 -376.70105) (xy 8.969067 -376.754302) (xy 8.95795 -376.806513) (xy 8.939664 -376.856665)
			(xy 8.914565 -376.903779) (xy 8.883144 -376.946934) (xy 8.846013 -376.985287) (xy 8.82523 -377.00204)
			(xy 8.816443 -377.009577) (xy 8.806276 -377.030355) (xy 8.805672 -377.041918) (xy 8.805672 -377.122182)
			(xy 8.806228 -377.133752) (xy 8.81643 -377.154525) (xy 8.82523 -377.16206) (xy 8.847701 -377.180266)
			(xy 8.887435 -377.222284) (xy 8.920375 -377.269816) (xy 8.945765 -377.321774) (xy 8.963025 -377.376968)
			(xy 8.971758 -377.434135) (xy 8.972296 -377.46305) (xy 8.97181 -377.490301) (xy 8.964054 -377.544249)
			(xy 8.948699 -377.596544) (xy 8.926057 -377.646121) (xy 8.896591 -377.691971) (xy 8.8609 -377.733162)
			(xy 8.819709 -377.768853) (xy 8.773859 -377.798319) (xy 8.724282 -377.820961) (xy 8.671987 -377.836316)
			(xy 8.618039 -377.844072) (xy 8.563537 -377.844072) (xy 8.509589 -377.836316) (xy 8.457294 -377.820961)
			(xy 8.407717 -377.798319) (xy 8.361867 -377.768853) (xy 8.320676 -377.733162) (xy 8.284985 -377.691971)
			(xy 8.255519 -377.646121) (xy 8.232877 -377.596544) (xy 8.217522 -377.544249) (xy 8.209766 -377.490301)
			(xy 8.20928 -377.46305) (xy 8.209804 -377.434133) (xy 8.218528 -377.376961) (xy 8.235783 -377.321761)
			(xy 8.261173 -377.269798) (xy 8.294117 -377.222265) (xy 8.33386 -377.180249) (xy 8.356346 -377.16206)
			(xy 8.365129 -377.154519) (xy 8.375299 -377.133744) (xy 8.375904 -377.122182) (xy 8.375904 -377.041918)
			(xy 8.375322 -377.030352) (xy 8.365135 -377.009581) (xy 8.356346 -377.00204) (xy 8.335563 -376.985287)
			(xy 8.298433 -376.946933) (xy 8.267012 -376.903779) (xy 8.241913 -376.856665) (xy 8.223627 -376.806513)
			(xy 8.21251 -376.754301) (xy 8.208781 -376.70105) (xy 4.454652 -376.70105) (xy 4.454652 -377.963938)
			(xy 14.292072 -377.963938) (xy 14.292535 -377.937592) (xy 14.299764 -377.885398) (xy 14.314103 -377.834694)
			(xy 14.335281 -377.786445) (xy 14.362894 -377.741567) (xy 14.396418 -377.700914) (xy 14.415516 -377.68276)
			(xy 14.42339 -377.675648) (xy 14.431772 -377.656852) (xy 14.43355 -377.562364) (xy 14.42593 -377.543314)
			(xy 14.41831 -377.535694) (xy 14.397291 -377.514057) (xy 14.361641 -377.465399) (xy 14.334096 -377.411735)
			(xy 14.315343 -377.354404) (xy 14.30585 -377.294836) (xy 14.30528 -377.264676) (xy 14.305729 -377.23727)
			(xy 14.313582 -377.183025) (xy 14.329122 -377.130463) (xy 14.352029 -377.080668) (xy 14.38183 -377.034666)
			(xy 14.399514 -377.013724) (xy 14.40561 -377.006612) (xy 14.41196 -376.989594) (xy 14.41196 -376.903996)
			(xy 14.40561 -376.886978) (xy 14.399514 -376.879866) (xy 14.381832 -376.858924) (xy 14.352039 -376.812919)
			(xy 14.329139 -376.763124) (xy 14.313605 -376.710562) (xy 14.305756 -376.656318) (xy 14.30528 -376.628914)
			(xy 14.305825 -376.598573) (xy 14.315443 -376.538657) (xy 14.334423 -376.481018) (xy 14.362287 -376.427111)
			(xy 14.398332 -376.378293) (xy 14.41958 -376.356626) (xy 14.4272 -376.34926) (xy 14.43482 -376.330718)
			(xy 14.43482 -376.237246) (xy 14.4272 -376.218704) (xy 14.41958 -376.211338) (xy 14.39832 -376.189683)
			(xy 14.362282 -376.140862) (xy 14.334429 -376.08695) (xy 14.315462 -376.029309) (xy 14.305862 -375.969391)
			(xy 14.30528 -375.93905) (xy 14.305804 -375.910133) (xy 14.314528 -375.852961) (xy 14.331783 -375.797761)
			(xy 14.357173 -375.745798) (xy 14.390117 -375.698265) (xy 14.42986 -375.656249) (xy 14.452346 -375.63806)
			(xy 14.461129 -375.630519) (xy 14.471299 -375.609744) (xy 14.471904 -375.598182) (xy 14.471904 -375.517918)
			(xy 14.471322 -375.506352) (xy 14.461135 -375.485581) (xy 14.452346 -375.47804) (xy 14.42987 -375.45984)
			(xy 14.390137 -375.417821) (xy 14.357199 -375.370287) (xy 14.33181 -375.318328) (xy 14.314551 -375.263133)
			(xy 14.305818 -375.205965) (xy 14.30528 -375.17705) (xy 14.305766 -375.149799) (xy 14.313522 -375.095851)
			(xy 14.328877 -375.043556) (xy 14.351519 -374.993979) (xy 14.380985 -374.948129) (xy 14.416676 -374.906938)
			(xy 14.457867 -374.871247) (xy 14.503717 -374.841781) (xy 14.553294 -374.819139) (xy 14.605589 -374.803784)
			(xy 14.659537 -374.796028) (xy 14.714039 -374.796028) (xy 14.767987 -374.803784) (xy 14.820282 -374.819139)
			(xy 14.869859 -374.841781) (xy 14.915709 -374.871247) (xy 14.9569 -374.906938) (xy 14.992591 -374.948129)
			(xy 15.022057 -374.993979) (xy 15.044699 -375.043556) (xy 15.060054 -375.095851) (xy 15.06781 -375.149799)
			(xy 15.068296 -375.17705) (xy 15.067743 -375.205966) (xy 15.059022 -375.263135) (xy 15.041771 -375.318334)
			(xy 15.016385 -375.370295) (xy 14.983448 -375.41783) (xy 14.943713 -375.459849) (xy 14.92123 -375.47804)
			(xy 14.912443 -375.485577) (xy 14.902276 -375.506355) (xy 14.901672 -375.517918) (xy 14.901672 -375.598182)
			(xy 14.902228 -375.609752) (xy 14.91243 -375.630525) (xy 14.92123 -375.63806) (xy 14.943701 -375.656266)
			(xy 14.983435 -375.698284) (xy 15.016375 -375.745816) (xy 15.041765 -375.797774) (xy 15.059025 -375.852968)
			(xy 15.067758 -375.910135) (xy 15.068296 -375.93905) (xy 15.067706 -375.969389) (xy 15.058096 -376.029302)
			(xy 15.039125 -376.086939) (xy 15.011272 -376.140847) (xy 14.975238 -376.189668) (xy 14.953996 -376.211338)
			(xy 14.946376 -376.218704) (xy 14.938756 -376.237246) (xy 14.938756 -376.330718) (xy 14.946376 -376.34926)
			(xy 14.953996 -376.356626) (xy 14.975234 -376.378301) (xy 15.011276 -376.427116) (xy 15.039134 -376.481023)
			(xy 15.058105 -376.53866) (xy 15.067711 -376.598574) (xy 15.068296 -376.628914) (xy 15.067847 -376.65632)
			(xy 15.059995 -376.710566) (xy 15.044456 -376.763128) (xy 15.021548 -376.812923) (xy 14.991746 -376.858924)
			(xy 14.974062 -376.879866) (xy 14.967966 -376.886978) (xy 14.961616 -376.903996) (xy 14.961616 -376.989594)
			(xy 14.967966 -377.006612) (xy 14.974062 -377.013724) (xy 14.991735 -377.034673) (xy 15.021531 -377.080675)
			(xy 15.044432 -377.130469) (xy 15.059969 -377.183029) (xy 15.06782 -377.237272) (xy 15.068296 -377.264676)
			(xy 15.067853 -377.291023) (xy 15.060621 -377.343219) (xy 15.046279 -377.393923) (xy 15.025097 -377.442172)
			(xy 14.99748 -377.48705) (xy 14.963953 -377.527701) (xy 14.944852 -377.545854) (xy 14.936978 -377.552966)
			(xy 14.928596 -377.571762) (xy 14.926818 -377.66625) (xy 14.934438 -377.6853) (xy 14.942058 -377.69292)
			(xy 14.963096 -377.71454) (xy 14.998741 -377.763204) (xy 15.026281 -377.816872) (xy 15.045029 -377.874206)
			(xy 15.054519 -377.933777) (xy 15.054911 -377.95454) (xy 16.559276 -377.95454) (xy 16.559865 -377.924417)
			(xy 16.56934 -377.864921) (xy 16.588047 -377.807653) (xy 16.615519 -377.754036) (xy 16.651074 -377.705401)
			(xy 16.672052 -377.683776) (xy 16.679418 -377.67641) (xy 16.687038 -377.658376) (xy 16.687546 -377.56592)
			(xy 16.68018 -377.547632) (xy 16.672814 -377.540266) (xy 16.652346 -377.5187) (xy 16.617644 -377.470424)
			(xy 16.590855 -377.417347) (xy 16.572626 -377.360757) (xy 16.563401 -377.302023) (xy 16.562832 -377.272296)
			(xy 16.563335 -377.243378) (xy 16.572066 -377.186206) (xy 16.589326 -377.131006) (xy 16.61472 -377.079044)
			(xy 16.647667 -377.031511) (xy 16.687411 -376.989495) (xy 16.709898 -376.971306) (xy 16.718652 -376.963737)
			(xy 16.72884 -376.942984) (xy 16.729456 -376.931428) (xy 16.729456 -376.851164) (xy 16.728864 -376.839599)
			(xy 16.718686 -376.818826) (xy 16.709898 -376.811286) (xy 16.687407 -376.793103) (xy 16.647673 -376.751082)
			(xy 16.614735 -376.703545) (xy 16.589347 -376.651582) (xy 16.572093 -376.596383) (xy 16.563366 -376.539212)
			(xy 16.562832 -376.510296) (xy 16.563308 -376.483052) (xy 16.571066 -376.429118) (xy 16.586423 -376.376839)
			(xy 16.609066 -376.327278) (xy 16.638534 -376.281445) (xy 16.674227 -376.240275) (xy 16.715418 -376.204605)
			(xy 16.738092 -376.189494) (xy 16.74876 -376.182382) (xy 16.760952 -376.160538) (xy 16.763746 -376.051064)
			(xy 16.752316 -376.028458) (xy 16.742156 -376.021092) (xy 16.721253 -376.00571) (xy 16.68343 -375.970175)
			(xy 16.650778 -375.929836) (xy 16.623903 -375.885439) (xy 16.6033 -375.837806) (xy 16.589352 -375.787818)
			(xy 16.582316 -375.736399) (xy 16.581882 -375.71045) (xy 16.582315 -375.684786) (xy 16.589185 -375.633921)
			(xy 16.602819 -375.584437) (xy 16.622972 -375.537232) (xy 16.649278 -375.493158) (xy 16.681262 -375.453015)
			(xy 16.718345 -375.417527) (xy 16.738854 -375.402094) (xy 16.747998 -375.39549) (xy 16.758666 -375.376186)
			(xy 16.76654 -375.276618) (xy 16.75892 -375.256044) (xy 16.750792 -375.247916) (xy 16.729976 -375.226332)
			(xy 16.694724 -375.177826) (xy 16.667497 -375.124401) (xy 16.648966 -375.067374) (xy 16.639587 -375.008149)
			(xy 16.639032 -374.978168) (xy 16.639518 -374.950917) (xy 16.647274 -374.896969) (xy 16.662629 -374.844674)
			(xy 16.685271 -374.795097) (xy 16.714737 -374.749247) (xy 16.750428 -374.708056) (xy 16.791619 -374.672365)
			(xy 16.837469 -374.642899) (xy 16.887046 -374.620257) (xy 16.939341 -374.604902) (xy 16.993289 -374.597146)
			(xy 17.047791 -374.597146) (xy 17.101739 -374.604902) (xy 17.154034 -374.620257) (xy 17.203611 -374.642899)
			(xy 17.249461 -374.672365) (xy 17.290652 -374.708056) (xy 17.326343 -374.749247) (xy 17.355809 -374.795097)
			(xy 17.378451 -374.844674) (xy 17.393806 -374.896969) (xy 17.401562 -374.950917) (xy 17.402048 -374.978168)
			(xy 17.401616 -375.003832) (xy 17.394745 -375.054697) (xy 17.38111 -375.10418) (xy 17.360956 -375.151385)
			(xy 17.33465 -375.195458) (xy 17.302666 -375.235602) (xy 17.265584 -375.27109) (xy 17.245076 -375.286524)
			(xy 17.235932 -375.293128) (xy 17.225264 -375.312432) (xy 17.21739 -375.412) (xy 17.22501 -375.432574)
			(xy 17.233138 -375.440702) (xy 17.25395 -375.46229) (xy 17.289205 -375.510794) (xy 17.316434 -375.564217)
			(xy 17.334966 -375.621244) (xy 17.344343 -375.680469) (xy 17.344898 -375.71045) (xy 17.344444 -375.737695)
			(xy 17.33668 -375.791629) (xy 17.321318 -375.843908) (xy 17.298671 -375.893469) (xy 17.2692 -375.939301)
			(xy 17.233505 -375.980471) (xy 17.192313 -376.016141) (xy 17.169638 -376.031252) (xy 17.15897 -376.038364)
			(xy 17.146778 -376.060208) (xy 17.143984 -376.169682) (xy 17.155414 -376.192288) (xy 17.165574 -376.199654)
			(xy 17.186458 -376.21506) (xy 17.224281 -376.250592) (xy 17.256933 -376.290928) (xy 17.28381 -376.33532)
			(xy 17.304416 -376.382949) (xy 17.318368 -376.432933) (xy 17.32541 -376.484348) (xy 17.325848 -376.510296)
			(xy 17.325346 -376.539214) (xy 17.316617 -376.596387) (xy 17.299357 -376.651587) (xy 17.273962 -376.703549)
			(xy 17.241015 -376.751082) (xy 17.20127 -376.793097) (xy 17.178782 -376.811286) (xy 17.170028 -376.818855)
			(xy 17.159841 -376.839608) (xy 17.159224 -376.851164) (xy 17.159224 -376.931428) (xy 17.159827 -376.942992)
			(xy 17.169998 -376.963764) (xy 17.178782 -376.971306) (xy 17.201265 -376.989498) (xy 17.241001 -377.031517)
			(xy 17.27394 -377.079052) (xy 17.299329 -377.131013) (xy 17.316585 -377.18621) (xy 17.325314 -377.24338)
			(xy 17.325848 -377.272296) (xy 17.325275 -377.302419) (xy 17.315795 -377.361916) (xy 17.297085 -377.419184)
			(xy 17.269609 -377.472801) (xy 17.234051 -377.521435) (xy 17.213072 -377.54306) (xy 17.205706 -377.550426)
			(xy 17.198086 -377.56846) (xy 17.197578 -377.660916) (xy 17.204944 -377.679204) (xy 17.21231 -377.68657)
			(xy 17.232799 -377.708117) (xy 17.267497 -377.756399) (xy 17.294282 -377.80948) (xy 17.312506 -377.866075)
			(xy 17.321726 -377.924812) (xy 17.322292 -377.95454) (xy 17.321806 -377.981791) (xy 17.31405 -378.035739)
			(xy 17.298695 -378.088034) (xy 17.276053 -378.137611) (xy 17.246587 -378.183461) (xy 17.210896 -378.224652)
			(xy 17.169705 -378.260343) (xy 17.123855 -378.289809) (xy 17.074278 -378.312451) (xy 17.021983 -378.327806)
			(xy 16.968035 -378.335562) (xy 16.913533 -378.335562) (xy 16.859585 -378.327806) (xy 16.80729 -378.312451)
			(xy 16.757713 -378.289809) (xy 16.711863 -378.260343) (xy 16.670672 -378.224652) (xy 16.634981 -378.183461)
			(xy 16.605515 -378.137611) (xy 16.582873 -378.088034) (xy 16.567518 -378.035739) (xy 16.559762 -377.981791)
			(xy 16.559276 -377.95454) (xy 15.054911 -377.95454) (xy 15.055088 -377.963938) (xy 15.054596 -377.991648)
			(xy 15.046568 -378.046482) (xy 15.030685 -378.099577) (xy 15.007284 -378.149813) (xy 14.976857 -378.196133)
			(xy 14.958822 -378.217176) (xy 14.952726 -378.224288) (xy 14.946122 -378.24156) (xy 14.946376 -378.328174)
			(xy 14.95298 -378.345446) (xy 14.95933 -378.352558) (xy 14.977614 -378.373652) (xy 15.00844 -378.420193)
			(xy 15.032153 -378.470729) (xy 15.048248 -378.524181) (xy 15.056381 -378.579408) (xy 15.056866 -378.60732)
			(xy 15.05638 -378.634571) (xy 15.048624 -378.688519) (xy 15.033269 -378.740814) (xy 15.010627 -378.790391)
			(xy 14.981161 -378.836241) (xy 14.94547 -378.877432) (xy 14.904279 -378.913123) (xy 14.858429 -378.942589)
			(xy 14.808852 -378.965231) (xy 14.756557 -378.980586) (xy 14.702609 -378.988342) (xy 14.648107 -378.988342)
			(xy 14.594159 -378.980586) (xy 14.541864 -378.965231) (xy 14.492287 -378.942589) (xy 14.446437 -378.913123)
			(xy 14.405246 -378.877432) (xy 14.369555 -378.836241) (xy 14.340089 -378.790391) (xy 14.317447 -378.740814)
			(xy 14.302092 -378.688519) (xy 14.294336 -378.634571) (xy 14.29385 -378.60732) (xy 14.294333 -378.57961)
			(xy 14.302366 -378.524776) (xy 14.318251 -378.471681) (xy 14.341654 -378.421445) (xy 14.372081 -378.375126)
			(xy 14.390116 -378.354082) (xy 14.396212 -378.34697) (xy 14.402816 -378.329698) (xy 14.402562 -378.243084)
			(xy 14.395958 -378.225812) (xy 14.389608 -378.2187) (xy 14.371357 -378.197578) (xy 14.340525 -378.151046)
			(xy 14.316805 -378.100517) (xy 14.300702 -378.047071) (xy 14.292561 -377.991848) (xy 14.292072 -377.963938)
			(xy 4.454652 -377.963938) (xy 4.454652 -381.608076) (xy 4.455096 -381.618105) (xy 4.462681 -381.63667)
			(xy 4.469384 -381.644144) (xy 11.354054 -388.528814) (xy 11.37721 -388.552729) (xy 11.417749 -388.60553)
			(xy 11.451054 -388.663167) (xy 11.476557 -388.724657) (xy 11.493822 -388.788947) (xy 11.502553 -388.85494)
			(xy 11.503152 -388.888224) (xy 11.503152 -389.22833) (xy 11.907264 -389.22833) (xy 11.911335 -389.172708)
			(xy 11.923461 -389.118271) (xy 11.943384 -389.06618) (xy 11.97068 -389.017545) (xy 12.004766 -388.973402)
			(xy 12.044915 -388.934693) (xy 12.090273 -388.902242) (xy 12.139873 -388.876741) (xy 12.192657 -388.858734)
			(xy 12.2475 -388.848604) (xy 12.303234 -388.846567) (xy 12.358671 -388.852667) (xy 12.412628 -388.866773)
			(xy 12.463957 -388.888585) (xy 12.511563 -388.917639) (xy 12.554431 -388.953314) (xy 12.591648 -388.994851)
			(xy 12.622421 -389.041364) (xy 12.646093 -389.091861) (xy 12.662161 -389.145268) (xy 12.670281 -389.200444)
			(xy 12.67079 -389.22833) (xy 12.670281 -389.256216) (xy 12.662161 -389.311392) (xy 12.646093 -389.364799)
			(xy 12.622421 -389.415296) (xy 12.591648 -389.461809) (xy 12.554431 -389.503346) (xy 12.511563 -389.539021)
			(xy 12.463957 -389.568075) (xy 12.412628 -389.589887) (xy 12.358671 -389.603993) (xy 12.303234 -389.610093)
			(xy 12.2475 -389.608056) (xy 12.192657 -389.597926) (xy 12.139873 -389.579919) (xy 12.090273 -389.554418)
			(xy 12.044915 -389.521967) (xy 12.004766 -389.483258) (xy 11.97068 -389.439115) (xy 11.943384 -389.39048)
			(xy 11.923461 -389.338389) (xy 11.911335 -389.283952) (xy 11.907264 -389.22833) (xy 11.503152 -389.22833)
			(xy 11.503152 -390.219184) (xy 11.84986 -390.219184) (xy 11.853931 -390.163562) (xy 11.866057 -390.109125)
			(xy 11.88598 -390.057034) (xy 11.913276 -390.008399) (xy 11.947362 -389.964256) (xy 11.987511 -389.925547)
			(xy 12.032869 -389.893096) (xy 12.082469 -389.867595) (xy 12.135253 -389.849588) (xy 12.190096 -389.839458)
			(xy 12.24583 -389.837421) (xy 12.301267 -389.843521) (xy 12.355224 -389.857627) (xy 12.406553 -389.879439)
			(xy 12.454159 -389.908493) (xy 12.497027 -389.944168) (xy 12.534244 -389.985705) (xy 12.565017 -390.032218)
			(xy 12.588689 -390.082715) (xy 12.604757 -390.136122) (xy 12.612877 -390.191298) (xy 12.613386 -390.219184)
			(xy 12.612877 -390.24707) (xy 12.604757 -390.302246) (xy 12.588689 -390.355653) (xy 12.565017 -390.40615)
			(xy 12.534244 -390.452663) (xy 12.497027 -390.4942) (xy 12.454159 -390.529875) (xy 12.406553 -390.558929)
			(xy 12.355224 -390.580741) (xy 12.301267 -390.594847) (xy 12.24583 -390.600947) (xy 12.190096 -390.59891)
			(xy 12.135253 -390.58878) (xy 12.082469 -390.570773) (xy 12.032869 -390.545272) (xy 11.987511 -390.512821)
			(xy 11.947362 -390.474112) (xy 11.913276 -390.429969) (xy 11.88598 -390.381334) (xy 11.866057 -390.329243)
			(xy 11.853931 -390.274806) (xy 11.84986 -390.219184) (xy 11.503152 -390.219184) (xy 11.503152 -392.674094)
			(xy 11.892278 -392.674094) (xy 11.896349 -392.618472) (xy 11.908475 -392.564035) (xy 11.928398 -392.511944)
			(xy 11.955694 -392.463309) (xy 11.98978 -392.419166) (xy 12.029929 -392.380457) (xy 12.075287 -392.348006)
			(xy 12.124887 -392.322505) (xy 12.177671 -392.304498) (xy 12.232514 -392.294368) (xy 12.288248 -392.292331)
			(xy 12.343685 -392.298431) (xy 12.397642 -392.312537) (xy 12.448971 -392.334349) (xy 12.496577 -392.363403)
			(xy 12.539445 -392.399078) (xy 12.576662 -392.440615) (xy 12.607435 -392.487128) (xy 12.631107 -392.537625)
			(xy 12.647175 -392.591032) (xy 12.655295 -392.646208) (xy 12.655804 -392.674094) (xy 12.655295 -392.70198)
			(xy 12.647175 -392.757156) (xy 12.631107 -392.810563) (xy 12.607435 -392.86106) (xy 12.576662 -392.907573)
			(xy 12.562991 -392.922831) (xy 15.26665 -392.922831) (xy 15.26665 -392.868329) (xy 15.274406 -392.814381)
			(xy 15.289761 -392.762087) (xy 15.312402 -392.71251) (xy 15.341868 -392.66666) (xy 15.37756 -392.62547)
			(xy 15.41875 -392.589778) (xy 15.4646 -392.560312) (xy 15.514177 -392.537671) (xy 15.566471 -392.522316)
			(xy 15.620419 -392.51456) (xy 15.64767 -392.514074) (xy 15.676293 -392.514562) (xy 15.732896 -392.523107)
			(xy 15.787589 -392.540011) (xy 15.839143 -392.564893) (xy 15.863062 -392.580622) (xy 15.871698 -392.586464)
			(xy 15.891256 -392.590528) (xy 15.983204 -392.571986) (xy 15.999968 -392.56081) (xy 16.005556 -392.55192)
			(xy 16.020677 -392.529346) (xy 16.056374 -392.488382) (xy 16.097522 -392.452896) (xy 16.143288 -392.423608)
			(xy 16.192746 -392.401109) (xy 16.244896 -392.385854) (xy 16.298682 -392.378152) (xy 16.32585 -392.377676)
			(xy 16.353102 -392.378154) (xy 16.40705 -392.38591) (xy 16.459345 -392.401266) (xy 16.508923 -392.423907)
			(xy 16.554774 -392.453374) (xy 16.595964 -392.489066) (xy 16.631656 -392.530256) (xy 16.661123 -392.576107)
			(xy 16.683764 -392.625685) (xy 16.69912 -392.67798) (xy 16.706876 -392.731928) (xy 16.706876 -392.786432)
			(xy 16.69912 -392.84038) (xy 16.683764 -392.892675) (xy 16.661123 -392.942253) (xy 16.631656 -392.988104)
			(xy 16.595964 -393.029294) (xy 16.554774 -393.064986) (xy 16.508923 -393.094453) (xy 16.459345 -393.117094)
			(xy 16.40705 -393.13245) (xy 16.353102 -393.140206) (xy 16.32585 -393.140692) (xy 16.297228 -393.1402)
			(xy 16.240624 -393.131657) (xy 16.185931 -393.114755) (xy 16.134377 -393.089873) (xy 16.110458 -393.074144)
			(xy 16.101822 -393.068302) (xy 16.082264 -393.064238) (xy 15.990316 -393.08278) (xy 15.973552 -393.093956)
			(xy 15.967964 -393.102846) (xy 15.952818 -393.125403) (xy 15.917126 -393.166369) (xy 15.875984 -393.201857)
			(xy 15.830222 -393.231148) (xy 15.780767 -393.25365) (xy 15.728621 -393.268907) (xy 15.674837 -393.276612)
			(xy 15.64767 -393.27709) (xy 15.620419 -393.2766) (xy 15.566471 -393.268844) (xy 15.514177 -393.253489)
			(xy 15.4646 -393.230848) (xy 15.41875 -393.201382) (xy 15.37756 -393.16569) (xy 15.341868 -393.1245)
			(xy 15.312402 -393.07865) (xy 15.289761 -393.029073) (xy 15.274406 -392.976779) (xy 15.26665 -392.922831)
			(xy 12.562991 -392.922831) (xy 12.539445 -392.94911) (xy 12.496577 -392.984785) (xy 12.448971 -393.013839)
			(xy 12.397642 -393.035651) (xy 12.343685 -393.049757) (xy 12.288248 -393.055857) (xy 12.232514 -393.05382)
			(xy 12.177671 -393.04369) (xy 12.124887 -393.025683) (xy 12.075287 -393.000182) (xy 12.029929 -392.967731)
			(xy 11.98978 -392.929022) (xy 11.955694 -392.884879) (xy 11.928398 -392.836244) (xy 11.908475 -392.784153)
			(xy 11.896349 -392.729716) (xy 11.892278 -392.674094) (xy 11.503152 -392.674094) (xy 11.503152 -393.582144)
			(xy 16.440148 -393.582144) (xy 16.444219 -393.526522) (xy 16.456345 -393.472085) (xy 16.476268 -393.419994)
			(xy 16.503564 -393.371359) (xy 16.53765 -393.327216) (xy 16.577799 -393.288507) (xy 16.623157 -393.256056)
			(xy 16.672757 -393.230555) (xy 16.725541 -393.212548) (xy 16.780384 -393.202418) (xy 16.836118 -393.200381)
			(xy 16.891555 -393.206481) (xy 16.945512 -393.220587) (xy 16.996841 -393.242399) (xy 17.044447 -393.271453)
			(xy 17.087315 -393.307128) (xy 17.124532 -393.348665) (xy 17.155305 -393.395178) (xy 17.178977 -393.445675)
			(xy 17.195045 -393.499082) (xy 17.203165 -393.554258) (xy 17.203674 -393.582144) (xy 17.203165 -393.61003)
			(xy 17.195045 -393.665206) (xy 17.178977 -393.718613) (xy 17.155305 -393.76911) (xy 17.124532 -393.815623)
			(xy 17.087315 -393.85716) (xy 17.044447 -393.892835) (xy 16.996841 -393.921889) (xy 16.945512 -393.943701)
			(xy 16.891555 -393.957807) (xy 16.836118 -393.963907) (xy 16.780384 -393.96187) (xy 16.725541 -393.95174)
			(xy 16.672757 -393.933733) (xy 16.623157 -393.908232) (xy 16.577799 -393.875781) (xy 16.53765 -393.837072)
			(xy 16.503564 -393.792929) (xy 16.476268 -393.744294) (xy 16.456345 -393.692203) (xy 16.444219 -393.637766)
			(xy 16.440148 -393.582144) (xy 11.503152 -393.582144) (xy 11.503152 -393.642596) (xy 11.503599 -393.652624)
			(xy 11.51119 -393.671183) (xy 11.517884 -393.678664) (xy 11.940794 -394.101574) (xy 11.948238 -394.108268)
			(xy 11.966736 -394.115867) (xy 11.986734 -394.115853) (xy 11.996166 -394.112496) (xy 12.097258 -394.070586)
			(xy 12.114276 -394.044932) (xy 12.114276 -394.029438) (xy 12.114688 -394.00215) (xy 12.12236 -393.948118)
			(xy 12.137652 -393.895731) (xy 12.160252 -393.846057) (xy 12.1897 -393.80011) (xy 12.225394 -393.758827)
			(xy 12.266605 -393.723052) (xy 12.312494 -393.693514) (xy 12.362123 -393.670815) (xy 12.414481 -393.65542)
			(xy 12.468497 -393.647642) (xy 12.495784 -393.647168) (xy 12.523037 -393.647653) (xy 12.576987 -393.655407)
			(xy 12.629285 -393.670761) (xy 12.678866 -393.693401) (xy 12.72472 -393.722866) (xy 12.765914 -393.758557)
			(xy 12.80161 -393.799748) (xy 12.83108 -393.845599) (xy 12.853725 -393.895177) (xy 12.869084 -393.947473)
			(xy 12.876844 -394.001423) (xy 12.877292 -394.028676) (xy 12.877029 -394.043154) (xy 13.681962 -394.043154)
			(xy 13.686033 -393.987532) (xy 13.698159 -393.933095) (xy 13.718082 -393.881004) (xy 13.745378 -393.832369)
			(xy 13.779464 -393.788226) (xy 13.819613 -393.749517) (xy 13.864971 -393.717066) (xy 13.914571 -393.691565)
			(xy 13.967355 -393.673558) (xy 14.022198 -393.663428) (xy 14.077932 -393.661391) (xy 14.133369 -393.667491)
			(xy 14.187326 -393.681597) (xy 14.238655 -393.703409) (xy 14.286261 -393.732463) (xy 14.329129 -393.768138)
			(xy 14.366346 -393.809675) (xy 14.397119 -393.856188) (xy 14.420791 -393.906685) (xy 14.436859 -393.960092)
			(xy 14.444979 -394.015268) (xy 14.445488 -394.043154) (xy 14.444979 -394.07104) (xy 14.436859 -394.126216)
			(xy 14.420791 -394.179623) (xy 14.397119 -394.23012) (xy 14.366346 -394.276633) (xy 14.329129 -394.31817)
			(xy 14.286261 -394.353845) (xy 14.238655 -394.382899) (xy 14.187326 -394.404711) (xy 14.133369 -394.418817)
			(xy 14.077932 -394.424917) (xy 14.022198 -394.42288) (xy 13.967355 -394.41275) (xy 13.914571 -394.394743)
			(xy 13.864971 -394.369242) (xy 13.819613 -394.336791) (xy 13.779464 -394.298082) (xy 13.745378 -394.253939)
			(xy 13.718082 -394.205304) (xy 13.698159 -394.153213) (xy 13.686033 -394.098776) (xy 13.681962 -394.043154)
			(xy 12.877029 -394.043154) (xy 12.87678 -394.05687) (xy 12.868473 -394.112644) (xy 12.85205 -394.166589)
			(xy 12.827869 -394.21753) (xy 12.796457 -394.26436) (xy 12.758497 -394.306058) (xy 12.714815 -394.341717)
			(xy 12.690856 -394.35659) (xy 12.679426 -394.363448) (xy 12.666218 -394.386308) (xy 12.665202 -394.5001)
			(xy 12.678156 -394.523214) (xy 12.689332 -394.530326) (xy 12.716592 -394.547744) (xy 12.766886 -394.588432)
			(xy 12.811609 -394.635175) (xy 12.850037 -394.687217) (xy 12.881547 -394.743716) (xy 12.905631 -394.803757)
			(xy 12.921899 -394.86637) (xy 12.930087 -394.930542) (xy 12.930632 -394.962888) (xy 12.930169 -394.99361)
			(xy 12.922767 -395.054607) (xy 12.908068 -395.114268) (xy 12.886288 -395.171722) (xy 12.857744 -395.226134)
			(xy 12.822851 -395.27671) (xy 12.782117 -395.322712) (xy 12.736138 -395.363471) (xy 12.685582 -395.398393)
			(xy 12.631187 -395.426969) (xy 12.573745 -395.448782) (xy 12.514093 -395.463514) (xy 12.4531 -395.470952)
			(xy 12.422378 -395.471396) (xy 11.851386 -395.471396) (xy 11.841359 -395.471845) (xy 11.822799 -395.479435)
			(xy 11.815318 -395.486128) (xy 11.240516 -396.06093) (xy 12.002514 -396.06093) (xy 12.006585 -396.005308)
			(xy 12.018711 -395.950871) (xy 12.038634 -395.89878) (xy 12.06593 -395.850145) (xy 12.100016 -395.806002)
			(xy 12.140165 -395.767293) (xy 12.185523 -395.734842) (xy 12.235123 -395.709341) (xy 12.287907 -395.691334)
			(xy 12.34275 -395.681204) (xy 12.398484 -395.679167) (xy 12.453921 -395.685267) (xy 12.507878 -395.699373)
			(xy 12.559207 -395.721185) (xy 12.606813 -395.750239) (xy 12.649681 -395.785914) (xy 12.686898 -395.827451)
			(xy 12.717671 -395.873964) (xy 12.741343 -395.924461) (xy 12.757411 -395.977868) (xy 12.765531 -396.033044)
			(xy 12.76604 -396.06093) (xy 12.765531 -396.088816) (xy 12.757411 -396.143992) (xy 12.741343 -396.197399)
			(xy 12.717671 -396.247896) (xy 12.686898 -396.294409) (xy 12.649681 -396.335946) (xy 12.606813 -396.371621)
			(xy 12.559207 -396.400675) (xy 12.507878 -396.422487) (xy 12.453921 -396.436593) (xy 12.398484 -396.442693)
			(xy 12.34275 -396.440656) (xy 12.287907 -396.430526) (xy 12.235123 -396.412519) (xy 12.185523 -396.387018)
			(xy 12.140165 -396.354567) (xy 12.100016 -396.315858) (xy 12.06593 -396.271715) (xy 12.038634 -396.22308)
			(xy 12.018711 -396.170989) (xy 12.006585 -396.116552) (xy 12.002514 -396.06093) (xy 11.240516 -396.06093)
			(xy 7.281164 -400.020282) (xy 7.274387 -400.027707) (xy 7.266793 -400.046304) (xy 7.266432 -400.05635)
			(xy 7.266432 -402.56079) (xy 11.742672 -402.56079) (xy 11.746743 -402.505168) (xy 11.758869 -402.450731)
			(xy 11.778792 -402.39864) (xy 11.806088 -402.350005) (xy 11.840174 -402.305862) (xy 11.880323 -402.267153)
			(xy 11.925681 -402.234702) (xy 11.975281 -402.209201) (xy 12.028065 -402.191194) (xy 12.082908 -402.181064)
			(xy 12.138642 -402.179027) (xy 12.194079 -402.185127) (xy 12.248036 -402.199233) (xy 12.299365 -402.221045)
			(xy 12.346971 -402.250099) (xy 12.389839 -402.285774) (xy 12.427056 -402.327311) (xy 12.457829 -402.373824)
			(xy 12.481501 -402.424321) (xy 12.497569 -402.477728) (xy 12.505689 -402.532904) (xy 12.506198 -402.56079)
			(xy 12.505689 -402.588676) (xy 12.497569 -402.643852) (xy 12.481501 -402.697259) (xy 12.457829 -402.747756)
			(xy 12.427056 -402.794269) (xy 12.389839 -402.835806) (xy 12.346971 -402.871481) (xy 12.299365 -402.900535)
			(xy 12.248036 -402.922347) (xy 12.194079 -402.936453) (xy 12.138642 -402.942553) (xy 12.082908 -402.940516)
			(xy 12.028065 -402.930386) (xy 11.975281 -402.912379) (xy 11.925681 -402.886878) (xy 11.880323 -402.854427)
			(xy 11.840174 -402.815718) (xy 11.806088 -402.771575) (xy 11.778792 -402.72294) (xy 11.758869 -402.670849)
			(xy 11.746743 -402.616412) (xy 11.742672 -402.56079) (xy 7.266432 -402.56079) (xy 7.266432 -403.220174)
			(xy 14.510764 -403.220174) (xy 14.514835 -403.164552) (xy 14.526961 -403.110115) (xy 14.546884 -403.058024)
			(xy 14.57418 -403.009389) (xy 14.608266 -402.965246) (xy 14.648415 -402.926537) (xy 14.693773 -402.894086)
			(xy 14.743373 -402.868585) (xy 14.796157 -402.850578) (xy 14.851 -402.840448) (xy 14.906734 -402.838411)
			(xy 14.962171 -402.844511) (xy 15.016128 -402.858617) (xy 15.067457 -402.880429) (xy 15.115063 -402.909483)
			(xy 15.157931 -402.945158) (xy 15.195148 -402.986695) (xy 15.225921 -403.033208) (xy 15.249593 -403.083705)
			(xy 15.265661 -403.137112) (xy 15.273781 -403.192288) (xy 15.27429 -403.220174) (xy 15.780764 -403.220174)
			(xy 15.784835 -403.164552) (xy 15.796961 -403.110115) (xy 15.816884 -403.058024) (xy 15.84418 -403.009389)
			(xy 15.878266 -402.965246) (xy 15.918415 -402.926537) (xy 15.963773 -402.894086) (xy 16.013373 -402.868585)
			(xy 16.066157 -402.850578) (xy 16.121 -402.840448) (xy 16.176734 -402.838411) (xy 16.232171 -402.844511)
			(xy 16.286128 -402.858617) (xy 16.337457 -402.880429) (xy 16.385063 -402.909483) (xy 16.427931 -402.945158)
			(xy 16.465148 -402.986695) (xy 16.495921 -403.033208) (xy 16.519593 -403.083705) (xy 16.535661 -403.137112)
			(xy 16.543781 -403.192288) (xy 16.54429 -403.220174) (xy 16.543781 -403.24806) (xy 16.535661 -403.303236)
			(xy 16.528937 -403.325584) (xy 16.923764 -403.325584) (xy 16.927835 -403.269962) (xy 16.939961 -403.215525)
			(xy 16.959884 -403.163434) (xy 16.98718 -403.114799) (xy 17.021266 -403.070656) (xy 17.061415 -403.031947)
			(xy 17.106773 -402.999496) (xy 17.156373 -402.973995) (xy 17.209157 -402.955988) (xy 17.264 -402.945858)
			(xy 17.319734 -402.943821) (xy 17.375171 -402.949921) (xy 17.429128 -402.964027) (xy 17.480457 -402.985839)
			(xy 17.528063 -403.014893) (xy 17.570931 -403.050568) (xy 17.608148 -403.092105) (xy 17.638921 -403.138618)
			(xy 17.662593 -403.189115) (xy 17.663073 -403.19071) (xy 18.073622 -403.19071) (xy 18.077693 -403.135088)
			(xy 18.089819 -403.080651) (xy 18.109742 -403.02856) (xy 18.137038 -402.979925) (xy 18.171124 -402.935782)
			(xy 18.211273 -402.897073) (xy 18.256631 -402.864622) (xy 18.306231 -402.839121) (xy 18.359015 -402.821114)
			(xy 18.413858 -402.810984) (xy 18.469592 -402.808947) (xy 18.525029 -402.815047) (xy 18.578986 -402.829153)
			(xy 18.630315 -402.850965) (xy 18.677921 -402.880019) (xy 18.720789 -402.915694) (xy 18.758006 -402.957231)
			(xy 18.788779 -403.003744) (xy 18.812451 -403.054241) (xy 18.828519 -403.107648) (xy 18.836639 -403.162824)
			(xy 18.837148 -403.19071) (xy 18.836639 -403.218596) (xy 18.828519 -403.273772) (xy 18.812451 -403.327179)
			(xy 18.788779 -403.377676) (xy 18.758006 -403.424189) (xy 18.720789 -403.465726) (xy 18.677921 -403.501401)
			(xy 18.630315 -403.530455) (xy 18.578986 -403.552267) (xy 18.525029 -403.566373) (xy 18.469592 -403.572473)
			(xy 18.413858 -403.570436) (xy 18.359015 -403.560306) (xy 18.306231 -403.542299) (xy 18.256631 -403.516798)
			(xy 18.211273 -403.484347) (xy 18.171124 -403.445638) (xy 18.137038 -403.401495) (xy 18.109742 -403.35286)
			(xy 18.089819 -403.300769) (xy 18.077693 -403.246332) (xy 18.073622 -403.19071) (xy 17.663073 -403.19071)
			(xy 17.678661 -403.242522) (xy 17.686781 -403.297698) (xy 17.68729 -403.325584) (xy 17.686781 -403.35347)
			(xy 17.678661 -403.408646) (xy 17.662593 -403.462053) (xy 17.638921 -403.51255) (xy 17.608148 -403.559063)
			(xy 17.570931 -403.6006) (xy 17.528063 -403.636275) (xy 17.480457 -403.665329) (xy 17.429128 -403.687141)
			(xy 17.375171 -403.701247) (xy 17.319734 -403.707347) (xy 17.264 -403.70531) (xy 17.209157 -403.69518)
			(xy 17.156373 -403.677173) (xy 17.106773 -403.651672) (xy 17.061415 -403.619221) (xy 17.021266 -403.580512)
			(xy 16.98718 -403.536369) (xy 16.959884 -403.487734) (xy 16.939961 -403.435643) (xy 16.927835 -403.381206)
			(xy 16.923764 -403.325584) (xy 16.528937 -403.325584) (xy 16.519593 -403.356643) (xy 16.495921 -403.40714)
			(xy 16.465148 -403.453653) (xy 16.427931 -403.49519) (xy 16.385063 -403.530865) (xy 16.337457 -403.559919)
			(xy 16.286128 -403.581731) (xy 16.232171 -403.595837) (xy 16.176734 -403.601937) (xy 16.121 -403.5999)
			(xy 16.066157 -403.58977) (xy 16.013373 -403.571763) (xy 15.963773 -403.546262) (xy 15.918415 -403.513811)
			(xy 15.878266 -403.475102) (xy 15.84418 -403.430959) (xy 15.816884 -403.382324) (xy 15.796961 -403.330233)
			(xy 15.784835 -403.275796) (xy 15.780764 -403.220174) (xy 15.27429 -403.220174) (xy 15.273781 -403.24806)
			(xy 15.265661 -403.303236) (xy 15.249593 -403.356643) (xy 15.225921 -403.40714) (xy 15.195148 -403.453653)
			(xy 15.157931 -403.49519) (xy 15.115063 -403.530865) (xy 15.067457 -403.559919) (xy 15.016128 -403.581731)
			(xy 14.962171 -403.595837) (xy 14.906734 -403.601937) (xy 14.851 -403.5999) (xy 14.796157 -403.58977)
			(xy 14.743373 -403.571763) (xy 14.693773 -403.546262) (xy 14.648415 -403.513811) (xy 14.608266 -403.475102)
			(xy 14.57418 -403.430959) (xy 14.546884 -403.382324) (xy 14.526961 -403.330233) (xy 14.514835 -403.275796)
			(xy 14.510764 -403.220174) (xy 7.266432 -403.220174) (xy 7.266432 -404.21687) (xy 9.284714 -404.21687)
			(xy 9.288785 -404.161248) (xy 9.300911 -404.106811) (xy 9.320834 -404.05472) (xy 9.34813 -404.006085)
			(xy 9.382216 -403.961942) (xy 9.422365 -403.923233) (xy 9.467723 -403.890782) (xy 9.517323 -403.865281)
			(xy 9.570107 -403.847274) (xy 9.62495 -403.837144) (xy 9.680684 -403.835107) (xy 9.736121 -403.841207)
			(xy 9.789546 -403.855174) (xy 11.803124 -403.855174) (xy 11.807195 -403.799552) (xy 11.819321 -403.745115)
			(xy 11.839244 -403.693024) (xy 11.86654 -403.644389) (xy 11.900626 -403.600246) (xy 11.940775 -403.561537)
			(xy 11.986133 -403.529086) (xy 12.035733 -403.503585) (xy 12.088517 -403.485578) (xy 12.14336 -403.475448)
			(xy 12.199094 -403.473411) (xy 12.254531 -403.479511) (xy 12.308488 -403.493617) (xy 12.359817 -403.515429)
			(xy 12.407423 -403.544483) (xy 12.450291 -403.580158) (xy 12.487508 -403.621695) (xy 12.518281 -403.668208)
			(xy 12.541953 -403.718705) (xy 12.558021 -403.772112) (xy 12.566141 -403.827288) (xy 12.56665 -403.855174)
			(xy 12.566141 -403.88306) (xy 12.558021 -403.938236) (xy 12.541953 -403.991643) (xy 12.518281 -404.04214)
			(xy 12.487508 -404.088653) (xy 12.450291 -404.13019) (xy 12.407423 -404.165865) (xy 12.359817 -404.194919)
			(xy 12.308488 -404.216731) (xy 12.254531 -404.230837) (xy 12.199094 -404.236937) (xy 12.14336 -404.2349)
			(xy 12.088517 -404.22477) (xy 12.035733 -404.206763) (xy 11.986133 -404.181262) (xy 11.940775 -404.148811)
			(xy 11.900626 -404.110102) (xy 11.86654 -404.065959) (xy 11.839244 -404.017324) (xy 11.819321 -403.965233)
			(xy 11.807195 -403.910796) (xy 11.803124 -403.855174) (xy 9.789546 -403.855174) (xy 9.790078 -403.855313)
			(xy 9.841407 -403.877125) (xy 9.889013 -403.906179) (xy 9.931881 -403.941854) (xy 9.969098 -403.983391)
			(xy 9.999871 -404.029904) (xy 10.023543 -404.080401) (xy 10.039611 -404.133808) (xy 10.047731 -404.188984)
			(xy 10.04824 -404.21687) (xy 10.047731 -404.244756) (xy 10.039611 -404.299932) (xy 10.023543 -404.353339)
			(xy 9.999871 -404.403836) (xy 9.969098 -404.450349) (xy 9.931881 -404.491886) (xy 9.889013 -404.527561)
			(xy 9.841407 -404.556615) (xy 9.790078 -404.578427) (xy 9.736121 -404.592533) (xy 9.680684 -404.598633)
			(xy 9.62495 -404.596596) (xy 9.570107 -404.586466) (xy 9.517323 -404.568459) (xy 9.467723 -404.542958)
			(xy 9.422365 -404.510507) (xy 9.382216 -404.471798) (xy 9.34813 -404.427655) (xy 9.320834 -404.37902)
			(xy 9.300911 -404.326929) (xy 9.288785 -404.272492) (xy 9.284714 -404.21687) (xy 7.266432 -404.21687)
			(xy 7.266432 -404.68931) (xy 20.193506 -404.68931) (xy 20.197577 -404.633688) (xy 20.209703 -404.579251)
			(xy 20.229626 -404.52716) (xy 20.256922 -404.478525) (xy 20.291008 -404.434382) (xy 20.331157 -404.395673)
			(xy 20.376515 -404.363222) (xy 20.426115 -404.337721) (xy 20.478899 -404.319714) (xy 20.533742 -404.309584)
			(xy 20.589476 -404.307547) (xy 20.644913 -404.313647) (xy 20.69887 -404.327753) (xy 20.750199 -404.349565)
			(xy 20.797805 -404.378619) (xy 20.840673 -404.414294) (xy 20.87789 -404.455831) (xy 20.908663 -404.502344)
			(xy 20.932335 -404.552841) (xy 20.948403 -404.606248) (xy 20.956523 -404.661424) (xy 20.957032 -404.68931)
			(xy 20.956523 -404.717196) (xy 20.948403 -404.772372) (xy 20.932335 -404.825779) (xy 20.908663 -404.876276)
			(xy 20.87789 -404.922789) (xy 20.840673 -404.964326) (xy 20.797805 -405.000001) (xy 20.750199 -405.029055)
			(xy 20.69887 -405.050867) (xy 20.644913 -405.064973) (xy 20.589476 -405.071073) (xy 20.533742 -405.069036)
			(xy 20.478899 -405.058906) (xy 20.426115 -405.040899) (xy 20.376515 -405.015398) (xy 20.331157 -404.982947)
			(xy 20.291008 -404.944238) (xy 20.256922 -404.900095) (xy 20.229626 -404.85146) (xy 20.209703 -404.799369)
			(xy 20.197577 -404.744932) (xy 20.193506 -404.68931) (xy 7.266432 -404.68931) (xy 7.266432 -405.114252)
			(xy 7.266916 -405.124215) (xy 7.274504 -405.14264) (xy 7.281164 -405.150066) (xy 7.288022 -405.156924)
			(xy 7.295642 -405.175466) (xy 7.295642 -405.828754) (xy 7.296172 -405.838744) (xy 7.303879 -405.857184)
			(xy 7.310628 -405.864568) (xy 7.931404 -406.485344) (xy 7.938747 -406.49216) (xy 7.95721 -406.4999)
			(xy 7.967218 -406.50033) (xy 8.53821 -406.50033) (xy 8.547462 -406.49988) (xy 8.564738 -406.493241)
			(xy 8.578558 -406.48093) (xy 8.583168 -406.472898) (xy 8.631428 -406.379934) (xy 8.629396 -406.35174)
			(xy 8.621014 -406.340056) (xy 8.604481 -406.315744) (xy 8.578291 -406.263107) (xy 8.56048 -406.207078)
			(xy 8.551469 -406.14898) (xy 8.55091 -406.119584) (xy 8.551396 -406.092333) (xy 8.559152 -406.038385)
			(xy 8.574507 -405.98609) (xy 8.597149 -405.936513) (xy 8.626615 -405.890663) (xy 8.662306 -405.849472)
			(xy 8.703497 -405.813781) (xy 8.749347 -405.784315) (xy 8.798924 -405.761673) (xy 8.851219 -405.746318)
			(xy 8.905167 -405.738562) (xy 8.959669 -405.738562) (xy 9.013617 -405.746318) (xy 9.065912 -405.761673)
			(xy 9.115489 -405.784315) (xy 9.161339 -405.813781) (xy 9.20253 -405.849472) (xy 9.238221 -405.890663)
			(xy 9.266555 -405.934751) (xy 14.302972 -405.934751) (xy 14.302972 -405.880249) (xy 14.310728 -405.826301)
			(xy 14.326083 -405.774005) (xy 14.348724 -405.724428) (xy 14.378191 -405.678577) (xy 14.413882 -405.637386)
			(xy 14.455072 -405.601694) (xy 14.500923 -405.572227) (xy 14.5505 -405.549585) (xy 14.602795 -405.53423)
			(xy 14.656743 -405.526472) (xy 14.683994 -405.525986) (xy 14.713337 -405.526528) (xy 14.771331 -405.535514)
			(xy 14.827264 -405.553275) (xy 14.879819 -405.579391) (xy 14.927754 -405.613248) (xy 14.969939 -405.654045)
			(xy 15.005379 -405.700822) (xy 15.019782 -405.726392) (xy 15.027447 -405.739632) (xy 15.049269 -405.76106)
			(xy 15.076451 -405.775076) (xy 15.106563 -405.780428) (xy 15.136911 -405.776636) (xy 15.16478 -405.764039)
			(xy 15.187677 -405.743765) (xy 15.196058 -405.730964) (xy 15.21095 -405.707329) (xy 15.2466 -405.66432)
			(xy 15.288146 -405.626974) (xy 15.334697 -405.596092) (xy 15.385257 -405.572334) (xy 15.438742 -405.556209)
			(xy 15.494008 -405.548062) (xy 15.52194 -405.547576) (xy 15.549192 -405.548054) (xy 15.60314 -405.55581)
			(xy 15.655435 -405.571166) (xy 15.705013 -405.593807) (xy 15.750864 -405.623274) (xy 15.792054 -405.658966)
			(xy 15.827746 -405.700156) (xy 15.857213 -405.746007) (xy 15.879854 -405.795585) (xy 15.89521 -405.84788)
			(xy 15.902966 -405.901828) (xy 15.902966 -405.956332) (xy 15.89521 -406.01028) (xy 15.892127 -406.020778)
			(xy 22.643338 -406.020778) (xy 22.64375 -405.995078) (xy 22.65065 -405.944142) (xy 22.664322 -405.894593)
			(xy 22.684518 -405.847326) (xy 22.710874 -405.803197) (xy 22.742913 -405.763003) (xy 22.761194 -405.744934)
			(xy 22.768814 -405.737822) (xy 22.776688 -405.71928) (xy 22.777704 -405.625554) (xy 22.770084 -405.607012)
			(xy 22.762464 -405.599646) (xy 22.741488 -405.578031) (xy 22.705977 -405.529382) (xy 22.678555 -405.475756)
			(xy 22.659903 -405.418487) (xy 22.650485 -405.358998) (xy 22.649942 -405.328882) (xy 22.650387 -405.301511)
			(xy 22.658209 -405.247331) (xy 22.673702 -405.194827) (xy 22.696549 -405.14508) (xy 22.726278 -405.099115)
			(xy 22.743922 -405.078184) (xy 22.750018 -405.071072) (xy 22.756368 -405.054054) (xy 22.756368 -404.96871)
			(xy 22.750018 -404.951692) (xy 22.743922 -404.94458) (xy 22.726264 -404.923661) (xy 22.69654 -404.877691)
			(xy 22.673696 -404.827942) (xy 22.658202 -404.775438) (xy 22.650375 -404.721258) (xy 22.650377 -404.666515)
			(xy 22.658207 -404.612335) (xy 22.673706 -404.559832) (xy 22.696553 -404.510085) (xy 22.72628 -404.464117)
			(xy 22.743922 -404.443184) (xy 22.750018 -404.436072) (xy 22.756368 -404.419054) (xy 22.756368 -404.33371)
			(xy 22.750018 -404.316692) (xy 22.743922 -404.30958) (xy 22.72631 -404.288626) (xy 22.696594 -404.242659)
			(xy 22.673752 -404.192918) (xy 22.658255 -404.140422) (xy 22.65042 -404.08625) (xy 22.649942 -404.058882)
			(xy 22.650428 -404.031631) (xy 22.658184 -403.977683) (xy 22.673539 -403.925388) (xy 22.696181 -403.875811)
			(xy 22.725647 -403.829961) (xy 22.761338 -403.78877) (xy 22.802529 -403.753079) (xy 22.848379 -403.723613)
			(xy 22.897956 -403.700971) (xy 22.950251 -403.685616) (xy 23.004199 -403.67786) (xy 23.058701 -403.67786)
			(xy 23.112649 -403.685616) (xy 23.164944 -403.700971) (xy 23.214521 -403.723613) (xy 23.260371 -403.753079)
			(xy 23.301562 -403.78877) (xy 23.337253 -403.829961) (xy 23.366719 -403.875811) (xy 23.389361 -403.925388)
			(xy 23.404716 -403.977683) (xy 23.412472 -404.031631) (xy 23.412958 -404.058882) (xy 23.412492 -404.086252)
			(xy 23.404675 -404.140432) (xy 23.389187 -404.192935) (xy 23.366345 -404.242682) (xy 23.33662 -404.288649)
			(xy 23.318978 -404.30958) (xy 23.312882 -404.316692) (xy 23.306532 -404.33371) (xy 23.306532 -404.419054)
			(xy 23.312882 -404.436072) (xy 23.318978 -404.443184) (xy 23.323804 -404.448772) (xy 23.330662 -404.4569)
			(xy 23.34895 -404.466298) (xy 23.443692 -404.472394) (xy 23.462996 -404.465282) (xy 23.470616 -404.45817)
			(xy 23.491895 -404.439221) (xy 23.539032 -404.407212) (xy 23.590401 -404.382562) (xy 23.644862 -404.365818)
			(xy 23.701207 -404.357351) (xy 23.729696 -404.356824) (xy 23.759819 -404.357405) (xy 23.819314 -404.366885)
			(xy 23.876582 -404.385593) (xy 23.930199 -404.413067) (xy 23.978834 -404.448623) (xy 24.00046 -404.4696)
			(xy 24.007572 -404.476966) (xy 24.026368 -404.484586) (xy 24.118824 -404.484586) (xy 24.13762 -404.476966)
			(xy 24.144732 -404.4696) (xy 24.166364 -404.448627) (xy 24.214991 -404.413058) (xy 24.268605 -404.385577)
			(xy 24.325874 -404.366867) (xy 24.385372 -404.357393) (xy 24.415496 -404.356824) (xy 24.441793 -404.357286)
			(xy 24.493889 -404.364503) (xy 24.544499 -404.378814) (xy 24.59266 -404.399948) (xy 24.637458 -404.427503)
			(xy 24.678041 -404.460956) (xy 24.696166 -404.480014) (xy 24.703278 -404.487634) (xy 24.721566 -404.496016)
			(xy 24.814022 -404.499318) (xy 24.833072 -404.49246) (xy 24.840438 -404.485348) (xy 24.861768 -404.466081)
			(xy 24.909129 -404.433514) (xy 24.96084 -404.40842) (xy 25.01573 -404.391369) (xy 25.072557 -404.382745)
			(xy 25.101296 -404.382224) (xy 25.131419 -404.382805) (xy 25.190914 -404.392285) (xy 25.248182 -404.410993)
			(xy 25.301799 -404.438467) (xy 25.350434 -404.474023) (xy 25.37206 -404.495) (xy 25.379172 -404.502366)
			(xy 25.397968 -404.509986) (xy 25.490424 -404.509986) (xy 25.50922 -404.502366) (xy 25.516332 -404.495)
			(xy 25.537964 -404.474027) (xy 25.586591 -404.438458) (xy 25.640205 -404.410977) (xy 25.697474 -404.392267)
			(xy 25.756972 -404.382793) (xy 25.787096 -404.382224) (xy 25.81435 -404.382659) (xy 25.868304 -404.390416)
			(xy 25.920604 -404.405774) (xy 25.970186 -404.428418) (xy 26.016041 -404.457888) (xy 26.057235 -404.493585)
			(xy 26.092928 -404.534781) (xy 26.122396 -404.580638) (xy 26.145036 -404.630222) (xy 26.16039 -404.682524)
			(xy 26.168143 -404.736478) (xy 26.168604 -404.763732) (xy 26.168156 -404.791103) (xy 26.160333 -404.845283)
			(xy 26.14484 -404.897786) (xy 26.121995 -404.947532) (xy 26.092267 -404.993499) (xy 26.074624 -405.01443)
			(xy 26.068528 -405.021542) (xy 26.062178 -405.03856) (xy 26.062178 -405.123904) (xy 26.068528 -405.140922)
			(xy 26.074624 -405.148034) (xy 26.092249 -405.168977) (xy 26.121962 -405.214947) (xy 26.144801 -405.264692)
			(xy 26.160295 -405.31719) (xy 26.168127 -405.371364) (xy 26.168604 -405.398732) (xy 26.168145 -405.425093)
			(xy 26.160898 -405.477315) (xy 26.146532 -405.528043) (xy 26.125321 -405.57631) (xy 26.097669 -405.621199)
			(xy 26.081228 -405.64181) (xy 26.075132 -405.649176) (xy 26.06929 -405.666702) (xy 26.0731 -405.754078)
			(xy 26.080466 -405.771096) (xy 26.087324 -405.777954) (xy 26.107808 -405.799505) (xy 26.142506 -405.847786)
			(xy 26.169292 -405.900866) (xy 26.187517 -405.95746) (xy 26.196739 -406.016196) (xy 26.197306 -406.045924)
			(xy 26.196845 -406.073176) (xy 26.189085 -406.127125) (xy 26.173726 -406.17942) (xy 26.151082 -406.228997)
			(xy 26.121613 -406.274848) (xy 26.085919 -406.316038) (xy 26.044727 -406.351729) (xy 25.998875 -406.381195)
			(xy 25.949296 -406.403836) (xy 25.896999 -406.41919) (xy 25.84305 -406.426946) (xy 25.815798 -406.427432)
			(xy 25.785674 -406.426868) (xy 25.726177 -406.417386) (xy 25.668909 -406.398674) (xy 25.615292 -406.371196)
			(xy 25.566658 -406.335636) (xy 25.545034 -406.314656) (xy 25.537922 -406.30729) (xy 25.519126 -406.29967)
			(xy 25.42667 -406.29967) (xy 25.407874 -406.30729) (xy 25.400762 -406.314656) (xy 25.379126 -406.335624)
			(xy 25.330501 -406.371196) (xy 25.276887 -406.398679) (xy 25.219619 -406.41739) (xy 25.160122 -406.426863)
			(xy 25.129998 -406.427432) (xy 25.1037 -406.426988) (xy 25.051602 -406.419769) (xy 25.000992 -406.405455)
			(xy 24.952831 -406.384318) (xy 24.908034 -406.356759) (xy 24.867451 -406.323303) (xy 24.849328 -406.304242)
			(xy 24.842216 -406.296622) (xy 24.823928 -406.28824) (xy 24.731472 -406.284938) (xy 24.712422 -406.291796)
			(xy 24.705056 -406.298908) (xy 24.683722 -406.31817) (xy 24.636363 -406.35074) (xy 24.584653 -406.375835)
			(xy 24.529763 -406.392887) (xy 24.472937 -406.401511) (xy 24.444198 -406.402032) (xy 24.414074 -406.401468)
			(xy 24.354577 -406.391986) (xy 24.297309 -406.373274) (xy 24.243692 -406.345796) (xy 24.195058 -406.310236)
			(xy 24.173434 -406.289256) (xy 24.166322 -406.28189) (xy 24.147526 -406.27427) (xy 24.05507 -406.27427)
			(xy 24.036274 -406.28189) (xy 24.029162 -406.289256) (xy 24.007526 -406.310224) (xy 23.958901 -406.345796)
			(xy 23.905287 -406.373279) (xy 23.848019 -406.39199) (xy 23.788522 -406.401463) (xy 23.758398 -406.402032)
			(xy 23.730987 -406.401592) (xy 23.676728 -406.393743) (xy 23.624152 -406.378209) (xy 23.574342 -406.355307)
			(xy 23.528323 -406.325511) (xy 23.487043 -406.289434) (xy 23.468838 -406.268936) (xy 23.461472 -406.260554)
			(xy 23.441406 -406.251156) (xy 23.342092 -406.251156) (xy 23.321772 -406.260554) (xy 23.31466 -406.268936)
			(xy 23.296441 -406.28946) (xy 23.255134 -406.325592) (xy 23.209079 -406.355436) (xy 23.159225 -406.378377)
			(xy 23.106598 -406.393941) (xy 23.052286 -406.401807) (xy 23.024846 -406.402286) (xy 22.997593 -406.401802)
			(xy 22.943642 -406.394051) (xy 22.891343 -406.378699) (xy 22.841762 -406.35606) (xy 22.795907 -406.326595)
			(xy 22.754714 -406.290903) (xy 22.719019 -406.249712) (xy 22.689551 -406.203859) (xy 22.666909 -406.154279)
			(xy 22.651555 -406.101982) (xy 22.6438 -406.048031) (xy 22.643338 -406.020778) (xy 15.892127 -406.020778)
			(xy 15.879854 -406.062575) (xy 15.857213 -406.112153) (xy 15.827746 -406.158004) (xy 15.792054 -406.199194)
			(xy 15.750864 -406.234886) (xy 15.705013 -406.264353) (xy 15.655435 -406.286994) (xy 15.60314 -406.30235)
			(xy 15.549192 -406.310106) (xy 15.52194 -406.310592) (xy 15.492597 -406.310034) (xy 15.434604 -406.301053)
			(xy 15.37867 -406.283296) (xy 15.326115 -406.257182) (xy 15.27818 -406.223328) (xy 15.235995 -406.182531)
			(xy 15.200555 -406.135756) (xy 15.186152 -406.110186) (xy 15.178439 -406.096978) (xy 15.156625 -406.075557)
			(xy 15.129453 -406.061544) (xy 15.099353 -406.05619) (xy 15.069016 -406.059975) (xy 15.041153 -406.07256)
			(xy 15.018258 -406.09282) (xy 15.009876 -406.105614) (xy 14.994953 -406.129229) (xy 14.959309 -406.172239)
			(xy 14.917769 -406.209586) (xy 14.871223 -406.240472) (xy 14.820668 -406.264233) (xy 14.767187 -406.280362)
			(xy 14.711924 -406.288514) (xy 14.683994 -406.289002) (xy 14.656743 -406.288528) (xy 14.602795 -406.28077)
			(xy 14.5505 -406.265415) (xy 14.500923 -406.242773) (xy 14.455072 -406.213306) (xy 14.413882 -406.177614)
			(xy 14.378191 -406.136423) (xy 14.348724 -406.090572) (xy 14.326083 -406.040995) (xy 14.310728 -405.988699)
			(xy 14.302972 -405.934751) (xy 9.266555 -405.934751) (xy 9.267687 -405.936513) (xy 9.290329 -405.98609)
			(xy 9.305684 -406.038385) (xy 9.31344 -406.092333) (xy 9.313926 -406.119584) (xy 9.313385 -406.148981)
			(xy 9.304373 -406.207081) (xy 9.286558 -406.263112) (xy 9.260364 -406.315748) (xy 9.243822 -406.340056)
			(xy 9.23544 -406.35174) (xy 9.233408 -406.379934) (xy 9.281668 -406.472898) (xy 9.286268 -406.480946)
			(xy 9.300063 -406.493304) (xy 9.317365 -406.499915) (xy 9.326626 -406.50033) (xy 10.953242 -406.50033)
			(xy 10.963308 -406.500761) (xy 10.981899 -406.50849) (xy 10.98931 -406.515316) (xy 11.101578 -406.627584)
			(xy 11.716764 -406.627584) (xy 11.720835 -406.571962) (xy 11.732961 -406.517525) (xy 11.752884 -406.465434)
			(xy 11.78018 -406.416799) (xy 11.814266 -406.372656) (xy 11.854415 -406.333947) (xy 11.899773 -406.301496)
			(xy 11.949373 -406.275995) (xy 12.002157 -406.257988) (xy 12.057 -406.247858) (xy 12.112734 -406.245821)
			(xy 12.168171 -406.251921) (xy 12.222128 -406.266027) (xy 12.273457 -406.287839) (xy 12.321063 -406.316893)
			(xy 12.363931 -406.352568) (xy 12.401148 -406.394105) (xy 12.431921 -406.440618) (xy 12.455593 -406.491115)
			(xy 12.471661 -406.544522) (xy 12.479781 -406.599698) (xy 12.48029 -406.627584) (xy 12.479781 -406.65547)
			(xy 12.471661 -406.710646) (xy 12.455593 -406.764053) (xy 12.431921 -406.81455) (xy 12.401148 -406.861063)
			(xy 12.363931 -406.9026) (xy 12.321063 -406.938275) (xy 12.273457 -406.967329) (xy 12.222128 -406.989141)
			(xy 12.168171 -407.003247) (xy 12.112734 -407.009347) (xy 12.057 -407.00731) (xy 12.002157 -406.99718)
			(xy 11.949373 -406.979173) (xy 11.899773 -406.953672) (xy 11.854415 -406.921221) (xy 11.814266 -406.882512)
			(xy 11.78018 -406.838369) (xy 11.752884 -406.789734) (xy 11.732961 -406.737643) (xy 11.720835 -406.683206)
			(xy 11.716764 -406.627584) (xy 11.101578 -406.627584) (xy 11.982704 -407.50871) (xy 18.001232 -407.50871)
			(xy 18.005303 -407.453088) (xy 18.017429 -407.398651) (xy 18.037352 -407.34656) (xy 18.064648 -407.297925)
			(xy 18.098734 -407.253782) (xy 18.138883 -407.215073) (xy 18.184241 -407.182622) (xy 18.233841 -407.157121)
			(xy 18.286625 -407.139114) (xy 18.341468 -407.128984) (xy 18.397202 -407.126947) (xy 18.452639 -407.133047)
			(xy 18.506596 -407.147153) (xy 18.557925 -407.168965) (xy 18.605531 -407.198019) (xy 18.648399 -407.233694)
			(xy 18.685616 -407.275231) (xy 18.716389 -407.321744) (xy 18.740061 -407.372241) (xy 18.756129 -407.425648)
			(xy 18.764249 -407.480824) (xy 18.764758 -407.50871) (xy 18.764249 -407.536596) (xy 18.756129 -407.591772)
			(xy 18.740061 -407.645179) (xy 18.716389 -407.695676) (xy 18.685616 -407.742189) (xy 18.648399 -407.783726)
			(xy 18.605531 -407.819401) (xy 18.557925 -407.848455) (xy 18.506596 -407.870267) (xy 18.452639 -407.884373)
			(xy 18.397202 -407.890473) (xy 18.341468 -407.888436) (xy 18.286625 -407.878306) (xy 18.233841 -407.860299)
			(xy 18.184241 -407.834798) (xy 18.138883 -407.802347) (xy 18.098734 -407.763638) (xy 18.064648 -407.719495)
			(xy 18.037352 -407.67086) (xy 18.017429 -407.618769) (xy 18.005303 -407.564332) (xy 18.001232 -407.50871)
			(xy 11.982704 -407.50871) (xy 12.595352 -408.121358) (xy 12.602195 -408.128757) (xy 12.609915 -408.147356)
			(xy 12.610338 -408.157426) (xy 12.610338 -410.64942) (xy 17.970752 -410.64942) (xy 17.974823 -410.593798)
			(xy 17.986949 -410.539361) (xy 18.006872 -410.48727) (xy 18.034168 -410.438635) (xy 18.068254 -410.394492)
			(xy 18.108403 -410.355783) (xy 18.153761 -410.323332) (xy 18.203361 -410.297831) (xy 18.256145 -410.279824)
			(xy 18.310988 -410.269694) (xy 18.366722 -410.267657) (xy 18.422159 -410.273757) (xy 18.476116 -410.287863)
			(xy 18.527445 -410.309675) (xy 18.575051 -410.338729) (xy 18.617919 -410.374404) (xy 18.655136 -410.415941)
			(xy 18.685909 -410.462454) (xy 18.709581 -410.512951) (xy 18.725649 -410.566358) (xy 18.733769 -410.621534)
			(xy 18.734278 -410.64942) (xy 18.733769 -410.677306) (xy 18.725649 -410.732482) (xy 18.709581 -410.785889)
			(xy 18.685909 -410.836386) (xy 18.655136 -410.882899) (xy 18.617919 -410.924436) (xy 18.575051 -410.960111)
			(xy 18.527445 -410.989165) (xy 18.476116 -411.010977) (xy 18.422159 -411.025083) (xy 18.366722 -411.031183)
			(xy 18.310988 -411.029146) (xy 18.256145 -411.019016) (xy 18.203361 -411.001009) (xy 18.153761 -410.975508)
			(xy 18.108403 -410.943057) (xy 18.068254 -410.904348) (xy 18.034168 -410.860205) (xy 18.006872 -410.81157)
			(xy 17.986949 -410.759479) (xy 17.974823 -410.705042) (xy 17.970752 -410.64942) (xy 12.610338 -410.64942)
			(xy 12.610338 -412.686754) (xy 12.610772 -412.696819) (xy 12.618504 -412.715406) (xy 12.625324 -412.722822)
			(xy 13.09878 -413.196278) (xy 13.106182 -413.203114) (xy 13.12478 -413.210823) (xy 13.134848 -413.211264)
		)
		(stroke
			(width 0)
			(type solid)
		)
		(fill yes)
		(layer "In6.Cu")
		(net "GND")
	)
	(gr_poly
		(pts
			(xy 161.578798 -398.31518) (xy 161.588868 -398.314757) (xy 161.607471 -398.307041) (xy 161.614866 -398.300194)
			(xy 165.508432 -394.406628) (xy 165.51525 -394.399308) (xy 165.522998 -394.380881) (xy 165.523072 -394.360892)
			(xy 165.519608 -394.35151) (xy 165.478968 -394.250672) (xy 165.453822 -394.2334) (xy 165.438582 -394.233146)
			(xy 165.41288 -394.232229) (xy 165.362213 -394.223421) (xy 165.31352 -394.206876) (xy 165.267975 -394.182992)
			(xy 165.226677 -394.152346) (xy 165.190621 -394.115676) (xy 165.160676 -394.073867) (xy 165.137564 -394.027925)
			(xy 165.121843 -393.97896) (xy 165.113891 -393.928152) (xy 165.113462 -393.902438) (xy 165.11401 -393.874949)
			(xy 165.123106 -393.820728) (xy 165.141037 -393.768756) (xy 165.16731 -393.720462) (xy 165.18382 -393.698476)
			(xy 165.189662 -393.69111) (xy 165.194996 -393.67333) (xy 165.189662 -393.587224) (xy 165.182042 -393.57046)
			(xy 165.175438 -393.563856) (xy 165.154416 -393.542224) (xy 165.118781 -393.493558) (xy 165.091247 -393.439892)
			(xy 165.072498 -393.382562) (xy 165.063003 -393.322997) (xy 165.062408 -393.292838) (xy 165.062408 -392.429238)
			(xy 165.062851 -392.402879) (xy 165.070106 -392.350664) (xy 165.084483 -392.299946) (xy 165.105709 -392.251691)
			(xy 165.133378 -392.206819) (xy 165.166964 -392.166185) (xy 165.186106 -392.14806) (xy 165.193218 -392.14171)
			(xy 165.201346 -392.124946) (xy 165.209728 -392.038332) (xy 165.204648 -392.020552) (xy 165.19906 -392.012678)
			(xy 165.184902 -391.992833) (xy 165.162415 -391.949585) (xy 165.147097 -391.90331) (xy 165.139338 -391.855186)
			(xy 165.138862 -391.830814) (xy 165.139384 -391.805559) (xy 165.147697 -391.755737) (xy 165.164098 -391.707963)
			(xy 165.188139 -391.66354) (xy 165.219163 -391.62368) (xy 165.256325 -391.58947) (xy 165.298611 -391.561844)
			(xy 165.344867 -391.541554) (xy 165.393832 -391.529154) (xy 165.44417 -391.524983) (xy 165.494508 -391.529154)
			(xy 165.543473 -391.541554) (xy 165.589729 -391.561844) (xy 165.632015 -391.58947) (xy 165.669177 -391.62368)
			(xy 165.700201 -391.66354) (xy 165.724242 -391.707963) (xy 165.740643 -391.755737) (xy 165.748956 -391.805559)
			(xy 165.749478 -391.830814) (xy 165.74898 -391.855184) (xy 165.741201 -391.9033) (xy 165.72589 -391.949574)
			(xy 165.703434 -391.992834) (xy 165.68928 -392.012678) (xy 165.683692 -392.020552) (xy 165.678612 -392.038332)
			(xy 165.686994 -392.124946) (xy 165.695122 -392.14171) (xy 165.702234 -392.14806) (xy 165.721358 -392.166202)
			(xy 165.754932 -392.206838) (xy 165.782594 -392.251709) (xy 165.803818 -392.29996) (xy 165.818198 -392.350673)
			(xy 165.825461 -392.402882) (xy 165.825932 -392.429238) (xy 165.825932 -393.0015) (xy 165.826539 -393.014115)
			(xy 165.838414 -393.036366) (xy 165.848538 -393.043918) (xy 165.930072 -393.097766) (xy 165.955472 -393.100052)
			(xy 165.96741 -393.094972) (xy 165.991185 -393.085254) (xy 166.040692 -393.071575) (xy 166.091589 -393.064677)
			(xy 166.11727 -393.064238) (xy 166.142179 -393.064636) (xy 166.191572 -393.071118) (xy 166.239698 -393.083987)
			(xy 166.285734 -393.103025) (xy 166.328893 -393.127905) (xy 166.348918 -393.142724) (xy 166.360602 -393.15136)
			(xy 166.389304 -393.154154) (xy 166.484046 -393.107418) (xy 166.492285 -393.102837) (xy 166.504981 -393.088926)
			(xy 166.511799 -393.071369) (xy 166.51224 -393.061952) (xy 166.51224 -390.590786) (xy 166.511693 -390.580186)
			(xy 166.503157 -390.560778) (xy 166.49573 -390.553194) (xy 166.432484 -390.495282) (xy 166.412672 -390.488424)
			(xy 166.40175 -390.48944) (xy 166.373048 -390.49071) (xy 166.347056 -390.49023) (xy 166.295711 -390.482105)
			(xy 166.24627 -390.466047) (xy 166.19995 -390.442452) (xy 166.157892 -390.4119) (xy 166.121131 -390.375145)
			(xy 166.090573 -390.333091) (xy 166.066971 -390.286774) (xy 166.050906 -390.237335) (xy 166.042773 -390.185992)
			(xy 166.042773 -390.134008) (xy 166.050906 -390.082665) (xy 166.066971 -390.033226) (xy 166.090573 -389.986909)
			(xy 166.121131 -389.944855) (xy 166.157892 -389.9081) (xy 166.19995 -389.877548) (xy 166.24627 -389.853953)
			(xy 166.295711 -389.837895) (xy 166.347056 -389.82977) (xy 166.373048 -389.829294) (xy 166.40175 -389.830564)
			(xy 166.412672 -389.83158) (xy 166.432484 -389.824722) (xy 166.49573 -389.76681) (xy 166.503277 -389.759312)
			(xy 166.51182 -389.739849) (xy 166.51224 -389.729218) (xy 166.51224 -387.528562) (xy 166.511808 -387.518496)
			(xy 166.504078 -387.499907) (xy 166.497254 -387.492494) (xy 165.490906 -386.486146) (xy 165.48351 -386.479294)
			(xy 165.464912 -386.47155) (xy 165.454838 -386.47116) (xy 165.362636 -386.47116) (xy 165.334442 -386.494274)
			(xy 165.330886 -386.512308) (xy 165.325397 -386.537875) (xy 165.30744 -386.586984) (xy 165.281981 -386.632657)
			(xy 165.249654 -386.673756) (xy 165.23081 -386.691886) (xy 165.223364 -386.699379) (xy 165.214829 -386.718674)
			(xy 165.2143 -386.729224) (xy 165.2143 -386.8039) (xy 165.214891 -386.814433) (xy 165.223425 -386.833703)
			(xy 165.23081 -386.841238) (xy 165.250466 -386.86017) (xy 165.28391 -386.90329) (xy 165.309819 -386.951317)
			(xy 165.327489 -387.002946) (xy 165.336441 -387.056777) (xy 165.336982 -387.084062) (xy 165.336549 -387.108179)
			(xy 165.329553 -387.155904) (xy 165.315704 -387.202108) (xy 165.295294 -387.245813) (xy 165.282372 -387.26618)
			(xy 165.27653 -387.27507) (xy 165.272974 -387.295136) (xy 165.294056 -387.387338) (xy 165.306248 -387.404102)
			(xy 165.315138 -387.409436) (xy 165.335939 -387.422292) (xy 165.373855 -387.45317) (xy 165.406804 -387.489301)
			(xy 165.434066 -387.529895) (xy 165.455046 -387.574065) (xy 165.469284 -387.620845) (xy 165.476469 -387.669212)
			(xy 165.476936 -387.693662) (xy 165.476498 -387.718033) (xy 165.469342 -387.766245) (xy 165.455194 -387.812888)
			(xy 165.434359 -387.856952) (xy 165.407288 -387.897484) (xy 165.374566 -387.933609) (xy 165.356032 -387.94944)
			(xy 165.347142 -387.956552) (xy 165.337744 -387.97611) (xy 165.33495 -388.075424) (xy 165.343586 -388.09549)
			(xy 165.351968 -388.10311) (xy 165.370386 -388.1206) (xy 165.401721 -388.16057) (xy 165.426013 -388.205173)
			(xy 165.442591 -388.25318) (xy 165.450999 -388.303268) (xy 165.451536 -388.328662) (xy 165.451464 -388.33802)
			(xy 165.450318 -388.356702) (xy 165.44925 -388.366) (xy 165.448234 -388.37489) (xy 165.452044 -388.391654)
			(xy 165.495986 -388.461504) (xy 165.509702 -388.471918) (xy 165.518084 -388.474712) (xy 165.542121 -388.483164)
			(xy 165.587306 -388.506707) (xy 165.628122 -388.537203) (xy 165.663509 -388.573859) (xy 165.692549 -388.615723)
			(xy 165.714486 -388.661708) (xy 165.722046 -388.68604) (xy 165.72357 -388.691882) (xy 166.043864 -389.245602)
			(xy 166.047928 -389.24992) (xy 166.064144 -389.267619) (xy 166.091574 -389.307009) (xy 166.112719 -389.3501)
			(xy 166.127091 -389.395898) (xy 166.134357 -389.443344) (xy 166.134796 -389.467344) (xy 166.134331 -389.492147)
			(xy 166.126561 -389.54114) (xy 166.11122 -389.588314) (xy 166.088686 -389.632506) (xy 166.059513 -389.672627)
			(xy 166.024422 -389.707689) (xy 165.984276 -389.736827) (xy 165.940064 -389.759323) (xy 165.892877 -389.774624)
			(xy 165.843877 -389.782352) (xy 165.819074 -389.782812) (xy 165.793681 -389.782302) (xy 165.743552 -389.774168)
			(xy 165.695371 -389.758115) (xy 165.650381 -389.734555) (xy 165.609743 -389.704098) (xy 165.574504 -389.667528)
			(xy 165.545574 -389.625788) (xy 165.523698 -389.579956) (xy 165.516052 -389.555736) (xy 165.514528 -389.549894)
			(xy 165.194234 -388.996174) (xy 165.19017 -388.991856) (xy 165.173982 -388.974146) (xy 165.14661 -388.934743)
			(xy 165.125523 -388.891647) (xy 165.111207 -388.845854) (xy 165.103994 -388.798422) (xy 165.103556 -388.774432)
			(xy 165.103642 -388.762384) (xy 165.105425 -388.738355) (xy 165.107112 -388.726426) (xy 165.108382 -388.717536)
			(xy 165.105334 -388.700518) (xy 165.06317 -388.629652) (xy 165.049962 -388.618476) (xy 165.04158 -388.615428)
			(xy 165.01984 -388.607022) (xy 164.978995 -388.58457) (xy 164.942038 -388.55617) (xy 164.909825 -388.522484)
			(xy 164.883106 -388.484293) (xy 164.862502 -388.442486) (xy 164.848491 -388.398033) (xy 164.841398 -388.351966)
			(xy 164.84092 -388.328662) (xy 164.84142 -388.303264) (xy 164.84982 -388.253168) (xy 164.866399 -388.205154)
			(xy 164.890698 -388.160548) (xy 164.922047 -388.12058) (xy 164.940488 -388.10311) (xy 164.94887 -388.09549)
			(xy 164.957506 -388.075424) (xy 164.954712 -387.97611) (xy 164.945314 -387.956552) (xy 164.936424 -387.94944)
			(xy 164.917862 -387.933638) (xy 164.885133 -387.897513) (xy 164.858058 -387.856976) (xy 164.837223 -387.812906)
			(xy 164.82308 -387.766256) (xy 164.815934 -387.718035) (xy 164.81552 -387.693662) (xy 164.815959 -387.669546)
			(xy 164.822965 -387.621826) (xy 164.836823 -387.575628) (xy 164.85724 -387.531931) (xy 164.87013 -387.511544)
			(xy 164.875972 -387.502654) (xy 164.879528 -387.482588) (xy 164.858446 -387.390386) (xy 164.846254 -387.373622)
			(xy 164.837364 -387.368288) (xy 164.816561 -387.355433) (xy 164.778643 -387.324555) (xy 164.745691 -387.288425)
			(xy 164.718426 -387.247831) (xy 164.697444 -387.203662) (xy 164.683202 -387.156881) (xy 164.676013 -387.108512)
			(xy 164.675566 -387.084062) (xy 164.676127 -387.056779) (xy 164.685087 -387.002954) (xy 164.702758 -386.951329)
			(xy 164.728661 -386.903303) (xy 164.762093 -386.860179) (xy 164.781738 -386.841238) (xy 164.789182 -386.833744)
			(xy 164.797718 -386.814449) (xy 164.798248 -386.8039) (xy 164.798248 -386.729224) (xy 164.79766 -386.71869)
			(xy 164.789126 -386.699419) (xy 164.781738 -386.691886) (xy 164.762271 -386.673151) (xy 164.729085 -386.630518)
			(xy 164.715698 -386.60705) (xy 164.710594 -386.598686) (xy 164.695424 -386.586313) (xy 164.676722 -386.580528)
			(xy 164.66693 -386.580888) (xy 164.618924 -386.58292) (xy 164.583895 -386.582358) (xy 164.514356 -386.573851)
			(xy 164.446347 -386.557032) (xy 164.380858 -386.532144) (xy 164.318844 -386.49955) (xy 164.28974 -386.48005)
			(xy 164.283136 -386.475732) (xy 164.268658 -386.47116) (xy 164.16274 -386.47116) (xy 164.134546 -386.494274)
			(xy 164.13099 -386.512308) (xy 164.125501 -386.537875) (xy 164.107544 -386.586984) (xy 164.082086 -386.632657)
			(xy 164.049759 -386.673757) (xy 164.030914 -386.691886) (xy 164.023468 -386.699379) (xy 164.014931 -386.718674)
			(xy 164.014404 -386.729224) (xy 164.014404 -386.8039) (xy 164.014995 -386.814433) (xy 164.023529 -386.833702)
			(xy 164.030914 -386.841238) (xy 164.05057 -386.86017) (xy 164.084014 -386.90329) (xy 164.109922 -386.951317)
			(xy 164.127592 -387.002947) (xy 164.136544 -387.056777) (xy 164.137086 -387.084062) (xy 164.136653 -387.108179)
			(xy 164.129657 -387.155904) (xy 164.115808 -387.202108) (xy 164.095399 -387.245813) (xy 164.082476 -387.26618)
			(xy 164.076634 -387.27507) (xy 164.073078 -387.295136) (xy 164.09416 -387.387338) (xy 164.106352 -387.404102)
			(xy 164.115242 -387.409436) (xy 164.136043 -387.422292) (xy 164.173959 -387.45317) (xy 164.206907 -387.489301)
			(xy 164.234169 -387.529895) (xy 164.255148 -387.574065) (xy 164.269386 -387.620845) (xy 164.276571 -387.669212)
			(xy 164.27704 -387.693662) (xy 164.276602 -387.718033) (xy 164.269446 -387.766246) (xy 164.255298 -387.812888)
			(xy 164.234463 -387.856952) (xy 164.207392 -387.897485) (xy 164.174671 -387.933609) (xy 164.156136 -387.94944)
			(xy 164.147246 -387.956552) (xy 164.137848 -387.97611) (xy 164.135054 -388.075424) (xy 164.14369 -388.09549)
			(xy 164.152072 -388.10311) (xy 164.170495 -388.120597) (xy 164.20184 -388.160564) (xy 164.226139 -388.205167)
			(xy 164.242723 -388.253175) (xy 164.251134 -388.303266) (xy 164.25164 -388.328662) (xy 164.251568 -388.33802)
			(xy 164.250422 -388.356702) (xy 164.249354 -388.366) (xy 164.248338 -388.37489) (xy 164.252148 -388.391654)
			(xy 164.29609 -388.461504) (xy 164.309806 -388.471918) (xy 164.318188 -388.474712) (xy 164.342284 -388.483195)
			(xy 164.387572 -388.506824) (xy 164.428466 -388.537436) (xy 164.463898 -388.574232) (xy 164.492944 -388.616252)
			(xy 164.514848 -388.6624) (xy 164.522404 -388.686802) (xy 164.523928 -388.692644) (xy 164.843714 -389.245602)
			(xy 164.847778 -389.24992) (xy 164.863969 -389.267628) (xy 164.891349 -389.30703) (xy 164.912443 -389.350125)
			(xy 164.926765 -389.395918) (xy 164.933983 -389.443353) (xy 164.934392 -389.467344) (xy 164.933903 -389.492132)
			(xy 164.926142 -389.541097) (xy 164.910817 -389.588245) (xy 164.888307 -389.632416) (xy 164.859164 -389.672523)
			(xy 164.824108 -389.707577) (xy 164.783999 -389.736717) (xy 164.739827 -389.759225) (xy 164.692678 -389.774546)
			(xy 164.643712 -389.782304) (xy 164.618924 -389.782812) (xy 164.593529 -389.782306) (xy 164.543394 -389.774179)
			(xy 164.495206 -389.75813) (xy 164.45021 -389.734574) (xy 164.409565 -389.704118) (xy 164.37432 -389.667547)
			(xy 164.345384 -389.625806) (xy 164.323504 -389.579971) (xy 164.315902 -389.555736) (xy 164.314378 -389.549894)
			(xy 163.99383 -388.995412) (xy 163.989766 -388.991094) (xy 163.973687 -388.973416) (xy 163.946499 -388.934118)
			(xy 163.925541 -388.891174) (xy 163.911291 -388.845562) (xy 163.904073 -388.798325) (xy 163.90366 -388.774432)
			(xy 163.903746 -388.762384) (xy 163.905529 -388.738355) (xy 163.907216 -388.726426) (xy 163.908486 -388.717536)
			(xy 163.905438 -388.700518) (xy 163.863274 -388.629652) (xy 163.850066 -388.618476) (xy 163.841684 -388.615428)
			(xy 163.819943 -388.607023) (xy 163.779099 -388.58457) (xy 163.74214 -388.556171) (xy 163.709928 -388.522485)
			(xy 163.683208 -388.484294) (xy 163.662604 -388.442486) (xy 163.648592 -388.398033) (xy 163.641499 -388.351967)
			(xy 163.641024 -388.328662) (xy 163.641524 -388.303264) (xy 163.649924 -388.253168) (xy 163.666503 -388.205154)
			(xy 163.690802 -388.160548) (xy 163.722152 -388.120581) (xy 163.740592 -388.10311) (xy 163.748974 -388.09549)
			(xy 163.75761 -388.075424) (xy 163.754816 -387.97611) (xy 163.745418 -387.956552) (xy 163.736528 -387.94944)
			(xy 163.717965 -387.933638) (xy 163.685236 -387.897513) (xy 163.658161 -387.856976) (xy 163.637326 -387.812906)
			(xy 163.623183 -387.766256) (xy 163.616036 -387.718036) (xy 163.615624 -387.693662) (xy 163.616063 -387.669546)
			(xy 163.623069 -387.621826) (xy 163.636927 -387.575628) (xy 163.657344 -387.531931) (xy 163.670234 -387.511544)
			(xy 163.676076 -387.502654) (xy 163.679632 -387.482588) (xy 163.65855 -387.390386) (xy 163.646358 -387.373622)
			(xy 163.637468 -387.368288) (xy 163.616665 -387.355433) (xy 163.578746 -387.324556) (xy 163.545794 -387.288425)
			(xy 163.518529 -387.247832) (xy 163.497546 -387.203662) (xy 163.483304 -387.156881) (xy 163.476115 -387.108512)
			(xy 163.47567 -387.084062) (xy 163.476231 -387.056779) (xy 163.485191 -387.002954) (xy 163.502862 -386.951329)
			(xy 163.528765 -386.903303) (xy 163.562198 -386.860179) (xy 163.581842 -386.841238) (xy 163.589298 -386.833749)
			(xy 163.597851 -386.814453) (xy 163.598352 -386.8039) (xy 163.598352 -386.729224) (xy 163.597765 -386.71869)
			(xy 163.589231 -386.699419) (xy 163.581842 -386.691886) (xy 163.562374 -386.673151) (xy 163.529189 -386.630519)
			(xy 163.515802 -386.60705) (xy 163.510698 -386.598686) (xy 163.495528 -386.586312) (xy 163.476826 -386.580525)
			(xy 163.467034 -386.580888) (xy 163.419028 -386.58292) (xy 163.383999 -386.582358) (xy 163.314459 -386.573852)
			(xy 163.24645 -386.557033) (xy 163.180961 -386.532145) (xy 163.118947 -386.499552) (xy 163.089844 -386.48005)
			(xy 163.08324 -386.475732) (xy 163.068762 -386.47116) (xy 162.96259 -386.47116) (xy 162.934396 -386.494274)
			(xy 162.93084 -386.512308) (xy 162.925351 -386.537875) (xy 162.907397 -386.586987) (xy 162.881941 -386.632662)
			(xy 162.849618 -386.673765) (xy 162.830764 -386.691886) (xy 162.823324 -386.699381) (xy 162.814796 -386.718676)
			(xy 162.814254 -386.729224) (xy 162.814254 -386.8039) (xy 162.814846 -386.814432) (xy 162.823387 -386.833696)
			(xy 162.830764 -386.841238) (xy 162.850417 -386.860172) (xy 162.883856 -386.903293) (xy 162.909761 -386.95132)
			(xy 162.927428 -387.002949) (xy 162.936378 -387.056778) (xy 162.936936 -387.084062) (xy 162.936503 -387.10818)
			(xy 162.929508 -387.155905) (xy 162.915661 -387.20211) (xy 162.895254 -387.245816) (xy 162.882326 -387.26618)
			(xy 162.876484 -387.27507) (xy 162.872928 -387.295136) (xy 162.89401 -387.387338) (xy 162.906202 -387.404102)
			(xy 162.915092 -387.409436) (xy 162.935896 -387.42229) (xy 162.973817 -387.453166) (xy 163.00677 -387.489295)
			(xy 163.034036 -387.529889) (xy 163.055019 -387.57406) (xy 163.069259 -387.620841) (xy 163.076445 -387.669211)
			(xy 163.07689 -387.693662) (xy 163.076453 -387.718033) (xy 163.069297 -387.766247) (xy 163.05515 -387.812891)
			(xy 163.034318 -387.856957) (xy 163.00725 -387.897492) (xy 162.974531 -387.933621) (xy 162.955986 -387.94944)
			(xy 162.947096 -387.956552) (xy 162.937698 -387.97611) (xy 162.934904 -388.075424) (xy 162.94354 -388.09549)
			(xy 162.951922 -388.10311) (xy 162.970343 -388.120599) (xy 163.001682 -388.160567) (xy 163.025977 -388.20517)
			(xy 163.042558 -388.253178) (xy 163.050967 -388.303267) (xy 163.05149 -388.328662) (xy 163.051418 -388.33802)
			(xy 163.050272 -388.356702) (xy 163.049204 -388.366) (xy 163.048188 -388.37489) (xy 163.051998 -388.391654)
			(xy 163.09594 -388.461504) (xy 163.109656 -388.471918) (xy 163.118038 -388.474712) (xy 163.142072 -388.483167)
			(xy 163.18725 -388.506715) (xy 163.22806 -388.537214) (xy 163.263441 -388.573871) (xy 163.292475 -388.615735)
			(xy 163.314409 -388.661719) (xy 163.322 -388.68604) (xy 163.323524 -388.691882) (xy 163.643818 -389.245602)
			(xy 163.647882 -389.24992) (xy 163.664073 -389.267628) (xy 163.691453 -389.30703) (xy 163.712547 -389.350125)
			(xy 163.726868 -389.395919) (xy 163.734085 -389.443353) (xy 163.734496 -389.467344) (xy 163.734007 -389.492132)
			(xy 163.726246 -389.541097) (xy 163.710921 -389.588246) (xy 163.688411 -389.632417) (xy 163.659269 -389.672524)
			(xy 163.624212 -389.707579) (xy 163.584104 -389.736719) (xy 163.539931 -389.759227) (xy 163.492782 -389.774549)
			(xy 163.443816 -389.782308) (xy 163.419028 -389.782812) (xy 163.393633 -389.782306) (xy 163.343497 -389.77418)
			(xy 163.295309 -389.758131) (xy 163.250312 -389.734575) (xy 163.209667 -389.704119) (xy 163.174421 -389.667549)
			(xy 163.145485 -389.625808) (xy 163.123605 -389.579972) (xy 163.116006 -389.555736) (xy 163.114482 -389.549894)
			(xy 162.794188 -388.996174) (xy 162.790124 -388.991856) (xy 162.773907 -388.974158) (xy 162.746476 -388.934769)
			(xy 162.72533 -388.891677) (xy 162.710959 -388.845879) (xy 162.703695 -388.798432) (xy 162.703256 -388.774432)
			(xy 162.703414 -388.76238) (xy 162.705323 -388.738352) (xy 162.707066 -388.726426) (xy 162.708336 -388.717536)
			(xy 162.705288 -388.700518) (xy 162.663124 -388.629652) (xy 162.649916 -388.618476) (xy 162.641534 -388.615428)
			(xy 162.619796 -388.60702) (xy 162.578957 -388.584564) (xy 162.542005 -388.556162) (xy 162.509797 -388.522475)
			(xy 162.483083 -388.484285) (xy 162.462482 -388.442479) (xy 162.448473 -388.398028) (xy 162.441382 -388.351965)
			(xy 162.440874 -388.328662) (xy 162.441373 -388.303264) (xy 162.449773 -388.253167) (xy 162.466349 -388.205151)
			(xy 162.490646 -388.160542) (xy 162.521992 -388.120571) (xy 162.540442 -388.10311) (xy 162.548824 -388.09549)
			(xy 162.55746 -388.075424) (xy 162.554666 -387.97611) (xy 162.545268 -387.956552) (xy 162.536378 -387.94944)
			(xy 162.517818 -387.933637) (xy 162.485093 -387.897509) (xy 162.458022 -387.856972) (xy 162.437191 -387.812902)
			(xy 162.42305 -387.766253) (xy 162.415904 -387.718035) (xy 162.415474 -387.693662) (xy 162.415913 -387.669546)
			(xy 162.422918 -387.621825) (xy 162.436774 -387.575627) (xy 162.457189 -387.531928) (xy 162.470084 -387.511544)
			(xy 162.475926 -387.502654) (xy 162.479482 -387.482588) (xy 162.4584 -387.390386) (xy 162.446208 -387.373622)
			(xy 162.437318 -387.368288) (xy 162.416513 -387.355435) (xy 162.378588 -387.32456) (xy 162.345631 -387.288431)
			(xy 162.318362 -387.247838) (xy 162.297375 -387.203667) (xy 162.283131 -387.156885) (xy 162.275941 -387.108514)
			(xy 162.27552 -387.084062) (xy 162.276081 -387.05678) (xy 162.285042 -387.002956) (xy 162.302715 -386.951332)
			(xy 162.328621 -386.903309) (xy 162.362057 -386.860189) (xy 162.381692 -386.841238) (xy 162.389142 -386.833746)
			(xy 162.397686 -386.814451) (xy 162.398202 -386.8039) (xy 162.398202 -386.729224) (xy 162.397616 -386.718689)
			(xy 162.389088 -386.699412) (xy 162.381692 -386.691886) (xy 162.362222 -386.673153) (xy 162.329032 -386.630523)
			(xy 162.315652 -386.60705) (xy 162.310551 -386.598679) (xy 162.295382 -386.58629) (xy 162.276677 -386.580486)
			(xy 162.266884 -386.580888) (xy 162.218878 -386.58292) (xy 162.18385 -386.582355) (xy 162.114313 -386.573843)
			(xy 162.046307 -386.557019) (xy 161.980821 -386.532127) (xy 161.918811 -386.49953) (xy 161.889694 -386.48005)
			(xy 161.88309 -386.475732) (xy 161.868612 -386.47116) (xy 161.762694 -386.47116) (xy 161.7345 -386.494274)
			(xy 161.730944 -386.512308) (xy 161.725455 -386.537875) (xy 161.707501 -386.586987) (xy 161.682046 -386.632663)
			(xy 161.649722 -386.673766) (xy 161.630868 -386.691886) (xy 161.623427 -386.699381) (xy 161.614899 -386.718676)
			(xy 161.614358 -386.729224) (xy 161.614358 -386.8039) (xy 161.61495 -386.814432) (xy 161.623491 -386.833695)
			(xy 161.630868 -386.841238) (xy 161.650521 -386.860172) (xy 161.68396 -386.903293) (xy 161.709864 -386.951321)
			(xy 161.727531 -387.002949) (xy 161.736481 -387.056778) (xy 161.73704 -387.084062) (xy 161.736607 -387.10818)
			(xy 161.729612 -387.155905) (xy 161.715765 -387.20211) (xy 161.695359 -387.245816) (xy 161.68243 -387.26618)
			(xy 161.676588 -387.27507) (xy 161.673032 -387.295136) (xy 161.694114 -387.387338) (xy 161.706306 -387.404102)
			(xy 161.715196 -387.409436) (xy 161.736 -387.42229) (xy 161.77392 -387.453166) (xy 161.806873 -387.489296)
			(xy 161.834139 -387.52989) (xy 161.855121 -387.57406) (xy 161.869361 -387.620842) (xy 161.876548 -387.669211)
			(xy 161.876994 -387.693662) (xy 161.876557 -387.718033) (xy 161.869401 -387.766247) (xy 161.855255 -387.812891)
			(xy 161.834422 -387.856957) (xy 161.807354 -387.897493) (xy 161.774636 -387.933622) (xy 161.75609 -387.94944)
			(xy 161.7472 -387.956552) (xy 161.737802 -387.97611) (xy 161.735008 -388.075424) (xy 161.743644 -388.09549)
			(xy 161.752026 -388.10311) (xy 161.770446 -388.120599) (xy 161.801786 -388.160567) (xy 161.82608 -388.20517)
			(xy 161.842661 -388.253178) (xy 161.85107 -388.303267) (xy 161.851594 -388.328662) (xy 161.851522 -388.33802)
			(xy 161.850376 -388.356702) (xy 161.849308 -388.366) (xy 161.848292 -388.37489) (xy 161.852102 -388.391654)
			(xy 161.896044 -388.461504) (xy 161.90976 -388.471918) (xy 161.918142 -388.474712) (xy 161.942235 -388.483198)
			(xy 161.987517 -388.506832) (xy 162.028404 -388.537448) (xy 162.06383 -388.574245) (xy 162.092871 -388.616264)
			(xy 162.11477 -388.662411) (xy 162.122358 -388.686802) (xy 162.123882 -388.692644) (xy 162.443668 -389.245602)
			(xy 162.447732 -389.24992) (xy 162.463947 -389.267619) (xy 162.491377 -389.307009) (xy 162.512522 -389.3501)
			(xy 162.526894 -389.395898) (xy 162.53416 -389.443344) (xy 162.5346 -389.467344) (xy 162.534135 -389.492147)
			(xy 162.526365 -389.541141) (xy 162.511024 -389.588315) (xy 162.48849 -389.632507) (xy 162.459317 -389.672629)
			(xy 162.424226 -389.70769) (xy 162.38408 -389.736829) (xy 162.339869 -389.759326) (xy 162.292682 -389.774627)
			(xy 162.243681 -389.782356) (xy 162.218878 -389.782812) (xy 162.193485 -389.782303) (xy 162.143355 -389.774169)
			(xy 162.095174 -389.758116) (xy 162.050183 -389.734557) (xy 162.009544 -389.7041) (xy 161.974305 -389.667529)
			(xy 161.945375 -389.62579) (xy 161.923499 -389.579957) (xy 161.915856 -389.555736) (xy 161.914332 -389.549894)
			(xy 161.593784 -388.995412) (xy 161.58972 -388.991094) (xy 161.573616 -388.973425) (xy 161.546378 -388.934139)
			(xy 161.525369 -388.891199) (xy 161.511068 -388.845583) (xy 161.503802 -388.798334) (xy 161.50336 -388.774432)
			(xy 161.503518 -388.76238) (xy 161.505427 -388.738352) (xy 161.50717 -388.726426) (xy 161.50844 -388.717536)
			(xy 161.505392 -388.700518) (xy 161.463228 -388.629652) (xy 161.45002 -388.618476) (xy 161.441638 -388.615428)
			(xy 161.4199 -388.60702) (xy 161.37906 -388.584564) (xy 161.342108 -388.556163) (xy 161.3099 -388.522476)
			(xy 161.283185 -388.484286) (xy 161.262584 -388.44248) (xy 161.248575 -388.398029) (xy 161.241483 -388.351965)
			(xy 161.240978 -388.328662) (xy 161.241477 -388.303264) (xy 161.249877 -388.253167) (xy 161.266453 -388.205151)
			(xy 161.29075 -388.160543) (xy 161.322097 -388.120572) (xy 161.340546 -388.10311) (xy 161.348928 -388.09549)
			(xy 161.357564 -388.075424) (xy 161.35477 -387.97611) (xy 161.345372 -387.956552) (xy 161.336482 -387.94944)
			(xy 161.317922 -387.933637) (xy 161.285197 -387.89751) (xy 161.258125 -387.856973) (xy 161.237294 -387.812903)
			(xy 161.223152 -387.766254) (xy 161.216007 -387.718035) (xy 161.215578 -387.693662) (xy 161.216017 -387.669546)
			(xy 161.223022 -387.621825) (xy 161.236879 -387.575627) (xy 161.257293 -387.531928) (xy 161.270188 -387.511544)
			(xy 161.27603 -387.502654) (xy 161.279586 -387.482588) (xy 161.258504 -387.390386) (xy 161.246312 -387.373622)
			(xy 161.237422 -387.368288) (xy 161.216622 -387.355431) (xy 161.178708 -387.324551) (xy 161.14576 -387.28842)
			(xy 161.118499 -387.247826) (xy 161.097519 -387.203657) (xy 161.08328 -387.156878) (xy 161.076092 -387.108511)
			(xy 161.075624 -387.084062) (xy 161.076185 -387.05678) (xy 161.085147 -387.002956) (xy 161.10282 -386.951333)
			(xy 161.128726 -386.90331) (xy 161.162162 -386.86019) (xy 161.181796 -386.841238) (xy 161.189245 -386.833746)
			(xy 161.197789 -386.814451) (xy 161.198306 -386.8039) (xy 161.198306 -386.729224) (xy 161.19772 -386.718689)
			(xy 161.189193 -386.699412) (xy 161.181796 -386.691886) (xy 161.16233 -386.67315) (xy 161.129149 -386.630515)
			(xy 161.115756 -386.60705) (xy 161.110655 -386.598679) (xy 161.095486 -386.586289) (xy 161.076781 -386.580483)
			(xy 161.066988 -386.580888) (xy 161.018982 -386.58292) (xy 160.983954 -386.582355) (xy 160.914417 -386.573844)
			(xy 160.84641 -386.55702) (xy 160.780925 -386.532129) (xy 160.718914 -386.499532) (xy 160.689798 -386.48005)
			(xy 160.683194 -386.475732) (xy 160.668716 -386.47116) (xy 160.562544 -386.47116) (xy 160.53435 -386.494274)
			(xy 160.530794 -386.512308) (xy 160.525476 -386.537087) (xy 160.508313 -386.584769) (xy 160.484077 -386.629274)
			(xy 160.453334 -386.669561) (xy 160.416805 -386.704686) (xy 160.375344 -386.733826) (xy 160.329923 -386.756299)
			(xy 160.281604 -386.771579) (xy 160.23152 -386.779308) (xy 160.206182 -386.77977) (xy 160.180826 -386.779284)
			(xy 160.130709 -386.771543) (xy 160.08236 -386.756245) (xy 160.036912 -386.733749) (xy 159.995428 -386.704581)
			(xy 159.958882 -386.669425) (xy 159.928127 -386.629103) (xy 159.915606 -386.60705) (xy 159.910502 -386.598685)
			(xy 159.895333 -386.58631) (xy 159.87663 -386.580522) (xy 159.866838 -386.580888) (xy 159.819086 -386.58292)
			(xy 159.784058 -386.582355) (xy 159.71452 -386.573845) (xy 159.646514 -386.557021) (xy 159.581028 -386.53213)
			(xy 159.519016 -386.499534) (xy 159.489902 -386.48005) (xy 159.483298 -386.475732) (xy 159.46882 -386.47116)
			(xy 159.362648 -386.47116) (xy 159.334454 -386.494274) (xy 159.330898 -386.512308) (xy 159.326407 -386.533496)
			(xy 159.312609 -386.574553) (xy 159.293565 -386.613453) (xy 159.281876 -386.631688) (xy 159.277126 -386.639659)
			(xy 159.273106 -386.657757) (xy 159.274002 -386.666994) (xy 159.27832 -386.697982) (xy 159.280125 -386.707234)
			(xy 159.289385 -386.723636) (xy 159.296354 -386.729986) (xy 159.318448 -386.748661) (xy 159.35822 -386.790672)
			(xy 159.39238 -386.837361) (xy 159.420384 -386.887983) (xy 159.441786 -386.94173) (xy 159.456243 -386.997745)
			(xy 159.463526 -387.055136) (xy 159.463994 -387.084062) (xy 159.46339 -387.117382) (xy 159.453721 -387.183317)
			(xy 159.434596 -387.247154) (xy 159.421068 -387.27761) (xy 159.416806 -387.288079) (xy 159.41688 -387.310653)
			(xy 159.426636 -387.331011) (xy 159.435038 -387.33857) (xy 159.457285 -387.357244) (xy 159.497348 -387.3993)
			(xy 159.531769 -387.446087) (xy 159.559996 -387.496851) (xy 159.581573 -387.550779) (xy 159.596155 -387.607003)
			(xy 159.603508 -387.66462) (xy 159.603948 -387.693662) (xy 159.603497 -387.722666) (xy 159.596167 -387.78021)
			(xy 159.581632 -387.836368) (xy 159.560123 -387.890242) (xy 159.531986 -387.94097) (xy 159.497671 -387.987741)
			(xy 159.457726 -388.029805) (xy 159.435546 -388.0485) (xy 159.428434 -388.054088) (xy 159.41929 -388.069328)
			(xy 159.40405 -388.152132) (xy 159.406844 -388.169404) (xy 159.411416 -388.177532) (xy 159.424009 -388.200711)
			(xy 159.441895 -388.250331) (xy 159.450976 -388.302289) (xy 159.451548 -388.328662) (xy 160.040828 -388.328662)
			(xy 160.04135 -388.303407) (xy 160.049663 -388.253585) (xy 160.066064 -388.205811) (xy 160.090105 -388.161388)
			(xy 160.121129 -388.121528) (xy 160.158291 -388.087318) (xy 160.200577 -388.059692) (xy 160.246833 -388.039402)
			(xy 160.295798 -388.027002) (xy 160.346136 -388.022831) (xy 160.396474 -388.027002) (xy 160.445439 -388.039402)
			(xy 160.491695 -388.059692) (xy 160.533981 -388.087318) (xy 160.571143 -388.121528) (xy 160.602167 -388.161388)
			(xy 160.626208 -388.205811) (xy 160.642609 -388.253585) (xy 160.650922 -388.303407) (xy 160.651444 -388.328662)
			(xy 160.651375 -388.338021) (xy 160.650232 -388.356703) (xy 160.649158 -388.366) (xy 160.648142 -388.37489)
			(xy 160.651952 -388.391654) (xy 160.695894 -388.461504) (xy 160.70961 -388.471918) (xy 160.717992 -388.474712)
			(xy 160.742011 -388.483205) (xy 160.787184 -388.506752) (xy 160.827991 -388.537245) (xy 160.863372 -388.573896)
			(xy 160.89241 -388.615751) (xy 160.91435 -388.661726) (xy 160.921954 -388.68604) (xy 160.923478 -388.691882)
			(xy 161.243772 -389.245602) (xy 161.247836 -389.24992) (xy 161.264034 -389.267633) (xy 161.291458 -389.307023)
			(xy 161.312601 -389.350112) (xy 161.326976 -389.395904) (xy 161.334252 -389.443346) (xy 161.334704 -389.467344)
			(xy 161.334247 -389.492148) (xy 161.326477 -389.541143) (xy 161.311136 -389.588319) (xy 161.288601 -389.632512)
			(xy 161.259428 -389.672635) (xy 161.224335 -389.707698) (xy 161.184188 -389.736838) (xy 161.139976 -389.759336)
			(xy 161.092788 -389.774638) (xy 161.043786 -389.782367) (xy 161.018982 -389.782812) (xy 160.993587 -389.782327)
			(xy 160.943453 -389.774194) (xy 160.895267 -389.75814) (xy 160.850272 -389.734579) (xy 160.80963 -389.70412)
			(xy 160.774387 -389.667547) (xy 160.745454 -389.625804) (xy 160.723576 -389.579967) (xy 160.71596 -389.555736)
			(xy 160.714436 -389.549894) (xy 160.394142 -388.996174) (xy 160.390078 -388.991856) (xy 160.373923 -388.974118)
			(xy 160.346553 -388.934718) (xy 160.325461 -388.891629) (xy 160.311133 -388.845845) (xy 160.303898 -388.798419)
			(xy 160.303464 -388.774432) (xy 160.303544 -388.762384) (xy 160.305327 -388.738355) (xy 160.30702 -388.726426)
			(xy 160.30829 -388.717536) (xy 160.305242 -388.700518) (xy 160.263078 -388.629652) (xy 160.24987 -388.618476)
			(xy 160.241488 -388.615428) (xy 160.219744 -388.607023) (xy 160.178885 -388.584584) (xy 160.141914 -388.556193)
			(xy 160.10969 -388.522509) (xy 160.082964 -388.484316) (xy 160.062358 -388.442504) (xy 160.04835 -388.398043)
			(xy 160.041266 -388.35197) (xy 160.040828 -388.328662) (xy 159.451548 -388.328662) (xy 159.451476 -388.33802)
			(xy 159.45033 -388.356702) (xy 159.449262 -388.366) (xy 159.448246 -388.37489) (xy 159.452056 -388.391654)
			(xy 159.495998 -388.461504) (xy 159.509714 -388.471918) (xy 159.518096 -388.474712) (xy 159.542132 -388.483165)
			(xy 159.587316 -388.506709) (xy 159.62813 -388.537205) (xy 159.663516 -388.573862) (xy 159.692555 -388.615726)
			(xy 159.714491 -388.661711) (xy 159.722058 -388.68604) (xy 159.723582 -388.691882) (xy 160.043876 -389.245602)
			(xy 160.04794 -389.24992) (xy 160.064155 -389.267619) (xy 160.091584 -389.307009) (xy 160.112729 -389.3501)
			(xy 160.1271 -389.395898) (xy 160.134366 -389.443344) (xy 160.134808 -389.467344) (xy 160.134343 -389.492147)
			(xy 160.126573 -389.541141) (xy 160.111232 -389.588316) (xy 160.088698 -389.632509) (xy 160.059526 -389.672631)
			(xy 160.024434 -389.707694) (xy 159.984289 -389.736833) (xy 159.940077 -389.759331) (xy 159.89289 -389.774633)
			(xy 159.84389 -389.782363) (xy 159.819086 -389.782812) (xy 159.793693 -389.782303) (xy 159.743562 -389.774171)
			(xy 159.695379 -389.758118) (xy 159.650388 -389.73456) (xy 159.609748 -389.704103) (xy 159.574508 -389.667533)
			(xy 159.545576 -389.625793) (xy 159.5237 -389.57996) (xy 159.516064 -389.555736) (xy 159.51454 -389.549894)
			(xy 159.194246 -388.996174) (xy 159.190182 -388.991856) (xy 159.173994 -388.974146) (xy 159.14662 -388.934743)
			(xy 159.125532 -388.891648) (xy 159.111216 -388.845855) (xy 159.104003 -388.798422) (xy 159.103568 -388.774432)
			(xy 159.103654 -388.762384) (xy 159.105437 -388.738355) (xy 159.107124 -388.726426) (xy 159.108394 -388.717536)
			(xy 159.105346 -388.700518) (xy 159.063182 -388.629652) (xy 159.049974 -388.618476) (xy 159.041592 -388.615428)
			(xy 159.019851 -388.607023) (xy 158.979005 -388.584571) (xy 158.942046 -388.556172) (xy 158.909832 -388.522486)
			(xy 158.883112 -388.484295) (xy 158.862507 -388.442488) (xy 158.848495 -388.398034) (xy 158.841402 -388.351967)
			(xy 158.840932 -388.328662) (xy 158.841514 -388.302291) (xy 158.850615 -388.25034) (xy 158.868489 -388.200719)
			(xy 158.881064 -388.177532) (xy 158.885636 -388.169404) (xy 158.88843 -388.152132) (xy 158.87319 -388.069328)
			(xy 158.864046 -388.054088) (xy 158.856934 -388.0485) (xy 158.834745 -388.029815) (xy 158.794796 -387.987754)
			(xy 158.760479 -387.940984) (xy 158.732346 -387.890254) (xy 158.710847 -387.836376) (xy 158.696325 -387.780213)
			(xy 158.689015 -387.722667) (xy 158.688532 -387.693662) (xy 158.689135 -387.660342) (xy 158.698801 -387.594406)
			(xy 158.717923 -387.530568) (xy 158.731458 -387.500114) (xy 158.735725 -387.489643) (xy 158.735658 -387.467062)
			(xy 158.725911 -387.446693) (xy 158.717488 -387.439154) (xy 158.695243 -387.420479) (xy 158.655185 -387.378422)
			(xy 158.62077 -387.331635) (xy 158.59255 -387.280869) (xy 158.57098 -387.226942) (xy 158.556406 -387.170718)
			(xy 158.549063 -387.113103) (xy 158.548578 -387.084062) (xy 158.549023 -387.055136) (xy 158.556316 -386.997746)
			(xy 158.570781 -386.941732) (xy 158.592187 -386.887986) (xy 158.620194 -386.837365) (xy 158.654355 -386.790677)
			(xy 158.694126 -386.748663) (xy 158.716218 -386.729986) (xy 158.723283 -386.723716) (xy 158.732555 -386.707274)
			(xy 158.734252 -386.697982) (xy 158.73857 -386.666994) (xy 158.739518 -386.657756) (xy 158.735482 -386.639646)
			(xy 158.730696 -386.631688) (xy 158.71571 -386.60705) (xy 158.710607 -386.598685) (xy 158.695437 -386.586308)
			(xy 158.676735 -386.580519) (xy 158.666942 -386.580888) (xy 158.618936 -386.58292) (xy 158.583909 -386.582352)
			(xy 158.514374 -386.573836) (xy 158.44637 -386.557008) (xy 158.380888 -386.532112) (xy 158.31888 -386.499512)
			(xy 158.289752 -386.48005) (xy 158.283148 -386.475732) (xy 158.26867 -386.47116) (xy 158.162498 -386.47116)
			(xy 158.134304 -386.494274) (xy 158.130748 -386.512308) (xy 158.125259 -386.537875) (xy 158.107306 -386.586987)
			(xy 158.08185 -386.632663) (xy 158.049527 -386.673767) (xy 158.030672 -386.691886) (xy 158.023231 -386.699381)
			(xy 158.014702 -386.718676) (xy 158.014162 -386.729224) (xy 158.014162 -386.8039) (xy 158.014754 -386.814432)
			(xy 158.023296 -386.833695) (xy 158.030672 -386.841238) (xy 158.050325 -386.860172) (xy 158.083763 -386.903294)
			(xy 158.109667 -386.951321) (xy 158.127334 -387.002949) (xy 158.136283 -387.056778) (xy 158.136844 -387.084062)
			(xy 158.136411 -387.10818) (xy 158.129416 -387.155905) (xy 158.115569 -387.20211) (xy 158.095163 -387.245817)
			(xy 158.082234 -387.26618) (xy 158.076392 -387.27507) (xy 158.072836 -387.295136) (xy 158.093918 -387.387338)
			(xy 158.10611 -387.404102) (xy 158.115 -387.409436) (xy 158.135803 -387.42229) (xy 158.173723 -387.453166)
			(xy 158.206676 -387.489296) (xy 158.233941 -387.52989) (xy 158.254923 -387.574061) (xy 158.269163 -387.620842)
			(xy 158.27635 -387.669212) (xy 158.276798 -387.693662) (xy 158.276361 -387.718033) (xy 158.269205 -387.766247)
			(xy 158.255059 -387.812892) (xy 158.234227 -387.856958) (xy 158.207159 -387.897494) (xy 158.174441 -387.933623)
			(xy 158.155894 -387.94944) (xy 158.147004 -387.956552) (xy 158.137606 -387.97611) (xy 158.134812 -388.075424)
			(xy 158.143448 -388.09549) (xy 158.15183 -388.10311) (xy 158.17025 -388.120599) (xy 158.201589 -388.160568)
			(xy 158.225883 -388.20517) (xy 158.242464 -388.253178) (xy 158.250873 -388.303267) (xy 158.251398 -388.328662)
			(xy 158.251326 -388.33802) (xy 158.25018 -388.356702) (xy 158.249112 -388.366) (xy 158.248096 -388.37489)
			(xy 158.251906 -388.391654) (xy 158.295848 -388.461504) (xy 158.309564 -388.471918) (xy 158.317946 -388.474712)
			(xy 158.34198 -388.483168) (xy 158.387157 -388.506717) (xy 158.427966 -388.537216) (xy 158.463346 -388.573873)
			(xy 158.492379 -388.615737) (xy 158.514312 -388.661721) (xy 158.521908 -388.68604) (xy 158.523432 -388.691882)
			(xy 158.843726 -389.245602) (xy 158.84779 -389.24992) (xy 158.863981 -389.267628) (xy 158.89136 -389.30703)
			(xy 158.912453 -389.350125) (xy 158.926774 -389.395919) (xy 158.933991 -389.443353) (xy 158.934404 -389.467344)
			(xy 158.933915 -389.492132) (xy 158.926154 -389.541098) (xy 158.910829 -389.588247) (xy 158.888319 -389.632419)
			(xy 158.859177 -389.672526) (xy 158.82412 -389.707582) (xy 158.784012 -389.736723) (xy 158.73984 -389.759232)
			(xy 158.69269 -389.774556) (xy 158.643724 -389.782315) (xy 158.618936 -389.782812) (xy 158.593541 -389.782307)
			(xy 158.543404 -389.774181) (xy 158.495215 -389.758134) (xy 158.450217 -389.734578) (xy 158.40957 -389.704122)
			(xy 158.374324 -389.667552) (xy 158.345387 -389.625811) (xy 158.323506 -389.579975) (xy 158.315914 -389.555736)
			(xy 158.31439 -389.549894) (xy 157.994096 -388.996174) (xy 157.990032 -388.991856) (xy 157.973815 -388.974158)
			(xy 157.946383 -388.934769) (xy 157.925237 -388.891678) (xy 157.910865 -388.84588) (xy 157.903601 -388.798432)
			(xy 157.903164 -388.774432) (xy 157.903322 -388.76238) (xy 157.905231 -388.738352) (xy 157.906974 -388.726426)
			(xy 157.908244 -388.717536) (xy 157.905196 -388.700518) (xy 157.863032 -388.629652) (xy 157.849824 -388.618476)
			(xy 157.841442 -388.615428) (xy 157.819704 -388.60702) (xy 157.778864 -388.584565) (xy 157.741911 -388.556163)
			(xy 157.709702 -388.522476) (xy 157.682987 -388.484286) (xy 157.662386 -388.44248) (xy 157.648376 -388.398029)
			(xy 157.641285 -388.351965) (xy 157.640782 -388.328662) (xy 157.641281 -388.303264) (xy 157.649681 -388.253167)
			(xy 157.666258 -388.205152) (xy 157.690555 -388.160543) (xy 157.721902 -388.120573) (xy 157.74035 -388.10311)
			(xy 157.748732 -388.09549) (xy 157.757368 -388.075424) (xy 157.754574 -387.97611) (xy 157.745176 -387.956552)
			(xy 157.736286 -387.94944) (xy 157.717726 -387.933637) (xy 157.685 -387.89751) (xy 157.657929 -387.856973)
			(xy 157.637097 -387.812903) (xy 157.622955 -387.766254) (xy 157.61581 -387.718035) (xy 157.615382 -387.693662)
			(xy 157.615821 -387.669546) (xy 157.622826 -387.621825) (xy 157.636683 -387.575627) (xy 157.657097 -387.531928)
			(xy 157.669992 -387.511544) (xy 157.675834 -387.502654) (xy 157.67939 -387.482588) (xy 157.658308 -387.390386)
			(xy 157.646116 -387.373622) (xy 157.637226 -387.368288) (xy 157.616425 -387.355431) (xy 157.578511 -387.324552)
			(xy 157.545563 -387.28842) (xy 157.518301 -387.247827) (xy 157.497321 -387.203658) (xy 157.483082 -387.156879)
			(xy 157.475894 -387.108511) (xy 157.475428 -387.084062) (xy 157.475989 -387.05678) (xy 157.484951 -387.002956)
			(xy 157.502624 -386.951333) (xy 157.52853 -386.90331) (xy 157.561966 -386.86019) (xy 157.5816 -386.841238)
			(xy 157.589049 -386.833746) (xy 157.597592 -386.814451) (xy 157.59811 -386.8039) (xy 157.59811 -386.729224)
			(xy 157.597524 -386.718688) (xy 157.588997 -386.699411) (xy 157.5816 -386.691886) (xy 157.562134 -386.67315)
			(xy 157.528952 -386.630515) (xy 157.51556 -386.60705) (xy 157.510459 -386.598678) (xy 157.495291 -386.586287)
			(xy 157.476585 -386.58048) (xy 157.466792 -386.580888) (xy 157.41904 -386.58292) (xy 157.384013 -386.582353)
			(xy 157.314477 -386.573837) (xy 157.246473 -386.557009) (xy 157.180991 -386.532114) (xy 157.118983 -386.499514)
			(xy 157.089856 -386.48005) (xy 157.083252 -386.475732) (xy 157.068774 -386.47116) (xy 156.962602 -386.47116)
			(xy 156.934408 -386.494274) (xy 156.930852 -386.512308) (xy 156.925364 -386.537875) (xy 156.90741 -386.586987)
			(xy 156.881955 -386.632664) (xy 156.849632 -386.673767) (xy 156.830776 -386.691886) (xy 156.823334 -386.699381)
			(xy 156.814804 -386.718676) (xy 156.814266 -386.729224) (xy 156.814266 -386.8039) (xy 156.814858 -386.814431)
			(xy 156.8234 -386.833694) (xy 156.830776 -386.841238) (xy 156.850429 -386.860172) (xy 156.883866 -386.903294)
			(xy 156.90977 -386.951321) (xy 156.927436 -387.00295) (xy 156.936386 -387.056778) (xy 156.936948 -387.084062)
			(xy 156.936515 -387.108179) (xy 156.929518 -387.155904) (xy 156.915668 -387.202107) (xy 156.895257 -387.24581)
			(xy 156.882338 -387.26618) (xy 156.876496 -387.27507) (xy 156.87294 -387.295136) (xy 156.894022 -387.387338)
			(xy 156.906214 -387.404102) (xy 156.915104 -387.409436) (xy 156.935907 -387.42229) (xy 156.973827 -387.453167)
			(xy 157.006779 -387.489297) (xy 157.034044 -387.529891) (xy 157.055026 -387.574061) (xy 157.069265 -387.620842)
			(xy 157.076452 -387.669212) (xy 157.076902 -387.693662) (xy 157.076464 -387.718032) (xy 157.069308 -387.766244)
			(xy 157.055158 -387.812886) (xy 157.034322 -387.856948) (xy 157.007249 -387.897479) (xy 156.974525 -387.933601)
			(xy 156.955998 -387.94944) (xy 156.947108 -387.956552) (xy 156.93771 -387.97611) (xy 156.934916 -388.075424)
			(xy 156.943552 -388.09549) (xy 156.951934 -388.10311) (xy 156.970354 -388.120599) (xy 157.001692 -388.160568)
			(xy 157.025986 -388.205171) (xy 157.042566 -388.253178) (xy 157.050976 -388.303267) (xy 157.051502 -388.328662)
			(xy 157.05143 -388.33802) (xy 157.050284 -388.356702) (xy 157.049216 -388.366) (xy 157.0482 -388.37489)
			(xy 157.05201 -388.391654) (xy 157.095952 -388.461504) (xy 157.109668 -388.471918) (xy 157.11805 -388.474712)
			(xy 157.142084 -388.483168) (xy 157.18726 -388.506717) (xy 157.228068 -388.537217) (xy 157.263448 -388.573874)
			(xy 157.292481 -388.615738) (xy 157.314414 -388.661722) (xy 157.322012 -388.68604) (xy 157.323536 -388.691882)
			(xy 157.64383 -389.245602) (xy 157.647894 -389.24992) (xy 157.664085 -389.267628) (xy 157.691463 -389.307031)
			(xy 157.712556 -389.350126) (xy 157.726877 -389.395919) (xy 157.734094 -389.443353) (xy 157.734508 -389.467344)
			(xy 157.734019 -389.492132) (xy 157.726258 -389.541098) (xy 157.710933 -389.588248) (xy 157.688423 -389.63242)
			(xy 157.659281 -389.672528) (xy 157.624225 -389.707584) (xy 157.584117 -389.736725) (xy 157.539944 -389.759235)
			(xy 157.492794 -389.774559) (xy 157.443829 -389.782319) (xy 157.41904 -389.782812) (xy 157.393644 -389.782307)
			(xy 157.343507 -389.774182) (xy 157.295318 -389.758135) (xy 157.250319 -389.73458) (xy 157.209672 -389.704124)
			(xy 157.174425 -389.667554) (xy 157.145488 -389.625812) (xy 157.123606 -389.579976) (xy 157.116018 -389.555736)
			(xy 157.114494 -389.549894) (xy 156.7942 -388.996174) (xy 156.790136 -388.991856) (xy 156.773919 -388.974158)
			(xy 156.746486 -388.934769) (xy 156.72534 -388.891678) (xy 156.710968 -388.84588) (xy 156.703704 -388.798432)
			(xy 156.703268 -388.774432) (xy 156.703426 -388.76238) (xy 156.705335 -388.738352) (xy 156.707078 -388.726426)
			(xy 156.708348 -388.717536) (xy 156.7053 -388.700518) (xy 156.663136 -388.629652) (xy 156.649928 -388.618476)
			(xy 156.641546 -388.615428) (xy 156.619808 -388.607021) (xy 156.578967 -388.584565) (xy 156.542013 -388.556164)
			(xy 156.509805 -388.522477) (xy 156.483089 -388.484287) (xy 156.462487 -388.442481) (xy 156.448478 -388.398029)
			(xy 156.441386 -388.351965) (xy 156.440886 -388.328662) (xy 156.441385 -388.303264) (xy 156.449785 -388.253167)
			(xy 156.466362 -388.205152) (xy 156.490659 -388.160544) (xy 156.522007 -388.120574) (xy 156.540454 -388.10311)
			(xy 156.548836 -388.09549) (xy 156.557472 -388.075424) (xy 156.554678 -387.97611) (xy 156.54528 -387.956552)
			(xy 156.53639 -387.94944) (xy 156.517829 -387.933637) (xy 156.485104 -387.89751) (xy 156.458032 -387.856973)
			(xy 156.437199 -387.812903) (xy 156.423058 -387.766254) (xy 156.415912 -387.718035) (xy 156.415486 -387.693662)
			(xy 156.415925 -387.669546) (xy 156.42293 -387.621826) (xy 156.436787 -387.575627) (xy 156.457202 -387.531928)
			(xy 156.470096 -387.511544) (xy 156.475938 -387.502654) (xy 156.479494 -387.482588) (xy 156.458412 -387.390386)
			(xy 156.44622 -387.373622) (xy 156.43733 -387.368288) (xy 156.416529 -387.355432) (xy 156.378614 -387.324552)
			(xy 156.345666 -387.288421) (xy 156.318404 -387.247827) (xy 156.297424 -387.203658) (xy 156.283184 -387.156879)
			(xy 156.275996 -387.108511) (xy 156.275532 -387.084062) (xy 156.276093 -387.056779) (xy 156.285052 -387.002953)
			(xy 156.302722 -386.951327) (xy 156.328623 -386.903299) (xy 156.362053 -386.860172) (xy 156.381704 -386.841238)
			(xy 156.389152 -386.833746) (xy 156.397694 -386.814451) (xy 156.398214 -386.8039) (xy 156.398214 -386.729224)
			(xy 156.397628 -386.718688) (xy 156.389102 -386.69941) (xy 156.381704 -386.691886) (xy 156.362238 -386.67315)
			(xy 156.329056 -386.630516) (xy 156.315664 -386.60705) (xy 156.310563 -386.598678) (xy 156.295395 -386.586285)
			(xy 156.276689 -386.580477) (xy 156.266896 -386.580888) (xy 156.21889 -386.58292) (xy 156.183862 -386.582356)
			(xy 156.114324 -386.573845) (xy 156.046317 -386.557022) (xy 155.980831 -386.532132) (xy 155.918819 -386.499535)
			(xy 155.889706 -386.48005) (xy 155.883102 -386.475732) (xy 155.868624 -386.47116) (xy 155.762706 -386.47116)
			(xy 155.734512 -386.494274) (xy 155.730956 -386.512308) (xy 155.725468 -386.537876) (xy 155.707514 -386.586987)
			(xy 155.682059 -386.632664) (xy 155.649736 -386.673768) (xy 155.63088 -386.691886) (xy 155.623438 -386.699381)
			(xy 155.614907 -386.718675) (xy 155.61437 -386.729224) (xy 155.61437 -386.8039) (xy 155.61496 -386.814434)
			(xy 155.62349 -386.833707) (xy 155.63088 -386.841238) (xy 155.650532 -386.860172) (xy 155.68397 -386.903294)
			(xy 155.709873 -386.951321) (xy 155.727539 -387.00295) (xy 155.736489 -387.056778) (xy 155.737052 -387.084062)
			(xy 155.736619 -387.108179) (xy 155.729622 -387.155904) (xy 155.715772 -387.202107) (xy 155.695361 -387.245811)
			(xy 155.682442 -387.26618) (xy 155.6766 -387.27507) (xy 155.673044 -387.295136) (xy 155.694126 -387.387338)
			(xy 155.706318 -387.404102) (xy 155.715208 -387.409436) (xy 155.736011 -387.42229) (xy 155.77393 -387.453167)
			(xy 155.806882 -387.489297) (xy 155.834147 -387.529891) (xy 155.855128 -387.574061) (xy 155.869367 -387.620842)
			(xy 155.876554 -387.669212) (xy 155.877006 -387.693662) (xy 155.876568 -387.718032) (xy 155.869412 -387.766245)
			(xy 155.855262 -387.812886) (xy 155.834426 -387.856949) (xy 155.807353 -387.897479) (xy 155.77463 -387.933601)
			(xy 155.756102 -387.94944) (xy 155.747212 -387.956552) (xy 155.737814 -387.97611) (xy 155.73502 -388.075424)
			(xy 155.743656 -388.09549) (xy 155.752038 -388.10311) (xy 155.770458 -388.120599) (xy 155.801796 -388.160568)
			(xy 155.82609 -388.205171) (xy 155.842669 -388.253178) (xy 155.851078 -388.303267) (xy 155.851606 -388.328662)
			(xy 155.851534 -388.33802) (xy 155.850388 -388.356702) (xy 155.84932 -388.366) (xy 155.848304 -388.37489)
			(xy 155.852114 -388.391654) (xy 155.896056 -388.461504) (xy 155.909772 -388.471918) (xy 155.918154 -388.474712)
			(xy 155.942252 -388.483193) (xy 155.987544 -388.506819) (xy 156.028442 -388.537429) (xy 156.063878 -388.574224)
			(xy 156.092928 -388.616244) (xy 156.114834 -388.662393) (xy 156.12237 -388.686802) (xy 156.123894 -388.692644)
			(xy 156.44368 -389.245602) (xy 156.447744 -389.24992) (xy 156.463963 -389.267617) (xy 156.491401 -389.307004)
			(xy 156.512552 -389.350095) (xy 156.526928 -389.395894) (xy 156.534196 -389.443343) (xy 156.534612 -389.467344)
			(xy 156.534147 -389.492147) (xy 156.526377 -389.541142) (xy 156.511036 -389.588317) (xy 156.488502 -389.63251)
			(xy 156.45933 -389.672632) (xy 156.424239 -389.707695) (xy 156.384093 -389.736835) (xy 156.339882 -389.759334)
			(xy 156.292694 -389.774636) (xy 156.243694 -389.782367) (xy 156.21889 -389.782812) (xy 156.193497 -389.782303)
			(xy 156.143365 -389.774172) (xy 156.095182 -389.75812) (xy 156.05019 -389.734561) (xy 156.00955 -389.704104)
			(xy 155.974309 -389.667534) (xy 155.945377 -389.625794) (xy 155.9235 -389.579961) (xy 155.915868 -389.555736)
			(xy 155.914344 -389.549894) (xy 155.593796 -388.995412) (xy 155.589732 -388.991094) (xy 155.573628 -388.973425)
			(xy 155.546389 -388.93414) (xy 155.525379 -388.891199) (xy 155.511077 -388.845584) (xy 155.503811 -388.798334)
			(xy 155.503372 -388.774432) (xy 155.50353 -388.76238) (xy 155.505439 -388.738352) (xy 155.507182 -388.726426)
			(xy 155.508452 -388.717536) (xy 155.505404 -388.700518) (xy 155.46324 -388.629652) (xy 155.450032 -388.618476)
			(xy 155.44165 -388.615428) (xy 155.419911 -388.607021) (xy 155.37907 -388.584566) (xy 155.342116 -388.556165)
			(xy 155.309907 -388.522478) (xy 155.283191 -388.484288) (xy 155.262589 -388.442481) (xy 155.248579 -388.39803)
			(xy 155.241487 -388.351965) (xy 155.24099 -388.328662) (xy 155.24149 -388.303264) (xy 155.249889 -388.253167)
			(xy 155.266467 -388.205152) (xy 155.290764 -388.160544) (xy 155.322112 -388.120575) (xy 155.340558 -388.10311)
			(xy 155.34894 -388.09549) (xy 155.357576 -388.075424) (xy 155.354782 -387.97611) (xy 155.345384 -387.956552)
			(xy 155.336494 -387.94944) (xy 155.317933 -387.933637) (xy 155.285207 -387.897511) (xy 155.258135 -387.856974)
			(xy 155.237302 -387.812904) (xy 155.22316 -387.766254) (xy 155.216015 -387.718035) (xy 155.21559 -387.693662)
			(xy 155.216029 -387.669546) (xy 155.223034 -387.621826) (xy 155.236891 -387.575627) (xy 155.257306 -387.531929)
			(xy 155.2702 -387.511544) (xy 155.276042 -387.502654) (xy 155.279598 -387.482588) (xy 155.258516 -387.390386)
			(xy 155.246324 -387.373622) (xy 155.237434 -387.368288) (xy 155.216633 -387.355432) (xy 155.178718 -387.324553)
			(xy 155.145769 -387.288421) (xy 155.118506 -387.247828) (xy 155.097526 -387.203659) (xy 155.083286 -387.156879)
			(xy 155.076098 -387.108512) (xy 155.075636 -387.084062) (xy 155.076197 -387.056779) (xy 155.085156 -387.002953)
			(xy 155.102826 -386.951327) (xy 155.128727 -386.9033) (xy 155.162158 -386.860173) (xy 155.181808 -386.841238)
			(xy 155.189256 -386.833745) (xy 155.197797 -386.814451) (xy 155.198318 -386.8039) (xy 155.198318 -386.729224)
			(xy 155.197732 -386.718688) (xy 155.189206 -386.69941) (xy 155.181808 -386.691886) (xy 155.162342 -386.67315)
			(xy 155.129159 -386.630516) (xy 155.115768 -386.60705) (xy 155.110667 -386.598677) (xy 155.095499 -386.586283)
			(xy 155.076793 -386.580473) (xy 155.067 -386.580888) (xy 155.018994 -386.58292) (xy 154.983966 -386.582356)
			(xy 154.914428 -386.573846) (xy 154.846421 -386.557023) (xy 154.780934 -386.532133) (xy 154.718922 -386.499537)
			(xy 154.68981 -386.48005) (xy 154.683206 -386.475732) (xy 154.668728 -386.47116) (xy 154.562556 -386.47116)
			(xy 154.534362 -386.494274) (xy 154.530806 -386.512308) (xy 154.525317 -386.537875) (xy 154.507361 -386.586985)
			(xy 154.481903 -386.632659) (xy 154.449578 -386.673759) (xy 154.43073 -386.691886) (xy 154.423282 -386.699378)
			(xy 154.414743 -386.718673) (xy 154.41422 -386.729224) (xy 154.41422 -386.8039) (xy 154.414811 -386.814433)
			(xy 154.423347 -386.8337) (xy 154.43073 -386.841238) (xy 154.450385 -386.860171) (xy 154.483827 -386.903291)
			(xy 154.509735 -386.951318) (xy 154.527404 -387.002947) (xy 154.536355 -387.056777) (xy 154.536902 -387.084062)
			(xy 154.536469 -387.10818) (xy 154.529473 -387.155905) (xy 154.515625 -387.202109) (xy 154.495217 -387.245814)
			(xy 154.482292 -387.26618) (xy 154.47645 -387.27507) (xy 154.472894 -387.295136) (xy 154.493976 -387.387338)
			(xy 154.506168 -387.404102) (xy 154.515058 -387.409436) (xy 154.535858 -387.422292) (xy 154.573772 -387.453172)
			(xy 154.606719 -387.489303) (xy 154.633979 -387.529897) (xy 154.654957 -387.574067) (xy 154.669194 -387.620846)
			(xy 154.676379 -387.669213) (xy 154.676856 -387.693662) (xy 154.676418 -387.718033) (xy 154.669263 -387.766246)
			(xy 154.655115 -387.812889) (xy 154.634281 -387.856954) (xy 154.607211 -387.897487) (xy 154.57449 -387.933613)
			(xy 154.555952 -387.94944) (xy 154.547062 -387.956552) (xy 154.537664 -387.97611) (xy 154.53487 -388.075424)
			(xy 154.543506 -388.09549) (xy 154.551888 -388.10311) (xy 154.57031 -388.120598) (xy 154.601653 -388.160565)
			(xy 154.625951 -388.205168) (xy 154.642534 -388.253176) (xy 154.650944 -388.303266) (xy 154.651456 -388.328662)
			(xy 154.651384 -388.33802) (xy 154.650238 -388.356702) (xy 154.64917 -388.366) (xy 154.648154 -388.37489)
			(xy 154.651964 -388.391654) (xy 154.695906 -388.461504) (xy 154.709622 -388.471918) (xy 154.718004 -388.474712)
			(xy 154.74204 -388.483165) (xy 154.787222 -388.50671) (xy 154.828036 -388.537207) (xy 154.863421 -388.573863)
			(xy 154.892458 -388.615728) (xy 154.914395 -388.661712) (xy 154.921966 -388.68604) (xy 154.92349 -388.691882)
			(xy 155.243784 -389.245602) (xy 155.247848 -389.24992) (xy 155.264067 -389.267617) (xy 155.291504 -389.307005)
			(xy 155.312655 -389.350096) (xy 155.327031 -389.395894) (xy 155.334299 -389.443343) (xy 155.334716 -389.467344)
			(xy 155.334251 -389.492147) (xy 155.326481 -389.541142) (xy 155.31114 -389.588317) (xy 155.288606 -389.632511)
			(xy 155.259434 -389.672633) (xy 155.224343 -389.707697) (xy 155.184197 -389.736837) (xy 155.139986 -389.759336)
			(xy 155.092799 -389.77464) (xy 155.043798 -389.78237) (xy 155.018994 -389.782812) (xy 154.993601 -389.782304)
			(xy 154.943469 -389.774173) (xy 154.895285 -389.758121) (xy 154.850292 -389.734563) (xy 154.809651 -389.704106)
			(xy 154.77441 -389.667536) (xy 154.745478 -389.625796) (xy 154.723601 -389.579962) (xy 154.715972 -389.555736)
			(xy 154.714448 -389.549894) (xy 154.394154 -388.996174) (xy 154.39009 -388.991856) (xy 154.373901 -388.974147)
			(xy 154.346527 -388.934744) (xy 154.325439 -388.891648) (xy 154.311122 -388.845855) (xy 154.303909 -388.798422)
			(xy 154.303476 -388.774432) (xy 154.303562 -388.762384) (xy 154.305345 -388.738355) (xy 154.307032 -388.726426)
			(xy 154.308302 -388.717536) (xy 154.305254 -388.700518) (xy 154.26309 -388.629652) (xy 154.249882 -388.618476)
			(xy 154.2415 -388.615428) (xy 154.219759 -388.607024) (xy 154.178912 -388.584572) (xy 154.141952 -388.556174)
			(xy 154.109737 -388.522488) (xy 154.083016 -388.484297) (xy 154.062411 -388.442489) (xy 154.048398 -388.398035)
			(xy 154.041305 -388.351967) (xy 154.04084 -388.328662) (xy 154.04134 -388.303264) (xy 154.049741 -388.253169)
			(xy 154.06632 -388.205156) (xy 154.09062 -388.16055) (xy 154.121971 -388.120584) (xy 154.140408 -388.10311)
			(xy 154.14879 -388.09549) (xy 154.157426 -388.075424) (xy 154.154632 -387.97611) (xy 154.145234 -387.956552)
			(xy 154.136344 -387.94944) (xy 154.117781 -387.933639) (xy 154.08505 -387.897514) (xy 154.057973 -387.856978)
			(xy 154.037138 -387.812907) (xy 154.022993 -387.766257) (xy 154.015847 -387.718036) (xy 154.01544 -387.693662)
			(xy 154.015879 -387.669546) (xy 154.022885 -387.621826) (xy 154.036744 -387.575629) (xy 154.057162 -387.531932)
			(xy 154.07005 -387.511544) (xy 154.075892 -387.502654) (xy 154.079448 -387.482588) (xy 154.058366 -387.390386)
			(xy 154.046174 -387.373622) (xy 154.037284 -387.368288) (xy 154.01648 -387.355434) (xy 153.97856 -387.324557)
			(xy 153.945606 -387.288427) (xy 153.918339 -387.247834) (xy 153.897355 -387.203664) (xy 153.883113 -387.156882)
			(xy 153.875923 -387.108513) (xy 153.875486 -387.084062) (xy 153.876047 -387.056779) (xy 153.885008 -387.002955)
			(xy 153.902679 -386.95133) (xy 153.928583 -386.903305) (xy 153.962017 -386.860182) (xy 153.981658 -386.841238)
			(xy 153.989112 -386.833748) (xy 153.997662 -386.814453) (xy 153.998168 -386.8039) (xy 153.998168 -386.729224)
			(xy 153.997581 -386.71869) (xy 153.989049 -386.699417) (xy 153.981658 -386.691886) (xy 153.96219 -386.673152)
			(xy 153.929003 -386.63052) (xy 153.915618 -386.60705) (xy 153.910515 -386.598684) (xy 153.895345 -386.586305)
			(xy 153.876643 -386.580513) (xy 153.86685 -386.580888) (xy 153.819098 -386.58292) (xy 153.78407 -386.582356)
			(xy 153.714532 -386.573847) (xy 153.646524 -386.557025) (xy 153.581037 -386.532134) (xy 153.519025 -386.499539)
			(xy 153.489914 -386.48005) (xy 153.48331 -386.475732) (xy 153.468832 -386.47116) (xy 153.36266 -386.47116)
			(xy 153.334466 -386.494274) (xy 153.33091 -386.512308) (xy 153.326419 -386.533496) (xy 153.312622 -386.574553)
			(xy 153.293578 -386.613454) (xy 153.281888 -386.631688) (xy 153.277137 -386.639658) (xy 153.273116 -386.657757)
			(xy 153.274014 -386.666994) (xy 153.278332 -386.697982) (xy 153.280138 -386.707234) (xy 153.289399 -386.723634)
			(xy 153.296366 -386.729986) (xy 153.318464 -386.748659) (xy 153.358243 -386.790667) (xy 153.39241 -386.837354)
			(xy 153.420419 -386.887976) (xy 153.441825 -386.941724) (xy 153.456285 -386.997741) (xy 153.46357 -387.055135)
			(xy 153.464006 -387.084062) (xy 153.463402 -387.117382) (xy 153.453733 -387.183317) (xy 153.434609 -387.247154)
			(xy 153.42108 -387.27761) (xy 153.416817 -387.288079) (xy 153.416891 -387.310653) (xy 153.426648 -387.331009)
			(xy 153.43505 -387.33857) (xy 153.457296 -387.357245) (xy 153.497359 -387.399301) (xy 153.531779 -387.446088)
			(xy 153.560004 -387.496852) (xy 153.581581 -387.55078) (xy 153.596163 -387.607003) (xy 153.603515 -387.66462)
			(xy 153.60396 -387.693662) (xy 153.603509 -387.722666) (xy 153.596178 -387.780208) (xy 153.58164 -387.836364)
			(xy 153.560129 -387.890235) (xy 153.531989 -387.94096) (xy 153.497669 -387.987725) (xy 153.45772 -388.029784)
			(xy 153.435558 -388.0485) (xy 153.428446 -388.054088) (xy 153.419302 -388.069328) (xy 153.404062 -388.152132)
			(xy 153.406856 -388.169404) (xy 153.411428 -388.177532) (xy 153.424024 -388.20071) (xy 153.441915 -388.25033)
			(xy 153.450999 -388.302289) (xy 153.45156 -388.328662) (xy 153.451488 -388.33802) (xy 153.450342 -388.356702)
			(xy 153.449274 -388.366) (xy 153.448258 -388.37489) (xy 153.452068 -388.391654) (xy 153.49601 -388.461504)
			(xy 153.509726 -388.471918) (xy 153.518108 -388.474712) (xy 153.542144 -388.483166) (xy 153.587325 -388.506711)
			(xy 153.628139 -388.537208) (xy 153.663523 -388.573864) (xy 153.69256 -388.615729) (xy 153.714496 -388.661713)
			(xy 153.72207 -388.68604) (xy 153.723594 -388.691882) (xy 154.043888 -389.245602) (xy 154.047952 -389.24992)
			(xy 154.064171 -389.267617) (xy 154.091608 -389.307005) (xy 154.112758 -389.350096) (xy 154.127134 -389.395895)
			(xy 154.134402 -389.443343) (xy 154.13482 -389.467344) (xy 154.134355 -389.492145) (xy 154.126584 -389.541134)
			(xy 154.111242 -389.588303) (xy 154.088707 -389.632489) (xy 154.059533 -389.672604) (xy 154.02444 -389.707658)
			(xy 153.984294 -389.736788) (xy 153.940083 -389.759275) (xy 153.892897 -389.774565) (xy 153.843899 -389.782282)
			(xy 153.819098 -389.782812) (xy 153.793704 -389.782304) (xy 153.743572 -389.774173) (xy 153.695388 -389.758122)
			(xy 153.650395 -389.734564) (xy 153.609753 -389.704107) (xy 153.574512 -389.667537) (xy 153.545579 -389.625797)
			(xy 153.523701 -389.579963) (xy 153.516076 -389.555736) (xy 153.514552 -389.549894) (xy 153.194258 -388.996174)
			(xy 153.190194 -388.991856) (xy 153.174005 -388.974147) (xy 153.146631 -388.934744) (xy 153.125542 -388.891648)
			(xy 153.111225 -388.845855) (xy 153.104012 -388.798422) (xy 153.10358 -388.774432) (xy 153.103666 -388.762384)
			(xy 153.105449 -388.738355) (xy 153.107136 -388.726426) (xy 153.108406 -388.717536) (xy 153.105358 -388.700518)
			(xy 153.063194 -388.629652) (xy 153.049986 -388.618476) (xy 153.041604 -388.615428) (xy 153.019862 -388.607024)
			(xy 152.979015 -388.584573) (xy 152.942055 -388.556174) (xy 152.90984 -388.522488) (xy 152.883118 -388.484298)
			(xy 152.862512 -388.442489) (xy 152.8485 -388.398035) (xy 152.841406 -388.351967) (xy 152.840944 -388.328662)
			(xy 152.841526 -388.302291) (xy 152.850627 -388.25034) (xy 152.868502 -388.200719) (xy 152.881076 -388.177532)
			(xy 152.885648 -388.169404) (xy 152.888442 -388.152132) (xy 152.873202 -388.069328) (xy 152.864058 -388.054088)
			(xy 152.856946 -388.0485) (xy 152.834757 -388.029815) (xy 152.794806 -387.987755) (xy 152.760489 -387.940985)
			(xy 152.732355 -387.890255) (xy 152.710855 -387.836376) (xy 152.696333 -387.780214) (xy 152.689022 -387.722667)
			(xy 152.688544 -387.693662) (xy 152.689147 -387.660342) (xy 152.698813 -387.594406) (xy 152.717936 -387.530568)
			(xy 152.73147 -387.500114) (xy 152.735736 -387.489643) (xy 152.735669 -387.467062) (xy 152.725924 -387.446692)
			(xy 152.7175 -387.439154) (xy 152.695255 -387.420479) (xy 152.655196 -387.378423) (xy 152.620779 -387.331636)
			(xy 152.592559 -387.28087) (xy 152.570988 -387.226942) (xy 152.556414 -387.170719) (xy 152.54907 -387.113103)
			(xy 152.54859 -387.084062) (xy 152.549035 -387.055136) (xy 152.556328 -386.997746) (xy 152.570793 -386.941732)
			(xy 152.5922 -386.887987) (xy 152.620207 -386.837367) (xy 152.654369 -386.790679) (xy 152.69414 -386.748666)
			(xy 152.71623 -386.729986) (xy 152.723305 -386.723722) (xy 152.732593 -386.707281) (xy 152.734264 -386.697982)
			(xy 152.738582 -386.666994) (xy 152.73953 -386.657756) (xy 152.735495 -386.639646) (xy 152.730708 -386.631688)
			(xy 152.715722 -386.60705) (xy 152.710619 -386.598683) (xy 152.69545 -386.586303) (xy 152.676747 -386.580509)
			(xy 152.666954 -386.580888) (xy 152.618948 -386.58292) (xy 152.583921 -386.582353) (xy 152.514385 -386.573838)
			(xy 152.44638 -386.557011) (xy 152.380897 -386.532116) (xy 152.318889 -386.499517) (xy 152.289764 -386.48005)
			(xy 152.28316 -386.475732) (xy 152.268682 -386.47116) (xy 152.16251 -386.47116) (xy 152.134316 -386.494274)
			(xy 152.13076 -386.512308) (xy 152.125441 -386.537086) (xy 152.108278 -386.584765) (xy 152.084041 -386.629268)
			(xy 152.053298 -386.669552) (xy 152.016768 -386.704673) (xy 151.975307 -386.733809) (xy 151.929886 -386.756278)
			(xy 151.881568 -386.771553) (xy 151.831485 -386.779277) (xy 151.806148 -386.77977) (xy 151.780794 -386.779282)
			(xy 151.73068 -386.771536) (xy 151.682335 -386.756235) (xy 151.63689 -386.733736) (xy 151.595411 -386.704567)
			(xy 151.558868 -386.66941) (xy 151.528118 -386.629088) (xy 151.515572 -386.60705) (xy 151.510467 -386.59869)
			(xy 151.495296 -386.586325) (xy 151.476596 -386.580549) (xy 151.466804 -386.580888) (xy 151.419052 -386.58292)
			(xy 151.384025 -386.582353) (xy 151.314489 -386.573839) (xy 151.246484 -386.557012) (xy 151.181001 -386.532118)
			(xy 151.118992 -386.499519) (xy 151.089868 -386.48005) (xy 151.083264 -386.475732) (xy 151.068786 -386.47116)
			(xy 150.962614 -386.47116) (xy 150.93442 -386.494274) (xy 150.930864 -386.512308) (xy 150.925374 -386.537874)
			(xy 150.907417 -386.586983) (xy 150.881957 -386.632655) (xy 150.849628 -386.673752) (xy 150.830788 -386.691886)
			(xy 150.823345 -386.69938) (xy 150.814813 -386.718675) (xy 150.814278 -386.729224) (xy 150.814278 -386.8039)
			(xy 150.814868 -386.814434) (xy 150.823399 -386.833706) (xy 150.830788 -386.841238) (xy 150.85044 -386.860172)
			(xy 150.883877 -386.903295) (xy 150.909779 -386.951322) (xy 150.927445 -387.00295) (xy 150.936394 -387.056778)
			(xy 150.93696 -387.084062) (xy 150.936527 -387.108179) (xy 150.92953 -387.155904) (xy 150.91568 -387.202107)
			(xy 150.89527 -387.245811) (xy 150.88235 -387.26618) (xy 150.876508 -387.27507) (xy 150.872952 -387.295136)
			(xy 150.894034 -387.387338) (xy 150.906226 -387.404102) (xy 150.915116 -387.409436) (xy 150.935919 -387.422291)
			(xy 150.973837 -387.453168) (xy 151.006788 -387.489298) (xy 151.034052 -387.529892) (xy 151.055033 -387.574062)
			(xy 151.069272 -387.620843) (xy 151.076458 -387.669212) (xy 151.076914 -387.693662) (xy 151.076476 -387.718032)
			(xy 151.06932 -387.766245) (xy 151.055171 -387.812887) (xy 151.034335 -387.856949) (xy 151.007263 -387.89748)
			(xy 150.97454 -387.933603) (xy 150.95601 -387.94944) (xy 150.94712 -387.956552) (xy 150.937722 -387.97611)
			(xy 150.934928 -388.075424) (xy 150.943564 -388.09549) (xy 150.951946 -388.10311) (xy 150.970365 -388.120599)
			(xy 151.001703 -388.160569) (xy 151.025996 -388.205171) (xy 151.042575 -388.253179) (xy 151.050984 -388.303267)
			(xy 151.051514 -388.328662) (xy 151.640794 -388.328662) (xy 151.641316 -388.303407) (xy 151.649629 -388.253585)
			(xy 151.66603 -388.205811) (xy 151.690071 -388.161388) (xy 151.721095 -388.121528) (xy 151.758257 -388.087318)
			(xy 151.800543 -388.059692) (xy 151.846799 -388.039402) (xy 151.895764 -388.027002) (xy 151.946102 -388.022831)
			(xy 151.99644 -388.027002) (xy 152.045405 -388.039402) (xy 152.091661 -388.059692) (xy 152.133947 -388.087318)
			(xy 152.171109 -388.121528) (xy 152.202133 -388.161388) (xy 152.226174 -388.205811) (xy 152.242575 -388.253585)
			(xy 152.250888 -388.303407) (xy 152.25141 -388.328662) (xy 152.251341 -388.338021) (xy 152.250198 -388.356703)
			(xy 152.249124 -388.366) (xy 152.248108 -388.37489) (xy 152.251918 -388.391654) (xy 152.29586 -388.461504)
			(xy 152.309576 -388.471918) (xy 152.317958 -388.474712) (xy 152.34199 -388.48317) (xy 152.387162 -388.506725)
			(xy 152.427966 -388.537227) (xy 152.463345 -388.573884) (xy 152.492379 -388.615745) (xy 152.514317 -388.661724)
			(xy 152.52192 -388.68604) (xy 152.523444 -388.691882) (xy 152.843738 -389.245602) (xy 152.847802 -389.24992)
			(xy 152.86399 -389.267629) (xy 152.891356 -389.307037) (xy 152.912442 -389.350133) (xy 152.926762 -389.395924)
			(xy 152.933987 -389.443355) (xy 152.934416 -389.467344) (xy 152.933923 -389.492132) (xy 152.926162 -389.541098)
			(xy 152.910838 -389.588247) (xy 152.888328 -389.63242) (xy 152.859187 -389.672528) (xy 152.824131 -389.707584)
			(xy 152.784023 -389.736726) (xy 152.739851 -389.759236) (xy 152.692702 -389.774561) (xy 152.643736 -389.782322)
			(xy 152.618948 -389.782812) (xy 152.593555 -389.782269) (xy 152.543423 -389.774146) (xy 152.495239 -389.758102)
			(xy 152.450245 -389.73455) (xy 152.409601 -389.704098) (xy 152.374358 -389.667532) (xy 152.345423 -389.625796)
			(xy 152.323543 -389.579965) (xy 152.315926 -389.555736) (xy 152.314402 -389.549894) (xy 151.994108 -388.996174)
			(xy 151.990044 -388.991856) (xy 151.973831 -388.974156) (xy 151.946411 -388.934762) (xy 151.92527 -388.89167)
			(xy 151.910899 -388.845875) (xy 151.903626 -388.798431) (xy 151.903176 -388.774432) (xy 151.903318 -388.76238)
			(xy 151.905224 -388.73835) (xy 151.906986 -388.726426) (xy 151.908256 -388.717536) (xy 151.905208 -388.700518)
			(xy 151.863044 -388.629652) (xy 151.849836 -388.618476) (xy 151.841454 -388.615428) (xy 151.819703 -388.607042)
			(xy 151.778845 -388.584599) (xy 151.741875 -388.556203) (xy 151.709653 -388.522517) (xy 151.682928 -388.484322)
			(xy 151.662322 -388.442507) (xy 151.648315 -388.398045) (xy 151.641232 -388.35197) (xy 151.640794 -388.328662)
			(xy 151.051514 -388.328662) (xy 151.051442 -388.33802) (xy 151.050296 -388.356702) (xy 151.049228 -388.366)
			(xy 151.048212 -388.37489) (xy 151.052022 -388.391654) (xy 151.095964 -388.461504) (xy 151.10968 -388.471918)
			(xy 151.118062 -388.474712) (xy 151.142095 -388.483169) (xy 151.18727 -388.506719) (xy 151.228077 -388.537219)
			(xy 151.263456 -388.573877) (xy 151.292487 -388.615741) (xy 151.314419 -388.661724) (xy 151.322024 -388.68604)
			(xy 151.323548 -388.691882) (xy 151.643842 -389.245602) (xy 151.647906 -389.24992) (xy 151.664096 -389.267629)
			(xy 151.691474 -389.307031) (xy 151.712566 -389.350126) (xy 151.726886 -389.395919) (xy 151.734103 -389.443354)
			(xy 151.73452 -389.467344) (xy 151.734056 -389.492132) (xy 151.726293 -389.541097) (xy 151.710967 -389.588244)
			(xy 151.688453 -389.632413) (xy 151.659308 -389.672517) (xy 151.624247 -389.707567) (xy 151.584135 -389.736702)
			(xy 151.539959 -389.759202) (xy 151.492807 -389.774515) (xy 151.44384 -389.782263) (xy 151.419052 -389.782812)
			(xy 151.39366 -389.782301) (xy 151.343533 -389.774164) (xy 151.295355 -389.758108) (xy 151.250368 -389.734547)
			(xy 151.209733 -389.704089) (xy 151.174497 -389.667519) (xy 151.145569 -389.62578) (xy 151.123696 -389.579949)
			(xy 151.11603 -389.555736) (xy 151.114506 -389.549894) (xy 150.794212 -388.996174) (xy 150.790148 -388.991856)
			(xy 150.77393 -388.974158) (xy 150.746497 -388.93477) (xy 150.725349 -388.891679) (xy 150.710977 -388.84588)
			(xy 150.703713 -388.798432) (xy 150.70328 -388.774432) (xy 150.703438 -388.76238) (xy 150.705347 -388.738352)
			(xy 150.70709 -388.726426) (xy 150.70836 -388.717536) (xy 150.705312 -388.700518) (xy 150.663148 -388.629652)
			(xy 150.64994 -388.618476) (xy 150.641558 -388.615428) (xy 150.619819 -388.607021) (xy 150.578977 -388.584567)
			(xy 150.542022 -388.556166) (xy 150.509812 -388.52248) (xy 150.483095 -388.484289) (xy 150.462493 -388.442483)
			(xy 150.448482 -388.398031) (xy 150.44139 -388.351966) (xy 150.440898 -388.328662) (xy 150.441398 -388.303264)
			(xy 150.449798 -388.253167) (xy 150.466375 -388.205153) (xy 150.490673 -388.160545) (xy 150.522021 -388.120576)
			(xy 150.540466 -388.10311) (xy 150.548848 -388.09549) (xy 150.557484 -388.075424) (xy 150.55469 -387.97611)
			(xy 150.545292 -387.956552) (xy 150.536402 -387.94944) (xy 150.517841 -387.933638) (xy 150.485114 -387.897511)
			(xy 150.458041 -387.856974) (xy 150.437208 -387.812904) (xy 150.423065 -387.766255) (xy 150.41592 -387.718035)
			(xy 150.415498 -387.693662) (xy 150.415937 -387.669546) (xy 150.422942 -387.621826) (xy 150.4368 -387.575627)
			(xy 150.457215 -387.531929) (xy 150.470108 -387.511544) (xy 150.47595 -387.502654) (xy 150.479506 -387.482588)
			(xy 150.458424 -387.390386) (xy 150.446232 -387.373622) (xy 150.437342 -387.368288) (xy 150.41654 -387.355432)
			(xy 150.378624 -387.324553) (xy 150.345675 -387.288422) (xy 150.318412 -387.247829) (xy 150.297431 -387.203659)
			(xy 150.28319 -387.15688) (xy 150.276002 -387.108512) (xy 150.275544 -387.084062) (xy 150.276105 -387.056779)
			(xy 150.285065 -387.002953) (xy 150.302735 -386.951327) (xy 150.328636 -386.903301) (xy 150.362067 -386.860175)
			(xy 150.381716 -386.841238) (xy 150.389163 -386.833745) (xy 150.397703 -386.81445) (xy 150.398226 -386.8039)
			(xy 150.398226 -386.729224) (xy 150.397641 -386.718688) (xy 150.389116 -386.699409) (xy 150.381716 -386.691886)
			(xy 150.36225 -386.67315) (xy 150.329066 -386.630517) (xy 150.315676 -386.60705) (xy 150.310571 -386.598689)
			(xy 150.2954 -386.586323) (xy 150.2767 -386.580545) (xy 150.266908 -386.580888) (xy 150.218902 -386.58292)
			(xy 150.183874 -386.582356) (xy 150.114335 -386.573847) (xy 150.046327 -386.557026) (xy 149.980841 -386.532136)
			(xy 149.918828 -386.49954) (xy 149.889718 -386.48005) (xy 149.883114 -386.475732) (xy 149.868636 -386.47116)
			(xy 149.762718 -386.47116) (xy 149.734524 -386.494274) (xy 149.730968 -386.512308) (xy 149.725478 -386.537874)
			(xy 149.707521 -386.586983) (xy 149.682061 -386.632655) (xy 149.649733 -386.673753) (xy 149.630892 -386.691886)
			(xy 149.623448 -386.69938) (xy 149.614916 -386.718675) (xy 149.614382 -386.729224) (xy 149.614382 -386.8039)
			(xy 149.614972 -386.814434) (xy 149.623504 -386.833705) (xy 149.630892 -386.841238) (xy 149.650544 -386.860172)
			(xy 149.68398 -386.903295) (xy 149.709882 -386.951322) (xy 149.727548 -387.00295) (xy 149.736497 -387.056778)
			(xy 149.737064 -387.084062) (xy 149.736631 -387.108179) (xy 149.729634 -387.155904) (xy 149.715784 -387.202108)
			(xy 149.695374 -387.245811) (xy 149.682454 -387.26618) (xy 149.676612 -387.27507) (xy 149.673056 -387.295136)
			(xy 149.694138 -387.387338) (xy 149.70633 -387.404102) (xy 149.71522 -387.409436) (xy 149.736022 -387.422291)
			(xy 149.77394 -387.453168) (xy 149.806891 -387.489299) (xy 149.834154 -387.529893) (xy 149.855135 -387.574063)
			(xy 149.869374 -387.620843) (xy 149.87656 -387.669212) (xy 149.877018 -387.693662) (xy 149.87658 -387.718032)
			(xy 149.869424 -387.766245) (xy 149.855275 -387.812887) (xy 149.834439 -387.85695) (xy 149.807367 -387.897481)
			(xy 149.774644 -387.933604) (xy 149.756114 -387.94944) (xy 149.747224 -387.956552) (xy 149.737826 -387.97611)
			(xy 149.735032 -388.075424) (xy 149.743668 -388.09549) (xy 149.75205 -388.10311) (xy 149.770469 -388.120599)
			(xy 149.801806 -388.160569) (xy 149.826099 -388.205172) (xy 149.842678 -388.253179) (xy 149.851086 -388.303267)
			(xy 149.851618 -388.328662) (xy 149.851546 -388.33802) (xy 149.8504 -388.356702) (xy 149.849332 -388.366)
			(xy 149.848316 -388.37489) (xy 149.852126 -388.391654) (xy 149.896068 -388.461504) (xy 149.909784 -388.471918)
			(xy 149.918166 -388.474712) (xy 149.942263 -388.483193) (xy 149.987554 -388.506821) (xy 150.02845 -388.537432)
			(xy 150.063885 -388.574227) (xy 150.092933 -388.616247) (xy 150.114839 -388.662395) (xy 150.122382 -388.686802)
			(xy 150.123906 -388.692644) (xy 150.443692 -389.245602) (xy 150.447756 -389.24992) (xy 150.463975 -389.267617)
			(xy 150.491411 -389.307005) (xy 150.512562 -389.350096) (xy 150.526937 -389.395895) (xy 150.534205 -389.443343)
			(xy 150.534624 -389.467344) (xy 150.534159 -389.492145) (xy 150.526388 -389.541134) (xy 150.511047 -389.588303)
			(xy 150.488511 -389.63249) (xy 150.459337 -389.672605) (xy 150.424245 -389.70766) (xy 150.384098 -389.73679)
			(xy 150.339887 -389.759278) (xy 150.292701 -389.774568) (xy 150.243703 -389.782285) (xy 150.218902 -389.782812)
			(xy 150.193508 -389.782304) (xy 150.143375 -389.774174) (xy 150.095191 -389.758123) (xy 150.050197 -389.734566)
			(xy 150.009555 -389.704109) (xy 149.974313 -389.667539) (xy 149.94538 -389.625798) (xy 149.923502 -389.579965)
			(xy 149.91588 -389.555736) (xy 149.914356 -389.549894) (xy 149.593808 -388.995412) (xy 149.589744 -388.991094)
			(xy 149.573639 -388.973426) (xy 149.546399 -388.93414) (xy 149.525388 -388.8912) (xy 149.511087 -388.845584)
			(xy 149.50382 -388.798334) (xy 149.503384 -388.774432) (xy 149.503542 -388.76238) (xy 149.505451 -388.738352)
			(xy 149.507194 -388.726426) (xy 149.508464 -388.717536) (xy 149.505416 -388.700518) (xy 149.463252 -388.629652)
			(xy 149.450044 -388.618476) (xy 149.441662 -388.615428) (xy 149.419923 -388.607022) (xy 149.37908 -388.584567)
			(xy 149.342125 -388.556167) (xy 149.309914 -388.52248) (xy 149.283197 -388.48429) (xy 149.262594 -388.442483)
			(xy 149.248584 -388.398031) (xy 149.241492 -388.351966) (xy 149.241002 -388.328662) (xy 149.241502 -388.303264)
			(xy 149.249902 -388.253168) (xy 149.266479 -388.205153) (xy 149.290778 -388.160546) (xy 149.322126 -388.120577)
			(xy 149.34057 -388.10311) (xy 149.348952 -388.09549) (xy 149.357588 -388.075424) (xy 149.354794 -387.97611)
			(xy 149.345396 -387.956552) (xy 149.336506 -387.94944) (xy 149.317945 -387.933638) (xy 149.285217 -387.897511)
			(xy 149.258144 -387.856974) (xy 149.237311 -387.812904) (xy 149.223168 -387.766255) (xy 149.216022 -387.718035)
			(xy 149.215602 -387.693662) (xy 149.216041 -387.669546) (xy 149.223046 -387.621826) (xy 149.236904 -387.575627)
			(xy 149.25732 -387.53193) (xy 149.270212 -387.511544) (xy 149.276054 -387.502654) (xy 149.27961 -387.482588)
			(xy 149.258528 -387.390386) (xy 149.246336 -387.373622) (xy 149.237446 -387.368288) (xy 149.216644 -387.355432)
			(xy 149.178728 -387.324554) (xy 149.145778 -387.288423) (xy 149.118514 -387.247829) (xy 149.097533 -387.20366)
			(xy 149.083292 -387.15688) (xy 149.076104 -387.108512) (xy 149.075648 -387.084062) (xy 149.076209 -387.056779)
			(xy 149.085169 -387.002953) (xy 149.102839 -386.951328) (xy 149.128741 -386.903301) (xy 149.162172 -386.860175)
			(xy 149.18182 -386.841238) (xy 149.189266 -386.833745) (xy 149.197806 -386.81445) (xy 149.19833 -386.8039)
			(xy 149.19833 -386.729224) (xy 149.197745 -386.718688) (xy 149.18922 -386.699408) (xy 149.18182 -386.691886)
			(xy 149.162353 -386.67315) (xy 149.12917 -386.630517) (xy 149.11578 -386.60705) (xy 149.110675 -386.598689)
			(xy 149.095504 -386.586321) (xy 149.076804 -386.580542) (xy 149.067012 -386.580888) (xy 149.019006 -386.58292)
			(xy 148.983978 -386.582357) (xy 148.914439 -386.573848) (xy 148.846431 -386.557027) (xy 148.780944 -386.532137)
			(xy 148.718931 -386.499542) (xy 148.689822 -386.48005) (xy 148.683218 -386.475732) (xy 148.66874 -386.47116)
			(xy 148.562568 -386.47116) (xy 148.534374 -386.494274) (xy 148.530818 -386.512308) (xy 148.525329 -386.537875)
			(xy 148.507374 -386.586986) (xy 148.481917 -386.63266) (xy 148.449592 -386.673761) (xy 148.430742 -386.691886)
			(xy 148.423292 -386.699377) (xy 148.414751 -386.718673) (xy 148.414232 -386.729224) (xy 148.414232 -386.8039)
			(xy 148.414824 -386.814432) (xy 148.423361 -386.833698) (xy 148.430742 -386.841238) (xy 148.450396 -386.860171)
			(xy 148.483838 -386.903292) (xy 148.509744 -386.951319) (xy 148.527412 -387.002948) (xy 148.536363 -387.056778)
			(xy 148.536914 -387.084062) (xy 148.536481 -387.10818) (xy 148.529485 -387.155905) (xy 148.515637 -387.202109)
			(xy 148.49523 -387.245815) (xy 148.482304 -387.26618) (xy 148.476462 -387.27507) (xy 148.472906 -387.295136)
			(xy 148.493988 -387.387338) (xy 148.50618 -387.404102) (xy 148.51507 -387.409436) (xy 148.53587 -387.422293)
			(xy 148.573782 -387.453173) (xy 148.606728 -387.489305) (xy 148.633987 -387.529899) (xy 148.654964 -387.574068)
			(xy 148.669201 -387.620847) (xy 148.676385 -387.669213) (xy 148.676868 -387.693662) (xy 148.67643 -387.718033)
			(xy 148.669275 -387.766246) (xy 148.655127 -387.81289) (xy 148.634294 -387.856955) (xy 148.607224 -387.897489)
			(xy 148.574505 -387.933616) (xy 148.555964 -387.94944) (xy 148.547074 -387.956552) (xy 148.537676 -387.97611)
			(xy 148.534882 -388.075424) (xy 148.543518 -388.09549) (xy 148.5519 -388.10311) (xy 148.570322 -388.120598)
			(xy 148.601664 -388.160566) (xy 148.62596 -388.205168) (xy 148.642542 -388.253177) (xy 148.650953 -388.303267)
			(xy 148.651468 -388.328662) (xy 148.651396 -388.33802) (xy 148.65025 -388.356702) (xy 148.649182 -388.366)
			(xy 148.648166 -388.37489) (xy 148.651976 -388.391654) (xy 148.695918 -388.461504) (xy 148.709634 -388.471918)
			(xy 148.718016 -388.474712) (xy 148.742051 -388.483166) (xy 148.787232 -388.506712) (xy 148.828044 -388.537209)
			(xy 148.863428 -388.573866) (xy 148.892464 -388.61573) (xy 148.9144 -388.661715) (xy 148.921978 -388.68604)
			(xy 148.923502 -388.691882) (xy 149.243796 -389.245602) (xy 149.24786 -389.24992) (xy 149.264079 -389.267617)
			(xy 149.291515 -389.307005) (xy 149.312665 -389.350096) (xy 149.32704 -389.395895) (xy 149.334308 -389.443343)
			(xy 149.334728 -389.467344) (xy 149.334263 -389.492145) (xy 149.326492 -389.541134) (xy 149.311151 -389.588304)
			(xy 149.288615 -389.632491) (xy 149.259442 -389.672606) (xy 149.224349 -389.707661) (xy 149.184202 -389.736792)
			(xy 149.139991 -389.75928) (xy 149.092805 -389.774571) (xy 149.043807 -389.782289) (xy 149.019006 -389.782812)
			(xy 148.993612 -389.782305) (xy 148.943479 -389.774175) (xy 148.895294 -389.758125) (xy 148.850299 -389.734567)
			(xy 148.809657 -389.704111) (xy 148.774414 -389.66754) (xy 148.74548 -389.6258) (xy 148.723602 -389.579966)
			(xy 148.715984 -389.555736) (xy 148.71446 -389.549894) (xy 148.394166 -388.996174) (xy 148.390102 -388.991856)
			(xy 148.373913 -388.974147) (xy 148.346538 -388.934744) (xy 148.325448 -388.891649) (xy 148.311131 -388.845856)
			(xy 148.303918 -388.798422) (xy 148.303488 -388.774432) (xy 148.303574 -388.762384) (xy 148.305356 -388.738355)
			(xy 148.307044 -388.726426) (xy 148.308314 -388.717536) (xy 148.305266 -388.700518) (xy 148.263102 -388.629652)
			(xy 148.249894 -388.618476) (xy 148.241512 -388.615428) (xy 148.21977 -388.607024) (xy 148.178922 -388.584574)
			(xy 148.14196 -388.556176) (xy 148.109744 -388.52249) (xy 148.083023 -388.484299) (xy 148.062416 -388.44249)
			(xy 148.048403 -388.398036) (xy 148.041309 -388.351967) (xy 148.040852 -388.328662) (xy 148.041351 -388.303263)
			(xy 148.04975 -388.253166) (xy 148.066326 -388.20515) (xy 148.090621 -388.16054) (xy 148.121966 -388.120567)
			(xy 148.14042 -388.10311) (xy 148.148802 -388.09549) (xy 148.157438 -388.075424) (xy 148.154644 -387.97611)
			(xy 148.145246 -387.956552) (xy 148.136356 -387.94944) (xy 148.117792 -387.933639) (xy 148.08506 -387.897515)
			(xy 148.057983 -387.856978) (xy 148.037146 -387.812908) (xy 148.023001 -387.766257) (xy 148.015854 -387.718036)
			(xy 148.015452 -387.693662) (xy 148.015891 -387.669546) (xy 148.022897 -387.621827) (xy 148.036757 -387.575629)
			(xy 148.057175 -387.531933) (xy 148.070062 -387.511544) (xy 148.075904 -387.502654) (xy 148.07946 -387.482588)
			(xy 148.058378 -387.390386) (xy 148.046186 -387.373622) (xy 148.037296 -387.368288) (xy 148.016492 -387.355434)
			(xy 147.97857 -387.324558) (xy 147.945615 -387.288429) (xy 147.918347 -387.247835) (xy 147.897362 -387.203665)
			(xy 147.883119 -387.156883) (xy 147.87593 -387.108513) (xy 147.875498 -387.084062) (xy 147.876059 -387.056779)
			(xy 147.88502 -387.002955) (xy 147.902692 -386.951331) (xy 147.928597 -386.903307) (xy 147.962031 -386.860185)
			(xy 147.98167 -386.841238) (xy 147.989122 -386.833748) (xy 147.99767 -386.814452) (xy 147.99818 -386.8039)
			(xy 147.99818 -386.729224) (xy 147.997593 -386.718689) (xy 147.989063 -386.699415) (xy 147.98167 -386.691886)
			(xy 147.962201 -386.673152) (xy 147.929013 -386.630521) (xy 147.91563 -386.60705) (xy 147.910527 -386.598682)
			(xy 147.895358 -386.5863) (xy 147.876655 -386.580503) (xy 147.866862 -386.580888) (xy 147.81911 -386.58292)
			(xy 147.784082 -386.582357) (xy 147.714543 -386.573849) (xy 147.646534 -386.557028) (xy 147.581047 -386.532139)
			(xy 147.519034 -386.499544) (xy 147.489926 -386.48005) (xy 147.483322 -386.475732) (xy 147.468844 -386.47116)
			(xy 147.362672 -386.47116) (xy 147.334478 -386.494274) (xy 147.330922 -386.512308) (xy 147.325433 -386.537875)
			(xy 147.307478 -386.586986) (xy 147.282021 -386.632661) (xy 147.249696 -386.673762) (xy 147.230846 -386.691886)
			(xy 147.223396 -386.699377) (xy 147.214854 -386.718673) (xy 147.214336 -386.729224) (xy 147.214336 -386.8039)
			(xy 147.214928 -386.814432) (xy 147.223466 -386.833698) (xy 147.230846 -386.841238) (xy 147.2505 -386.860171)
			(xy 147.283941 -386.903292) (xy 147.309847 -386.951319) (xy 147.327515 -387.002948) (xy 147.336466 -387.056778)
			(xy 147.337018 -387.084062) (xy 147.336585 -387.10818) (xy 147.329589 -387.155905) (xy 147.315742 -387.202109)
			(xy 147.295334 -387.245815) (xy 147.282408 -387.26618) (xy 147.276566 -387.27507) (xy 147.27301 -387.295136)
			(xy 147.294092 -387.387338) (xy 147.306284 -387.404102) (xy 147.315174 -387.409436) (xy 147.335974 -387.422293)
			(xy 147.373886 -387.453173) (xy 147.406831 -387.489305) (xy 147.43409 -387.529899) (xy 147.455067 -387.574068)
			(xy 147.469303 -387.620847) (xy 147.476488 -387.669213) (xy 147.476972 -387.693662) (xy 147.476534 -387.718033)
			(xy 147.469379 -387.766247) (xy 147.455232 -387.81289) (xy 147.434398 -387.856955) (xy 147.407329 -387.89749)
			(xy 147.374609 -387.933617) (xy 147.356068 -387.94944) (xy 147.347178 -387.956552) (xy 147.33778 -387.97611)
			(xy 147.334986 -388.075424) (xy 147.343622 -388.09549) (xy 147.352004 -388.10311) (xy 147.370426 -388.120598)
			(xy 147.401767 -388.160566) (xy 147.426063 -388.205169) (xy 147.442645 -388.253177) (xy 147.451055 -388.303267)
			(xy 147.451572 -388.328662) (xy 147.4515 -388.33802) (xy 147.450354 -388.356702) (xy 147.449286 -388.366)
			(xy 147.44827 -388.37489) (xy 147.45208 -388.391654) (xy 147.496022 -388.461504) (xy 147.509738 -388.471918)
			(xy 147.51812 -388.474712) (xy 147.542155 -388.483166) (xy 147.587335 -388.506713) (xy 147.628147 -388.53721)
			(xy 147.66353 -388.573867) (xy 147.692566 -388.615731) (xy 147.714501 -388.661716) (xy 147.722082 -388.68604)
			(xy 147.723606 -388.691882) (xy 148.0439 -389.245602) (xy 148.047964 -389.24992) (xy 148.064183 -389.267617)
			(xy 148.091618 -389.307005) (xy 148.112768 -389.350097) (xy 148.127143 -389.395895) (xy 148.134411 -389.443343)
			(xy 148.134832 -389.467344) (xy 148.134367 -389.492145) (xy 148.126596 -389.541135) (xy 148.111255 -389.588305)
			(xy 148.088719 -389.632492) (xy 148.059546 -389.672608) (xy 148.024453 -389.707663) (xy 147.984307 -389.736794)
			(xy 147.940095 -389.759283) (xy 147.892909 -389.774574) (xy 147.843912 -389.782293) (xy 147.81911 -389.782812)
			(xy 147.793716 -389.782305) (xy 147.743582 -389.774176) (xy 147.695396 -389.758126) (xy 147.650402 -389.734569)
			(xy 147.609759 -389.704112) (xy 147.574515 -389.667542) (xy 147.545581 -389.625801) (xy 147.523703 -389.579967)
			(xy 147.516088 -389.555736) (xy 147.514564 -389.549894) (xy 147.19427 -388.996174) (xy 147.190206 -388.991856)
			(xy 147.174017 -388.974147) (xy 147.146641 -388.934744) (xy 147.125551 -388.891649) (xy 147.111234 -388.845856)
			(xy 147.104021 -388.798422) (xy 147.103592 -388.774432) (xy 147.103678 -388.762384) (xy 147.10546 -388.738355)
			(xy 147.107148 -388.726426) (xy 147.108418 -388.717536) (xy 147.10537 -388.700518) (xy 147.063206 -388.629652)
			(xy 147.049998 -388.618476) (xy 147.041616 -388.615428) (xy 147.019874 -388.607024) (xy 146.979025 -388.584574)
			(xy 146.942063 -388.556176) (xy 146.909847 -388.522491) (xy 146.883125 -388.4843) (xy 146.862517 -388.442491)
			(xy 146.848504 -388.398036) (xy 146.84141 -388.351968) (xy 146.840956 -388.328662) (xy 146.841455 -388.303264)
			(xy 146.849854 -388.253166) (xy 146.86643 -388.20515) (xy 146.890726 -388.16054) (xy 146.922071 -388.120568)
			(xy 146.940524 -388.10311) (xy 146.948906 -388.09549) (xy 146.957542 -388.075424) (xy 146.954748 -387.97611)
			(xy 146.94535 -387.956552) (xy 146.93646 -387.94944) (xy 146.917901 -387.933636) (xy 146.885178 -387.897508)
			(xy 146.858108 -387.856971) (xy 146.837278 -387.812901) (xy 146.823138 -387.766253) (xy 146.815993 -387.718034)
			(xy 146.815556 -387.693662) (xy 146.815995 -387.669546) (xy 146.822999 -387.621825) (xy 146.836855 -387.575626)
			(xy 146.857269 -387.531926) (xy 146.870166 -387.511544) (xy 146.876008 -387.502654) (xy 146.879564 -387.482588)
			(xy 146.858482 -387.390386) (xy 146.84629 -387.373622) (xy 146.8374 -387.368288) (xy 146.816595 -387.355434)
			(xy 146.778673 -387.324559) (xy 146.745718 -387.288429) (xy 146.71845 -387.247836) (xy 146.697465 -387.203665)
			(xy 146.683222 -387.156884) (xy 146.676032 -387.108513) (xy 146.675602 -387.084062) (xy 146.676163 -387.056779)
			(xy 146.685124 -387.002955) (xy 146.702796 -386.951331) (xy 146.728701 -386.903307) (xy 146.762136 -386.860185)
			(xy 146.781774 -386.841238) (xy 146.789225 -386.833747) (xy 146.797773 -386.814452) (xy 146.798284 -386.8039)
			(xy 146.798284 -386.729224) (xy 146.797698 -386.718689) (xy 146.789168 -386.699414) (xy 146.781774 -386.691886)
			(xy 146.76291 -386.673773) (xy 146.730576 -386.632674) (xy 146.705115 -386.586998) (xy 146.687161 -386.537882)
			(xy 146.681698 -386.512308) (xy 146.678142 -386.494274) (xy 146.649948 -386.47116) (xy 146.114262 -386.47116)
			(xy 146.104196 -386.471592) (xy 146.085607 -386.479322) (xy 146.078194 -386.486146) (xy 144.760696 -387.803644)
			(xy 144.754585 -387.810284) (xy 144.747057 -387.82667) (xy 144.745653 -387.844649) (xy 144.747742 -387.853428)
			(xy 144.775682 -387.95198) (xy 144.795494 -387.971284) (xy 144.808956 -387.974332) (xy 144.832791 -387.980437)
			(xy 144.878462 -387.998739) (xy 144.920917 -388.023606) (xy 144.959218 -388.054489) (xy 144.99252 -388.090707)
			(xy 145.020088 -388.131459) (xy 145.041313 -388.175847) (xy 145.055726 -388.22289) (xy 145.06301 -388.271549)
			(xy 145.063464 -388.29615) (xy 145.062985 -388.322141) (xy 145.054859 -388.373483) (xy 145.038801 -388.422921)
			(xy 145.015205 -388.469238) (xy 144.984653 -388.511293) (xy 144.947897 -388.548049) (xy 144.905843 -388.578602)
			(xy 144.859527 -388.602199) (xy 144.810088 -388.618258) (xy 144.758747 -388.626384) (xy 144.732756 -388.626858)
			(xy 144.708157 -388.626404) (xy 144.659503 -388.61911) (xy 144.612465 -388.604689) (xy 144.568083 -388.58346)
			(xy 144.527335 -388.555892) (xy 144.49112 -388.522591) (xy 144.460237 -388.484294) (xy 144.435367 -388.441845)
			(xy 144.41706 -388.39618) (xy 144.410938 -388.37235) (xy 144.40789 -388.358888) (xy 144.388586 -388.339076)
			(xy 144.290034 -388.311136) (xy 144.281259 -388.308999) (xy 144.263265 -388.310382) (xy 144.246886 -388.317962)
			(xy 144.24025 -388.32409) (xy 144.19834 -388.366) (xy 144.191736 -388.377938) (xy 144.189958 -388.38505)
			(xy 144.183464 -388.410689) (xy 144.164358 -388.460007) (xy 144.138623 -388.506214) (xy 144.106751 -388.548422)
			(xy 144.069355 -388.585823) (xy 144.02715 -388.617699) (xy 143.980947 -388.64344) (xy 143.931631 -388.662552)
			(xy 143.905986 -388.669022) (xy 143.898874 -388.6708) (xy 143.886936 -388.677404) (xy 143.159226 -389.405114)
			(xy 143.151828 -389.411958) (xy 143.133228 -389.419679) (xy 143.123158 -389.4201) (xy 142.926562 -389.4201)
			(xy 142.916495 -389.41967) (xy 142.897901 -389.411946) (xy 142.890494 -389.405114) (xy 142.88516 -389.39978)
			(xy 142.866618 -389.39216) (xy 140.968476 -389.39216) (xy 140.964158 -389.392922) (xy 140.947658 -389.395664)
			(xy 140.914335 -389.398593) (xy 140.89761 -389.398764) (xy 140.880885 -389.398586) (xy 140.847562 -389.395665)
			(xy 140.831062 -389.392922) (xy 140.826744 -389.39216) (xy 139.898882 -389.39216) (xy 139.888815 -389.392588)
			(xy 139.870221 -389.400314) (xy 139.862814 -389.407146) (xy 139.308586 -389.961374) (xy 139.301742 -389.968772)
			(xy 139.294021 -389.987372) (xy 139.2936 -389.997442) (xy 139.2936 -390.360662) (xy 139.293983 -390.369515)
			(xy 139.300001 -390.386167) (xy 139.311304 -390.399796) (xy 139.318746 -390.404604) (xy 139.344908 -390.419844)
			(xy 139.356116 -390.425661) (xy 139.381316 -390.426612) (xy 139.392914 -390.421622) (xy 139.40409 -390.416542)
			(xy 139.413445 -390.411538) (xy 139.427354 -390.39555) (xy 139.433663 -390.375319) (xy 139.433046 -390.364726)
			(xy 139.431591 -390.350611) (xy 139.430068 -390.322273) (xy 139.429998 -390.308084) (xy 139.4305 -390.276123)
			(xy 139.438511 -390.212705) (xy 139.454408 -390.150791) (xy 139.47794 -390.091358) (xy 139.508734 -390.035343)
			(xy 139.546307 -389.983628) (xy 139.590064 -389.937031) (xy 139.639317 -389.896286) (xy 139.693288 -389.862035)
			(xy 139.751127 -389.834818) (xy 139.81192 -389.815065) (xy 139.87471 -389.803087) (xy 139.938506 -389.799074)
			(xy 140.002302 -389.803087) (xy 140.065092 -389.815065) (xy 140.125885 -389.834818) (xy 140.183724 -389.862035)
			(xy 140.237695 -389.896286) (xy 140.286948 -389.937031) (xy 140.330705 -389.983628) (xy 140.368278 -390.035343)
			(xy 140.399072 -390.091358) (xy 140.422604 -390.150791) (xy 140.438501 -390.212705) (xy 140.446512 -390.276123)
			(xy 140.447014 -390.308084) (xy 140.44652 -390.340247) (xy 140.438405 -390.40406) (xy 140.422302 -390.466339)
			(xy 140.398468 -390.526088) (xy 140.367285 -390.582351) (xy 140.329252 -390.63423) (xy 140.284976 -390.680894)
			(xy 140.235165 -390.721599) (xy 140.180616 -390.755692) (xy 140.151612 -390.769602) (xy 140.142249 -390.774603)
			(xy 140.128322 -390.79059) (xy 140.121992 -390.810825) (xy 140.122656 -390.821418) (xy 140.124112 -390.835533)
			(xy 140.125639 -390.86387) (xy 140.125704 -390.87806) (xy 140.125161 -390.911867) (xy 140.116235 -390.97889)
			(xy 140.107924 -391.011664) (xy 140.105384 -391.021062) (xy 140.107416 -391.040112) (xy 140.149326 -391.118852)
			(xy 140.164058 -391.131298) (xy 140.173202 -391.134346) (xy 140.202983 -391.144991) (xy 140.259867 -391.172634)
			(xy 140.312887 -391.207113) (xy 140.361226 -391.247897) (xy 140.404139 -391.294356) (xy 140.440964 -391.345774)
			(xy 140.471133 -391.40136) (xy 140.494183 -391.460255) (xy 140.509756 -391.521553) (xy 140.517614 -391.584308)
			(xy 140.518134 -391.61593) (xy 140.517653 -391.646624) (xy 140.510229 -391.707563) (xy 140.495528 -391.767167)
			(xy 140.473764 -391.824569) (xy 140.445253 -391.878936) (xy 140.428218 -391.904474) (xy 140.42275 -391.913225)
			(xy 140.418631 -391.933425) (xy 140.42277 -391.953621) (xy 140.428218 -391.962386) (xy 140.445272 -391.987913)
			(xy 140.4738 -392.042276) (xy 140.495571 -392.09968) (xy 140.510266 -392.159288) (xy 140.517671 -392.220233)
			(xy 140.518134 -392.25093) (xy 140.517668 -392.28166) (xy 140.510257 -392.342673) (xy 140.495546 -392.402347)
			(xy 140.47375 -392.459813) (xy 140.445186 -392.514233) (xy 140.410271 -392.564814) (xy 140.369515 -392.610818)
			(xy 140.323511 -392.651574) (xy 140.27293 -392.686488) (xy 140.218509 -392.715051) (xy 140.161043 -392.736847)
			(xy 140.101369 -392.751558) (xy 140.040356 -392.758968) (xy 140.009626 -392.759438) (xy 139.988544 -392.75893)
			(xy 139.977622 -392.758422) (xy 139.958064 -392.766042) (xy 139.889738 -392.834368) (xy 139.882118 -392.853926)
			(xy 139.882626 -392.864848) (xy 139.883134 -392.88593) (xy 139.882653 -392.916624) (xy 139.875229 -392.977563)
			(xy 139.860528 -393.037167) (xy 139.838764 -393.094569) (xy 139.810253 -393.148936) (xy 139.793218 -393.174474)
			(xy 139.78775 -393.183225) (xy 139.783631 -393.203425) (xy 139.78777 -393.223621) (xy 139.793218 -393.232386)
			(xy 139.810272 -393.257913) (xy 139.8388 -393.312276) (xy 139.860571 -393.36968) (xy 139.875266 -393.429288)
			(xy 139.882671 -393.490233) (xy 139.883134 -393.52093) (xy 140.738098 -393.52093) (xy 140.738582 -393.49356)
			(xy 140.746396 -393.439382) (xy 140.761881 -393.386879) (xy 140.784718 -393.337132) (xy 140.814439 -393.291164)
			(xy 140.832078 -393.270232) (xy 140.838174 -393.26312) (xy 140.844524 -393.246102) (xy 140.844524 -393.160758)
			(xy 140.838174 -393.14374) (xy 140.832078 -393.136628) (xy 140.814469 -393.11567) (xy 140.784746 -393.069706)
			(xy 140.761902 -393.019963) (xy 140.746406 -392.967465) (xy 140.738576 -392.913291) (xy 140.738572 -392.858554)
			(xy 140.746396 -392.804379) (xy 140.761886 -392.751879) (xy 140.784725 -392.702134) (xy 140.814441 -392.656166)
			(xy 140.832078 -392.635232) (xy 140.838174 -392.62812) (xy 140.844524 -392.611102) (xy 140.844524 -392.525758)
			(xy 140.838174 -392.50874) (xy 140.832078 -392.501628) (xy 140.814469 -392.48067) (xy 140.784746 -392.434706)
			(xy 140.761902 -392.384963) (xy 140.746406 -392.332465) (xy 140.738576 -392.278291) (xy 140.738572 -392.223554)
			(xy 140.746396 -392.169379) (xy 140.761886 -392.116879) (xy 140.784725 -392.067134) (xy 140.814441 -392.021166)
			(xy 140.832078 -392.000232) (xy 140.838174 -391.99312) (xy 140.844524 -391.976102) (xy 140.844524 -391.890758)
			(xy 140.838174 -391.87374) (xy 140.832078 -391.866628) (xy 140.814435 -391.845699) (xy 140.784725 -391.799725)
			(xy 140.76189 -391.749977) (xy 140.7464 -391.697475) (xy 140.738572 -391.643299) (xy 140.738098 -391.61593)
			(xy 140.738601 -391.588394) (xy 140.746503 -391.533894) (xy 140.762163 -391.481096) (xy 140.785253 -391.4311)
			(xy 140.815294 -391.384945) (xy 140.851662 -391.34359) (xy 140.8936 -391.307897) (xy 140.91666 -391.292842)
			(xy 140.925296 -391.287508) (xy 140.936726 -391.271252) (xy 140.957808 -391.181844) (xy 140.954506 -391.162286)
			(xy 140.949172 -391.15365) (xy 140.935741 -391.130982) (xy 140.91457 -391.082732) (xy 140.900225 -391.032032)
			(xy 140.892977 -390.979843) (xy 140.89253 -390.953498) (xy 140.892988 -390.926127) (xy 140.900806 -390.871948)
			(xy 140.916297 -390.819444) (xy 140.939141 -390.769697) (xy 140.968868 -390.723731) (xy 140.98651 -390.7028)
			(xy 140.992606 -390.695688) (xy 140.998956 -390.67867) (xy 140.998956 -390.593326) (xy 140.992606 -390.576308)
			(xy 140.98651 -390.569196) (xy 140.968857 -390.548275) (xy 140.939147 -390.502299) (xy 140.916314 -390.452549)
			(xy 140.900826 -390.400046) (xy 140.893002 -390.345868) (xy 140.89253 -390.318498) (xy 140.893016 -390.291247)
			(xy 140.900772 -390.237299) (xy 140.916127 -390.185004) (xy 140.938769 -390.135427) (xy 140.968235 -390.089577)
			(xy 141.003926 -390.048386) (xy 141.045117 -390.012695) (xy 141.090967 -389.983229) (xy 141.140544 -389.960587)
			(xy 141.192839 -389.945232) (xy 141.246787 -389.937476) (xy 141.301289 -389.937476) (xy 141.355237 -389.945232)
			(xy 141.407532 -389.960587) (xy 141.457109 -389.983229) (xy 141.502959 -390.012695) (xy 141.54415 -390.048386)
			(xy 141.579841 -390.089577) (xy 141.609307 -390.135427) (xy 141.631949 -390.185004) (xy 141.647304 -390.237299)
			(xy 141.65506 -390.291247) (xy 141.655546 -390.318498) (xy 141.655092 -390.345869) (xy 141.647273 -390.400049)
			(xy 141.631782 -390.452553) (xy 141.608937 -390.502299) (xy 141.579209 -390.548265) (xy 141.561566 -390.569196)
			(xy 141.55547 -390.576308) (xy 141.54912 -390.593326) (xy 141.54912 -390.626092) (xy 144.390364 -390.626092)
			(xy 144.390783 -390.602859) (xy 144.397277 -390.556849) (xy 144.410148 -390.512202) (xy 144.429145 -390.469797)
			(xy 144.453892 -390.43047) (xy 144.468596 -390.412478) (xy 144.474692 -390.405366) (xy 144.480788 -390.388856)
			(xy 144.480788 -390.304528) (xy 144.474692 -390.288018) (xy 144.468596 -390.280906) (xy 144.453875 -390.262926)
			(xy 144.429131 -390.223594) (xy 144.410134 -390.181186) (xy 144.397258 -390.136538) (xy 144.390757 -390.090526)
			(xy 144.390364 -390.067292) (xy 144.390874 -390.041305) (xy 144.399004 -389.98997) (xy 144.415065 -389.94054)
			(xy 144.438661 -389.89423) (xy 144.469211 -389.852182) (xy 144.505962 -389.815431) (xy 144.54801 -389.784881)
			(xy 144.59432 -389.761285) (xy 144.64375 -389.745224) (xy 144.695085 -389.737094) (xy 144.747059 -389.737094)
			(xy 144.798394 -389.745224) (xy 144.847824 -389.761285) (xy 144.894134 -389.784881) (xy 144.936182 -389.815431)
			(xy 144.972933 -389.852182) (xy 145.003483 -389.89423) (xy 145.027079 -389.94054) (xy 145.04314 -389.98997)
			(xy 145.05127 -390.041305) (xy 145.05178 -390.067292) (xy 145.051423 -390.090527) (xy 145.044917 -390.13654)
			(xy 145.038146 -390.160002) (xy 146.712952 -390.160002) (xy 146.716912 -390.110948) (xy 146.728689 -390.063164)
			(xy 146.74798 -390.017888) (xy 146.774283 -389.976292) (xy 146.806918 -389.939455) (xy 146.845039 -389.90833)
			(xy 146.88766 -389.883723) (xy 146.933676 -389.866271) (xy 146.981895 -389.856427) (xy 147.03107 -389.854446)
			(xy 147.079925 -389.860378) (xy 147.127196 -389.87407) (xy 147.171658 -389.895168) (xy 147.212161 -389.923124)
			(xy 147.247654 -389.957216) (xy 147.277219 -389.99656) (xy 147.30009 -390.040137) (xy 147.315674 -390.086818)
			(xy 147.323569 -390.135395) (xy 147.324064 -390.160002) (xy 147.913102 -390.160002) (xy 147.917062 -390.110948)
			(xy 147.928839 -390.063164) (xy 147.94813 -390.017888) (xy 147.974433 -389.976292) (xy 148.007068 -389.939455)
			(xy 148.045189 -389.90833) (xy 148.08781 -389.883723) (xy 148.133826 -389.866271) (xy 148.182045 -389.856427)
			(xy 148.23122 -389.854446) (xy 148.280075 -389.860378) (xy 148.327346 -389.87407) (xy 148.371808 -389.895168)
			(xy 148.412311 -389.923124) (xy 148.447804 -389.957216) (xy 148.477369 -389.99656) (xy 148.50024 -390.040137)
			(xy 148.515824 -390.086818) (xy 148.523719 -390.135395) (xy 148.524214 -390.160002) (xy 149.113252 -390.160002)
			(xy 149.117212 -390.110948) (xy 149.128989 -390.063164) (xy 149.14828 -390.017888) (xy 149.174583 -389.976292)
			(xy 149.207218 -389.939455) (xy 149.245339 -389.90833) (xy 149.28796 -389.883723) (xy 149.333976 -389.866271)
			(xy 149.382195 -389.856427) (xy 149.43137 -389.854446) (xy 149.480225 -389.860378) (xy 149.527496 -389.87407)
			(xy 149.571958 -389.895168) (xy 149.612461 -389.923124) (xy 149.647954 -389.957216) (xy 149.677519 -389.99656)
			(xy 149.70039 -390.040137) (xy 149.715974 -390.086818) (xy 149.723869 -390.135395) (xy 149.724364 -390.160002)
			(xy 150.313148 -390.160002) (xy 150.317108 -390.110948) (xy 150.328885 -390.063164) (xy 150.348176 -390.017888)
			(xy 150.374479 -389.976292) (xy 150.407114 -389.939455) (xy 150.445235 -389.90833) (xy 150.487856 -389.883723)
			(xy 150.533872 -389.866271) (xy 150.582091 -389.856427) (xy 150.631266 -389.854446) (xy 150.680121 -389.860378)
			(xy 150.727392 -389.87407) (xy 150.771854 -389.895168) (xy 150.812357 -389.923124) (xy 150.84785 -389.957216)
			(xy 150.877415 -389.99656) (xy 150.900286 -390.040137) (xy 150.91587 -390.086818) (xy 150.923765 -390.135395)
			(xy 150.92426 -390.160002) (xy 151.513298 -390.160002) (xy 151.517258 -390.110948) (xy 151.529035 -390.063164)
			(xy 151.548326 -390.017888) (xy 151.574629 -389.976292) (xy 151.607264 -389.939455) (xy 151.645385 -389.90833)
			(xy 151.688006 -389.883723) (xy 151.734022 -389.866271) (xy 151.782241 -389.856427) (xy 151.831416 -389.854446)
			(xy 151.880271 -389.860378) (xy 151.927542 -389.87407) (xy 151.972004 -389.895168) (xy 152.012507 -389.923124)
			(xy 152.048 -389.957216) (xy 152.077565 -389.99656) (xy 152.100436 -390.040137) (xy 152.11602 -390.086818)
			(xy 152.123915 -390.135395) (xy 152.12441 -390.160002) (xy 152.713194 -390.160002) (xy 152.717154 -390.110948)
			(xy 152.728931 -390.063164) (xy 152.748222 -390.017888) (xy 152.774525 -389.976292) (xy 152.80716 -389.939455)
			(xy 152.845281 -389.90833) (xy 152.887902 -389.883723) (xy 152.933918 -389.866271) (xy 152.982137 -389.856427)
			(xy 153.031312 -389.854446) (xy 153.080167 -389.860378) (xy 153.127438 -389.87407) (xy 153.1719 -389.895168)
			(xy 153.212403 -389.923124) (xy 153.247896 -389.957216) (xy 153.277461 -389.99656) (xy 153.300332 -390.040137)
			(xy 153.315916 -390.086818) (xy 153.323811 -390.135395) (xy 153.324306 -390.160002) (xy 153.91309 -390.160002)
			(xy 153.91705 -390.110948) (xy 153.928827 -390.063164) (xy 153.948118 -390.017888) (xy 153.974421 -389.976292)
			(xy 154.007056 -389.939455) (xy 154.045177 -389.90833) (xy 154.087798 -389.883723) (xy 154.133814 -389.866271)
			(xy 154.182033 -389.856427) (xy 154.231208 -389.854446) (xy 154.280063 -389.860378) (xy 154.327334 -389.87407)
			(xy 154.371796 -389.895168) (xy 154.412299 -389.923124) (xy 154.447792 -389.957216) (xy 154.477357 -389.99656)
			(xy 154.500228 -390.040137) (xy 154.515812 -390.086818) (xy 154.523707 -390.135395) (xy 154.524202 -390.160002)
			(xy 155.11324 -390.160002) (xy 155.1172 -390.110948) (xy 155.128977 -390.063164) (xy 155.148268 -390.017888)
			(xy 155.174571 -389.976292) (xy 155.207206 -389.939455) (xy 155.245327 -389.90833) (xy 155.287948 -389.883723)
			(xy 155.333964 -389.866271) (xy 155.382183 -389.856427) (xy 155.431358 -389.854446) (xy 155.480213 -389.860378)
			(xy 155.527484 -389.87407) (xy 155.571946 -389.895168) (xy 155.612449 -389.923124) (xy 155.647942 -389.957216)
			(xy 155.677507 -389.99656) (xy 155.700378 -390.040137) (xy 155.715962 -390.086818) (xy 155.723857 -390.135395)
			(xy 155.724352 -390.160002) (xy 156.313136 -390.160002) (xy 156.317096 -390.110948) (xy 156.328873 -390.063164)
			(xy 156.348164 -390.017888) (xy 156.374467 -389.976292) (xy 156.407102 -389.939455) (xy 156.445223 -389.90833)
			(xy 156.487844 -389.883723) (xy 156.53386 -389.866271) (xy 156.582079 -389.856427) (xy 156.631254 -389.854446)
			(xy 156.680109 -389.860378) (xy 156.72738 -389.87407) (xy 156.771842 -389.895168) (xy 156.812345 -389.923124)
			(xy 156.847838 -389.957216) (xy 156.877403 -389.99656) (xy 156.900274 -390.040137) (xy 156.915858 -390.086818)
			(xy 156.923753 -390.135395) (xy 156.924248 -390.160002) (xy 157.513286 -390.160002) (xy 157.517246 -390.110948)
			(xy 157.529023 -390.063164) (xy 157.548314 -390.017888) (xy 157.574617 -389.976292) (xy 157.607252 -389.939455)
			(xy 157.645373 -389.90833) (xy 157.687994 -389.883723) (xy 157.73401 -389.866271) (xy 157.782229 -389.856427)
			(xy 157.831404 -389.854446) (xy 157.880259 -389.860378) (xy 157.92753 -389.87407) (xy 157.971992 -389.895168)
			(xy 158.012495 -389.923124) (xy 158.047988 -389.957216) (xy 158.077553 -389.99656) (xy 158.100424 -390.040137)
			(xy 158.116008 -390.086818) (xy 158.123903 -390.135395) (xy 158.124398 -390.160002) (xy 158.713182 -390.160002)
			(xy 158.717142 -390.110948) (xy 158.728919 -390.063164) (xy 158.74821 -390.017888) (xy 158.774513 -389.976292)
			(xy 158.807148 -389.939455) (xy 158.845269 -389.90833) (xy 158.88789 -389.883723) (xy 158.933906 -389.866271)
			(xy 158.982125 -389.856427) (xy 159.0313 -389.854446) (xy 159.080155 -389.860378) (xy 159.127426 -389.87407)
			(xy 159.171888 -389.895168) (xy 159.212391 -389.923124) (xy 159.247884 -389.957216) (xy 159.277449 -389.99656)
			(xy 159.30032 -390.040137) (xy 159.315904 -390.086818) (xy 159.323799 -390.135395) (xy 159.324294 -390.160002)
			(xy 159.913078 -390.160002) (xy 159.917038 -390.110948) (xy 159.928815 -390.063164) (xy 159.948106 -390.017888)
			(xy 159.974409 -389.976292) (xy 160.007044 -389.939455) (xy 160.045165 -389.90833) (xy 160.087786 -389.883723)
			(xy 160.133802 -389.866271) (xy 160.182021 -389.856427) (xy 160.231196 -389.854446) (xy 160.280051 -389.860378)
			(xy 160.327322 -389.87407) (xy 160.371784 -389.895168) (xy 160.412287 -389.923124) (xy 160.44778 -389.957216)
			(xy 160.477345 -389.99656) (xy 160.500216 -390.040137) (xy 160.5158 -390.086818) (xy 160.523695 -390.135395)
			(xy 160.52419 -390.160002) (xy 161.113228 -390.160002) (xy 161.117188 -390.110948) (xy 161.128965 -390.063164)
			(xy 161.148256 -390.017888) (xy 161.174559 -389.976292) (xy 161.207194 -389.939455) (xy 161.245315 -389.90833)
			(xy 161.287936 -389.883723) (xy 161.333952 -389.866271) (xy 161.382171 -389.856427) (xy 161.431346 -389.854446)
			(xy 161.480201 -389.860378) (xy 161.527472 -389.87407) (xy 161.571934 -389.895168) (xy 161.612437 -389.923124)
			(xy 161.64793 -389.957216) (xy 161.677495 -389.99656) (xy 161.700366 -390.040137) (xy 161.71595 -390.086818)
			(xy 161.723845 -390.135395) (xy 161.72434 -390.160002) (xy 162.313124 -390.160002) (xy 162.317084 -390.110948)
			(xy 162.328861 -390.063164) (xy 162.348152 -390.017888) (xy 162.374455 -389.976292) (xy 162.40709 -389.939455)
			(xy 162.445211 -389.90833) (xy 162.487832 -389.883723) (xy 162.533848 -389.866271) (xy 162.582067 -389.856427)
			(xy 162.631242 -389.854446) (xy 162.680097 -389.860378) (xy 162.727368 -389.87407) (xy 162.77183 -389.895168)
			(xy 162.812333 -389.923124) (xy 162.847826 -389.957216) (xy 162.877391 -389.99656) (xy 162.900262 -390.040137)
			(xy 162.915846 -390.086818) (xy 162.923741 -390.135395) (xy 162.924236 -390.160002) (xy 163.513274 -390.160002)
			(xy 163.517234 -390.110948) (xy 163.529011 -390.063164) (xy 163.548302 -390.017888) (xy 163.574605 -389.976292)
			(xy 163.60724 -389.939455) (xy 163.645361 -389.90833) (xy 163.687982 -389.883723) (xy 163.733998 -389.866271)
			(xy 163.782217 -389.856427) (xy 163.831392 -389.854446) (xy 163.880247 -389.860378) (xy 163.927518 -389.87407)
			(xy 163.97198 -389.895168) (xy 164.012483 -389.923124) (xy 164.047976 -389.957216) (xy 164.077541 -389.99656)
			(xy 164.100412 -390.040137) (xy 164.115996 -390.086818) (xy 164.123891 -390.135395) (xy 164.124386 -390.160002)
			(xy 164.71317 -390.160002) (xy 164.71713 -390.110948) (xy 164.728907 -390.063164) (xy 164.748198 -390.017888)
			(xy 164.774501 -389.976292) (xy 164.807136 -389.939455) (xy 164.845257 -389.90833) (xy 164.887878 -389.883723)
			(xy 164.933894 -389.866271) (xy 164.982113 -389.856427) (xy 165.031288 -389.854446) (xy 165.080143 -389.860378)
			(xy 165.127414 -389.87407) (xy 165.171876 -389.895168) (xy 165.212379 -389.923124) (xy 165.247872 -389.957216)
			(xy 165.277437 -389.99656) (xy 165.300308 -390.040137) (xy 165.315892 -390.086818) (xy 165.323787 -390.135395)
			(xy 165.324282 -390.160002) (xy 165.323787 -390.184609) (xy 165.315892 -390.233186) (xy 165.300308 -390.279867)
			(xy 165.277437 -390.323444) (xy 165.247872 -390.362788) (xy 165.212379 -390.39688) (xy 165.171876 -390.424836)
			(xy 165.127414 -390.445934) (xy 165.080143 -390.459626) (xy 165.031288 -390.465558) (xy 164.982113 -390.463577)
			(xy 164.933894 -390.453733) (xy 164.887878 -390.436281) (xy 164.845257 -390.411674) (xy 164.807136 -390.380549)
			(xy 164.774501 -390.343712) (xy 164.748198 -390.302116) (xy 164.728907 -390.25684) (xy 164.71713 -390.209056)
			(xy 164.71317 -390.160002) (xy 164.124386 -390.160002) (xy 164.123891 -390.184609) (xy 164.115996 -390.233186)
			(xy 164.100412 -390.279867) (xy 164.077541 -390.323444) (xy 164.047976 -390.362788) (xy 164.012483 -390.39688)
			(xy 163.97198 -390.424836) (xy 163.927518 -390.445934) (xy 163.880247 -390.459626) (xy 163.831392 -390.465558)
			(xy 163.782217 -390.463577) (xy 163.733998 -390.453733) (xy 163.687982 -390.436281) (xy 163.645361 -390.411674)
			(xy 163.60724 -390.380549) (xy 163.574605 -390.343712) (xy 163.548302 -390.302116) (xy 163.529011 -390.25684)
			(xy 163.517234 -390.209056) (xy 163.513274 -390.160002) (xy 162.924236 -390.160002) (xy 162.923741 -390.184609)
			(xy 162.915846 -390.233186) (xy 162.900262 -390.279867) (xy 162.877391 -390.323444) (xy 162.847826 -390.362788)
			(xy 162.812333 -390.39688) (xy 162.77183 -390.424836) (xy 162.727368 -390.445934) (xy 162.680097 -390.459626)
			(xy 162.631242 -390.465558) (xy 162.582067 -390.463577) (xy 162.533848 -390.453733) (xy 162.487832 -390.436281)
			(xy 162.445211 -390.411674) (xy 162.40709 -390.380549) (xy 162.374455 -390.343712) (xy 162.348152 -390.302116)
			(xy 162.328861 -390.25684) (xy 162.317084 -390.209056) (xy 162.313124 -390.160002) (xy 161.72434 -390.160002)
			(xy 161.723845 -390.184609) (xy 161.71595 -390.233186) (xy 161.700366 -390.279867) (xy 161.677495 -390.323444)
			(xy 161.64793 -390.362788) (xy 161.612437 -390.39688) (xy 161.571934 -390.424836) (xy 161.527472 -390.445934)
			(xy 161.480201 -390.459626) (xy 161.431346 -390.465558) (xy 161.382171 -390.463577) (xy 161.333952 -390.453733)
			(xy 161.287936 -390.436281) (xy 161.245315 -390.411674) (xy 161.207194 -390.380549) (xy 161.174559 -390.343712)
			(xy 161.148256 -390.302116) (xy 161.128965 -390.25684) (xy 161.117188 -390.209056) (xy 161.113228 -390.160002)
			(xy 160.52419 -390.160002) (xy 160.523695 -390.184609) (xy 160.5158 -390.233186) (xy 160.500216 -390.279867)
			(xy 160.477345 -390.323444) (xy 160.44778 -390.362788) (xy 160.412287 -390.39688) (xy 160.371784 -390.424836)
			(xy 160.327322 -390.445934) (xy 160.280051 -390.459626) (xy 160.231196 -390.465558) (xy 160.182021 -390.463577)
			(xy 160.133802 -390.453733) (xy 160.087786 -390.436281) (xy 160.045165 -390.411674) (xy 160.007044 -390.380549)
			(xy 159.974409 -390.343712) (xy 159.948106 -390.302116) (xy 159.928815 -390.25684) (xy 159.917038 -390.209056)
			(xy 159.913078 -390.160002) (xy 159.324294 -390.160002) (xy 159.323799 -390.184609) (xy 159.315904 -390.233186)
			(xy 159.30032 -390.279867) (xy 159.277449 -390.323444) (xy 159.247884 -390.362788) (xy 159.212391 -390.39688)
			(xy 159.171888 -390.424836) (xy 159.127426 -390.445934) (xy 159.080155 -390.459626) (xy 159.0313 -390.465558)
			(xy 158.982125 -390.463577) (xy 158.933906 -390.453733) (xy 158.88789 -390.436281) (xy 158.845269 -390.411674)
			(xy 158.807148 -390.380549) (xy 158.774513 -390.343712) (xy 158.74821 -390.302116) (xy 158.728919 -390.25684)
			(xy 158.717142 -390.209056) (xy 158.713182 -390.160002) (xy 158.124398 -390.160002) (xy 158.123903 -390.184609)
			(xy 158.116008 -390.233186) (xy 158.100424 -390.279867) (xy 158.077553 -390.323444) (xy 158.047988 -390.362788)
			(xy 158.012495 -390.39688) (xy 157.971992 -390.424836) (xy 157.92753 -390.445934) (xy 157.880259 -390.459626)
			(xy 157.831404 -390.465558) (xy 157.782229 -390.463577) (xy 157.73401 -390.453733) (xy 157.687994 -390.436281)
			(xy 157.645373 -390.411674) (xy 157.607252 -390.380549) (xy 157.574617 -390.343712) (xy 157.548314 -390.302116)
			(xy 157.529023 -390.25684) (xy 157.517246 -390.209056) (xy 157.513286 -390.160002) (xy 156.924248 -390.160002)
			(xy 156.923753 -390.184609) (xy 156.915858 -390.233186) (xy 156.900274 -390.279867) (xy 156.877403 -390.323444)
			(xy 156.847838 -390.362788) (xy 156.812345 -390.39688) (xy 156.771842 -390.424836) (xy 156.72738 -390.445934)
			(xy 156.680109 -390.459626) (xy 156.631254 -390.465558) (xy 156.582079 -390.463577) (xy 156.53386 -390.453733)
			(xy 156.487844 -390.436281) (xy 156.445223 -390.411674) (xy 156.407102 -390.380549) (xy 156.374467 -390.343712)
			(xy 156.348164 -390.302116) (xy 156.328873 -390.25684) (xy 156.317096 -390.209056) (xy 156.313136 -390.160002)
			(xy 155.724352 -390.160002) (xy 155.723857 -390.184609) (xy 155.715962 -390.233186) (xy 155.700378 -390.279867)
			(xy 155.677507 -390.323444) (xy 155.647942 -390.362788) (xy 155.612449 -390.39688) (xy 155.571946 -390.424836)
			(xy 155.527484 -390.445934) (xy 155.480213 -390.459626) (xy 155.431358 -390.465558) (xy 155.382183 -390.463577)
			(xy 155.333964 -390.453733) (xy 155.287948 -390.436281) (xy 155.245327 -390.411674) (xy 155.207206 -390.380549)
			(xy 155.174571 -390.343712) (xy 155.148268 -390.302116) (xy 155.128977 -390.25684) (xy 155.1172 -390.209056)
			(xy 155.11324 -390.160002) (xy 154.524202 -390.160002) (xy 154.523707 -390.184609) (xy 154.515812 -390.233186)
			(xy 154.500228 -390.279867) (xy 154.477357 -390.323444) (xy 154.447792 -390.362788) (xy 154.412299 -390.39688)
			(xy 154.371796 -390.424836) (xy 154.327334 -390.445934) (xy 154.280063 -390.459626) (xy 154.231208 -390.465558)
			(xy 154.182033 -390.463577) (xy 154.133814 -390.453733) (xy 154.087798 -390.436281) (xy 154.045177 -390.411674)
			(xy 154.007056 -390.380549) (xy 153.974421 -390.343712) (xy 153.948118 -390.302116) (xy 153.928827 -390.25684)
			(xy 153.91705 -390.209056) (xy 153.91309 -390.160002) (xy 153.324306 -390.160002) (xy 153.323811 -390.184609)
			(xy 153.315916 -390.233186) (xy 153.300332 -390.279867) (xy 153.277461 -390.323444) (xy 153.247896 -390.362788)
			(xy 153.212403 -390.39688) (xy 153.1719 -390.424836) (xy 153.127438 -390.445934) (xy 153.080167 -390.459626)
			(xy 153.031312 -390.465558) (xy 152.982137 -390.463577) (xy 152.933918 -390.453733) (xy 152.887902 -390.436281)
			(xy 152.845281 -390.411674) (xy 152.80716 -390.380549) (xy 152.774525 -390.343712) (xy 152.748222 -390.302116)
			(xy 152.728931 -390.25684) (xy 152.717154 -390.209056) (xy 152.713194 -390.160002) (xy 152.12441 -390.160002)
			(xy 152.123915 -390.184609) (xy 152.11602 -390.233186) (xy 152.100436 -390.279867) (xy 152.077565 -390.323444)
			(xy 152.048 -390.362788) (xy 152.012507 -390.39688) (xy 151.972004 -390.424836) (xy 151.927542 -390.445934)
			(xy 151.880271 -390.459626) (xy 151.831416 -390.465558) (xy 151.782241 -390.463577) (xy 151.734022 -390.453733)
			(xy 151.688006 -390.436281) (xy 151.645385 -390.411674) (xy 151.607264 -390.380549) (xy 151.574629 -390.343712)
			(xy 151.548326 -390.302116) (xy 151.529035 -390.25684) (xy 151.517258 -390.209056) (xy 151.513298 -390.160002)
			(xy 150.92426 -390.160002) (xy 150.923765 -390.184609) (xy 150.91587 -390.233186) (xy 150.900286 -390.279867)
			(xy 150.877415 -390.323444) (xy 150.84785 -390.362788) (xy 150.812357 -390.39688) (xy 150.771854 -390.424836)
			(xy 150.727392 -390.445934) (xy 150.680121 -390.459626) (xy 150.631266 -390.465558) (xy 150.582091 -390.463577)
			(xy 150.533872 -390.453733) (xy 150.487856 -390.436281) (xy 150.445235 -390.411674) (xy 150.407114 -390.380549)
			(xy 150.374479 -390.343712) (xy 150.348176 -390.302116) (xy 150.328885 -390.25684) (xy 150.317108 -390.209056)
			(xy 150.313148 -390.160002) (xy 149.724364 -390.160002) (xy 149.723869 -390.184609) (xy 149.715974 -390.233186)
			(xy 149.70039 -390.279867) (xy 149.677519 -390.323444) (xy 149.647954 -390.362788) (xy 149.612461 -390.39688)
			(xy 149.571958 -390.424836) (xy 149.527496 -390.445934) (xy 149.480225 -390.459626) (xy 149.43137 -390.465558)
			(xy 149.382195 -390.463577) (xy 149.333976 -390.453733) (xy 149.28796 -390.436281) (xy 149.245339 -390.411674)
			(xy 149.207218 -390.380549) (xy 149.174583 -390.343712) (xy 149.14828 -390.302116) (xy 149.128989 -390.25684)
			(xy 149.117212 -390.209056) (xy 149.113252 -390.160002) (xy 148.524214 -390.160002) (xy 148.523719 -390.184609)
			(xy 148.515824 -390.233186) (xy 148.50024 -390.279867) (xy 148.477369 -390.323444) (xy 148.447804 -390.362788)
			(xy 148.412311 -390.39688) (xy 148.371808 -390.424836) (xy 148.327346 -390.445934) (xy 148.280075 -390.459626)
			(xy 148.23122 -390.465558) (xy 148.182045 -390.463577) (xy 148.133826 -390.453733) (xy 148.08781 -390.436281)
			(xy 148.045189 -390.411674) (xy 148.007068 -390.380549) (xy 147.974433 -390.343712) (xy 147.94813 -390.302116)
			(xy 147.928839 -390.25684) (xy 147.917062 -390.209056) (xy 147.913102 -390.160002) (xy 147.324064 -390.160002)
			(xy 147.323569 -390.184609) (xy 147.315674 -390.233186) (xy 147.30009 -390.279867) (xy 147.277219 -390.323444)
			(xy 147.247654 -390.362788) (xy 147.212161 -390.39688) (xy 147.171658 -390.424836) (xy 147.127196 -390.445934)
			(xy 147.079925 -390.459626) (xy 147.03107 -390.465558) (xy 146.981895 -390.463577) (xy 146.933676 -390.453733)
			(xy 146.88766 -390.436281) (xy 146.845039 -390.411674) (xy 146.806918 -390.380549) (xy 146.774283 -390.343712)
			(xy 146.74798 -390.302116) (xy 146.728689 -390.25684) (xy 146.716912 -390.209056) (xy 146.712952 -390.160002)
			(xy 145.038146 -390.160002) (xy 145.032031 -390.181188) (xy 145.013021 -390.223593) (xy 144.988259 -390.262917)
			(xy 144.973548 -390.280906) (xy 144.967452 -390.288018) (xy 144.961356 -390.304528) (xy 144.961356 -390.388856)
			(xy 144.967452 -390.405366) (xy 144.973548 -390.412478) (xy 144.988253 -390.43047) (xy 145.013001 -390.469798)
			(xy 145.032002 -390.512203) (xy 145.044882 -390.556849) (xy 145.051386 -390.602859) (xy 145.05178 -390.626092)
			(xy 145.051368 -390.650185) (xy 145.044389 -390.697862) (xy 145.030577 -390.744025) (xy 145.020792 -390.766046)
			(xy 145.015458 -390.777476) (xy 145.016728 -390.802622) (xy 145.072862 -390.896602) (xy 145.094452 -390.909556)
			(xy 145.107152 -390.910318) (xy 145.132148 -390.912171) (xy 145.181192 -390.922501) (xy 145.228116 -390.940114)
			(xy 145.271845 -390.964605) (xy 145.311377 -390.995415) (xy 145.345808 -391.031837) (xy 145.374349 -391.073037)
			(xy 145.396346 -391.118072) (xy 145.411296 -391.165911) (xy 145.418856 -391.215458) (xy 145.419318 -391.240518)
			(xy 145.418808 -391.266505) (xy 145.410678 -391.31784) (xy 145.394617 -391.36727) (xy 145.371021 -391.41358)
			(xy 145.340471 -391.455628) (xy 145.30372 -391.492379) (xy 145.261672 -391.522929) (xy 145.215362 -391.546525)
			(xy 145.165932 -391.562586) (xy 145.114597 -391.570716) (xy 145.062623 -391.570716) (xy 145.011288 -391.562586)
			(xy 144.961858 -391.546525) (xy 144.915548 -391.522929) (xy 144.8735 -391.492379) (xy 144.836749 -391.455628)
			(xy 144.806199 -391.41358) (xy 144.782603 -391.36727) (xy 144.766542 -391.31784) (xy 144.758412 -391.266505)
			(xy 144.757902 -391.240518) (xy 144.758319 -391.216425) (xy 144.765296 -391.168748) (xy 144.779107 -391.122585)
			(xy 144.78889 -391.100564) (xy 144.794224 -391.089134) (xy 144.792954 -391.063988) (xy 144.73682 -390.970008)
			(xy 144.71523 -390.957054) (xy 144.70253 -390.956292) (xy 144.677534 -390.954445) (xy 144.62849 -390.944112)
			(xy 144.581567 -390.926498) (xy 144.537839 -390.902005) (xy 144.498307 -390.871195) (xy 144.463876 -390.834773)
			(xy 144.435336 -390.793573) (xy 144.413338 -390.748537) (xy 144.398388 -390.700699) (xy 144.390826 -390.651152)
			(xy 144.390364 -390.626092) (xy 141.54912 -390.626092) (xy 141.54912 -390.67867) (xy 141.55547 -390.695688)
			(xy 141.561566 -390.7028) (xy 141.579213 -390.723726) (xy 141.608925 -390.7697) (xy 141.63176 -390.819449)
			(xy 141.647249 -390.871951) (xy 141.655074 -390.926128) (xy 141.655546 -390.953498) (xy 141.655167 -390.977849)
			(xy 141.648946 -391.026152) (xy 141.636619 -391.073267) (xy 141.62786 -391.095992) (xy 141.623034 -391.108438)
			(xy 141.626082 -391.133838) (xy 141.692376 -391.225278) (xy 141.715744 -391.2362) (xy 141.728952 -391.235184)
			(xy 141.754606 -391.234422) (xy 141.781977 -391.234879) (xy 141.836156 -391.242698) (xy 141.88866 -391.258189)
			(xy 141.938406 -391.281033) (xy 141.984373 -391.31076) (xy 142.005304 -391.328402) (xy 142.012416 -391.334498)
			(xy 142.029434 -391.340848) (xy 142.114778 -391.340848) (xy 142.131796 -391.334498) (xy 142.138908 -391.328402)
			(xy 142.159841 -391.310761) (xy 142.205809 -391.281037) (xy 142.255555 -391.258191) (xy 142.308057 -391.242695)
			(xy 142.362235 -391.234866) (xy 142.416977 -391.234866) (xy 142.471155 -391.242695) (xy 142.523657 -391.258191)
			(xy 142.573403 -391.281037) (xy 142.619371 -391.310761) (xy 142.640304 -391.328402) (xy 142.647416 -391.334498)
			(xy 142.664434 -391.340848) (xy 142.749778 -391.340848) (xy 142.766796 -391.334498) (xy 142.773908 -391.328402)
			(xy 142.794826 -391.310746) (xy 142.840803 -391.281037) (xy 142.890554 -391.258204) (xy 142.943058 -391.242717)
			(xy 142.997236 -391.234893) (xy 143.024606 -391.234422) (xy 143.05186 -391.23485) (xy 143.105814 -391.242608)
			(xy 143.158114 -391.257967) (xy 143.207697 -391.280612) (xy 143.253551 -391.310084) (xy 143.294745 -391.345781)
			(xy 143.330438 -391.386978) (xy 143.359905 -391.432835) (xy 143.382546 -391.482419) (xy 143.397899 -391.534721)
			(xy 143.405653 -391.588676) (xy 143.406114 -391.61593) (xy 143.405662 -391.643301) (xy 143.39784 -391.69748)
			(xy 143.382348 -391.749983) (xy 143.359503 -391.79973) (xy 143.329776 -391.845696) (xy 143.312134 -391.866628)
			(xy 143.306038 -391.87374) (xy 143.299688 -391.890758) (xy 143.299688 -391.976102) (xy 143.306038 -391.99312)
			(xy 143.312134 -392.000232) (xy 143.329806 -392.02114) (xy 143.359532 -392.067111) (xy 143.382378 -392.116861)
			(xy 143.397874 -392.169367) (xy 143.405701 -392.22355) (xy 143.405699 -392.251946) (xy 143.690848 -392.251946)
			(xy 143.691334 -392.224695) (xy 143.69909 -392.170747) (xy 143.714445 -392.118452) (xy 143.737087 -392.068875)
			(xy 143.766553 -392.023025) (xy 143.802244 -391.981834) (xy 143.843435 -391.946143) (xy 143.889285 -391.916677)
			(xy 143.938862 -391.894035) (xy 143.991157 -391.87868) (xy 144.045105 -391.870924) (xy 144.099607 -391.870924)
			(xy 144.153555 -391.87868) (xy 144.20585 -391.894035) (xy 144.255427 -391.916677) (xy 144.301277 -391.946143)
			(xy 144.342468 -391.981834) (xy 144.378159 -392.023025) (xy 144.407625 -392.068875) (xy 144.430267 -392.118452)
			(xy 144.445622 -392.170747) (xy 144.453378 -392.224695) (xy 144.453864 -392.251946) (xy 144.452594 -392.284204)
			(xy 144.451578 -392.293856) (xy 144.456912 -392.31189) (xy 144.474516 -392.33475) (xy 145.791936 -392.33475)
			(xy 145.792337 -392.311516) (xy 145.798836 -392.265506) (xy 145.811712 -392.220859) (xy 145.830712 -392.178454)
			(xy 145.855462 -392.139128) (xy 145.870168 -392.121136) (xy 145.876264 -392.114024) (xy 145.88236 -392.097514)
			(xy 145.88236 -392.013186) (xy 145.876264 -391.996676) (xy 145.870168 -391.989564) (xy 145.855485 -391.971555)
			(xy 145.830733 -391.932232) (xy 145.811727 -391.889832) (xy 145.798843 -391.845189) (xy 145.792333 -391.799182)
			(xy 145.791936 -391.77595) (xy 145.792446 -391.749963) (xy 145.800576 -391.698628) (xy 145.816637 -391.649198)
			(xy 145.840233 -391.602888) (xy 145.870783 -391.56084) (xy 145.907534 -391.524089) (xy 145.949582 -391.493539)
			(xy 145.995892 -391.469943) (xy 146.045322 -391.453882) (xy 146.096657 -391.445752) (xy 146.148631 -391.445752)
			(xy 146.199966 -391.453882) (xy 146.249396 -391.469943) (xy 146.295706 -391.493539) (xy 146.337754 -391.524089)
			(xy 146.374505 -391.56084) (xy 146.405055 -391.602888) (xy 146.428651 -391.649198) (xy 146.444712 -391.698628)
			(xy 146.452842 -391.749963) (xy 146.453352 -391.77595) (xy 146.452954 -391.799184) (xy 146.446455 -391.845194)
			(xy 146.433578 -391.889841) (xy 146.414577 -391.932246) (xy 146.389826 -391.971573) (xy 146.37512 -391.989564)
			(xy 146.369024 -391.996676) (xy 146.362928 -392.013186) (xy 146.362928 -392.097514) (xy 146.369024 -392.114024)
			(xy 146.37512 -392.121136) (xy 146.389816 -392.139135) (xy 146.414564 -392.178462) (xy 146.433565 -392.220865)
			(xy 146.446447 -392.265509) (xy 146.452955 -392.311517) (xy 146.453352 -392.33475) (xy 146.452842 -392.360737)
			(xy 146.444712 -392.412072) (xy 146.428651 -392.461502) (xy 146.405055 -392.507812) (xy 146.374505 -392.54986)
			(xy 146.337754 -392.586611) (xy 146.295706 -392.617161) (xy 146.249396 -392.640757) (xy 146.199966 -392.656818)
			(xy 146.148631 -392.664948) (xy 146.096657 -392.664948) (xy 146.045322 -392.656818) (xy 145.995892 -392.640757)
			(xy 145.949582 -392.617161) (xy 145.907534 -392.586611) (xy 145.870783 -392.54986) (xy 145.840233 -392.507812)
			(xy 145.816637 -392.461502) (xy 145.800576 -392.412072) (xy 145.792446 -392.360737) (xy 145.791936 -392.33475)
			(xy 144.474516 -392.33475) (xy 144.510506 -392.381486) (xy 144.526762 -392.391138) (xy 144.53616 -392.392916)
			(xy 144.562314 -392.398009) (xy 144.612988 -392.414476) (xy 144.660877 -392.437834) (xy 144.705049 -392.46763)
			(xy 144.744645 -392.503283) (xy 144.778894 -392.544099) (xy 144.80713 -392.589285) (xy 144.828803 -392.63796)
			(xy 144.843491 -392.689178) (xy 144.850908 -392.741941) (xy 144.851374 -392.768582) (xy 144.850888 -392.795833)
			(xy 144.843132 -392.849781) (xy 144.827777 -392.902076) (xy 144.805135 -392.951653) (xy 144.775669 -392.997503)
			(xy 144.739978 -393.038694) (xy 144.698787 -393.074385) (xy 144.652937 -393.103851) (xy 144.60336 -393.126493)
			(xy 144.551065 -393.141848) (xy 144.497117 -393.149604) (xy 144.442615 -393.149604) (xy 144.388667 -393.141848)
			(xy 144.336372 -393.126493) (xy 144.286795 -393.103851) (xy 144.240945 -393.074385) (xy 144.199754 -393.038694)
			(xy 144.164063 -392.997503) (xy 144.134597 -392.951653) (xy 144.111955 -392.902076) (xy 144.0966 -392.849781)
			(xy 144.088844 -392.795833) (xy 144.088358 -392.768582) (xy 144.089628 -392.736324) (xy 144.090644 -392.726672)
			(xy 144.08531 -392.708638) (xy 144.031716 -392.639042) (xy 144.01546 -392.62939) (xy 144.006062 -392.627612)
			(xy 143.979891 -392.622591) (xy 143.92921 -392.606122) (xy 143.881314 -392.582759) (xy 143.837136 -392.552957)
			(xy 143.797536 -392.517297) (xy 143.763285 -392.476471) (xy 143.73505 -392.431276) (xy 143.71338 -392.382591)
			(xy 143.698697 -392.331364) (xy 143.691288 -392.278591) (xy 143.690848 -392.251946) (xy 143.405699 -392.251946)
			(xy 143.405697 -392.278295) (xy 143.397864 -392.332477) (xy 143.382362 -392.384981) (xy 143.35951 -392.434728)
			(xy 143.329778 -392.480696) (xy 143.312134 -392.501628) (xy 143.306038 -392.50874) (xy 143.299688 -392.525758)
			(xy 143.299688 -392.611102) (xy 143.306038 -392.62812) (xy 143.312134 -392.635232) (xy 143.329806 -392.65614)
			(xy 143.359532 -392.702111) (xy 143.382378 -392.751861) (xy 143.397874 -392.804367) (xy 143.405701 -392.85855)
			(xy 143.405697 -392.913295) (xy 143.397864 -392.967477) (xy 143.382362 -393.019981) (xy 143.35951 -393.069728)
			(xy 143.329778 -393.115696) (xy 143.312134 -393.136628) (xy 143.306038 -393.14374) (xy 143.299688 -393.160758)
			(xy 143.299688 -393.246102) (xy 143.306038 -393.26312) (xy 143.312134 -393.270232) (xy 143.32976 -393.291175)
			(xy 143.330835 -393.292838) (xy 147.062444 -393.292838) (xy 147.062444 -392.429238) (xy 147.062923 -392.402882)
			(xy 147.070186 -392.350674) (xy 147.084565 -392.299961) (xy 147.105786 -392.25171) (xy 147.133447 -392.206839)
			(xy 147.167019 -392.166202) (xy 147.186142 -392.14806) (xy 147.193254 -392.14171) (xy 147.201382 -392.124946)
			(xy 147.209764 -392.038332) (xy 147.204684 -392.020552) (xy 147.199096 -392.012678) (xy 147.184951 -391.992827)
			(xy 147.162491 -391.949571) (xy 147.147177 -391.903299) (xy 147.139397 -391.855184) (xy 147.138898 -391.830814)
			(xy 147.13942 -391.805559) (xy 147.147733 -391.755737) (xy 147.164134 -391.707963) (xy 147.188175 -391.66354)
			(xy 147.219199 -391.62368) (xy 147.256361 -391.58947) (xy 147.298647 -391.561844) (xy 147.344903 -391.541554)
			(xy 147.393868 -391.529154) (xy 147.444206 -391.524983) (xy 147.494544 -391.529154) (xy 147.543509 -391.541554)
			(xy 147.589765 -391.561844) (xy 147.632051 -391.58947) (xy 147.669213 -391.62368) (xy 147.700237 -391.66354)
			(xy 147.724278 -391.707963) (xy 147.740679 -391.755737) (xy 147.748992 -391.805559) (xy 147.749514 -391.830814)
			(xy 147.749043 -391.855187) (xy 147.741283 -391.90331) (xy 147.725963 -391.949586) (xy 147.703475 -391.992834)
			(xy 147.689316 -392.012678) (xy 147.683728 -392.020552) (xy 147.678648 -392.038332) (xy 147.68703 -392.124946)
			(xy 147.695158 -392.14171) (xy 147.70227 -392.14806) (xy 147.721408 -392.16619) (xy 147.754995 -392.206822)
			(xy 147.782665 -392.251693) (xy 147.803892 -392.299947) (xy 147.81827 -392.350665) (xy 147.825525 -392.40288)
			(xy 147.825968 -392.429238) (xy 147.825968 -393.292838) (xy 148.26234 -393.292838) (xy 148.26234 -392.429238)
			(xy 148.26282 -392.402882) (xy 148.270083 -392.350674) (xy 148.284462 -392.299962) (xy 148.305683 -392.251711)
			(xy 148.333343 -392.20684) (xy 148.366915 -392.166202) (xy 148.386038 -392.14806) (xy 148.39315 -392.141456)
			(xy 148.401532 -392.124946) (xy 148.40966 -392.038078) (xy 148.404834 -392.020298) (xy 148.398992 -392.012678)
			(xy 148.384887 -391.992809) (xy 148.362464 -391.949554) (xy 148.347207 -391.903284) (xy 148.339502 -391.855175)
			(xy 148.339048 -391.830814) (xy 148.33957 -391.805559) (xy 148.347883 -391.755737) (xy 148.364284 -391.707963)
			(xy 148.388325 -391.66354) (xy 148.419349 -391.62368) (xy 148.456511 -391.58947) (xy 148.498797 -391.561844)
			(xy 148.545053 -391.541554) (xy 148.594018 -391.529154) (xy 148.644356 -391.524983) (xy 148.694694 -391.529154)
			(xy 148.743659 -391.541554) (xy 148.789915 -391.561844) (xy 148.832201 -391.58947) (xy 148.869363 -391.62368)
			(xy 148.900387 -391.66354) (xy 148.924428 -391.707963) (xy 148.940829 -391.755737) (xy 148.949142 -391.805559)
			(xy 148.949664 -391.830814) (xy 148.949197 -391.855217) (xy 148.941438 -391.903401) (xy 148.926118 -391.949739)
			(xy 148.903627 -391.993053) (xy 148.889466 -392.012932) (xy 148.883878 -392.020552) (xy 148.878798 -392.038332)
			(xy 148.886926 -392.1252) (xy 148.895308 -392.14171) (xy 148.90242 -392.148314) (xy 148.921489 -392.166466)
			(xy 148.95498 -392.207089) (xy 148.982577 -392.251924) (xy 149.003758 -392.300122) (xy 149.018123 -392.350772)
			(xy 149.025399 -392.402915) (xy 149.025864 -392.429238) (xy 149.025864 -393.292838) (xy 149.462744 -393.292838)
			(xy 149.462744 -392.429238) (xy 149.463216 -392.402892) (xy 149.470444 -392.350699) (xy 149.484783 -392.299996)
			(xy 149.505959 -392.251746) (xy 149.53357 -392.206868) (xy 149.567091 -392.166215) (xy 149.586188 -392.14806)
			(xy 149.5933 -392.14171) (xy 149.601428 -392.124946) (xy 149.60981 -392.038332) (xy 149.60473 -392.020552)
			(xy 149.599142 -392.012678) (xy 149.584991 -391.992832) (xy 149.562534 -391.949573) (xy 149.547222 -391.9033)
			(xy 149.539442 -391.855184) (xy 149.538944 -391.830814) (xy 149.539466 -391.805559) (xy 149.547779 -391.755737)
			(xy 149.56418 -391.707963) (xy 149.588221 -391.66354) (xy 149.619245 -391.62368) (xy 149.656407 -391.58947)
			(xy 149.698693 -391.561844) (xy 149.744949 -391.541554) (xy 149.793914 -391.529154) (xy 149.844252 -391.524983)
			(xy 149.89459 -391.529154) (xy 149.943555 -391.541554) (xy 149.989811 -391.561844) (xy 150.032097 -391.58947)
			(xy 150.069259 -391.62368) (xy 150.100283 -391.66354) (xy 150.124324 -391.707963) (xy 150.140725 -391.755737)
			(xy 150.149038 -391.805559) (xy 150.14956 -391.830814) (xy 150.14908 -391.855186) (xy 150.141321 -391.903309)
			(xy 150.126004 -391.949585) (xy 150.103519 -391.992833) (xy 150.089362 -392.012678) (xy 150.083774 -392.020552)
			(xy 150.078694 -392.038332) (xy 150.087076 -392.124946) (xy 150.095204 -392.14171) (xy 150.102316 -392.14806)
			(xy 150.121443 -392.166189) (xy 150.154986 -392.206835) (xy 150.182612 -392.251714) (xy 150.203793 -392.29997)
			(xy 150.218126 -392.350683) (xy 150.225338 -392.402888) (xy 150.22576 -392.429238) (xy 150.22576 -393.292838)
			(xy 150.66264 -393.292838) (xy 150.66264 -392.429238) (xy 150.663113 -392.402892) (xy 150.670341 -392.350699)
			(xy 150.68468 -392.299996) (xy 150.705855 -392.251747) (xy 150.733466 -392.206869) (xy 150.766987 -392.166215)
			(xy 150.786084 -392.14806) (xy 150.793196 -392.14171) (xy 150.801324 -392.124946) (xy 150.809706 -392.038332)
			(xy 150.804626 -392.020552) (xy 150.799038 -392.012678) (xy 150.784886 -391.992832) (xy 150.76243 -391.949573)
			(xy 150.747118 -391.9033) (xy 150.739338 -391.855184) (xy 150.73884 -391.830814) (xy 150.739362 -391.805559)
			(xy 150.747675 -391.755737) (xy 150.764076 -391.707963) (xy 150.788117 -391.66354) (xy 150.819141 -391.62368)
			(xy 150.856303 -391.58947) (xy 150.898589 -391.561844) (xy 150.944845 -391.541554) (xy 150.99381 -391.529154)
			(xy 151.044148 -391.524983) (xy 151.094486 -391.529154) (xy 151.143451 -391.541554) (xy 151.189707 -391.561844)
			(xy 151.231993 -391.58947) (xy 151.269155 -391.62368) (xy 151.300179 -391.66354) (xy 151.32422 -391.707963)
			(xy 151.340621 -391.755737) (xy 151.348934 -391.805559) (xy 151.349456 -391.830814) (xy 151.348977 -391.855186)
			(xy 151.341218 -391.903309) (xy 151.325901 -391.949585) (xy 151.303415 -391.992833) (xy 151.289258 -392.012678)
			(xy 151.28367 -392.020552) (xy 151.27859 -392.038332) (xy 151.286972 -392.124946) (xy 151.2951 -392.14171)
			(xy 151.302212 -392.14806) (xy 151.321338 -392.16619) (xy 151.354882 -392.206836) (xy 151.382508 -392.251714)
			(xy 151.403689 -392.29997) (xy 151.418022 -392.350684) (xy 151.425234 -392.402888) (xy 151.425656 -392.429238)
			(xy 151.425656 -393.292838) (xy 151.862536 -393.292838) (xy 151.862536 -392.429238) (xy 151.863017 -392.402882)
			(xy 151.87028 -392.350674) (xy 151.884659 -392.299962) (xy 151.90588 -392.251711) (xy 151.93354 -392.20684)
			(xy 151.967112 -392.166202) (xy 151.986234 -392.14806) (xy 151.993346 -392.14171) (xy 152.001474 -392.124946)
			(xy 152.009856 -392.038332) (xy 152.004776 -392.020552) (xy 151.999188 -392.012678) (xy 151.985042 -391.992828)
			(xy 151.962583 -391.949571) (xy 151.947269 -391.903299) (xy 151.939489 -391.855184) (xy 151.93899 -391.830814)
			(xy 151.939512 -391.805559) (xy 151.947825 -391.755737) (xy 151.964226 -391.707963) (xy 151.988267 -391.66354)
			(xy 152.019291 -391.62368) (xy 152.056453 -391.58947) (xy 152.098739 -391.561844) (xy 152.144995 -391.541554)
			(xy 152.19396 -391.529154) (xy 152.244298 -391.524983) (xy 152.294636 -391.529154) (xy 152.343601 -391.541554)
			(xy 152.389857 -391.561844) (xy 152.432143 -391.58947) (xy 152.469305 -391.62368) (xy 152.500329 -391.66354)
			(xy 152.52437 -391.707963) (xy 152.540771 -391.755737) (xy 152.549084 -391.805559) (xy 152.549606 -391.830814)
			(xy 152.549136 -391.855187) (xy 152.541376 -391.903311) (xy 152.526056 -391.949586) (xy 152.503567 -391.992834)
			(xy 152.489408 -392.012678) (xy 152.48382 -392.020552) (xy 152.47874 -392.038332) (xy 152.487122 -392.124946)
			(xy 152.49525 -392.14171) (xy 152.502362 -392.14806) (xy 152.521498 -392.166192) (xy 152.555086 -392.206823)
			(xy 152.582756 -392.251693) (xy 152.603983 -392.299947) (xy 152.618362 -392.350665) (xy 152.625617 -392.40288)
			(xy 152.62606 -392.429238) (xy 152.62606 -393.292838) (xy 153.062432 -393.292838) (xy 153.062432 -392.429238)
			(xy 153.062914 -392.402883) (xy 153.070177 -392.350674) (xy 153.084556 -392.299962) (xy 153.105777 -392.251711)
			(xy 153.133436 -392.20684) (xy 153.167008 -392.166203) (xy 153.18613 -392.14806) (xy 153.193242 -392.14171)
			(xy 153.20137 -392.124946) (xy 153.209752 -392.038332) (xy 153.204672 -392.020552) (xy 153.199084 -392.012678)
			(xy 153.184938 -391.992828) (xy 153.162479 -391.949571) (xy 153.147165 -391.903299) (xy 153.139385 -391.855184)
			(xy 153.138886 -391.830814) (xy 153.139408 -391.805559) (xy 153.147721 -391.755737) (xy 153.164122 -391.707963)
			(xy 153.188163 -391.66354) (xy 153.219187 -391.62368) (xy 153.256349 -391.58947) (xy 153.298635 -391.561844)
			(xy 153.344891 -391.541554) (xy 153.393856 -391.529154) (xy 153.444194 -391.524983) (xy 153.494532 -391.529154)
			(xy 153.543497 -391.541554) (xy 153.589753 -391.561844) (xy 153.632039 -391.58947) (xy 153.669201 -391.62368)
			(xy 153.700225 -391.66354) (xy 153.724266 -391.707963) (xy 153.740667 -391.755737) (xy 153.74898 -391.805559)
			(xy 153.749502 -391.830814) (xy 153.749033 -391.855187) (xy 153.741273 -391.903311) (xy 153.725953 -391.949586)
			(xy 153.703463 -391.992834) (xy 153.689304 -392.012678) (xy 153.683716 -392.020552) (xy 153.678636 -392.038332)
			(xy 153.687018 -392.124946) (xy 153.695146 -392.14171) (xy 153.702258 -392.14806) (xy 153.721393 -392.166192)
			(xy 153.754981 -392.206824) (xy 153.782652 -392.251694) (xy 153.803879 -392.299947) (xy 153.818258 -392.350665)
			(xy 153.825513 -392.40288) (xy 153.825956 -392.429238) (xy 153.825956 -393.292838) (xy 154.262836 -393.292838)
			(xy 154.262836 -392.429238) (xy 154.26331 -392.402892) (xy 154.270539 -392.350699) (xy 154.284877 -392.299996)
			(xy 154.306052 -392.251747) (xy 154.333663 -392.206869) (xy 154.367183 -392.166215) (xy 154.38628 -392.14806)
			(xy 154.393392 -392.14171) (xy 154.40152 -392.124946) (xy 154.409902 -392.038332) (xy 154.404822 -392.020552)
			(xy 154.399234 -392.012678) (xy 154.385082 -391.992833) (xy 154.362625 -391.949573) (xy 154.347314 -391.9033)
			(xy 154.339534 -391.855184) (xy 154.339036 -391.830814) (xy 154.339558 -391.805559) (xy 154.347871 -391.755737)
			(xy 154.364272 -391.707963) (xy 154.388313 -391.66354) (xy 154.419337 -391.62368) (xy 154.456499 -391.58947)
			(xy 154.498785 -391.561844) (xy 154.545041 -391.541554) (xy 154.594006 -391.529154) (xy 154.644344 -391.524983)
			(xy 154.694682 -391.529154) (xy 154.743647 -391.541554) (xy 154.789903 -391.561844) (xy 154.832189 -391.58947)
			(xy 154.869351 -391.62368) (xy 154.900375 -391.66354) (xy 154.924416 -391.707963) (xy 154.940817 -391.755737)
			(xy 154.94913 -391.805559) (xy 154.949652 -391.830814) (xy 154.949173 -391.855186) (xy 154.941415 -391.903309)
			(xy 154.926097 -391.949585) (xy 154.903611 -391.992833) (xy 154.889454 -392.012678) (xy 154.883866 -392.020552)
			(xy 154.878786 -392.038332) (xy 154.887168 -392.124946) (xy 154.895296 -392.14171) (xy 154.902408 -392.14806)
			(xy 154.921533 -392.166191) (xy 154.955077 -392.206836) (xy 154.982703 -392.251715) (xy 155.003885 -392.299971)
			(xy 155.018218 -392.350684) (xy 155.02543 -392.402888) (xy 155.025852 -392.429238) (xy 155.025852 -393.292838)
			(xy 155.462732 -393.292838) (xy 155.462732 -392.429238) (xy 155.463176 -392.402891) (xy 155.470406 -392.350695)
			(xy 155.484748 -392.29999) (xy 155.505929 -392.251741) (xy 155.533546 -392.206864) (xy 155.567075 -392.166212)
			(xy 155.586176 -392.14806) (xy 155.593288 -392.14171) (xy 155.601416 -392.124946) (xy 155.609798 -392.038332)
			(xy 155.604718 -392.020552) (xy 155.59913 -392.012678) (xy 155.584977 -391.992833) (xy 155.562521 -391.949573)
			(xy 155.54721 -391.9033) (xy 155.53943 -391.855184) (xy 155.538932 -391.830814) (xy 155.539454 -391.805559)
			(xy 155.547767 -391.755737) (xy 155.564168 -391.707963) (xy 155.588209 -391.66354) (xy 155.619233 -391.62368)
			(xy 155.656395 -391.58947) (xy 155.698681 -391.561844) (xy 155.744937 -391.541554) (xy 155.793902 -391.529154)
			(xy 155.84424 -391.524983) (xy 155.894578 -391.529154) (xy 155.943543 -391.541554) (xy 155.989799 -391.561844)
			(xy 156.032085 -391.58947) (xy 156.069247 -391.62368) (xy 156.100271 -391.66354) (xy 156.124312 -391.707963)
			(xy 156.140713 -391.755737) (xy 156.149026 -391.805559) (xy 156.149548 -391.830814) (xy 156.14907 -391.855186)
			(xy 156.141311 -391.90331) (xy 156.125993 -391.949585) (xy 156.103507 -391.992833) (xy 156.08935 -392.012678)
			(xy 156.083762 -392.020552) (xy 156.078682 -392.038332) (xy 156.087064 -392.124946) (xy 156.095192 -392.14171)
			(xy 156.102304 -392.14806) (xy 156.121429 -392.166191) (xy 156.154973 -392.206837) (xy 156.182599 -392.251715)
			(xy 156.203781 -392.299971) (xy 156.218114 -392.350684) (xy 156.225326 -392.402888) (xy 156.225748 -392.429238)
			(xy 156.225748 -393.292838) (xy 156.662628 -393.292838) (xy 156.662628 -392.429238) (xy 156.663061 -392.402911)
			(xy 156.670311 -392.350757) (xy 156.684665 -392.300096) (xy 156.70585 -392.251891) (xy 156.733463 -392.207057)
			(xy 156.76698 -392.166447) (xy 156.786072 -392.148314) (xy 156.793184 -392.14171) (xy 156.801566 -392.1252)
			(xy 156.809694 -392.038332) (xy 156.804614 -392.020552) (xy 156.799026 -392.012932) (xy 156.784874 -391.993048)
			(xy 156.762385 -391.949735) (xy 156.747066 -391.903398) (xy 156.739306 -391.855216) (xy 156.738828 -391.830814)
			(xy 156.73935 -391.805559) (xy 156.747663 -391.755737) (xy 156.764064 -391.707963) (xy 156.788105 -391.66354)
			(xy 156.819129 -391.62368) (xy 156.856291 -391.58947) (xy 156.898577 -391.561844) (xy 156.944833 -391.541554)
			(xy 156.993798 -391.529154) (xy 157.044136 -391.524983) (xy 157.094474 -391.529154) (xy 157.143439 -391.541554)
			(xy 157.189695 -391.561844) (xy 157.231981 -391.58947) (xy 157.269143 -391.62368) (xy 157.300167 -391.66354)
			(xy 157.324208 -391.707963) (xy 157.340609 -391.755737) (xy 157.348922 -391.805559) (xy 157.349444 -391.830814)
			(xy 157.348948 -391.855172) (xy 157.341235 -391.903275) (xy 157.325992 -391.949545) (xy 157.303603 -391.992812)
			(xy 157.2895 -392.012678) (xy 157.283658 -392.020298) (xy 157.278832 -392.038078) (xy 157.28696 -392.124946)
			(xy 157.295342 -392.141456) (xy 157.302454 -392.14806) (xy 157.321589 -392.166193) (xy 157.355176 -392.206824)
			(xy 157.382848 -392.251694) (xy 157.404075 -392.299948) (xy 157.418453 -392.350665) (xy 157.425709 -392.40288)
			(xy 157.426152 -392.429238) (xy 157.426152 -393.292838) (xy 157.862524 -393.292838) (xy 157.862524 -392.429238)
			(xy 157.863009 -392.402883) (xy 157.870272 -392.350674) (xy 157.88465 -392.299963) (xy 157.90587 -392.251712)
			(xy 157.933529 -392.206841) (xy 157.9671 -392.166203) (xy 157.986222 -392.14806) (xy 157.993334 -392.14171)
			(xy 158.001462 -392.124946) (xy 158.009844 -392.038332) (xy 158.004764 -392.020552) (xy 157.999176 -392.012678)
			(xy 157.985029 -391.992829) (xy 157.96257 -391.949571) (xy 157.947257 -391.903299) (xy 157.939476 -391.855184)
			(xy 157.938978 -391.830814) (xy 157.9395 -391.805559) (xy 157.947813 -391.755737) (xy 157.964214 -391.707963)
			(xy 157.988255 -391.66354) (xy 158.019279 -391.62368) (xy 158.056441 -391.58947) (xy 158.098727 -391.561844)
			(xy 158.144983 -391.541554) (xy 158.193948 -391.529154) (xy 158.244286 -391.524983) (xy 158.294624 -391.529154)
			(xy 158.343589 -391.541554) (xy 158.389845 -391.561844) (xy 158.432131 -391.58947) (xy 158.469293 -391.62368)
			(xy 158.500317 -391.66354) (xy 158.524358 -391.707963) (xy 158.540759 -391.755737) (xy 158.549072 -391.805559)
			(xy 158.549594 -391.830814) (xy 158.549127 -391.855187) (xy 158.541366 -391.903311) (xy 158.526046 -391.949587)
			(xy 158.503555 -391.992834) (xy 158.489396 -392.012678) (xy 158.483808 -392.020552) (xy 158.478728 -392.038332)
			(xy 158.48711 -392.124946) (xy 158.495238 -392.14171) (xy 158.50235 -392.14806) (xy 158.521484 -392.166194)
			(xy 158.555072 -392.206825) (xy 158.582743 -392.251694) (xy 158.603971 -392.299948) (xy 158.618349 -392.350665)
			(xy 158.625605 -392.40288) (xy 158.626048 -392.429238) (xy 158.626048 -393.292838) (xy 159.062928 -393.292838)
			(xy 159.062928 -392.429238) (xy 159.063351 -392.402921) (xy 159.070576 -392.350785) (xy 159.084894 -392.300136)
			(xy 159.106034 -392.251934) (xy 159.133595 -392.207093) (xy 159.167055 -392.166463) (xy 159.186118 -392.148314)
			(xy 159.19323 -392.14171) (xy 159.201612 -392.1252) (xy 159.20974 -392.038332) (xy 159.20466 -392.020552)
			(xy 159.199072 -392.012932) (xy 159.184913 -391.993052) (xy 159.162427 -391.949737) (xy 159.14711 -391.903399)
			(xy 159.139352 -391.855216) (xy 159.138874 -391.830814) (xy 159.139396 -391.805559) (xy 159.147709 -391.755737)
			(xy 159.16411 -391.707963) (xy 159.188151 -391.66354) (xy 159.219175 -391.62368) (xy 159.256337 -391.58947)
			(xy 159.298623 -391.561844) (xy 159.344879 -391.541554) (xy 159.393844 -391.529154) (xy 159.444182 -391.524983)
			(xy 159.49452 -391.529154) (xy 159.543485 -391.541554) (xy 159.589741 -391.561844) (xy 159.632027 -391.58947)
			(xy 159.669189 -391.62368) (xy 159.700213 -391.66354) (xy 159.724254 -391.707963) (xy 159.740655 -391.755737)
			(xy 159.748968 -391.805559) (xy 159.74949 -391.830814) (xy 159.749004 -391.855173) (xy 159.74129 -391.903276)
			(xy 159.726044 -391.949546) (xy 159.703651 -391.992813) (xy 159.689546 -392.012678) (xy 159.683704 -392.020298)
			(xy 159.678878 -392.038078) (xy 159.687006 -392.124946) (xy 159.695388 -392.141456) (xy 159.7025 -392.14806)
			(xy 159.721624 -392.166192) (xy 159.755168 -392.206837) (xy 159.782795 -392.251715) (xy 159.803976 -392.299971)
			(xy 159.81831 -392.350684) (xy 159.825522 -392.402888) (xy 159.825944 -392.429238) (xy 159.825944 -393.292838)
			(xy 160.262824 -393.292838) (xy 160.262824 -392.429238) (xy 160.26327 -392.402891) (xy 160.2705 -392.350695)
			(xy 160.284842 -392.299991) (xy 160.306023 -392.251741) (xy 160.333639 -392.206864) (xy 160.367167 -392.166213)
			(xy 160.386268 -392.14806) (xy 160.39338 -392.14171) (xy 160.401508 -392.124946) (xy 160.40989 -392.038332)
			(xy 160.40481 -392.020552) (xy 160.399222 -392.012678) (xy 160.385068 -391.992834) (xy 160.362612 -391.949574)
			(xy 160.347301 -391.9033) (xy 160.339522 -391.855184) (xy 160.339024 -391.830814) (xy 160.339546 -391.805559)
			(xy 160.347859 -391.755737) (xy 160.36426 -391.707963) (xy 160.388301 -391.66354) (xy 160.419325 -391.62368)
			(xy 160.456487 -391.58947) (xy 160.498773 -391.561844) (xy 160.545029 -391.541554) (xy 160.593994 -391.529154)
			(xy 160.644332 -391.524983) (xy 160.69467 -391.529154) (xy 160.743635 -391.541554) (xy 160.789891 -391.561844)
			(xy 160.832177 -391.58947) (xy 160.869339 -391.62368) (xy 160.900363 -391.66354) (xy 160.924404 -391.707963)
			(xy 160.940805 -391.755737) (xy 160.949118 -391.805559) (xy 160.94964 -391.830814) (xy 160.949164 -391.855186)
			(xy 160.941405 -391.90331) (xy 160.926086 -391.949585) (xy 160.903599 -391.992833) (xy 160.889442 -392.012678)
			(xy 160.883854 -392.020552) (xy 160.878774 -392.038332) (xy 160.887156 -392.124946) (xy 160.895284 -392.14171)
			(xy 160.902396 -392.14806) (xy 160.921519 -392.166193) (xy 160.955064 -392.206838) (xy 160.98269 -392.251716)
			(xy 161.003872 -392.299971) (xy 161.018206 -392.350684) (xy 161.025418 -392.402888) (xy 161.02584 -392.429238)
			(xy 161.02584 -393.292838) (xy 161.46272 -393.292838) (xy 161.46272 -392.429238) (xy 161.463167 -392.402891)
			(xy 161.470397 -392.350696) (xy 161.484739 -392.299991) (xy 161.505919 -392.251741) (xy 161.533536 -392.206864)
			(xy 161.567063 -392.166213) (xy 161.586164 -392.14806) (xy 161.593276 -392.14171) (xy 161.601404 -392.124946)
			(xy 161.609786 -392.038332) (xy 161.604706 -392.020552) (xy 161.599118 -392.012678) (xy 161.584964 -391.992834)
			(xy 161.562508 -391.949574) (xy 161.547197 -391.9033) (xy 161.539418 -391.855184) (xy 161.53892 -391.830814)
			(xy 161.539442 -391.805559) (xy 161.547755 -391.755737) (xy 161.564156 -391.707963) (xy 161.588197 -391.66354)
			(xy 161.619221 -391.62368) (xy 161.656383 -391.58947) (xy 161.698669 -391.561844) (xy 161.744925 -391.541554)
			(xy 161.79389 -391.529154) (xy 161.844228 -391.524983) (xy 161.894566 -391.529154) (xy 161.943531 -391.541554)
			(xy 161.989787 -391.561844) (xy 162.032073 -391.58947) (xy 162.069235 -391.62368) (xy 162.100259 -391.66354)
			(xy 162.1243 -391.707963) (xy 162.140701 -391.755737) (xy 162.149014 -391.805559) (xy 162.149536 -391.830814)
			(xy 162.14906 -391.855186) (xy 162.141301 -391.90331) (xy 162.125983 -391.949585) (xy 162.103496 -391.992833)
			(xy 162.089338 -392.012678) (xy 162.08375 -392.020552) (xy 162.07867 -392.038332) (xy 162.087052 -392.124946)
			(xy 162.09518 -392.14171) (xy 162.102292 -392.14806) (xy 162.121414 -392.166194) (xy 162.154959 -392.206838)
			(xy 162.182586 -392.251716) (xy 162.203768 -392.299971) (xy 162.218102 -392.350684) (xy 162.225314 -392.402888)
			(xy 162.225736 -392.429238) (xy 162.225736 -393.292838) (xy 162.662616 -393.292838) (xy 162.662616 -392.429238)
			(xy 162.663065 -392.402891) (xy 162.670295 -392.350696) (xy 162.684636 -392.299991) (xy 162.705816 -392.251742)
			(xy 162.733432 -392.206864) (xy 162.76696 -392.166213) (xy 162.78606 -392.14806) (xy 162.793172 -392.14171)
			(xy 162.8013 -392.124946) (xy 162.809682 -392.038332) (xy 162.804602 -392.020552) (xy 162.799014 -392.012678)
			(xy 162.784859 -391.992834) (xy 162.762404 -391.949574) (xy 162.747093 -391.9033) (xy 162.739314 -391.855184)
			(xy 162.738816 -391.830814) (xy 162.739338 -391.805559) (xy 162.747651 -391.755737) (xy 162.764052 -391.707963)
			(xy 162.788093 -391.66354) (xy 162.819117 -391.62368) (xy 162.856279 -391.58947) (xy 162.898565 -391.561844)
			(xy 162.944821 -391.541554) (xy 162.993786 -391.529154) (xy 163.044124 -391.524983) (xy 163.094462 -391.529154)
			(xy 163.143427 -391.541554) (xy 163.189683 -391.561844) (xy 163.231969 -391.58947) (xy 163.269131 -391.62368)
			(xy 163.300155 -391.66354) (xy 163.324196 -391.707963) (xy 163.340597 -391.755737) (xy 163.34891 -391.805559)
			(xy 163.349432 -391.830814) (xy 163.348957 -391.855186) (xy 163.341198 -391.90331) (xy 163.325879 -391.949585)
			(xy 163.303392 -391.992833) (xy 163.289234 -392.012678) (xy 163.283646 -392.020552) (xy 163.278566 -392.038332)
			(xy 163.286948 -392.124946) (xy 163.295076 -392.14171) (xy 163.302188 -392.14806) (xy 163.32131 -392.166194)
			(xy 163.354855 -392.206839) (xy 163.382482 -392.251716) (xy 163.403664 -392.299972) (xy 163.417998 -392.350684)
			(xy 163.42521 -392.402888) (xy 163.425632 -392.429238) (xy 163.425632 -393.292838) (xy 163.862512 -393.292838)
			(xy 163.862512 -392.429238) (xy 163.863001 -392.402883) (xy 163.870263 -392.350675) (xy 163.884641 -392.299963)
			(xy 163.905861 -392.251713) (xy 163.933519 -392.206841) (xy 163.967089 -392.166203) (xy 163.98621 -392.14806)
			(xy 163.993322 -392.14171) (xy 164.00145 -392.124946) (xy 164.009832 -392.038332) (xy 164.004752 -392.020552)
			(xy 163.999164 -392.012678) (xy 163.985015 -391.99283) (xy 163.962557 -391.949572) (xy 163.947244 -391.903299)
			(xy 163.939464 -391.855184) (xy 163.938966 -391.830814) (xy 163.939488 -391.805559) (xy 163.947801 -391.755737)
			(xy 163.964202 -391.707963) (xy 163.988243 -391.66354) (xy 164.019267 -391.62368) (xy 164.056429 -391.58947)
			(xy 164.098715 -391.561844) (xy 164.144971 -391.541554) (xy 164.193936 -391.529154) (xy 164.244274 -391.524983)
			(xy 164.294612 -391.529154) (xy 164.343577 -391.541554) (xy 164.389833 -391.561844) (xy 164.432119 -391.58947)
			(xy 164.469281 -391.62368) (xy 164.500305 -391.66354) (xy 164.524346 -391.707963) (xy 164.540747 -391.755737)
			(xy 164.54906 -391.805559) (xy 164.549582 -391.830814) (xy 164.549117 -391.855187) (xy 164.541356 -391.903311)
			(xy 164.526035 -391.949587) (xy 164.503544 -391.992834) (xy 164.489384 -392.012678) (xy 164.483796 -392.020552)
			(xy 164.478716 -392.038332) (xy 164.487098 -392.124946) (xy 164.495226 -392.14171) (xy 164.502338 -392.14806)
			(xy 164.52147 -392.166196) (xy 164.555058 -392.206826) (xy 164.58273 -392.251695) (xy 164.603958 -392.299948)
			(xy 164.618337 -392.350666) (xy 164.625593 -392.40288) (xy 164.626036 -392.429238) (xy 164.626036 -393.292838)
			(xy 164.625609 -393.319012) (xy 164.618413 -393.370864) (xy 164.6042 -393.421247) (xy 164.583239 -393.469216)
			(xy 164.555922 -393.513872) (xy 164.522761 -393.554378) (xy 164.503862 -393.572492) (xy 164.496496 -393.57935)
			(xy 164.488368 -393.596876) (xy 164.483034 -393.687046) (xy 164.48913 -393.705334) (xy 164.495734 -393.712954)
			(xy 164.510639 -393.730994) (xy 164.535702 -393.770513) (xy 164.554948 -393.813169) (xy 164.567994 -393.858109)
			(xy 164.57458 -393.90444) (xy 164.574982 -393.927838) (xy 164.574472 -393.953825) (xy 164.566342 -394.00516)
			(xy 164.550281 -394.05459) (xy 164.526685 -394.1009) (xy 164.496135 -394.142948) (xy 164.459384 -394.179699)
			(xy 164.417336 -394.210249) (xy 164.371026 -394.233845) (xy 164.321596 -394.249906) (xy 164.270261 -394.258036)
			(xy 164.218287 -394.258036) (xy 164.166952 -394.249906) (xy 164.117522 -394.233845) (xy 164.071212 -394.210249)
			(xy 164.029164 -394.179699) (xy 163.992413 -394.142948) (xy 163.961863 -394.1009) (xy 163.938267 -394.05459)
			(xy 163.922206 -394.00516) (xy 163.914076 -393.953825) (xy 163.913566 -393.927838) (xy 163.913987 -393.904441)
			(xy 163.920574 -393.858114) (xy 163.933621 -393.813177) (xy 163.952868 -393.770526) (xy 163.977932 -393.731011)
			(xy 163.992814 -393.712954) (xy 163.999418 -393.705334) (xy 164.005514 -393.687046) (xy 164.00018 -393.596876)
			(xy 163.992052 -393.57935) (xy 163.984686 -393.572492) (xy 163.965787 -393.554378) (xy 163.932624 -393.513874)
			(xy 163.905308 -393.469218) (xy 163.884351 -393.421248) (xy 163.870146 -393.370864) (xy 163.86296 -393.319012)
			(xy 163.862512 -393.292838) (xy 163.425632 -393.292838) (xy 163.425181 -393.319002) (xy 163.41803 -393.370838)
			(xy 163.403867 -393.421213) (xy 163.382957 -393.469181) (xy 163.355693 -393.513844) (xy 163.322585 -393.554366)
			(xy 163.303712 -393.572492) (xy 163.296346 -393.57935) (xy 163.288218 -393.596876) (xy 163.282884 -393.687046)
			(xy 163.28898 -393.705334) (xy 163.295584 -393.712954) (xy 163.310482 -393.731) (xy 163.335547 -393.770517)
			(xy 163.354795 -393.813171) (xy 163.367843 -393.85811) (xy 163.37443 -393.90444) (xy 163.374832 -393.927838)
			(xy 163.374322 -393.953825) (xy 163.366192 -394.00516) (xy 163.350131 -394.05459) (xy 163.326535 -394.1009)
			(xy 163.295985 -394.142948) (xy 163.259234 -394.179699) (xy 163.217186 -394.210249) (xy 163.170876 -394.233845)
			(xy 163.121446 -394.249906) (xy 163.070111 -394.258036) (xy 163.018137 -394.258036) (xy 162.966802 -394.249906)
			(xy 162.917372 -394.233845) (xy 162.871062 -394.210249) (xy 162.829014 -394.179699) (xy 162.792263 -394.142948)
			(xy 162.761713 -394.1009) (xy 162.738117 -394.05459) (xy 162.722056 -394.00516) (xy 162.713926 -393.953825)
			(xy 162.713416 -393.927838) (xy 162.713849 -393.904442) (xy 162.720434 -393.858116) (xy 162.733479 -393.813179)
			(xy 162.752724 -393.770528) (xy 162.777784 -393.731012) (xy 162.792664 -393.712954) (xy 162.799268 -393.705334)
			(xy 162.805364 -393.687046) (xy 162.80003 -393.596876) (xy 162.791902 -393.57935) (xy 162.784536 -393.572492)
			(xy 162.765648 -393.554379) (xy 162.732529 -393.513861) (xy 162.705258 -393.469197) (xy 162.684346 -393.421225)
			(xy 162.670186 -393.370846) (xy 162.663043 -393.319004) (xy 162.662616 -393.292838) (xy 162.225736 -393.292838)
			(xy 162.225202 -393.321743) (xy 162.216497 -393.378893) (xy 162.199276 -393.434077) (xy 162.173933 -393.486035)
			(xy 162.141048 -393.533579) (xy 162.121596 -393.554966) (xy 162.1155 -393.56157) (xy 162.108388 -393.577572)
			(xy 162.1028 -393.659868) (xy 162.107626 -393.676886) (xy 162.112706 -393.683998) (xy 162.127349 -393.705223)
			(xy 162.150599 -393.751246) (xy 162.166423 -393.800321) (xy 162.174437 -393.851257) (xy 162.174936 -393.877038)
			(xy 162.174426 -393.903025) (xy 162.166296 -393.95436) (xy 162.150235 -394.00379) (xy 162.126639 -394.0501)
			(xy 162.096089 -394.092148) (xy 162.059338 -394.128899) (xy 162.01729 -394.159449) (xy 161.97098 -394.183045)
			(xy 161.92155 -394.199106) (xy 161.870215 -394.207236) (xy 161.818241 -394.207236) (xy 161.766906 -394.199106)
			(xy 161.717476 -394.183045) (xy 161.671166 -394.159449) (xy 161.629118 -394.128899) (xy 161.592367 -394.092148)
			(xy 161.561817 -394.0501) (xy 161.538221 -394.00379) (xy 161.52216 -393.95436) (xy 161.51403 -393.903025)
			(xy 161.51352 -393.877038) (xy 161.513989 -393.851254) (xy 161.521997 -393.800313) (xy 161.537824 -393.751234)
			(xy 161.561087 -393.705212) (xy 161.57575 -393.683998) (xy 161.58083 -393.676886) (xy 161.585656 -393.659868)
			(xy 161.580068 -393.577572) (xy 161.572956 -393.56157) (xy 161.56686 -393.554966) (xy 161.54737 -393.533609)
			(xy 161.514465 -393.486069) (xy 161.489116 -393.434106) (xy 161.471905 -393.378909) (xy 161.463228 -393.321747)
			(xy 161.46272 -393.292838) (xy 161.02584 -393.292838) (xy 161.025386 -393.319002) (xy 161.018235 -393.370838)
			(xy 161.004073 -393.421212) (xy 160.983164 -393.46918) (xy 160.9559 -393.513844) (xy 160.922793 -393.554366)
			(xy 160.90392 -393.572492) (xy 160.896554 -393.57935) (xy 160.888426 -393.596876) (xy 160.883092 -393.687046)
			(xy 160.889188 -393.705334) (xy 160.895792 -393.712954) (xy 160.910691 -393.730999) (xy 160.935756 -393.770516)
			(xy 160.955004 -393.81317) (xy 160.968051 -393.85811) (xy 160.974638 -393.90444) (xy 160.97504 -393.927838)
			(xy 160.97453 -393.953825) (xy 160.9664 -394.00516) (xy 160.950339 -394.05459) (xy 160.926743 -394.1009)
			(xy 160.896193 -394.142948) (xy 160.859442 -394.179699) (xy 160.817394 -394.210249) (xy 160.771084 -394.233845)
			(xy 160.721654 -394.249906) (xy 160.670319 -394.258036) (xy 160.618345 -394.258036) (xy 160.56701 -394.249906)
			(xy 160.51758 -394.233845) (xy 160.47127 -394.210249) (xy 160.429222 -394.179699) (xy 160.392471 -394.142948)
			(xy 160.361921 -394.1009) (xy 160.338325 -394.05459) (xy 160.322264 -394.00516) (xy 160.314134 -393.953825)
			(xy 160.313624 -393.927838) (xy 160.314055 -393.904442) (xy 160.320641 -393.858116) (xy 160.333686 -393.813179)
			(xy 160.352931 -393.770528) (xy 160.377991 -393.731012) (xy 160.392872 -393.712954) (xy 160.399476 -393.705334)
			(xy 160.405572 -393.687046) (xy 160.400238 -393.596876) (xy 160.39211 -393.57935) (xy 160.384744 -393.572492)
			(xy 160.365858 -393.554377) (xy 160.332738 -393.51386) (xy 160.305467 -393.469196) (xy 160.284554 -393.421225)
			(xy 160.270394 -393.370845) (xy 160.263251 -393.319004) (xy 160.262824 -393.292838) (xy 159.825944 -393.292838)
			(xy 159.825489 -393.319002) (xy 159.818338 -393.370838) (xy 159.804176 -393.421212) (xy 159.783267 -393.46918)
			(xy 159.756004 -393.513844) (xy 159.722896 -393.554366) (xy 159.704024 -393.572492) (xy 159.696658 -393.57935)
			(xy 159.68853 -393.596876) (xy 159.683196 -393.687046) (xy 159.689292 -393.705334) (xy 159.695896 -393.712954)
			(xy 159.710795 -393.730999) (xy 159.73586 -393.770516) (xy 159.755108 -393.81317) (xy 159.768155 -393.85811)
			(xy 159.774742 -393.90444) (xy 159.775144 -393.927838) (xy 159.774634 -393.953825) (xy 159.766504 -394.00516)
			(xy 159.750443 -394.05459) (xy 159.726847 -394.1009) (xy 159.696297 -394.142948) (xy 159.659546 -394.179699)
			(xy 159.617498 -394.210249) (xy 159.571188 -394.233845) (xy 159.521758 -394.249906) (xy 159.470423 -394.258036)
			(xy 159.418449 -394.258036) (xy 159.367114 -394.249906) (xy 159.317684 -394.233845) (xy 159.271374 -394.210249)
			(xy 159.229326 -394.179699) (xy 159.192575 -394.142948) (xy 159.162025 -394.1009) (xy 159.138429 -394.05459)
			(xy 159.122368 -394.00516) (xy 159.114238 -393.953825) (xy 159.113728 -393.927838) (xy 159.114158 -393.904442)
			(xy 159.120744 -393.858116) (xy 159.133789 -393.813179) (xy 159.153034 -393.770527) (xy 159.178095 -393.731012)
			(xy 159.192976 -393.712954) (xy 159.19958 -393.705334) (xy 159.205676 -393.687046) (xy 159.200342 -393.596876)
			(xy 159.192214 -393.57935) (xy 159.184848 -393.572492) (xy 159.165963 -393.554377) (xy 159.132843 -393.513859)
			(xy 159.105571 -393.469196) (xy 159.084659 -393.421224) (xy 159.070498 -393.370845) (xy 159.063355 -393.319004)
			(xy 159.062928 -393.292838) (xy 158.626048 -393.292838) (xy 158.625618 -393.319012) (xy 158.618421 -393.370863)
			(xy 158.604209 -393.421246) (xy 158.583249 -393.469215) (xy 158.555932 -393.513871) (xy 158.522772 -393.554377)
			(xy 158.503874 -393.572492) (xy 158.496508 -393.57935) (xy 158.48838 -393.596876) (xy 158.483046 -393.687046)
			(xy 158.489142 -393.705334) (xy 158.495746 -393.712954) (xy 158.510653 -393.730993) (xy 158.535715 -393.770512)
			(xy 158.55496 -393.813168) (xy 158.568006 -393.858109) (xy 158.574592 -393.90444) (xy 158.574994 -393.927838)
			(xy 158.574484 -393.953825) (xy 158.566354 -394.00516) (xy 158.550293 -394.05459) (xy 158.526697 -394.1009)
			(xy 158.496147 -394.142948) (xy 158.459396 -394.179699) (xy 158.417348 -394.210249) (xy 158.371038 -394.233845)
			(xy 158.321608 -394.249906) (xy 158.270273 -394.258036) (xy 158.218299 -394.258036) (xy 158.166964 -394.249906)
			(xy 158.117534 -394.233845) (xy 158.071224 -394.210249) (xy 158.029176 -394.179699) (xy 157.992425 -394.142948)
			(xy 157.961875 -394.1009) (xy 157.938279 -394.05459) (xy 157.922218 -394.00516) (xy 157.914088 -393.953825)
			(xy 157.913578 -393.927838) (xy 157.913996 -393.904441) (xy 157.920583 -393.858114) (xy 157.93363 -393.813177)
			(xy 157.952878 -393.770525) (xy 157.977943 -393.731011) (xy 157.992826 -393.712954) (xy 157.99943 -393.705334)
			(xy 158.005526 -393.687046) (xy 158.000192 -393.596876) (xy 157.992064 -393.57935) (xy 157.984698 -393.572492)
			(xy 157.965801 -393.554376) (xy 157.932638 -393.513873) (xy 157.905321 -393.469218) (xy 157.884364 -393.421248)
			(xy 157.870158 -393.370864) (xy 157.862972 -393.319012) (xy 157.862524 -393.292838) (xy 157.426152 -393.292838)
			(xy 157.42572 -393.319012) (xy 157.418524 -393.370863) (xy 157.404312 -393.421246) (xy 157.383352 -393.469215)
			(xy 157.356036 -393.513871) (xy 157.322876 -393.554377) (xy 157.303978 -393.572492) (xy 157.296612 -393.57935)
			(xy 157.288484 -393.596876) (xy 157.28315 -393.687046) (xy 157.289246 -393.705334) (xy 157.29585 -393.712954)
			(xy 157.310758 -393.730992) (xy 157.335819 -393.770512) (xy 157.355065 -393.813168) (xy 157.36811 -393.858109)
			(xy 157.374696 -393.90444) (xy 157.375098 -393.927838) (xy 157.374588 -393.953825) (xy 157.366458 -394.00516)
			(xy 157.350397 -394.05459) (xy 157.326801 -394.1009) (xy 157.296251 -394.142948) (xy 157.2595 -394.179699)
			(xy 157.217452 -394.210249) (xy 157.171142 -394.233845) (xy 157.121712 -394.249906) (xy 157.070377 -394.258036)
			(xy 157.018403 -394.258036) (xy 156.967068 -394.249906) (xy 156.917638 -394.233845) (xy 156.871328 -394.210249)
			(xy 156.82928 -394.179699) (xy 156.792529 -394.142948) (xy 156.761979 -394.1009) (xy 156.738383 -394.05459)
			(xy 156.722322 -394.00516) (xy 156.714192 -393.953825) (xy 156.713682 -393.927838) (xy 156.714123 -393.904442)
			(xy 156.720708 -393.858117) (xy 156.733751 -393.813181) (xy 156.752993 -393.770529) (xy 156.778051 -393.731013)
			(xy 156.79293 -393.712954) (xy 156.799534 -393.705334) (xy 156.80563 -393.687046) (xy 156.800296 -393.596876)
			(xy 156.792168 -393.57935) (xy 156.784802 -393.572492) (xy 156.765906 -393.554375) (xy 156.732743 -393.513872)
			(xy 156.705426 -393.469217) (xy 156.684468 -393.421248) (xy 156.670262 -393.370864) (xy 156.663076 -393.319012)
			(xy 156.662628 -393.292838) (xy 156.225748 -393.292838) (xy 156.225191 -393.322987) (xy 156.215735 -393.382538)
			(xy 156.197032 -393.439862) (xy 156.169548 -393.493532) (xy 156.133967 -393.542212) (xy 156.112972 -393.563856)
			(xy 156.106368 -393.57046) (xy 156.098748 -393.587224) (xy 156.093414 -393.67333) (xy 156.098748 -393.69111)
			(xy 156.10459 -393.698476) (xy 156.121101 -393.720461) (xy 156.147374 -393.768756) (xy 156.165304 -393.820728)
			(xy 156.1744 -393.874949) (xy 156.174948 -393.902438) (xy 156.174438 -393.928425) (xy 156.166308 -393.97976)
			(xy 156.150247 -394.02919) (xy 156.126651 -394.0755) (xy 156.096101 -394.117548) (xy 156.05935 -394.154299)
			(xy 156.017302 -394.184849) (xy 155.970992 -394.208445) (xy 155.921562 -394.224506) (xy 155.870227 -394.232636)
			(xy 155.818253 -394.232636) (xy 155.766918 -394.224506) (xy 155.717488 -394.208445) (xy 155.671178 -394.184849)
			(xy 155.62913 -394.154299) (xy 155.592379 -394.117548) (xy 155.561829 -394.0755) (xy 155.538233 -394.02919)
			(xy 155.522172 -393.97976) (xy 155.514042 -393.928425) (xy 155.513532 -393.902438) (xy 155.514078 -393.874947)
			(xy 155.523155 -393.82072) (xy 155.541082 -393.768744) (xy 155.567364 -393.720451) (xy 155.58389 -393.698476)
			(xy 155.589732 -393.69111) (xy 155.595066 -393.67333) (xy 155.589732 -393.587224) (xy 155.582112 -393.57046)
			(xy 155.575508 -393.563856) (xy 155.554514 -393.542209) (xy 155.518922 -393.493535) (xy 155.491432 -393.439867)
			(xy 155.47273 -393.382542) (xy 155.463282 -393.322988) (xy 155.462732 -393.292838) (xy 155.025852 -393.292838)
			(xy 155.025314 -393.321742) (xy 155.016609 -393.378892) (xy 154.999389 -393.434076) (xy 154.974047 -393.486034)
			(xy 154.941163 -393.533579) (xy 154.921712 -393.554966) (xy 154.915616 -393.56157) (xy 154.908504 -393.577572)
			(xy 154.902916 -393.659868) (xy 154.907742 -393.676886) (xy 154.912822 -393.683998) (xy 154.927455 -393.70523)
			(xy 154.95071 -393.75125) (xy 154.966537 -393.800322) (xy 154.974553 -393.851257) (xy 154.975052 -393.877038)
			(xy 154.974542 -393.903025) (xy 154.966412 -393.95436) (xy 154.950351 -394.00379) (xy 154.926755 -394.0501)
			(xy 154.896205 -394.092148) (xy 154.859454 -394.128899) (xy 154.817406 -394.159449) (xy 154.771096 -394.183045)
			(xy 154.721666 -394.199106) (xy 154.670331 -394.207236) (xy 154.618357 -394.207236) (xy 154.567022 -394.199106)
			(xy 154.517592 -394.183045) (xy 154.471282 -394.159449) (xy 154.429234 -394.128899) (xy 154.392483 -394.092148)
			(xy 154.361933 -394.0501) (xy 154.338337 -394.00379) (xy 154.322276 -393.95436) (xy 154.314146 -393.903025)
			(xy 154.313636 -393.877038) (xy 154.31412 -393.851255) (xy 154.322126 -393.800315) (xy 154.337949 -393.751237)
			(xy 154.361206 -393.705213) (xy 154.375866 -393.683998) (xy 154.380946 -393.676886) (xy 154.385772 -393.659868)
			(xy 154.380184 -393.577572) (xy 154.373072 -393.56157) (xy 154.366976 -393.554966) (xy 154.347489 -393.533607)
			(xy 154.314582 -393.486068) (xy 154.289233 -393.434105) (xy 154.272021 -393.378909) (xy 154.263344 -393.321747)
			(xy 154.262836 -393.292838) (xy 153.825956 -393.292838) (xy 153.825524 -393.319012) (xy 153.818327 -393.370863)
			(xy 153.804116 -393.421246) (xy 153.783156 -393.469215) (xy 153.75584 -393.513871) (xy 153.72268 -393.554378)
			(xy 153.703782 -393.572492) (xy 153.696416 -393.57935) (xy 153.688288 -393.596876) (xy 153.682954 -393.687046)
			(xy 153.68905 -393.705334) (xy 153.695654 -393.712954) (xy 153.710547 -393.731004) (xy 153.735614 -393.770519)
			(xy 153.754864 -393.813172) (xy 153.767913 -393.858111) (xy 153.7745 -393.90444) (xy 153.774902 -393.927838)
			(xy 153.774392 -393.953825) (xy 153.766262 -394.00516) (xy 153.750201 -394.05459) (xy 153.726605 -394.1009)
			(xy 153.696055 -394.142948) (xy 153.659304 -394.179699) (xy 153.617256 -394.210249) (xy 153.570946 -394.233845)
			(xy 153.521516 -394.249906) (xy 153.470181 -394.258036) (xy 153.418207 -394.258036) (xy 153.366872 -394.249906)
			(xy 153.317442 -394.233845) (xy 153.271132 -394.210249) (xy 153.229084 -394.179699) (xy 153.192333 -394.142948)
			(xy 153.161783 -394.1009) (xy 153.138187 -394.05459) (xy 153.122126 -394.00516) (xy 153.113996 -393.953825)
			(xy 153.113486 -393.927838) (xy 153.113926 -393.904442) (xy 153.120511 -393.858117) (xy 153.133554 -393.81318)
			(xy 153.152797 -393.770529) (xy 153.177855 -393.731013) (xy 153.192734 -393.712954) (xy 153.199338 -393.705334)
			(xy 153.205434 -393.687046) (xy 153.2001 -393.596876) (xy 153.191972 -393.57935) (xy 153.184606 -393.572492)
			(xy 153.165711 -393.554375) (xy 153.132547 -393.513872) (xy 153.10523 -393.469217) (xy 153.084272 -393.421247)
			(xy 153.070066 -393.370864) (xy 153.06288 -393.319012) (xy 153.062432 -393.292838) (xy 152.62606 -393.292838)
			(xy 152.625657 -393.319013) (xy 152.618459 -393.370867) (xy 152.604244 -393.421251) (xy 152.583278 -393.469221)
			(xy 152.555956 -393.513876) (xy 152.522788 -393.55438) (xy 152.503886 -393.572492) (xy 152.49652 -393.57935)
			(xy 152.488392 -393.596876) (xy 152.483058 -393.687046) (xy 152.489154 -393.705334) (xy 152.495758 -393.712954)
			(xy 152.510652 -393.731004) (xy 152.535718 -393.770519) (xy 152.554968 -393.813172) (xy 152.568017 -393.858111)
			(xy 152.574604 -393.90444) (xy 152.575006 -393.927838) (xy 152.574496 -393.953825) (xy 152.566366 -394.00516)
			(xy 152.550305 -394.05459) (xy 152.526709 -394.1009) (xy 152.496159 -394.142948) (xy 152.459408 -394.179699)
			(xy 152.41736 -394.210249) (xy 152.37105 -394.233845) (xy 152.32162 -394.249906) (xy 152.270285 -394.258036)
			(xy 152.218311 -394.258036) (xy 152.166976 -394.249906) (xy 152.117546 -394.233845) (xy 152.071236 -394.210249)
			(xy 152.029188 -394.179699) (xy 151.992437 -394.142948) (xy 151.961887 -394.1009) (xy 151.938291 -394.05459)
			(xy 151.92223 -394.00516) (xy 151.9141 -393.953825) (xy 151.91359 -393.927838) (xy 151.914029 -393.904442)
			(xy 151.920614 -393.858117) (xy 151.933658 -393.81318) (xy 151.952901 -393.770529) (xy 151.977959 -393.731013)
			(xy 151.992838 -393.712954) (xy 151.999442 -393.705334) (xy 152.005538 -393.687046) (xy 152.000204 -393.596876)
			(xy 151.992076 -393.57935) (xy 151.98471 -393.572492) (xy 151.965816 -393.554374) (xy 151.932652 -393.513871)
			(xy 151.905334 -393.469217) (xy 151.884376 -393.421247) (xy 151.87017 -393.370864) (xy 151.862984 -393.319012)
			(xy 151.862536 -393.292838) (xy 151.425656 -393.292838) (xy 151.425117 -393.321742) (xy 151.416412 -393.378892)
			(xy 151.399192 -393.434076) (xy 151.373851 -393.486034) (xy 151.340967 -393.533579) (xy 151.321516 -393.554966)
			(xy 151.31542 -393.56157) (xy 151.308308 -393.577572) (xy 151.30272 -393.659868) (xy 151.307546 -393.676886)
			(xy 151.312626 -393.683998) (xy 151.327259 -393.70523) (xy 151.350514 -393.75125) (xy 151.366341 -393.800322)
			(xy 151.374357 -393.851257) (xy 151.374856 -393.877038) (xy 151.374346 -393.903025) (xy 151.366216 -393.95436)
			(xy 151.350155 -394.00379) (xy 151.326559 -394.0501) (xy 151.296009 -394.092148) (xy 151.259258 -394.128899)
			(xy 151.21721 -394.159449) (xy 151.1709 -394.183045) (xy 151.12147 -394.199106) (xy 151.070135 -394.207236)
			(xy 151.018161 -394.207236) (xy 150.966826 -394.199106) (xy 150.917396 -394.183045) (xy 150.871086 -394.159449)
			(xy 150.829038 -394.128899) (xy 150.792287 -394.092148) (xy 150.761737 -394.0501) (xy 150.738141 -394.00379)
			(xy 150.72208 -393.95436) (xy 150.71395 -393.903025) (xy 150.71344 -393.877038) (xy 150.713923 -393.851255)
			(xy 150.721929 -393.800314) (xy 150.737753 -393.751236) (xy 150.761009 -393.705213) (xy 150.77567 -393.683998)
			(xy 150.78075 -393.676886) (xy 150.785576 -393.659868) (xy 150.779988 -393.577572) (xy 150.772876 -393.56157)
			(xy 150.76678 -393.554966) (xy 150.747294 -393.533606) (xy 150.714387 -393.486068) (xy 150.689037 -393.434105)
			(xy 150.671825 -393.378909) (xy 150.663148 -393.321747) (xy 150.66264 -393.292838) (xy 150.22576 -393.292838)
			(xy 150.2253 -393.319001) (xy 150.21815 -393.370837) (xy 150.203988 -393.421211) (xy 150.18308 -393.469179)
			(xy 150.155818 -393.513843) (xy 150.122712 -393.554366) (xy 150.10384 -393.572492) (xy 150.096474 -393.57935)
			(xy 150.088346 -393.596876) (xy 150.083012 -393.687046) (xy 150.089108 -393.705334) (xy 150.095712 -393.712954)
			(xy 150.110614 -393.730997) (xy 150.135678 -393.770515) (xy 150.154925 -393.813169) (xy 150.167972 -393.85811)
			(xy 150.174558 -393.90444) (xy 150.17496 -393.927838) (xy 150.17445 -393.953825) (xy 150.16632 -394.00516)
			(xy 150.150259 -394.05459) (xy 150.126663 -394.1009) (xy 150.096113 -394.142948) (xy 150.059362 -394.179699)
			(xy 150.017314 -394.210249) (xy 149.971004 -394.233845) (xy 149.921574 -394.249906) (xy 149.870239 -394.258036)
			(xy 149.818265 -394.258036) (xy 149.76693 -394.249906) (xy 149.7175 -394.233845) (xy 149.67119 -394.210249)
			(xy 149.629142 -394.179699) (xy 149.592391 -394.142948) (xy 149.561841 -394.1009) (xy 149.538245 -394.05459)
			(xy 149.522184 -394.00516) (xy 149.514054 -393.953825) (xy 149.513544 -393.927838) (xy 149.51397 -393.904442)
			(xy 149.520556 -393.858115) (xy 149.533602 -393.813178) (xy 149.552848 -393.770527) (xy 149.57791 -393.731012)
			(xy 149.592792 -393.712954) (xy 149.599396 -393.705334) (xy 149.605492 -393.687046) (xy 149.600158 -393.596876)
			(xy 149.59203 -393.57935) (xy 149.584664 -393.572492) (xy 149.565763 -393.554393) (xy 149.532648 -393.51387)
			(xy 149.50538 -393.469203) (xy 149.484471 -393.421229) (xy 149.470313 -393.370847) (xy 149.463171 -393.319004)
			(xy 149.462744 -393.292838) (xy 149.025864 -393.292838) (xy 149.025249 -393.322996) (xy 149.015755 -393.382559)
			(xy 148.99701 -393.439888) (xy 148.969481 -393.493554) (xy 148.933853 -393.542222) (xy 148.912834 -393.563856)
			(xy 148.90623 -393.57046) (xy 148.89861 -393.587224) (xy 148.893276 -393.67333) (xy 148.89861 -393.69111)
			(xy 148.904452 -393.698476) (xy 148.920958 -393.720465) (xy 148.947233 -393.768758) (xy 148.965165 -393.820729)
			(xy 148.974261 -393.874949) (xy 148.97481 -393.902438) (xy 148.9743 -393.928425) (xy 148.96617 -393.97976)
			(xy 148.950109 -394.02919) (xy 148.926513 -394.0755) (xy 148.895963 -394.117548) (xy 148.859212 -394.154299)
			(xy 148.817164 -394.184849) (xy 148.770854 -394.208445) (xy 148.721424 -394.224506) (xy 148.670089 -394.232636)
			(xy 148.618115 -394.232636) (xy 148.56678 -394.224506) (xy 148.51735 -394.208445) (xy 148.47104 -394.184849)
			(xy 148.428992 -394.154299) (xy 148.392241 -394.117548) (xy 148.361691 -394.0755) (xy 148.338095 -394.02919)
			(xy 148.322034 -393.97976) (xy 148.313904 -393.928425) (xy 148.313394 -393.902438) (xy 148.313948 -393.874948)
			(xy 148.323024 -393.820722) (xy 148.340948 -393.768745) (xy 148.367227 -393.720452) (xy 148.383752 -393.698476)
			(xy 148.389594 -393.69111) (xy 148.394928 -393.67333) (xy 148.389594 -393.587224) (xy 148.381974 -393.57046)
			(xy 148.37537 -393.563856) (xy 148.354326 -393.542242) (xy 148.31868 -393.493577) (xy 148.291141 -393.439908)
			(xy 148.272394 -393.382572) (xy 148.262907 -393.323) (xy 148.26234 -393.292838) (xy 147.825968 -393.292838)
			(xy 147.825352 -393.322996) (xy 147.815858 -393.382559) (xy 147.797113 -393.439888) (xy 147.769584 -393.493554)
			(xy 147.733956 -393.542222) (xy 147.712938 -393.563856) (xy 147.706334 -393.57046) (xy 147.698714 -393.587224)
			(xy 147.69338 -393.67333) (xy 147.698714 -393.69111) (xy 147.704556 -393.698476) (xy 147.721062 -393.720465)
			(xy 147.747337 -393.768758) (xy 147.765269 -393.820729) (xy 147.774365 -393.874949) (xy 147.774914 -393.902438)
			(xy 147.774404 -393.928425) (xy 147.766274 -393.97976) (xy 147.750213 -394.02919) (xy 147.726617 -394.0755)
			(xy 147.696067 -394.117548) (xy 147.659316 -394.154299) (xy 147.617268 -394.184849) (xy 147.570958 -394.208445)
			(xy 147.521528 -394.224506) (xy 147.470193 -394.232636) (xy 147.418219 -394.232636) (xy 147.366884 -394.224506)
			(xy 147.317454 -394.208445) (xy 147.271144 -394.184849) (xy 147.229096 -394.154299) (xy 147.192345 -394.117548)
			(xy 147.161795 -394.0755) (xy 147.138199 -394.02919) (xy 147.122138 -393.97976) (xy 147.114008 -393.928425)
			(xy 147.113498 -393.902438) (xy 147.114051 -393.874948) (xy 147.123127 -393.820722) (xy 147.141052 -393.768745)
			(xy 147.167331 -393.720452) (xy 147.183856 -393.698476) (xy 147.189698 -393.69111) (xy 147.195032 -393.67333)
			(xy 147.189698 -393.587224) (xy 147.182078 -393.57046) (xy 147.175474 -393.563856) (xy 147.15443 -393.542242)
			(xy 147.118785 -393.493577) (xy 147.091245 -393.439908) (xy 147.072498 -393.382572) (xy 147.063011 -393.323)
			(xy 147.062444 -393.292838) (xy 143.330835 -393.292838) (xy 143.359473 -393.337145) (xy 143.382311 -393.38689)
			(xy 143.397805 -393.439388) (xy 143.405637 -393.493562) (xy 143.406114 -393.52093) (xy 143.40565 -393.548182)
			(xy 143.39789 -393.60213) (xy 143.382531 -393.654425) (xy 143.359887 -393.704002) (xy 143.330418 -393.749852)
			(xy 143.294724 -393.791041) (xy 143.253532 -393.826732) (xy 143.207681 -393.856198) (xy 143.158102 -393.878839)
			(xy 143.105806 -393.894195) (xy 143.051858 -393.901952) (xy 143.024606 -393.902438) (xy 142.997235 -393.901984)
			(xy 142.943055 -393.894165) (xy 142.890551 -393.878674) (xy 142.840804 -393.85583) (xy 142.794839 -393.826101)
			(xy 142.773908 -393.808458) (xy 142.766796 -393.802362) (xy 142.749778 -393.796012) (xy 142.664434 -393.796012)
			(xy 142.647416 -393.802362) (xy 142.640304 -393.808458) (xy 142.619371 -393.826099) (xy 142.573403 -393.855823)
			(xy 142.523657 -393.878669) (xy 142.471155 -393.894165) (xy 142.416977 -393.901994) (xy 142.362235 -393.901994)
			(xy 142.308057 -393.894165) (xy 142.255555 -393.878669) (xy 142.205809 -393.855823) (xy 142.159841 -393.826099)
			(xy 142.138908 -393.808458) (xy 142.131796 -393.802362) (xy 142.114778 -393.796012) (xy 142.029434 -393.796012)
			(xy 142.012416 -393.802362) (xy 142.005304 -393.808458) (xy 141.984371 -393.826099) (xy 141.938403 -393.855823)
			(xy 141.888657 -393.878669) (xy 141.836155 -393.894165) (xy 141.781977 -393.901994) (xy 141.727235 -393.901994)
			(xy 141.673057 -393.894165) (xy 141.620555 -393.878669) (xy 141.570809 -393.855823) (xy 141.524841 -393.826099)
			(xy 141.503908 -393.808458) (xy 141.496796 -393.802362) (xy 141.479778 -393.796012) (xy 141.394434 -393.796012)
			(xy 141.377416 -393.802362) (xy 141.370304 -393.808458) (xy 141.349376 -393.826102) (xy 141.303403 -393.855815)
			(xy 141.253654 -393.87865) (xy 141.201152 -393.89414) (xy 141.146976 -393.901966) (xy 141.119606 -393.902438)
			(xy 141.092356 -393.901917) (xy 141.038411 -393.894162) (xy 140.986119 -393.878809) (xy 140.936544 -393.856171)
			(xy 140.890695 -393.826708) (xy 140.849505 -393.79102) (xy 140.813814 -393.749834) (xy 140.784347 -393.703988)
			(xy 140.761704 -393.654415) (xy 140.746346 -393.602124) (xy 140.738586 -393.54818) (xy 140.738098 -393.52093)
			(xy 139.883134 -393.52093) (xy 139.882612 -393.553513) (xy 139.874283 -393.618145) (xy 139.857765 -393.681184)
			(xy 139.83333 -393.741595) (xy 139.801377 -393.79839) (xy 139.76243 -393.850638) (xy 139.717128 -393.897482)
			(xy 139.666213 -393.938155) (xy 139.610518 -393.97199) (xy 139.550958 -393.998433) (xy 139.488507 -394.01705)
			(xy 139.42419 -394.027536) (xy 139.391644 -394.029184) (xy 139.381738 -394.029438) (xy 139.363958 -394.037312)
			(xy 139.307824 -394.095478) (xy 139.30135 -394.102832) (xy 139.294052 -394.120995) (xy 139.2936 -394.130784)
			(xy 139.2936 -394.257022) (xy 139.294157 -394.26811) (xy 139.303481 -394.28823) (xy 139.320394 -394.302572)
			(xy 139.330938 -394.306044) (xy 139.663424 -394.398246) (xy 139.680188 -394.396976) (xy 139.688316 -394.393674)
			(xy 139.724315 -394.37901) (xy 139.79925 -394.358351) (xy 139.876273 -394.347876) (xy 139.915138 -394.347192)
			(xy 139.954238 -394.347868) (xy 139.984639 -394.352018) (xy 145.832828 -394.352018) (xy 145.836899 -394.296396)
			(xy 145.849025 -394.241959) (xy 145.868948 -394.189868) (xy 145.896244 -394.141233) (xy 145.93033 -394.09709)
			(xy 145.970479 -394.058381) (xy 146.015837 -394.02593) (xy 146.065437 -394.000429) (xy 146.118221 -393.982422)
			(xy 146.173064 -393.972292) (xy 146.228798 -393.970255) (xy 146.284235 -393.976355) (xy 146.338192 -393.990461)
			(xy 146.389521 -394.012273) (xy 146.437127 -394.041327) (xy 146.479995 -394.077002) (xy 146.517212 -394.118539)
			(xy 146.547985 -394.165052) (xy 146.571657 -394.215549) (xy 146.587725 -394.268956) (xy 146.595845 -394.324132)
			(xy 146.596354 -394.352018) (xy 146.595845 -394.379904) (xy 146.587725 -394.43508) (xy 146.571657 -394.488487)
			(xy 146.547985 -394.538984) (xy 146.517212 -394.585497) (xy 146.479995 -394.627034) (xy 146.437127 -394.662709)
			(xy 146.389521 -394.691763) (xy 146.338192 -394.713575) (xy 146.284235 -394.727681) (xy 146.228798 -394.733781)
			(xy 146.173064 -394.731744) (xy 146.118221 -394.721614) (xy 146.065437 -394.703607) (xy 146.015837 -394.678106)
			(xy 145.970479 -394.645655) (xy 145.93033 -394.606946) (xy 145.896244 -394.562803) (xy 145.868948 -394.514168)
			(xy 145.849025 -394.462077) (xy 145.836899 -394.40764) (xy 145.832828 -394.352018) (xy 139.984639 -394.352018)
			(xy 140.03172 -394.358445) (xy 140.06957 -394.368274) (xy 140.48105 -394.482066) (xy 140.512253 -394.491166)
			(xy 140.57257 -394.51539) (xy 140.6298 -394.546208) (xy 140.683224 -394.583233) (xy 140.732172 -394.626)
			(xy 140.776029 -394.673974) (xy 140.795502 -394.699998) (xy 140.800836 -394.707364) (xy 140.814552 -394.716762)
			(xy 142.86992 -395.285722) (xy 142.883382 -395.2875) (xy 143.257778 -395.2875) (xy 143.267842 -395.287938)
			(xy 143.286426 -395.295672) (xy 143.293846 -395.302486) (xy 143.423386 -395.432026) (xy 143.428166 -395.436496)
			(xy 143.43948 -395.443065) (xy 143.445738 -395.44498) (xy 145.999708 -396.151862) (xy 146.016472 -396.150846)
			(xy 146.0246 -396.14729) (xy 146.060639 -396.132612) (xy 146.135659 -396.111943) (xy 146.212769 -396.101479)
			(xy 146.251676 -396.100808) (xy 146.290775 -396.101487) (xy 146.368256 -396.11207) (xy 146.406108 -396.12189)
			(xy 146.817842 -396.235682) (xy 146.849086 -396.244761) (xy 146.909472 -396.268991) (xy 146.966762 -396.299837)
			(xy 147.020234 -396.336911) (xy 147.069212 -396.379744) (xy 147.113081 -396.427798) (xy 147.132548 -396.453868)
			(xy 147.137628 -396.461234) (xy 147.151598 -396.470632) (xy 148.735288 -396.909036) (xy 148.752052 -396.90802)
			(xy 148.76018 -396.904464) (xy 148.796221 -396.889811) (xy 148.871246 -396.869206) (xy 148.948354 -396.858834)
			(xy 148.987256 -396.858236) (xy 149.026349 -396.858842) (xy 149.103832 -396.86929) (xy 149.141688 -396.879064)
			(xy 149.553168 -396.992856) (xy 149.584371 -397.001957) (xy 149.644687 -397.026182) (xy 149.701916 -397.057)
			(xy 149.755339 -397.094026) (xy 149.804286 -397.136794) (xy 149.848143 -397.184767) (xy 149.86762 -397.210788)
			(xy 149.8727 -397.2179) (xy 149.88667 -397.227552) (xy 151.21382 -397.594836) (xy 151.230883 -397.599708)
			(xy 151.264435 -397.611272) (xy 151.280876 -397.61795) (xy 152.887172 -398.28343) (xy 152.891859 -398.28523)
			(xy 152.901711 -398.287152) (xy 152.90673 -398.28724) (xy 155.020518 -398.28724) (xy 155.030586 -398.287668)
			(xy 155.049182 -398.295391) (xy 155.056586 -398.302226) (xy 155.06192 -398.30756) (xy 155.080462 -398.31518)
		)
		(stroke
			(width 0)
			(type solid)
		)
		(fill yes)
		(layer "In6.Cu")
		(net "P0V9_CPU1_RT2_2A_2D")
	)
	(gr_poly
		(pts
			(xy 131.08686 -268.65326) (xy 131.087114 -268.632178) (xy 131.087368 -268.627606) (xy 131.090162 -268.60119)
			(xy 131.092702 -268.594586) (xy 131.096875 -268.585648) (xy 131.110845 -268.571743) (xy 131.129074 -268.564246)
			(xy 131.13893 -268.563852) (xy 131.41198 -268.563852) (xy 131.422734 -268.563382) (xy 131.442356 -268.554581)
			(xy 131.449826 -268.546834) (xy 131.506214 -268.483334) (xy 131.512564 -268.463014) (xy 131.511548 -268.452092)
			(xy 131.510587 -268.44317) (xy 131.509572 -268.425252) (xy 131.509516 -268.416278) (xy 131.510038 -268.391023)
			(xy 131.518351 -268.341201) (xy 131.534752 -268.293427) (xy 131.558793 -268.249004) (xy 131.589817 -268.209144)
			(xy 131.626979 -268.174934) (xy 131.669265 -268.147308) (xy 131.715521 -268.127018) (xy 131.764486 -268.114618)
			(xy 131.814824 -268.110447) (xy 131.865162 -268.114618) (xy 131.914127 -268.127018) (xy 131.960383 -268.147308)
			(xy 132.002669 -268.174934) (xy 132.039831 -268.209144) (xy 132.070855 -268.249004) (xy 132.094896 -268.293427)
			(xy 132.111297 -268.341201) (xy 132.11961 -268.391023) (xy 132.120132 -268.416278) (xy 132.12009 -268.425252)
			(xy 132.119072 -268.443171) (xy 132.1181 -268.452092) (xy 132.117084 -268.463014) (xy 132.123434 -268.483334)
			(xy 132.179822 -268.546834) (xy 132.18739 -268.554448) (xy 132.206949 -268.563236) (xy 132.217668 -268.563852)
			(xy 132.35178 -268.563852) (xy 132.362534 -268.563382) (xy 132.382156 -268.554581) (xy 132.389626 -268.546834)
			(xy 132.446014 -268.483334) (xy 132.452364 -268.463014) (xy 132.451348 -268.452092) (xy 132.450387 -268.44317)
			(xy 132.449372 -268.425252) (xy 132.449316 -268.416278) (xy 132.449838 -268.391023) (xy 132.458151 -268.341201)
			(xy 132.474552 -268.293427) (xy 132.498593 -268.249004) (xy 132.529617 -268.209144) (xy 132.566779 -268.174934)
			(xy 132.609065 -268.147308) (xy 132.655321 -268.127018) (xy 132.704286 -268.114618) (xy 132.754624 -268.110447)
			(xy 132.804962 -268.114618) (xy 132.853927 -268.127018) (xy 132.900183 -268.147308) (xy 132.942469 -268.174934)
			(xy 132.979631 -268.209144) (xy 133.010655 -268.249004) (xy 133.034696 -268.293427) (xy 133.051097 -268.341201)
			(xy 133.05941 -268.391023) (xy 133.059932 -268.416278) (xy 133.05989 -268.425252) (xy 133.058872 -268.443171)
			(xy 133.0579 -268.452092) (xy 133.056884 -268.463014) (xy 133.063234 -268.483334) (xy 133.119622 -268.546834)
			(xy 133.12719 -268.554448) (xy 133.146749 -268.563236) (xy 133.157468 -268.563852) (xy 133.291834 -268.563852)
			(xy 133.302583 -268.563371) (xy 133.322188 -268.554557) (xy 133.32968 -268.546834) (xy 133.386068 -268.483334)
			(xy 133.392418 -268.463014) (xy 133.391402 -268.452092) (xy 133.39044 -268.44317) (xy 133.389425 -268.425252)
			(xy 133.38937 -268.416278) (xy 133.389892 -268.391023) (xy 133.398205 -268.341201) (xy 133.414606 -268.293427)
			(xy 133.438647 -268.249004) (xy 133.469671 -268.209144) (xy 133.506833 -268.174934) (xy 133.549119 -268.147308)
			(xy 133.595375 -268.127018) (xy 133.64434 -268.114618) (xy 133.694678 -268.110447) (xy 133.745016 -268.114618)
			(xy 133.793981 -268.127018) (xy 133.840237 -268.147308) (xy 133.882523 -268.174934) (xy 133.919685 -268.209144)
			(xy 133.950709 -268.249004) (xy 133.97475 -268.293427) (xy 133.991151 -268.341201) (xy 133.999464 -268.391023)
			(xy 133.999986 -268.416278) (xy 133.999944 -268.425252) (xy 133.998926 -268.443171) (xy 133.997954 -268.452092)
			(xy 133.996938 -268.463014) (xy 134.003288 -268.483334) (xy 134.059676 -268.546834) (xy 134.067241 -268.554456)
			(xy 134.0868 -268.563261) (xy 134.097522 -268.563852) (xy 134.231888 -268.563852) (xy 134.242641 -268.56338)
			(xy 134.26226 -268.554577) (xy 134.269734 -268.546834) (xy 134.326122 -268.483334) (xy 134.332472 -268.463014)
			(xy 134.331456 -268.452092) (xy 134.330495 -268.44317) (xy 134.329479 -268.425252) (xy 134.329424 -268.416278)
			(xy 134.329946 -268.391023) (xy 134.338259 -268.341201) (xy 134.35466 -268.293427) (xy 134.378701 -268.249004)
			(xy 134.409725 -268.209144) (xy 134.446887 -268.174934) (xy 134.489173 -268.147308) (xy 134.535429 -268.127018)
			(xy 134.584394 -268.114618) (xy 134.634732 -268.110447) (xy 134.68507 -268.114618) (xy 134.734035 -268.127018)
			(xy 134.780291 -268.147308) (xy 134.822577 -268.174934) (xy 134.859739 -268.209144) (xy 134.890763 -268.249004)
			(xy 134.914804 -268.293427) (xy 134.931205 -268.341201) (xy 134.939518 -268.391023) (xy 134.94004 -268.416278)
			(xy 134.939998 -268.425252) (xy 134.93898 -268.443171) (xy 134.938008 -268.452092) (xy 134.936992 -268.463014)
			(xy 134.943342 -268.483334) (xy 134.99973 -268.546834) (xy 135.007298 -268.554447) (xy 135.026858 -268.563232)
			(xy 135.037576 -268.563852) (xy 135.171942 -268.563852) (xy 135.18269 -268.56337) (xy 135.202293 -268.554553)
			(xy 135.209788 -268.546834) (xy 135.266176 -268.483334) (xy 135.272526 -268.463014) (xy 135.27151 -268.452092)
			(xy 135.270548 -268.44317) (xy 135.269533 -268.425252) (xy 135.269478 -268.416278) (xy 135.27 -268.391023)
			(xy 135.278313 -268.341201) (xy 135.294714 -268.293427) (xy 135.318755 -268.249004) (xy 135.349779 -268.209144)
			(xy 135.386941 -268.174934) (xy 135.429227 -268.147308) (xy 135.475483 -268.127018) (xy 135.524448 -268.114618)
			(xy 135.574786 -268.110447) (xy 135.625124 -268.114618) (xy 135.674089 -268.127018) (xy 135.720345 -268.147308)
			(xy 135.762631 -268.174934) (xy 135.799793 -268.209144) (xy 135.830817 -268.249004) (xy 135.854858 -268.293427)
			(xy 135.871259 -268.341201) (xy 135.879572 -268.391023) (xy 135.880094 -268.416278) (xy 135.880052 -268.425252)
			(xy 135.879034 -268.443171) (xy 135.878062 -268.452092) (xy 135.877046 -268.463014) (xy 135.883396 -268.483334)
			(xy 135.939784 -268.546834) (xy 135.94735 -268.554455) (xy 135.966909 -268.563257) (xy 135.97763 -268.563852)
			(xy 136.111996 -268.563852) (xy 136.122748 -268.563379) (xy 136.142365 -268.554574) (xy 136.149842 -268.546834)
			(xy 136.20623 -268.483334) (xy 136.21258 -268.463014) (xy 136.211564 -268.452092) (xy 136.210603 -268.44317)
			(xy 136.209587 -268.425252) (xy 136.209532 -268.416278) (xy 136.210054 -268.391023) (xy 136.218367 -268.341201)
			(xy 136.234768 -268.293427) (xy 136.258809 -268.249004) (xy 136.289833 -268.209144) (xy 136.326995 -268.174934)
			(xy 136.369281 -268.147308) (xy 136.415537 -268.127018) (xy 136.464502 -268.114618) (xy 136.51484 -268.110447)
			(xy 136.565178 -268.114618) (xy 136.614143 -268.127018) (xy 136.660399 -268.147308) (xy 136.702685 -268.174934)
			(xy 136.739847 -268.209144) (xy 136.770871 -268.249004) (xy 136.794912 -268.293427) (xy 136.811313 -268.341201)
			(xy 136.819626 -268.391023) (xy 136.820148 -268.416278) (xy 136.820106 -268.425252) (xy 136.819088 -268.443171)
			(xy 136.818116 -268.452092) (xy 136.8171 -268.463014) (xy 136.82345 -268.483334) (xy 136.879838 -268.546834)
			(xy 136.887407 -268.554446) (xy 136.906966 -268.563227) (xy 136.917684 -268.563852) (xy 137.99185 -268.563852)
			(xy 138.002597 -268.563368) (xy 138.022198 -268.55455) (xy 138.029696 -268.546834) (xy 138.086084 -268.483334)
			(xy 138.092434 -268.463014) (xy 138.091418 -268.452092) (xy 138.090456 -268.44317) (xy 138.089441 -268.425252)
			(xy 138.089386 -268.416278) (xy 138.089908 -268.391023) (xy 138.098221 -268.341201) (xy 138.114622 -268.293427)
			(xy 138.138663 -268.249004) (xy 138.169687 -268.209144) (xy 138.206849 -268.174934) (xy 138.249135 -268.147308)
			(xy 138.295391 -268.127018) (xy 138.344356 -268.114618) (xy 138.394694 -268.110447) (xy 138.445032 -268.114618)
			(xy 138.493997 -268.127018) (xy 138.540253 -268.147308) (xy 138.582539 -268.174934) (xy 138.619701 -268.209144)
			(xy 138.650725 -268.249004) (xy 138.674766 -268.293427) (xy 138.691167 -268.341201) (xy 138.69948 -268.391023)
			(xy 138.700002 -268.416278) (xy 138.69996 -268.425252) (xy 138.698942 -268.443171) (xy 138.69797 -268.452092)
			(xy 138.696954 -268.463014) (xy 138.703304 -268.483334) (xy 138.759692 -268.546834) (xy 138.767258 -268.554453)
			(xy 138.786817 -268.563252) (xy 138.797538 -268.563852) (xy 138.931904 -268.563852) (xy 138.942656 -268.563377)
			(xy 138.96227 -268.55457) (xy 138.96975 -268.546834) (xy 139.026138 -268.483334) (xy 139.032488 -268.463014)
			(xy 139.031472 -268.452092) (xy 139.03051 -268.44317) (xy 139.029495 -268.425252) (xy 139.02944 -268.416278)
			(xy 139.029962 -268.391023) (xy 139.038275 -268.341201) (xy 139.054676 -268.293427) (xy 139.078717 -268.249004)
			(xy 139.109741 -268.209144) (xy 139.146903 -268.174934) (xy 139.189189 -268.147308) (xy 139.235445 -268.127018)
			(xy 139.28441 -268.114618) (xy 139.334748 -268.110447) (xy 139.385086 -268.114618) (xy 139.434051 -268.127018)
			(xy 139.480307 -268.147308) (xy 139.522593 -268.174934) (xy 139.559755 -268.209144) (xy 139.590779 -268.249004)
			(xy 139.61482 -268.293427) (xy 139.631221 -268.341201) (xy 139.639534 -268.391023) (xy 139.640056 -268.416278)
			(xy 139.640014 -268.425252) (xy 139.638996 -268.443171) (xy 139.638024 -268.452092) (xy 139.637008 -268.463014)
			(xy 139.643358 -268.483334) (xy 139.699746 -268.546834) (xy 139.707315 -268.554445) (xy 139.726875 -268.563223)
			(xy 139.737592 -268.563852) (xy 139.871958 -268.563852) (xy 139.882704 -268.563367) (xy 139.902303 -268.554546)
			(xy 139.909804 -268.546834) (xy 139.966192 -268.483334) (xy 139.972542 -268.463014) (xy 139.971526 -268.452092)
			(xy 139.970565 -268.44317) (xy 139.96955 -268.425252) (xy 139.969494 -268.416278) (xy 139.970016 -268.391023)
			(xy 139.978329 -268.341201) (xy 139.99473 -268.293427) (xy 140.018771 -268.249004) (xy 140.049795 -268.209144)
			(xy 140.086957 -268.174934) (xy 140.129243 -268.147308) (xy 140.175499 -268.127018) (xy 140.224464 -268.114618)
			(xy 140.274802 -268.110447) (xy 140.32514 -268.114618) (xy 140.374105 -268.127018) (xy 140.420361 -268.147308)
			(xy 140.462647 -268.174934) (xy 140.499809 -268.209144) (xy 140.530833 -268.249004) (xy 140.554874 -268.293427)
			(xy 140.571275 -268.341201) (xy 140.579588 -268.391023) (xy 140.58011 -268.416278) (xy 140.580068 -268.425252)
			(xy 140.57905 -268.443171) (xy 140.578078 -268.452092) (xy 140.577062 -268.463014) (xy 140.583412 -268.483334)
			(xy 140.6398 -268.546834) (xy 140.647367 -268.554452) (xy 140.666926 -268.563248) (xy 140.677646 -268.563852)
			(xy 140.740892 -268.563852) (xy 140.750764 -268.56338) (xy 140.769049 -268.555923) (xy 140.776452 -268.549374)
			(xy 140.776706 -268.54912) (xy 140.884148 -268.441678) (xy 140.884656 -268.44117) (xy 140.891241 -268.43379)
			(xy 140.8987 -268.415491) (xy 140.899134 -268.40561) (xy 140.899134 -268.008354) (xy 140.898635 -267.997515)
			(xy 140.889684 -267.977773) (xy 140.881862 -267.970254) (xy 140.817092 -267.913612) (xy 140.796264 -267.907262)
			(xy 140.785342 -267.908786) (xy 140.775231 -267.910075) (xy 140.754894 -267.911472) (xy 140.744702 -267.91158)
			(xy 140.72071 -267.911134) (xy 140.673315 -267.903627) (xy 140.627679 -267.888799) (xy 140.584925 -267.867013)
			(xy 140.546105 -267.838807) (xy 140.512176 -267.804875) (xy 140.483974 -267.766053) (xy 140.462191 -267.723297)
			(xy 140.447367 -267.677659) (xy 140.439864 -267.630264) (xy 140.439394 -267.606272) (xy 140.439532 -267.593509)
			(xy 140.441694 -267.568075) (xy 140.443712 -267.555472) (xy 140.443458 -267.555472) (xy 140.44793 -267.531682)
			(xy 140.463395 -267.485814) (xy 140.485907 -267.442963) (xy 140.514901 -267.404202) (xy 140.54965 -267.370505)
			(xy 140.589283 -267.342716) (xy 140.632806 -267.321531) (xy 140.679128 -267.307483) (xy 140.703046 -267.303758)
			(xy 140.715322 -267.301379) (xy 140.735557 -267.286735) (xy 140.741654 -267.275818) (xy 140.777722 -267.202158)
			(xy 140.78258 -267.190602) (xy 140.781634 -267.165578) (xy 140.775944 -267.154406) (xy 140.73124 -267.07719)
			(xy 140.720705 -267.058715) (xy 140.702145 -267.020446) (xy 140.694156 -267.000736) (xy 140.690513 -266.992445)
			(xy 140.678452 -266.978951) (xy 140.662443 -266.97051) (xy 140.653516 -266.968986) (xy 140.572236 -266.958064)
			(xy 140.562838 -266.95781) (xy 140.553534 -266.958685) (xy 140.536456 -266.966233) (xy 140.529564 -266.972542)
			(xy 140.504164 -266.997942) (xy 140.503148 -266.998958) (xy 140.485612 -267.017905) (xy 140.445339 -267.0502)
			(xy 140.400207 -267.075258) (xy 140.351502 -267.092366) (xy 140.300613 -267.101035) (xy 140.274802 -267.101574)
			(xy 140.249547 -267.101082) (xy 140.199726 -267.092768) (xy 140.151952 -267.076368) (xy 140.10753 -267.052328)
			(xy 140.06767 -267.021304) (xy 140.033461 -266.984143) (xy 140.005834 -266.941858) (xy 139.985545 -266.895602)
			(xy 139.973145 -266.846638) (xy 139.968974 -266.7963) (xy 139.973145 -266.745962) (xy 139.985545 -266.696998)
			(xy 140.005834 -266.650742) (xy 140.033461 -266.608457) (xy 140.06767 -266.571296) (xy 140.10753 -266.540272)
			(xy 140.151952 -266.516232) (xy 140.199726 -266.499832) (xy 140.249547 -266.491518) (xy 140.274802 -266.490958)
			(xy 140.300613 -266.491497) (xy 140.3515 -266.500175) (xy 140.400204 -266.517283) (xy 140.44534 -266.542336)
			(xy 140.485621 -266.574619) (xy 140.503148 -266.593574) (xy 140.504164 -266.59459) (xy 140.529564 -266.61999)
			(xy 140.536481 -266.626263) (xy 140.553544 -266.633808) (xy 140.562838 -266.634722) (xy 140.572236 -266.634468)
			(xy 140.66774 -266.621768) (xy 140.68933 -266.60475) (xy 140.69441 -266.591796) (xy 140.709956 -266.554122)
			(xy 140.750371 -266.483352) (xy 140.774928 -266.450826) (xy 140.780208 -266.443488) (xy 140.785728 -266.426285)
			(xy 140.784965 -266.408234) (xy 140.781786 -266.399772) (xy 140.743432 -266.30757) (xy 140.721842 -266.291314)
			(xy 140.708126 -266.289536) (xy 140.682805 -266.285943) (xy 140.633771 -266.271418) (xy 140.587842 -266.24893)
			(xy 140.546298 -266.219108) (xy 140.510302 -266.182783) (xy 140.480857 -266.140971) (xy 140.458786 -266.094839)
			(xy 140.444706 -266.045677) (xy 140.43901 -265.994855) (xy 140.441857 -265.943795) (xy 140.453167 -265.893922)
			(xy 140.472624 -265.846629) (xy 140.499686 -265.803237) (xy 140.533596 -265.764957) (xy 140.553186 -265.748516)
			(xy 140.575011 -265.731665) (xy 140.623441 -265.705317) (xy 140.675819 -265.688104) (xy 140.703046 -265.683746)
			(xy 140.715328 -265.681372) (xy 140.735584 -265.666741) (xy 140.741654 -265.655806) (xy 140.777722 -265.582146)
			(xy 140.782577 -265.57059) (xy 140.781626 -265.545569) (xy 140.775944 -265.534394) (xy 140.73124 -265.457178)
			(xy 140.720699 -265.438707) (xy 140.702136 -265.400438) (xy 140.694156 -265.380724) (xy 140.690511 -265.372434)
			(xy 140.67845 -265.358944) (xy 140.662441 -265.350505) (xy 140.653516 -265.348974) (xy 140.572236 -265.338052)
			(xy 140.562838 -265.337798) (xy 140.553536 -265.338675) (xy 140.536467 -265.346233) (xy 140.529564 -265.35253)
			(xy 140.504164 -265.37793) (xy 140.503148 -265.378946) (xy 140.485609 -265.397888) (xy 140.445334 -265.430174)
			(xy 140.400201 -265.455226) (xy 140.351498 -265.472328) (xy 140.300612 -265.480994) (xy 140.274802 -265.481562)
			(xy 140.249548 -265.48107) (xy 140.199729 -265.472757) (xy 140.151957 -265.456357) (xy 140.107537 -265.432318)
			(xy 140.067679 -265.401295) (xy 140.03347 -265.364136) (xy 140.005845 -265.321852) (xy 139.985556 -265.275598)
			(xy 139.973157 -265.226636) (xy 139.968986 -265.1763) (xy 139.973157 -265.125964) (xy 139.985556 -265.077002)
			(xy 140.005845 -265.030748) (xy 140.03347 -264.988464) (xy 140.067679 -264.951305) (xy 140.107537 -264.920282)
			(xy 140.151957 -264.896243) (xy 140.199729 -264.879843) (xy 140.249548 -264.87153) (xy 140.274802 -264.870946)
			(xy 140.300613 -264.871485) (xy 140.351501 -264.880162) (xy 140.400205 -264.897271) (xy 140.445341 -264.922322)
			(xy 140.485624 -264.954605) (xy 140.503148 -264.973562) (xy 140.504164 -264.974578) (xy 140.529564 -264.999978)
			(xy 140.53648 -265.006252) (xy 140.553544 -265.013799) (xy 140.562838 -265.01471) (xy 140.572236 -265.014456)
			(xy 140.66774 -265.001756) (xy 140.68933 -264.984738) (xy 140.69441 -264.971784) (xy 140.709956 -264.93411)
			(xy 140.750373 -264.863341) (xy 140.774928 -264.830814) (xy 140.780206 -264.823476) (xy 140.785722 -264.806273)
			(xy 140.784955 -264.788225) (xy 140.781786 -264.77976) (xy 140.743432 -264.687558) (xy 140.721842 -264.671302)
			(xy 140.708126 -264.669524) (xy 140.683934 -264.666119) (xy 140.636983 -264.652621) (xy 140.592777 -264.631829)
			(xy 140.552439 -264.604272) (xy 140.516997 -264.570651) (xy 140.487352 -264.531822) (xy 140.464259 -264.488773)
			(xy 140.448306 -264.442599) (xy 140.439898 -264.394476) (xy 140.43914 -264.370058) (xy 140.439394 -264.360152)
			(xy 140.439917 -264.344907) (xy 140.44361 -264.314625) (xy 140.44676 -264.2997) (xy 140.4493 -264.288524)
			(xy 140.443966 -264.266172) (xy 140.388594 -264.196322) (xy 140.38096 -264.187814) (xy 140.360383 -264.17793)
			(xy 140.34897 -264.177272) (xy 140.20038 -264.177272) (xy 140.188944 -264.177808) (xy 140.16834 -264.187742)
			(xy 140.160756 -264.196322) (xy 140.105384 -264.266172) (xy 140.10005 -264.288524) (xy 140.10259 -264.2997)
			(xy 140.105896 -264.315371) (xy 140.109586 -264.347188) (xy 140.109956 -264.3632) (xy 140.109956 -264.36701)
			(xy 140.109375 -264.392224) (xy 140.100963 -264.441948) (xy 140.084494 -264.489614) (xy 140.060416 -264.533926)
			(xy 140.029384 -264.573678) (xy 139.99224 -264.60779) (xy 139.949996 -264.635334) (xy 139.903799 -264.655561)
			(xy 139.854907 -264.667922) (xy 139.804648 -264.67208) (xy 139.754389 -264.667922) (xy 139.705497 -264.655561)
			(xy 139.6593 -264.635334) (xy 139.617056 -264.60779) (xy 139.579912 -264.573678) (xy 139.54888 -264.533926)
			(xy 139.524802 -264.489614) (xy 139.508333 -264.441948) (xy 139.499921 -264.392224) (xy 139.49934 -264.36701)
			(xy 139.49934 -264.36574) (xy 139.499586 -264.34909) (xy 139.503274 -264.315994) (xy 139.506706 -264.2997)
			(xy 139.509246 -264.288524) (xy 139.503912 -264.266172) (xy 139.44854 -264.196322) (xy 139.440909 -264.187806)
			(xy 139.420332 -264.177904) (xy 139.408916 -264.177272) (xy 139.26058 -264.177272) (xy 139.249144 -264.177808)
			(xy 139.22854 -264.187742) (xy 139.220956 -264.196322) (xy 139.165584 -264.266172) (xy 139.16025 -264.288524)
			(xy 139.16279 -264.2997) (xy 139.166096 -264.315371) (xy 139.169786 -264.347188) (xy 139.170156 -264.3632)
			(xy 139.170156 -264.36701) (xy 139.169575 -264.392224) (xy 139.161163 -264.441948) (xy 139.144694 -264.489614)
			(xy 139.120616 -264.533926) (xy 139.089584 -264.573678) (xy 139.05244 -264.60779) (xy 139.010196 -264.635334)
			(xy 138.963999 -264.655561) (xy 138.915107 -264.667922) (xy 138.864848 -264.67208) (xy 138.814589 -264.667922)
			(xy 138.765697 -264.655561) (xy 138.7195 -264.635334) (xy 138.677256 -264.60779) (xy 138.640112 -264.573678)
			(xy 138.60908 -264.533926) (xy 138.585002 -264.489614) (xy 138.568533 -264.441948) (xy 138.560121 -264.392224)
			(xy 138.55954 -264.36701) (xy 138.55954 -264.36574) (xy 138.559786 -264.34909) (xy 138.563474 -264.315994)
			(xy 138.566906 -264.2997) (xy 138.569446 -264.288524) (xy 138.564112 -264.266172) (xy 138.50874 -264.196322)
			(xy 138.501109 -264.187806) (xy 138.480532 -264.177904) (xy 138.469116 -264.177272) (xy 138.320526 -264.177272)
			(xy 138.309085 -264.177798) (xy 138.288467 -264.187721) (xy 138.280902 -264.196322) (xy 138.22553 -264.266172)
			(xy 138.220196 -264.288524) (xy 138.222736 -264.2997) (xy 138.226043 -264.315371) (xy 138.229733 -264.347188)
			(xy 138.230102 -264.3632) (xy 138.230102 -264.36701) (xy 138.229521 -264.392224) (xy 138.221109 -264.441948)
			(xy 138.20464 -264.489614) (xy 138.180562 -264.533926) (xy 138.14953 -264.573678) (xy 138.112386 -264.60779)
			(xy 138.070142 -264.635334) (xy 138.023945 -264.655561) (xy 137.975053 -264.667922) (xy 137.924794 -264.67208)
			(xy 137.874535 -264.667922) (xy 137.825643 -264.655561) (xy 137.779446 -264.635334) (xy 137.737202 -264.60779)
			(xy 137.700058 -264.573678) (xy 137.669026 -264.533926) (xy 137.644948 -264.489614) (xy 137.628479 -264.441948)
			(xy 137.620067 -264.392224) (xy 137.619486 -264.36701) (xy 137.619486 -264.36574) (xy 137.619732 -264.34909)
			(xy 137.623419 -264.315994) (xy 137.626852 -264.2997) (xy 137.629392 -264.288524) (xy 137.624058 -264.266172)
			(xy 137.568686 -264.196322) (xy 137.561052 -264.187815) (xy 137.540474 -264.177935) (xy 137.529062 -264.177272)
			(xy 137.380472 -264.177272) (xy 137.369026 -264.177789) (xy 137.348393 -264.1877) (xy 137.340848 -264.196322)
			(xy 137.285476 -264.266172) (xy 137.280142 -264.288524) (xy 137.282682 -264.2997) (xy 137.285988 -264.315371)
			(xy 137.289678 -264.347188) (xy 137.290048 -264.3632) (xy 137.290048 -264.36701) (xy 137.289467 -264.392224)
			(xy 137.281055 -264.441948) (xy 137.264586 -264.489614) (xy 137.240508 -264.533926) (xy 137.209476 -264.573678)
			(xy 137.172332 -264.60779) (xy 137.130088 -264.635334) (xy 137.083891 -264.655561) (xy 137.034999 -264.667922)
			(xy 136.98474 -264.67208) (xy 136.934481 -264.667922) (xy 136.885589 -264.655561) (xy 136.839392 -264.635334)
			(xy 136.797148 -264.60779) (xy 136.760004 -264.573678) (xy 136.728972 -264.533926) (xy 136.704894 -264.489614)
			(xy 136.688425 -264.441948) (xy 136.680013 -264.392224) (xy 136.679432 -264.36701) (xy 136.679432 -264.36574)
			(xy 136.679678 -264.34909) (xy 136.683366 -264.315994) (xy 136.686798 -264.2997) (xy 136.689338 -264.288524)
			(xy 136.684004 -264.266172) (xy 136.628632 -264.196322) (xy 136.621001 -264.187807) (xy 136.600424 -264.177909)
			(xy 136.589008 -264.177272) (xy 136.440418 -264.177272) (xy 136.428978 -264.1778) (xy 136.408362 -264.187725)
			(xy 136.400794 -264.196322) (xy 136.345422 -264.266172) (xy 136.340088 -264.288524) (xy 136.342628 -264.2997)
			(xy 136.345935 -264.315371) (xy 136.349626 -264.347188) (xy 136.349994 -264.3632) (xy 136.349994 -264.36701)
			(xy 136.349413 -264.392224) (xy 136.341001 -264.441948) (xy 136.324532 -264.489614) (xy 136.300454 -264.533926)
			(xy 136.269422 -264.573678) (xy 136.232278 -264.60779) (xy 136.190034 -264.635334) (xy 136.143837 -264.655561)
			(xy 136.094945 -264.667922) (xy 136.044686 -264.67208) (xy 135.994427 -264.667922) (xy 135.945535 -264.655561)
			(xy 135.899338 -264.635334) (xy 135.857094 -264.60779) (xy 135.81995 -264.573678) (xy 135.788918 -264.533926)
			(xy 135.76484 -264.489614) (xy 135.748371 -264.441948) (xy 135.739959 -264.392224) (xy 135.739378 -264.36701)
			(xy 135.739378 -264.36574) (xy 135.739624 -264.34909) (xy 135.743311 -264.315994) (xy 135.746744 -264.2997)
			(xy 135.749284 -264.288524) (xy 135.74395 -264.266172) (xy 135.688578 -264.196322) (xy 135.680943 -264.187816)
			(xy 135.660366 -264.177939) (xy 135.648954 -264.177272) (xy 135.500364 -264.177272) (xy 135.488919 -264.177791)
			(xy 135.468288 -264.187704) (xy 135.46074 -264.196322) (xy 135.405368 -264.266172) (xy 135.400034 -264.288524)
			(xy 135.402574 -264.2997) (xy 135.40588 -264.315371) (xy 135.409571 -264.347188) (xy 135.40994 -264.3632)
			(xy 135.40994 -264.36701) (xy 135.409359 -264.392224) (xy 135.400947 -264.441948) (xy 135.384478 -264.489614)
			(xy 135.3604 -264.533926) (xy 135.329368 -264.573678) (xy 135.292224 -264.60779) (xy 135.24998 -264.635334)
			(xy 135.203783 -264.655561) (xy 135.154891 -264.667922) (xy 135.104632 -264.67208) (xy 135.054373 -264.667922)
			(xy 135.005481 -264.655561) (xy 134.959284 -264.635334) (xy 134.91704 -264.60779) (xy 134.879896 -264.573678)
			(xy 134.848864 -264.533926) (xy 134.824786 -264.489614) (xy 134.808317 -264.441948) (xy 134.799905 -264.392224)
			(xy 134.799324 -264.36701) (xy 134.799324 -264.36574) (xy 134.79957 -264.34909) (xy 134.803258 -264.315994)
			(xy 134.80669 -264.2997) (xy 134.80923 -264.288524) (xy 134.803896 -264.266172) (xy 134.748524 -264.196322)
			(xy 134.740892 -264.187809) (xy 134.720315 -264.177913) (xy 134.7089 -264.177272) (xy 134.560564 -264.177272)
			(xy 134.549119 -264.177791) (xy 134.528488 -264.187704) (xy 134.52094 -264.196322) (xy 134.465568 -264.266172)
			(xy 134.460234 -264.288524) (xy 134.462774 -264.2997) (xy 134.46608 -264.315371) (xy 134.469771 -264.347188)
			(xy 134.47014 -264.3632) (xy 134.47014 -264.36701) (xy 134.469559 -264.392224) (xy 134.461147 -264.441948)
			(xy 134.444678 -264.489614) (xy 134.4206 -264.533926) (xy 134.389568 -264.573678) (xy 134.352424 -264.60779)
			(xy 134.31018 -264.635334) (xy 134.263983 -264.655561) (xy 134.215091 -264.667922) (xy 134.164832 -264.67208)
			(xy 134.114573 -264.667922) (xy 134.065681 -264.655561) (xy 134.019484 -264.635334) (xy 133.97724 -264.60779)
			(xy 133.940096 -264.573678) (xy 133.909064 -264.533926) (xy 133.884986 -264.489614) (xy 133.868517 -264.441948)
			(xy 133.860105 -264.392224) (xy 133.859524 -264.36701) (xy 133.859524 -264.36574) (xy 133.85977 -264.34909)
			(xy 133.863458 -264.315994) (xy 133.86689 -264.2997) (xy 133.86943 -264.288524) (xy 133.864096 -264.266172)
			(xy 133.808724 -264.196322) (xy 133.801092 -264.187809) (xy 133.780515 -264.177913) (xy 133.7691 -264.177272)
			(xy 133.62051 -264.177272) (xy 133.609071 -264.177802) (xy 133.588458 -264.187728) (xy 133.580886 -264.196322)
			(xy 133.533134 -264.256266) (xy 133.528308 -264.278872) (xy 133.531102 -264.290556) (xy 133.535459 -264.309176)
			(xy 133.540166 -264.347128) (xy 133.5405 -264.366248) (xy 133.540013 -264.391058) (xy 133.532251 -264.440066)
			(xy 133.516918 -264.487256) (xy 133.494391 -264.531467) (xy 133.465226 -264.57161) (xy 133.43014 -264.606696)
			(xy 133.389997 -264.635861) (xy 133.345786 -264.658388) (xy 133.298596 -264.673721) (xy 133.249588 -264.681483)
			(xy 133.199968 -264.681483) (xy 133.15096 -264.673721) (xy 133.10377 -264.658388) (xy 133.059559 -264.635861)
			(xy 133.019416 -264.606696) (xy 132.98433 -264.57161) (xy 132.955165 -264.531467) (xy 132.932638 -264.487256)
			(xy 132.917305 -264.440066) (xy 132.909543 -264.391058) (xy 132.909056 -264.366248) (xy 132.909567 -264.341306)
			(xy 132.917472 -264.29205) (xy 132.924804 -264.268204) (xy 132.924296 -264.266172) (xy 132.86867 -264.196322)
			(xy 132.861035 -264.187818) (xy 132.840457 -264.177944) (xy 132.829046 -264.177272) (xy 132.680456 -264.177272)
			(xy 132.669012 -264.177792) (xy 132.648384 -264.187708) (xy 132.640832 -264.196322) (xy 132.58546 -264.266172)
			(xy 132.580126 -264.288524) (xy 132.582666 -264.2997) (xy 132.585972 -264.315371) (xy 132.589663 -264.347188)
			(xy 132.590032 -264.3632) (xy 132.590032 -264.36701) (xy 132.589501 -264.39096) (xy 132.581895 -264.438256)
			(xy 132.566996 -264.483783) (xy 132.54517 -264.526425) (xy 132.516953 -264.565135) (xy 132.483037 -264.598964)
			(xy 132.444254 -264.627082) (xy 132.401556 -264.648798) (xy 132.35599 -264.663579) (xy 132.308676 -264.671064)
			(xy 132.284724 -264.671556) (xy 132.26073 -264.671087) (xy 132.213333 -264.663584) (xy 132.167692 -264.64876)
			(xy 132.124933 -264.626978) (xy 132.086107 -264.598776) (xy 132.052171 -264.564848) (xy 132.023959 -264.526029)
			(xy 132.002168 -264.483274) (xy 131.987332 -264.437637) (xy 131.979818 -264.390242) (xy 131.979416 -264.366248)
			(xy 131.979814 -264.344639) (xy 131.985946 -264.301858) (xy 131.99804 -264.260366) (xy 132.006594 -264.240518)
			(xy 132.008626 -264.235946) (xy 132.011166 -264.225278) (xy 132.012783 -264.216789) (xy 132.010872 -264.199626)
			(xy 132.003371 -264.184071) (xy 131.99745 -264.17778) (xy 131.636008 -263.816338) (xy 131.632452 -263.813798)
			(xy 131.610962 -263.797899) (xy 131.573161 -263.760108) (xy 131.557268 -263.738614) (xy 131.554728 -263.735058)
			(xy 131.244086 -263.424416) (xy 131.241008 -263.421276) (xy 131.235897 -263.414123) (xy 131.233926 -263.410192)
			(xy 131.223766 -263.387586) (xy 131.217162 -263.380982) (xy 131.18973 -263.35355) (xy 131.182618 -263.346184)
			(xy 131.163822 -263.338564) (xy 130.323082 -263.338564) (xy 130.311142 -263.3392) (xy 130.289802 -263.349921)
			(xy 130.282188 -263.359138) (xy 130.230372 -263.429242) (xy 130.228594 -263.440926) (xy 130.23872 -263.46867)
			(xy 130.249583 -263.526714) (xy 130.250184 -263.556242) (xy 130.249698 -263.581032) (xy 130.241942 -263.63)
			(xy 130.226621 -263.677153) (xy 130.204112 -263.721328) (xy 130.17497 -263.761439) (xy 130.139913 -263.796496)
			(xy 130.099802 -263.825638) (xy 130.055627 -263.848147) (xy 130.008474 -263.863468) (xy 129.959506 -263.871224)
			(xy 129.909926 -263.871224) (xy 129.860958 -263.863468) (xy 129.813805 -263.848147) (xy 129.76963 -263.825638)
			(xy 129.729519 -263.796496) (xy 129.694462 -263.761439) (xy 129.66532 -263.721328) (xy 129.642811 -263.677153)
			(xy 129.62749 -263.63) (xy 129.619734 -263.581032) (xy 129.619248 -263.556242) (xy 129.619898 -263.526641)
			(xy 129.6309 -263.468471) (xy 129.641092 -263.440672) (xy 129.63906 -263.429242) (xy 129.587244 -263.359138)
			(xy 129.579631 -263.349914) (xy 129.558294 -263.33918) (xy 129.54635 -263.338564) (xy 129.383028 -263.338564)
			(xy 129.371094 -263.339211) (xy 129.349773 -263.349945) (xy 129.342134 -263.359138) (xy 129.287524 -263.433306)
			(xy 129.28346 -263.456674) (xy 129.287016 -263.468358) (xy 129.293047 -263.489828) (xy 129.299555 -263.533945)
			(xy 129.29997 -263.556242) (xy 129.299448 -263.581497) (xy 129.291135 -263.631319) (xy 129.274734 -263.679093)
			(xy 129.250693 -263.723516) (xy 129.219669 -263.763376) (xy 129.182507 -263.797586) (xy 129.140221 -263.825212)
			(xy 129.093965 -263.845502) (xy 129.045 -263.857902) (xy 128.994662 -263.862073) (xy 128.944324 -263.857902)
			(xy 128.895359 -263.845502) (xy 128.849103 -263.825212) (xy 128.806817 -263.797586) (xy 128.769655 -263.763376)
			(xy 128.738631 -263.723516) (xy 128.71459 -263.679093) (xy 128.698189 -263.631319) (xy 128.689876 -263.581497)
			(xy 128.689354 -263.556242) (xy 128.689776 -263.534473) (xy 128.696019 -263.491382) (xy 128.7018 -263.47039)
			(xy 128.702816 -263.466326) (xy 128.703832 -263.459468) (xy 128.70462 -263.449761) (xy 128.69965 -263.43095)
			(xy 128.69418 -263.422892) (xy 128.64719 -263.359138) (xy 128.639574 -263.349923) (xy 128.618236 -263.339212)
			(xy 128.606296 -263.338564) (xy 128.443228 -263.338564) (xy 128.431294 -263.339211) (xy 128.409973 -263.349945)
			(xy 128.402334 -263.359138) (xy 128.350518 -263.429242) (xy 128.34874 -263.440926) (xy 128.35891 -263.468665)
			(xy 128.369908 -263.526706) (xy 128.370584 -263.556242) (xy 128.370097 -263.581052) (xy 128.362335 -263.63006)
			(xy 128.347002 -263.67725) (xy 128.324475 -263.721461) (xy 128.29531 -263.761604) (xy 128.260224 -263.79669)
			(xy 128.220081 -263.825855) (xy 128.17587 -263.848382) (xy 128.12868 -263.863715) (xy 128.079672 -263.871477)
			(xy 128.030052 -263.871477) (xy 127.981044 -263.863715) (xy 127.933854 -263.848382) (xy 127.889643 -263.825855)
			(xy 127.8495 -263.79669) (xy 127.814414 -263.761604) (xy 127.785249 -263.721461) (xy 127.762722 -263.67725)
			(xy 127.747389 -263.63006) (xy 127.739627 -263.581052) (xy 127.73914 -263.556242) (xy 127.73986 -263.526631)
			(xy 127.750987 -263.468461) (xy 127.761238 -263.440672) (xy 127.759206 -263.429242) (xy 127.70739 -263.359138)
			(xy 127.699774 -263.349923) (xy 127.678436 -263.339212) (xy 127.666496 -263.338564) (xy 127.503174 -263.338564)
			(xy 127.491235 -263.339201) (xy 127.469898 -263.349924) (xy 127.46228 -263.359138) (xy 127.40767 -263.433306)
			(xy 127.403606 -263.456674) (xy 127.407162 -263.468358) (xy 127.413193 -263.489828) (xy 127.419702 -263.533945)
			(xy 127.420116 -263.556242) (xy 127.419594 -263.581497) (xy 127.411281 -263.631319) (xy 127.39488 -263.679093)
			(xy 127.370839 -263.723516) (xy 127.339815 -263.763376) (xy 127.302653 -263.797586) (xy 127.260367 -263.825212)
			(xy 127.214111 -263.845502) (xy 127.165146 -263.857902) (xy 127.114808 -263.862073) (xy 127.06447 -263.857902)
			(xy 127.015505 -263.845502) (xy 126.969249 -263.825212) (xy 126.926963 -263.797586) (xy 126.889801 -263.763376)
			(xy 126.858777 -263.723516) (xy 126.834736 -263.679093) (xy 126.818335 -263.631319) (xy 126.810022 -263.581497)
			(xy 126.8095 -263.556242) (xy 126.809922 -263.534472) (xy 126.816164 -263.491382) (xy 126.821946 -263.47039)
			(xy 126.822962 -263.466326) (xy 126.823978 -263.459468) (xy 126.824766 -263.449762) (xy 126.819791 -263.430953)
			(xy 126.814326 -263.422892) (xy 126.767336 -263.359138) (xy 126.759723 -263.349915) (xy 126.738386 -263.339185)
			(xy 126.726442 -263.338564) (xy 125.623066 -263.338564) (xy 125.611127 -263.339203) (xy 125.589794 -263.349928)
			(xy 125.582172 -263.359138) (xy 125.527562 -263.433306) (xy 125.523498 -263.456674) (xy 125.527054 -263.468358)
			(xy 125.533085 -263.489828) (xy 125.539595 -263.533945) (xy 125.540008 -263.556242) (xy 125.539486 -263.581497)
			(xy 125.531173 -263.631319) (xy 125.514772 -263.679093) (xy 125.490731 -263.723516) (xy 125.459707 -263.763376)
			(xy 125.422545 -263.797586) (xy 125.380259 -263.825212) (xy 125.334003 -263.845502) (xy 125.285038 -263.857902)
			(xy 125.2347 -263.862073) (xy 125.184362 -263.857902) (xy 125.135397 -263.845502) (xy 125.089141 -263.825212)
			(xy 125.046855 -263.797586) (xy 125.009693 -263.763376) (xy 124.978669 -263.723516) (xy 124.954628 -263.679093)
			(xy 124.938227 -263.631319) (xy 124.929914 -263.581497) (xy 124.929392 -263.556242) (xy 124.929814 -263.534472)
			(xy 124.936056 -263.491382) (xy 124.941838 -263.47039) (xy 124.942854 -263.466326) (xy 124.94387 -263.459468)
			(xy 124.944658 -263.449762) (xy 124.939682 -263.430954) (xy 124.934218 -263.422892) (xy 124.887228 -263.359138)
			(xy 124.879614 -263.349916) (xy 124.858277 -263.339189) (xy 124.846334 -263.338564) (xy 124.085858 -263.338564)
			(xy 124.076017 -263.338035) (xy 124.057842 -263.330462) (xy 124.050552 -263.323832) (xy 123.779788 -263.053068)
			(xy 123.767342 -263.04621) (xy 123.759976 -263.044686) (xy 123.735689 -263.038912) (xy 123.689273 -263.02054)
			(xy 123.646463 -262.994866) (xy 123.608398 -262.962571) (xy 123.576091 -262.924516) (xy 123.550403 -262.881714)
			(xy 123.532017 -262.835305) (xy 123.526296 -262.811006) (xy 123.524772 -262.80364) (xy 123.517914 -262.791194)
			(xy 123.19127 -262.46455) (xy 123.184158 -262.457184) (xy 123.165362 -262.449564) (xy 123.142502 -262.449564)
			(xy 123.132491 -262.450051) (xy 123.113993 -262.457709) (xy 123.09983 -262.471861) (xy 123.092159 -262.490354)
			(xy 123.091702 -262.500364) (xy 123.091702 -262.51027) (xy 123.098814 -262.528304) (xy 123.105672 -262.535416)
			(xy 123.121413 -262.552567) (xy 123.148042 -262.59075) (xy 123.168568 -262.632532) (xy 123.182514 -262.676945)
			(xy 123.189559 -262.72296) (xy 123.19 -262.746236) (xy 123.189478 -262.771491) (xy 123.181165 -262.821313)
			(xy 123.164764 -262.869087) (xy 123.140723 -262.91351) (xy 123.109699 -262.95337) (xy 123.072537 -262.98758)
			(xy 123.030251 -263.015206) (xy 122.983995 -263.035496) (xy 122.93503 -263.047896) (xy 122.884692 -263.052067)
			(xy 122.834354 -263.047896) (xy 122.785389 -263.035496) (xy 122.739133 -263.015206) (xy 122.696847 -262.98758)
			(xy 122.659685 -262.95337) (xy 122.628661 -262.91351) (xy 122.60462 -262.869087) (xy 122.588219 -262.821313)
			(xy 122.579906 -262.771491) (xy 122.579384 -262.746236) (xy 122.579893 -262.720503) (xy 122.588491 -262.66976)
			(xy 122.605499 -262.621186) (xy 122.617484 -262.598408) (xy 122.624088 -262.586724) (xy 122.62358 -262.5598)
			(xy 122.573542 -262.474456) (xy 122.568713 -262.467049) (xy 122.555076 -262.455817) (xy 122.538435 -262.449883)
			(xy 122.5296 -262.449564) (xy 122.29973 -262.449564) (xy 122.290899 -262.449901) (xy 122.274266 -262.455833)
			(xy 122.260644 -262.46707) (xy 122.255788 -262.474456) (xy 122.20575 -262.5598) (xy 122.205242 -262.586724)
			(xy 122.211846 -262.598408) (xy 122.223814 -262.621192) (xy 122.24079 -262.669771) (xy 122.249405 -262.720506)
			(xy 122.249946 -262.746236) (xy 122.249424 -262.771491) (xy 122.241111 -262.821313) (xy 122.22471 -262.869087)
			(xy 122.200669 -262.91351) (xy 122.169645 -262.95337) (xy 122.132483 -262.98758) (xy 122.090197 -263.015206)
			(xy 122.043941 -263.035496) (xy 121.994976 -263.047896) (xy 121.944638 -263.052067) (xy 121.8943 -263.047896)
			(xy 121.845335 -263.035496) (xy 121.799079 -263.015206) (xy 121.756793 -262.98758) (xy 121.719631 -262.95337)
			(xy 121.688607 -262.91351) (xy 121.664566 -262.869087) (xy 121.648165 -262.821313) (xy 121.639852 -262.771491)
			(xy 121.63933 -262.746236) (xy 121.639839 -262.720503) (xy 121.648439 -262.669761) (xy 121.66545 -262.621188)
			(xy 121.67743 -262.598408) (xy 121.684034 -262.586724) (xy 121.683526 -262.5598) (xy 121.633488 -262.474456)
			(xy 121.628657 -262.467055) (xy 121.615017 -262.455838) (xy 121.598378 -262.449921) (xy 121.589546 -262.449564)
			(xy 119.640858 -262.449564) (xy 119.631017 -262.449035) (xy 119.612842 -262.441462) (xy 119.605552 -262.434832)
			(xy 119.00027 -261.82955) (xy 118.993158 -261.822184) (xy 118.974362 -261.814564) (xy 117.79631 -261.814564)
			(xy 117.793262 -261.814564) (xy 117.781582 -261.815862) (xy 117.761211 -261.827523) (xy 117.754146 -261.836916)
			(xy 117.750844 -261.842758) (xy 117.712998 -261.91845) (xy 117.708992 -261.927581) (xy 117.707546 -261.947449)
			(xy 117.710204 -261.957058) (xy 117.716046 -261.974838) (xy 117.720364 -261.980934) (xy 117.735394 -262.002891)
			(xy 117.759216 -262.050468) (xy 117.77542 -262.101148) (xy 117.783618 -262.15372) (xy 117.784118 -262.180324)
			(xy 117.784118 -262.187436) (xy 117.783065 -262.214056) (xy 117.773752 -262.266507) (xy 117.756453 -262.316892)
			(xy 117.731583 -262.364002) (xy 117.699738 -262.406707) (xy 117.661681 -262.443984) (xy 117.618326 -262.474938)
			(xy 117.570711 -262.498827) (xy 117.519979 -262.515079) (xy 117.467346 -262.523304) (xy 117.414074 -262.523304)
			(xy 117.361441 -262.515079) (xy 117.310709 -262.498827) (xy 117.263094 -262.474938) (xy 117.219739 -262.443984)
			(xy 117.181682 -262.406707) (xy 117.149837 -262.364002) (xy 117.124967 -262.316892) (xy 117.107668 -262.266507)
			(xy 117.098355 -262.214056) (xy 117.097302 -262.187436) (xy 117.097302 -262.180324) (xy 117.097798 -262.15372)
			(xy 117.105995 -262.101146) (xy 117.122195 -262.050463) (xy 117.146013 -262.002883) (xy 117.161056 -261.980934)
			(xy 117.165374 -261.974838) (xy 117.171216 -261.957058) (xy 117.173974 -261.947458) (xy 117.172538 -261.927551)
			(xy 117.168422 -261.91845) (xy 117.130576 -261.842758) (xy 117.127274 -261.836916) (xy 117.120171 -261.827478)
			(xy 117.099649 -261.815838) (xy 117.087904 -261.814564) (xy 116.661438 -261.814564) (xy 116.651598 -261.814031)
			(xy 116.633429 -261.806454) (xy 116.626132 -261.799832) (xy 116.445792 -261.619492) (xy 116.437274 -261.61178)
			(xy 116.415579 -261.604273) (xy 116.392777 -261.606933) (xy 116.3828 -261.612634) (xy 116.382546 -261.612634)
			(xy 116.361756 -261.625373) (xy 116.317344 -261.645497) (xy 116.270535 -261.659145) (xy 116.222267 -261.666045)
			(xy 116.197888 -261.666482) (xy 116.191538 -261.666482) (xy 116.164878 -261.665491) (xy 116.112333 -261.65628)
			(xy 116.061844 -261.639052) (xy 116.014628 -261.614223) (xy 115.97182 -261.58239) (xy 115.93445 -261.544319)
			(xy 115.903419 -261.500926) (xy 115.879473 -261.453256) (xy 115.863188 -261.402455) (xy 115.854956 -261.349748)
			(xy 115.85448 -261.323074) (xy 115.855011 -261.29609) (xy 115.863457 -261.242786) (xy 115.880137 -261.19146)
			(xy 115.90464 -261.143375) (xy 115.936363 -261.099715) (xy 115.974526 -261.061554) (xy 116.018187 -261.029833)
			(xy 116.066273 -261.005332) (xy 116.1176 -260.988654) (xy 116.170904 -260.98021) (xy 116.197888 -260.979666)
			(xy 116.225361 -260.980228) (xy 116.279596 -260.989039) (xy 116.305838 -260.997192) (xy 116.317522 -261.001002)
			(xy 116.341652 -260.997192) (xy 116.416582 -260.942836) (xy 116.425957 -260.935221) (xy 116.436939 -260.913747)
			(xy 116.437664 -260.901688) (xy 116.437664 -260.2611) (xy 116.43724 -260.251031) (xy 116.429522 -260.232429)
			(xy 116.422678 -260.225032) (xy 116.419122 -260.221476) (xy 116.349526 -260.17347) (xy 116.341099 -260.16827)
			(xy 116.32176 -260.164102) (xy 116.311934 -260.165342) (xy 116.302536 -260.166866) (xy 116.298472 -260.16839)
			(xy 116.270327 -260.177868) (xy 116.211831 -260.188094) (xy 116.18214 -260.18871) (xy 116.155151 -260.188211)
			(xy 116.101836 -260.179773) (xy 116.050497 -260.163097) (xy 116.0024 -260.138595) (xy 115.958728 -260.106871)
			(xy 115.920557 -260.068704) (xy 115.888827 -260.025036) (xy 115.864319 -259.976942) (xy 115.847637 -259.925605)
			(xy 115.839192 -259.872291) (xy 115.838732 -259.845302) (xy 115.839162 -259.820583) (xy 115.846248 -259.771654)
			(xy 115.860274 -259.724247) (xy 115.88095 -259.679339) (xy 115.90785 -259.637859) (xy 115.923822 -259.618988)
			(xy 115.924076 -259.61848) (xy 115.928602 -259.612974) (xy 115.934653 -259.600077) (xy 115.936014 -259.59308)
			(xy 115.936873 -259.58576) (xy 115.934798 -259.571176) (xy 115.93195 -259.564378) (xy 115.894866 -259.482336)
			(xy 115.88877 -259.46862) (xy 115.863624 -259.452364) (xy 113.915952 -259.452364) (xy 113.906243 -259.452802)
			(xy 113.88822 -259.460032) (xy 113.874173 -259.47344) (xy 113.869724 -259.482082) (xy 113.832386 -259.564378)
			(xy 113.828821 -259.573356) (xy 113.82798 -259.592639) (xy 113.834302 -259.610875) (xy 113.84026 -259.61848)
			(xy 113.840514 -259.618988) (xy 113.856483 -259.637863) (xy 113.883397 -259.679336) (xy 113.904082 -259.724242)
			(xy 113.918109 -259.771651) (xy 113.925188 -259.820582) (xy 113.925604 -259.845302) (xy 113.925124 -259.871001)
			(xy 113.917463 -259.921825) (xy 113.902314 -259.970939) (xy 113.880013 -260.017247) (xy 113.85106 -260.059714)
			(xy 113.8161 -260.097391) (xy 113.775916 -260.129437) (xy 113.731404 -260.155136) (xy 113.683559 -260.173913)
			(xy 113.63345 -260.185351) (xy 113.582196 -260.189192) (xy 113.530942 -260.185351) (xy 113.480833 -260.173913)
			(xy 113.432988 -260.155136) (xy 113.388476 -260.129437) (xy 113.348292 -260.097391) (xy 113.313332 -260.059714)
			(xy 113.284379 -260.017247) (xy 113.262078 -259.970939) (xy 113.246929 -259.921825) (xy 113.239268 -259.871001)
			(xy 113.238788 -259.845302) (xy 113.239217 -259.820582) (xy 113.246303 -259.771653) (xy 113.260327 -259.724245)
			(xy 113.281002 -259.679336) (xy 113.307899 -259.637853) (xy 113.323878 -259.618988) (xy 113.324132 -259.61848)
			(xy 113.328661 -259.612976) (xy 113.334718 -259.600079) (xy 113.33607 -259.59308) (xy 113.336929 -259.58576)
			(xy 113.334852 -259.571177) (xy 113.332006 -259.564378) (xy 113.294922 -259.482336) (xy 113.288826 -259.46862)
			(xy 113.26368 -259.452364) (xy 113.029746 -259.452364) (xy 113.019682 -259.452799) (xy 113.001097 -259.460534)
			(xy 112.993678 -259.46735) (xy 112.990884 -259.470144) (xy 112.98174 -259.473954) (xy 112.977172 -259.475704)
			(xy 112.96758 -259.477619) (xy 112.96269 -259.477764) (xy 111.886238 -259.477764) (xy 111.876398 -259.477231)
			(xy 111.858229 -259.469654) (xy 111.850932 -259.463032) (xy 111.517176 -259.129276) (xy 111.510064 -259.12191)
			(xy 111.491268 -259.11429) (xy 111.459772 -259.11429) (xy 111.451136 -259.117338) (xy 111.422425 -259.127266)
			(xy 111.362636 -259.137999) (xy 111.332264 -259.138674) (xy 111.305494 -259.138159) (xy 111.252604 -259.129846)
			(xy 111.201645 -259.113427) (xy 111.15385 -259.0893) (xy 111.110378 -259.05805) (xy 111.072281 -259.020432)
			(xy 111.040482 -258.977359) (xy 111.015752 -258.929873) (xy 110.99869 -258.879125) (xy 110.989708 -258.826345)
			(xy 110.988856 -258.799584) (xy 110.988856 -258.795012) (xy 110.989623 -258.762666) (xy 111.00177 -258.699123)
			(xy 111.012986 -258.668774) (xy 111.018574 -258.65455) (xy 111.012732 -258.624832) (xy 110.96625 -258.57835)
			(xy 110.959138 -258.570984) (xy 110.940342 -258.563364) (xy 109.255814 -258.563364) (xy 109.243834 -258.564008)
			(xy 109.222486 -258.574881) (xy 109.21492 -258.584192) (xy 109.169962 -258.645152) (xy 109.165381 -258.651851)
			(xy 109.160341 -258.667267) (xy 109.160056 -258.675378) (xy 109.160056 -258.692904) (xy 109.162088 -258.700016)
			(xy 109.16839 -258.723322) (xy 109.175154 -258.771126) (xy 109.17555 -258.795266) (xy 109.17555 -258.797044)
			(xy 109.17555 -258.798568) (xy 109.174795 -258.825196) (xy 109.166071 -258.877745) (xy 109.149338 -258.928317)
			(xy 109.124999 -258.9757) (xy 109.093636 -259.018756) (xy 109.056001 -259.056455) (xy 109.012998 -259.087891)
			(xy 108.965657 -259.112311) (xy 108.915114 -259.12913) (xy 108.86258 -259.137944) (xy 108.835952 -259.138674)
			(xy 108.831888 -259.138674) (xy 108.806119 -259.13819) (xy 108.755166 -259.130445) (xy 108.705941 -259.115177)
			(xy 108.682536 -259.104384) (xy 108.670598 -259.098542) (xy 108.644436 -259.100066) (xy 108.603542 -259.12572)
			(xy 108.596684 -259.129276) (xy 108.572046 -259.138166) (xy 108.561378 -259.1435) (xy 108.551518 -259.150737)
			(xy 108.539445 -259.171966) (xy 108.538264 -259.18414) (xy 108.538264 -259.44576) (xy 108.538604 -259.454369)
			(xy 108.544295 -259.470619) (xy 108.555022 -259.484087) (xy 108.56214 -259.48894) (xy 108.633006 -259.533644)
			(xy 108.638536 -259.536881) (xy 108.65075 -259.540746) (xy 108.657136 -259.541264) (xy 108.670344 -259.542026)
			(xy 108.67771 -259.53847) (xy 108.701801 -259.526934) (xy 108.752663 -259.510629) (xy 108.805436 -259.502388)
			(xy 108.832142 -259.501894) (xy 108.859125 -259.502426) (xy 108.912426 -259.510874) (xy 108.963749 -259.527556)
			(xy 109.011831 -259.55206) (xy 109.055487 -259.583784) (xy 109.093645 -259.621946) (xy 109.125363 -259.665607)
			(xy 109.149861 -259.713692) (xy 109.166536 -259.765017) (xy 109.174977 -259.818319) (xy 109.17555 -259.845302)
			(xy 110.988351 -259.845302) (xy 110.992381 -259.792804) (xy 111.004378 -259.741536) (xy 111.024061 -259.692701)
			(xy 111.050967 -259.647442) (xy 111.084467 -259.606821) (xy 111.123775 -259.57179) (xy 111.16797 -259.54317)
			(xy 111.216015 -259.521631) (xy 111.266786 -259.507679) (xy 111.319091 -259.501641) (xy 111.371705 -259.503658)
			(xy 111.423395 -259.513682) (xy 111.472948 -259.53148) (xy 111.519204 -259.556633) (xy 111.561078 -259.588552)
			(xy 111.59759 -259.62649) (xy 111.627882 -259.669556) (xy 111.651245 -259.716741) (xy 111.667131 -259.76694)
			(xy 111.675168 -259.818976) (xy 111.675672 -259.845302) (xy 111.675168 -259.871628) (xy 111.667131 -259.923664)
			(xy 111.651245 -259.973863) (xy 111.627882 -260.021048) (xy 111.59759 -260.064114) (xy 111.561078 -260.102052)
			(xy 111.519204 -260.133971) (xy 111.472948 -260.159124) (xy 111.423395 -260.176922) (xy 111.371705 -260.186946)
			(xy 111.319091 -260.188963) (xy 111.266786 -260.182925) (xy 111.216015 -260.168973) (xy 111.16797 -260.147434)
			(xy 111.123775 -260.118814) (xy 111.084467 -260.083783) (xy 111.050967 -260.043162) (xy 111.024061 -259.997903)
			(xy 111.004378 -259.949068) (xy 110.992381 -259.8978) (xy 110.988351 -259.845302) (xy 109.17555 -259.845302)
			(xy 109.175041 -259.872035) (xy 109.166755 -259.924854) (xy 109.150385 -259.975751) (xy 109.126326 -260.023497)
			(xy 109.095158 -260.066938) (xy 109.057635 -260.105025) (xy 109.014664 -260.136836) (xy 108.967282 -260.161605)
			(xy 108.916634 -260.178732) (xy 108.863944 -260.187804) (xy 108.837222 -260.18871) (xy 108.831888 -260.18871)
			(xy 108.806119 -260.188226) (xy 108.755165 -260.180482) (xy 108.70594 -260.165216) (xy 108.682536 -260.15442)
			(xy 108.670598 -260.148578) (xy 108.644436 -260.150102) (xy 108.603542 -260.175756) (xy 108.596684 -260.179312)
			(xy 108.572046 -260.188202) (xy 108.561378 -260.193536) (xy 108.551523 -260.200775) (xy 108.539466 -260.222005)
			(xy 108.538264 -260.234176) (xy 108.538264 -260.881114) (xy 108.538702 -260.890536) (xy 108.545474 -260.908125)
			(xy 108.551472 -260.915404) (xy 108.596176 -260.964426) (xy 108.599291 -260.967688) (xy 108.606449 -260.973173)
			(xy 108.6104 -260.975348) (xy 108.619798 -260.980174) (xy 108.629704 -260.98119) (xy 108.654944 -260.983996)
			(xy 108.704264 -260.996091) (xy 108.751266 -261.015317) (xy 108.794925 -261.041253) (xy 108.83429 -261.073334)
			(xy 108.868503 -261.110862) (xy 108.896817 -261.153017) (xy 108.918616 -261.198883) (xy 108.933424 -261.247457)
			(xy 108.940919 -261.297683) (xy 108.941362 -261.323074) (xy 109.204001 -261.323074) (xy 109.208031 -261.270576)
			(xy 109.220028 -261.219308) (xy 109.239711 -261.170473) (xy 109.266617 -261.125214) (xy 109.300117 -261.084593)
			(xy 109.339425 -261.049562) (xy 109.38362 -261.020942) (xy 109.431665 -260.999403) (xy 109.482436 -260.985451)
			(xy 109.534741 -260.979413) (xy 109.587355 -260.98143) (xy 109.639045 -260.991454) (xy 109.688598 -261.009252)
			(xy 109.734854 -261.034405) (xy 109.776728 -261.066324) (xy 109.81324 -261.104262) (xy 109.843532 -261.147328)
			(xy 109.866895 -261.194513) (xy 109.882781 -261.244712) (xy 109.890818 -261.296748) (xy 109.891322 -261.323074)
			(xy 110.153961 -261.323074) (xy 110.157991 -261.270576) (xy 110.169988 -261.219308) (xy 110.189671 -261.170473)
			(xy 110.216577 -261.125214) (xy 110.250077 -261.084593) (xy 110.289385 -261.049562) (xy 110.33358 -261.020942)
			(xy 110.381625 -260.999403) (xy 110.432396 -260.985451) (xy 110.484701 -260.979413) (xy 110.537315 -260.98143)
			(xy 110.589005 -260.991454) (xy 110.638558 -261.009252) (xy 110.684814 -261.034405) (xy 110.726688 -261.066324)
			(xy 110.7632 -261.104262) (xy 110.793492 -261.147328) (xy 110.816855 -261.194513) (xy 110.832741 -261.244712)
			(xy 110.840778 -261.296748) (xy 110.841282 -261.323074) (xy 111.103921 -261.323074) (xy 111.107951 -261.270576)
			(xy 111.119948 -261.219308) (xy 111.139631 -261.170473) (xy 111.166537 -261.125214) (xy 111.200037 -261.084593)
			(xy 111.239345 -261.049562) (xy 111.28354 -261.020942) (xy 111.331585 -260.999403) (xy 111.382356 -260.985451)
			(xy 111.434661 -260.979413) (xy 111.487275 -260.98143) (xy 111.538965 -260.991454) (xy 111.588518 -261.009252)
			(xy 111.634774 -261.034405) (xy 111.676648 -261.066324) (xy 111.71316 -261.104262) (xy 111.743452 -261.147328)
			(xy 111.766815 -261.194513) (xy 111.782701 -261.244712) (xy 111.790738 -261.296748) (xy 111.791242 -261.323074)
			(xy 112.053881 -261.323074) (xy 112.057911 -261.270576) (xy 112.069908 -261.219308) (xy 112.089591 -261.170473)
			(xy 112.116497 -261.125214) (xy 112.149997 -261.084593) (xy 112.189305 -261.049562) (xy 112.2335 -261.020942)
			(xy 112.281545 -260.999403) (xy 112.332316 -260.985451) (xy 112.384621 -260.979413) (xy 112.437235 -260.98143)
			(xy 112.488925 -260.991454) (xy 112.538478 -261.009252) (xy 112.584734 -261.034405) (xy 112.626608 -261.066324)
			(xy 112.66312 -261.104262) (xy 112.693412 -261.147328) (xy 112.716775 -261.194513) (xy 112.732661 -261.244712)
			(xy 112.740698 -261.296748) (xy 112.741202 -261.323074) (xy 113.004095 -261.323074) (xy 113.008125 -261.270576)
			(xy 113.020122 -261.219308) (xy 113.039805 -261.170473) (xy 113.066711 -261.125214) (xy 113.100211 -261.084593)
			(xy 113.139519 -261.049562) (xy 113.183714 -261.020942) (xy 113.231759 -260.999403) (xy 113.28253 -260.985451)
			(xy 113.334835 -260.979413) (xy 113.387449 -260.98143) (xy 113.439139 -260.991454) (xy 113.488692 -261.009252)
			(xy 113.534948 -261.034405) (xy 113.576822 -261.066324) (xy 113.613334 -261.104262) (xy 113.643626 -261.147328)
			(xy 113.666989 -261.194513) (xy 113.682875 -261.244712) (xy 113.690912 -261.296748) (xy 113.691416 -261.323074)
			(xy 113.954055 -261.323074) (xy 113.958085 -261.270576) (xy 113.970082 -261.219308) (xy 113.989765 -261.170473)
			(xy 114.016671 -261.125214) (xy 114.050171 -261.084593) (xy 114.089479 -261.049562) (xy 114.133674 -261.020942)
			(xy 114.181719 -260.999403) (xy 114.23249 -260.985451) (xy 114.284795 -260.979413) (xy 114.337409 -260.98143)
			(xy 114.389099 -260.991454) (xy 114.438652 -261.009252) (xy 114.484908 -261.034405) (xy 114.526782 -261.066324)
			(xy 114.563294 -261.104262) (xy 114.593586 -261.147328) (xy 114.616949 -261.194513) (xy 114.632835 -261.244712)
			(xy 114.640872 -261.296748) (xy 114.641376 -261.323074) (xy 114.904015 -261.323074) (xy 114.908045 -261.270576)
			(xy 114.920042 -261.219308) (xy 114.939725 -261.170473) (xy 114.966631 -261.125214) (xy 115.000131 -261.084593)
			(xy 115.039439 -261.049562) (xy 115.083634 -261.020942) (xy 115.131679 -260.999403) (xy 115.18245 -260.985451)
			(xy 115.234755 -260.979413) (xy 115.287369 -260.98143) (xy 115.339059 -260.991454) (xy 115.388612 -261.009252)
			(xy 115.434868 -261.034405) (xy 115.476742 -261.066324) (xy 115.513254 -261.104262) (xy 115.543546 -261.147328)
			(xy 115.566909 -261.194513) (xy 115.582795 -261.244712) (xy 115.590832 -261.296748) (xy 115.591336 -261.323074)
			(xy 115.590832 -261.3494) (xy 115.582795 -261.401436) (xy 115.566909 -261.451635) (xy 115.543546 -261.49882)
			(xy 115.513254 -261.541886) (xy 115.476742 -261.579824) (xy 115.434868 -261.611743) (xy 115.388612 -261.636896)
			(xy 115.339059 -261.654694) (xy 115.287369 -261.664718) (xy 115.234755 -261.666735) (xy 115.18245 -261.660697)
			(xy 115.131679 -261.646745) (xy 115.083634 -261.625206) (xy 115.039439 -261.596586) (xy 115.000131 -261.561555)
			(xy 114.966631 -261.520934) (xy 114.939725 -261.475675) (xy 114.920042 -261.42684) (xy 114.908045 -261.375572)
			(xy 114.904015 -261.323074) (xy 114.641376 -261.323074) (xy 114.640872 -261.3494) (xy 114.632835 -261.401436)
			(xy 114.616949 -261.451635) (xy 114.593586 -261.49882) (xy 114.563294 -261.541886) (xy 114.526782 -261.579824)
			(xy 114.484908 -261.611743) (xy 114.438652 -261.636896) (xy 114.389099 -261.654694) (xy 114.337409 -261.664718)
			(xy 114.284795 -261.666735) (xy 114.23249 -261.660697) (xy 114.181719 -261.646745) (xy 114.133674 -261.625206)
			(xy 114.089479 -261.596586) (xy 114.050171 -261.561555) (xy 114.016671 -261.520934) (xy 113.989765 -261.475675)
			(xy 113.970082 -261.42684) (xy 113.958085 -261.375572) (xy 113.954055 -261.323074) (xy 113.691416 -261.323074)
			(xy 113.690912 -261.3494) (xy 113.682875 -261.401436) (xy 113.666989 -261.451635) (xy 113.643626 -261.49882)
			(xy 113.613334 -261.541886) (xy 113.576822 -261.579824) (xy 113.534948 -261.611743) (xy 113.488692 -261.636896)
			(xy 113.439139 -261.654694) (xy 113.387449 -261.664718) (xy 113.334835 -261.666735) (xy 113.28253 -261.660697)
			(xy 113.231759 -261.646745) (xy 113.183714 -261.625206) (xy 113.139519 -261.596586) (xy 113.100211 -261.561555)
			(xy 113.066711 -261.520934) (xy 113.039805 -261.475675) (xy 113.020122 -261.42684) (xy 113.008125 -261.375572)
			(xy 113.004095 -261.323074) (xy 112.741202 -261.323074) (xy 112.740698 -261.3494) (xy 112.732661 -261.401436)
			(xy 112.716775 -261.451635) (xy 112.693412 -261.49882) (xy 112.66312 -261.541886) (xy 112.626608 -261.579824)
			(xy 112.584734 -261.611743) (xy 112.538478 -261.636896) (xy 112.488925 -261.654694) (xy 112.437235 -261.664718)
			(xy 112.384621 -261.666735) (xy 112.332316 -261.660697) (xy 112.281545 -261.646745) (xy 112.2335 -261.625206)
			(xy 112.189305 -261.596586) (xy 112.149997 -261.561555) (xy 112.116497 -261.520934) (xy 112.089591 -261.475675)
			(xy 112.069908 -261.42684) (xy 112.057911 -261.375572) (xy 112.053881 -261.323074) (xy 111.791242 -261.323074)
			(xy 111.790738 -261.3494) (xy 111.782701 -261.401436) (xy 111.766815 -261.451635) (xy 111.743452 -261.49882)
			(xy 111.71316 -261.541886) (xy 111.676648 -261.579824) (xy 111.634774 -261.611743) (xy 111.588518 -261.636896)
			(xy 111.538965 -261.654694) (xy 111.487275 -261.664718) (xy 111.434661 -261.666735) (xy 111.382356 -261.660697)
			(xy 111.331585 -261.646745) (xy 111.28354 -261.625206) (xy 111.239345 -261.596586) (xy 111.200037 -261.561555)
			(xy 111.166537 -261.520934) (xy 111.139631 -261.475675) (xy 111.119948 -261.42684) (xy 111.107951 -261.375572)
			(xy 111.103921 -261.323074) (xy 110.841282 -261.323074) (xy 110.840778 -261.3494) (xy 110.832741 -261.401436)
			(xy 110.816855 -261.451635) (xy 110.793492 -261.49882) (xy 110.7632 -261.541886) (xy 110.726688 -261.579824)
			(xy 110.684814 -261.611743) (xy 110.638558 -261.636896) (xy 110.589005 -261.654694) (xy 110.537315 -261.664718)
			(xy 110.484701 -261.666735) (xy 110.432396 -261.660697) (xy 110.381625 -261.646745) (xy 110.33358 -261.625206)
			(xy 110.289385 -261.596586) (xy 110.250077 -261.561555) (xy 110.216577 -261.520934) (xy 110.189671 -261.475675)
			(xy 110.169988 -261.42684) (xy 110.157991 -261.375572) (xy 110.153961 -261.323074) (xy 109.891322 -261.323074)
			(xy 109.890818 -261.3494) (xy 109.882781 -261.401436) (xy 109.866895 -261.451635) (xy 109.843532 -261.49882)
			(xy 109.81324 -261.541886) (xy 109.776728 -261.579824) (xy 109.734854 -261.611743) (xy 109.688598 -261.636896)
			(xy 109.639045 -261.654694) (xy 109.587355 -261.664718) (xy 109.534741 -261.666735) (xy 109.482436 -261.660697)
			(xy 109.431665 -261.646745) (xy 109.38362 -261.625206) (xy 109.339425 -261.596586) (xy 109.300117 -261.561555)
			(xy 109.266617 -261.520934) (xy 109.239711 -261.475675) (xy 109.220028 -261.42684) (xy 109.208031 -261.375572)
			(xy 109.204001 -261.323074) (xy 108.941362 -261.323074) (xy 108.940862 -261.350061) (xy 108.932422 -261.403372)
			(xy 108.915744 -261.454705) (xy 108.891241 -261.502797) (xy 108.859515 -261.546463) (xy 108.821348 -261.584628)
			(xy 108.77768 -261.616351) (xy 108.729587 -261.640852) (xy 108.678252 -261.657526) (xy 108.624941 -261.665964)
			(xy 108.597954 -261.666482) (xy 108.579329 -261.666271) (xy 108.54229 -261.662329) (xy 108.52404 -261.658608)
			(xy 108.51134 -261.655814) (xy 108.486448 -261.66318) (xy 108.349796 -261.799832) (xy 108.342557 -261.806544)
			(xy 108.324353 -261.814138) (xy 108.31449 -261.814564) (xy 108.255308 -261.814564) (xy 108.245472 -261.815103)
			(xy 108.227313 -261.822691) (xy 108.220002 -261.829296) (xy 107.979464 -262.06958) (xy 107.972677 -262.07582)
			(xy 107.95587 -262.083363) (xy 107.946698 -262.084312) (xy 107.86745 -262.088376) (xy 107.85811 -262.088404)
			(xy 107.840397 -262.082528) (xy 107.832906 -262.076946) (xy 107.802172 -262.051292) (xy 107.801918 -262.051292)
			(xy 107.785548 -262.038335) (xy 107.749277 -262.017668) (xy 107.709994 -262.003545) (xy 107.668867 -261.996386)
			(xy 107.647994 -261.99592) (xy 107.627748 -261.996324) (xy 107.58782 -262.003059) (xy 107.549574 -262.016358)
			(xy 107.51408 -262.035846) (xy 107.482332 -262.06098) (xy 107.455219 -262.091055) (xy 107.444032 -262.107934)
			(xy 107.442254 -262.110474) (xy 107.431267 -262.124761) (xy 107.403897 -262.148197) (xy 107.371831 -262.164632)
			(xy 107.336824 -262.173167) (xy 107.31881 -262.17372) (xy 106.734864 -262.17372) (xy 106.727665 -262.173421)
			(xy 106.713868 -262.169294) (xy 106.707686 -262.165592) (xy 106.656886 -262.132572) (xy 106.650951 -262.128359)
			(xy 106.641537 -262.117268) (xy 106.638344 -262.110728) (xy 106.63047 -262.091932) (xy 106.626152 -262.082534)
			(xy 106.617038 -262.063089) (xy 106.593 -262.02751) (xy 106.563054 -261.996736) (xy 106.528144 -261.971735)
			(xy 106.489367 -261.953293) (xy 106.447942 -261.941991) (xy 106.405172 -261.938184) (xy 106.362402 -261.941991)
			(xy 106.320977 -261.953293) (xy 106.2822 -261.971735) (xy 106.24729 -261.996736) (xy 106.217344 -262.02751)
			(xy 106.193306 -262.063089) (xy 106.184192 -262.082534) (xy 106.179874 -262.091932) (xy 106.172 -262.110728)
			(xy 106.168862 -262.117303) (xy 106.15943 -262.128398) (xy 106.153458 -262.132572) (xy 106.102658 -262.165592)
			(xy 106.0965 -262.169347) (xy 106.082688 -262.173479) (xy 106.07548 -262.17372) (xy 105.863136 -262.17372)
			(xy 105.834434 -262.199374) (xy 105.832148 -262.218678) (xy 105.828877 -262.243529) (xy 105.816063 -262.291986)
			(xy 105.796348 -262.338068) (xy 105.770148 -262.380798) (xy 105.738021 -262.41927) (xy 105.700646 -262.452668)
			(xy 105.658817 -262.480283) (xy 105.613421 -262.501531) (xy 105.56542 -262.51596) (xy 105.515833 -262.523264)
			(xy 105.490772 -262.523732) (xy 105.463995 -262.523217) (xy 105.41109 -262.514899) (xy 105.360117 -262.498471)
			(xy 105.312312 -262.474328) (xy 105.268835 -262.443058) (xy 105.230738 -262.405418) (xy 105.198946 -262.362321)
			(xy 105.174229 -262.314811) (xy 105.157186 -262.26404) (xy 105.15219 -262.237728) (xy 105.149142 -262.21944)
			(xy 105.120948 -262.195564) (xy 103.100378 -262.195564) (xy 103.090311 -262.195993) (xy 103.071718 -262.20372)
			(xy 103.06431 -262.21055) (xy 102.52964 -262.74522) (xy 102.52669 -262.748268) (xy 102.842072 -262.748268)
			(xy 102.846032 -262.699214) (xy 102.857809 -262.65143) (xy 102.8771 -262.606154) (xy 102.903403 -262.564558)
			(xy 102.936038 -262.527721) (xy 102.974159 -262.496596) (xy 103.01678 -262.471989) (xy 103.062796 -262.454537)
			(xy 103.111015 -262.444693) (xy 103.16019 -262.442712) (xy 103.209045 -262.448644) (xy 103.256316 -262.462336)
			(xy 103.300778 -262.483434) (xy 103.341281 -262.51139) (xy 103.376774 -262.545482) (xy 103.406339 -262.584826)
			(xy 103.42921 -262.628403) (xy 103.444794 -262.675084) (xy 103.452689 -262.723661) (xy 103.453184 -262.748268)
			(xy 103.782126 -262.748268) (xy 103.786086 -262.699214) (xy 103.797863 -262.65143) (xy 103.817154 -262.606154)
			(xy 103.843457 -262.564558) (xy 103.876092 -262.527721) (xy 103.914213 -262.496596) (xy 103.956834 -262.471989)
			(xy 104.00285 -262.454537) (xy 104.051069 -262.444693) (xy 104.100244 -262.442712) (xy 104.149099 -262.448644)
			(xy 104.19637 -262.462336) (xy 104.240832 -262.483434) (xy 104.281335 -262.51139) (xy 104.316828 -262.545482)
			(xy 104.346393 -262.584826) (xy 104.369264 -262.628403) (xy 104.384848 -262.675084) (xy 104.392743 -262.723661)
			(xy 104.393238 -262.748268) (xy 104.392743 -262.772875) (xy 104.384848 -262.821452) (xy 104.369264 -262.868133)
			(xy 104.346393 -262.91171) (xy 104.316828 -262.951054) (xy 104.281335 -262.985146) (xy 104.240832 -263.013102)
			(xy 104.19637 -263.0342) (xy 104.149099 -263.047892) (xy 104.100244 -263.053824) (xy 104.051069 -263.051843)
			(xy 104.00285 -263.041999) (xy 103.956834 -263.024547) (xy 103.914213 -262.99994) (xy 103.876092 -262.968815)
			(xy 103.843457 -262.931978) (xy 103.817154 -262.890382) (xy 103.797863 -262.845106) (xy 103.786086 -262.797322)
			(xy 103.782126 -262.748268) (xy 103.453184 -262.748268) (xy 103.452689 -262.772875) (xy 103.444794 -262.821452)
			(xy 103.42921 -262.868133) (xy 103.406339 -262.91171) (xy 103.376774 -262.951054) (xy 103.341281 -262.985146)
			(xy 103.300778 -263.013102) (xy 103.256316 -263.0342) (xy 103.209045 -263.047892) (xy 103.16019 -263.053824)
			(xy 103.111015 -263.051843) (xy 103.062796 -263.041999) (xy 103.01678 -263.024547) (xy 102.974159 -262.99994)
			(xy 102.936038 -262.968815) (xy 102.903403 -262.931978) (xy 102.8771 -262.890382) (xy 102.857809 -262.845106)
			(xy 102.846032 -262.797322) (xy 102.842072 -262.748268) (xy 102.52669 -262.748268) (xy 102.526545 -262.748418)
			(xy 102.521433 -262.7557) (xy 102.51948 -262.759698) (xy 102.515924 -262.767572) (xy 102.514908 -262.776208)
			(xy 102.511788 -262.80226) (xy 102.497784 -262.852823) (xy 102.475345 -262.900248) (xy 102.445131 -262.943141)
			(xy 102.408031 -262.980239) (xy 102.365137 -263.010451) (xy 102.317711 -263.032888) (xy 102.267148 -263.04689)
			(xy 102.241096 -263.05002) (xy 102.236819 -263.050534) (xy 102.228518 -263.052832) (xy 102.224586 -263.054592)
			(xy 102.216458 -263.058402) (xy 101.994208 -263.280652) (xy 101.987933 -263.287568) (xy 101.980385 -263.304632)
			(xy 101.979476 -263.313926) (xy 101.977444 -263.352788) (xy 101.982524 -263.369298) (xy 101.987604 -263.37641)
			(xy 102.001407 -263.396114) (xy 102.023303 -263.438949) (xy 102.038227 -263.484683) (xy 102.04581 -263.532189)
			(xy 102.046278 -263.556242) (xy 102.37522 -263.556242) (xy 102.37918 -263.507188) (xy 102.390957 -263.459404)
			(xy 102.410248 -263.414128) (xy 102.436551 -263.372532) (xy 102.469186 -263.335695) (xy 102.507307 -263.30457)
			(xy 102.549928 -263.279963) (xy 102.595944 -263.262511) (xy 102.644163 -263.252667) (xy 102.693338 -263.250686)
			(xy 102.742193 -263.256618) (xy 102.789464 -263.27031) (xy 102.833926 -263.291408) (xy 102.874429 -263.319364)
			(xy 102.909922 -263.353456) (xy 102.939487 -263.3928) (xy 102.962358 -263.436377) (xy 102.977942 -263.483058)
			(xy 102.985837 -263.531635) (xy 102.986332 -263.556242) (xy 102.985837 -263.580849) (xy 102.977942 -263.629426)
			(xy 102.962358 -263.676107) (xy 102.939487 -263.719684) (xy 102.909922 -263.759028) (xy 102.874429 -263.79312)
			(xy 102.833926 -263.821076) (xy 102.789464 -263.842174) (xy 102.774308 -263.846564) (xy 111.234223 -263.846564)
			(xy 111.238253 -263.794066) (xy 111.25025 -263.742798) (xy 111.269933 -263.693963) (xy 111.296839 -263.648704)
			(xy 111.330339 -263.608083) (xy 111.369647 -263.573052) (xy 111.413842 -263.544432) (xy 111.461887 -263.522893)
			(xy 111.512658 -263.508941) (xy 111.564963 -263.502903) (xy 111.617577 -263.50492) (xy 111.669267 -263.514944)
			(xy 111.71882 -263.532742) (xy 111.762036 -263.556242) (xy 121.168934 -263.556242) (xy 121.172894 -263.507188)
			(xy 121.184671 -263.459404) (xy 121.203962 -263.414128) (xy 121.230265 -263.372532) (xy 121.2629 -263.335695)
			(xy 121.301021 -263.30457) (xy 121.343642 -263.279963) (xy 121.389658 -263.262511) (xy 121.437877 -263.252667)
			(xy 121.487052 -263.250686) (xy 121.535907 -263.256618) (xy 121.583178 -263.27031) (xy 121.62764 -263.291408)
			(xy 121.668143 -263.319364) (xy 121.703636 -263.353456) (xy 121.733201 -263.3928) (xy 121.756072 -263.436377)
			(xy 121.771656 -263.483058) (xy 121.779551 -263.531635) (xy 121.780046 -263.556242) (xy 123.049042 -263.556242)
			(xy 123.053002 -263.507188) (xy 123.064779 -263.459404) (xy 123.08407 -263.414128) (xy 123.110373 -263.372532)
			(xy 123.143008 -263.335695) (xy 123.181129 -263.30457) (xy 123.22375 -263.279963) (xy 123.269766 -263.262511)
			(xy 123.317985 -263.252667) (xy 123.36716 -263.250686) (xy 123.416015 -263.256618) (xy 123.463286 -263.27031)
			(xy 123.507748 -263.291408) (xy 123.548251 -263.319364) (xy 123.583744 -263.353456) (xy 123.613309 -263.3928)
			(xy 123.63618 -263.436377) (xy 123.651764 -263.483058) (xy 123.659659 -263.531635) (xy 123.660154 -263.556242)
			(xy 123.659659 -263.580849) (xy 123.651764 -263.629426) (xy 123.63618 -263.676107) (xy 123.613309 -263.719684)
			(xy 123.583744 -263.759028) (xy 123.548251 -263.79312) (xy 123.507748 -263.821076) (xy 123.463286 -263.842174)
			(xy 123.416015 -263.855866) (xy 123.36716 -263.861798) (xy 123.317985 -263.859817) (xy 123.269766 -263.849973)
			(xy 123.22375 -263.832521) (xy 123.181129 -263.807914) (xy 123.143008 -263.776789) (xy 123.110373 -263.739952)
			(xy 123.08407 -263.698356) (xy 123.064779 -263.65308) (xy 123.053002 -263.605296) (xy 123.049042 -263.556242)
			(xy 121.780046 -263.556242) (xy 121.779551 -263.580849) (xy 121.771656 -263.629426) (xy 121.756072 -263.676107)
			(xy 121.733201 -263.719684) (xy 121.703636 -263.759028) (xy 121.668143 -263.79312) (xy 121.62764 -263.821076)
			(xy 121.583178 -263.842174) (xy 121.535907 -263.855866) (xy 121.487052 -263.861798) (xy 121.437877 -263.859817)
			(xy 121.389658 -263.849973) (xy 121.343642 -263.832521) (xy 121.301021 -263.807914) (xy 121.2629 -263.776789)
			(xy 121.230265 -263.739952) (xy 121.203962 -263.698356) (xy 121.184671 -263.65308) (xy 121.172894 -263.605296)
			(xy 121.168934 -263.556242) (xy 111.762036 -263.556242) (xy 111.765076 -263.557895) (xy 111.80695 -263.589814)
			(xy 111.843462 -263.627752) (xy 111.873754 -263.670818) (xy 111.897117 -263.718003) (xy 111.913003 -263.768202)
			(xy 111.92104 -263.820238) (xy 111.921544 -263.846564) (xy 111.92104 -263.87289) (xy 111.913003 -263.924926)
			(xy 111.897117 -263.975125) (xy 111.873754 -264.02231) (xy 111.843462 -264.065376) (xy 111.80695 -264.103314)
			(xy 111.765076 -264.135233) (xy 111.71882 -264.160386) (xy 111.669267 -264.178184) (xy 111.617577 -264.188208)
			(xy 111.564963 -264.190225) (xy 111.512658 -264.184187) (xy 111.461887 -264.170235) (xy 111.413842 -264.148696)
			(xy 111.369647 -264.120076) (xy 111.330339 -264.085045) (xy 111.296839 -264.044424) (xy 111.269933 -263.999165)
			(xy 111.25025 -263.95033) (xy 111.238253 -263.899062) (xy 111.234223 -263.846564) (xy 102.774308 -263.846564)
			(xy 102.742193 -263.855866) (xy 102.693338 -263.861798) (xy 102.644163 -263.859817) (xy 102.595944 -263.849973)
			(xy 102.549928 -263.832521) (xy 102.507307 -263.807914) (xy 102.469186 -263.776789) (xy 102.436551 -263.739952)
			(xy 102.410248 -263.698356) (xy 102.390957 -263.65308) (xy 102.37918 -263.605296) (xy 102.37522 -263.556242)
			(xy 102.046278 -263.556242) (xy 102.045804 -263.58023) (xy 102.038293 -263.627615) (xy 102.023461 -263.673242)
			(xy 102.001675 -263.715986) (xy 101.97347 -263.754797) (xy 101.939542 -263.788717) (xy 101.900725 -263.816913)
			(xy 101.857975 -263.838689) (xy 101.812345 -263.85351) (xy 101.764958 -263.86101) (xy 101.74097 -263.86155)
			(xy 101.716914 -263.861101) (xy 101.6694 -263.853548) (xy 101.623663 -263.838617) (xy 101.580844 -263.816682)
			(xy 101.561138 -263.802876) (xy 101.553928 -263.798044) (xy 101.537304 -263.793099) (xy 101.528626 -263.793224)
			(xy 101.498654 -263.794748) (xy 101.489349 -263.795621) (xy 101.472272 -263.803169) (xy 101.46538 -263.80948)
			(xy 101.086666 -264.188194) (xy 101.0793 -264.195306) (xy 101.07168 -264.214102) (xy 101.07168 -264.366248)
			(xy 101.90532 -264.366248) (xy 101.90928 -264.317194) (xy 101.921057 -264.26941) (xy 101.940348 -264.224134)
			(xy 101.966651 -264.182538) (xy 101.999286 -264.145701) (xy 102.037407 -264.114576) (xy 102.080028 -264.089969)
			(xy 102.126044 -264.072517) (xy 102.174263 -264.062673) (xy 102.223438 -264.060692) (xy 102.272293 -264.066624)
			(xy 102.319564 -264.080316) (xy 102.364026 -264.101414) (xy 102.404529 -264.12937) (xy 102.440022 -264.163462)
			(xy 102.469587 -264.202806) (xy 102.492458 -264.246383) (xy 102.508042 -264.293064) (xy 102.515937 -264.341641)
			(xy 102.516432 -264.366248) (xy 102.516391 -264.36828) (xy 103.782126 -264.36828) (xy 103.786086 -264.319226)
			(xy 103.797863 -264.271442) (xy 103.817154 -264.226166) (xy 103.843457 -264.18457) (xy 103.876092 -264.147733)
			(xy 103.914213 -264.116608) (xy 103.956834 -264.092001) (xy 104.00285 -264.074549) (xy 104.051069 -264.064705)
			(xy 104.100244 -264.062724) (xy 104.149099 -264.068656) (xy 104.19637 -264.082348) (xy 104.240832 -264.103446)
			(xy 104.281335 -264.131402) (xy 104.316828 -264.165494) (xy 104.346393 -264.204838) (xy 104.369264 -264.248415)
			(xy 104.384848 -264.295096) (xy 104.392743 -264.343673) (xy 104.393238 -264.36828) (xy 105.662234 -264.36828)
			(xy 105.666194 -264.319226) (xy 105.677971 -264.271442) (xy 105.697262 -264.226166) (xy 105.723565 -264.18457)
			(xy 105.7562 -264.147733) (xy 105.794321 -264.116608) (xy 105.836942 -264.092001) (xy 105.882958 -264.074549)
			(xy 105.931177 -264.064705) (xy 105.980352 -264.062724) (xy 106.029207 -264.068656) (xy 106.076478 -264.082348)
			(xy 106.12094 -264.103446) (xy 106.161443 -264.131402) (xy 106.196936 -264.165494) (xy 106.226501 -264.204838)
			(xy 106.249372 -264.248415) (xy 106.264956 -264.295096) (xy 106.272851 -264.343673) (xy 106.273346 -264.36828)
			(xy 107.542088 -264.36828) (xy 107.546048 -264.319226) (xy 107.557825 -264.271442) (xy 107.577116 -264.226166)
			(xy 107.603419 -264.18457) (xy 107.636054 -264.147733) (xy 107.674175 -264.116608) (xy 107.716796 -264.092001)
			(xy 107.762812 -264.074549) (xy 107.811031 -264.064705) (xy 107.860206 -264.062724) (xy 107.909061 -264.068656)
			(xy 107.956332 -264.082348) (xy 108.000794 -264.103446) (xy 108.041297 -264.131402) (xy 108.07679 -264.165494)
			(xy 108.106355 -264.204838) (xy 108.129226 -264.248415) (xy 108.14481 -264.295096) (xy 108.152705 -264.343673)
			(xy 108.1532 -264.36828) (xy 115.062012 -264.36828) (xy 115.065972 -264.319226) (xy 115.077749 -264.271442)
			(xy 115.09704 -264.226166) (xy 115.123343 -264.18457) (xy 115.155978 -264.147733) (xy 115.194099 -264.116608)
			(xy 115.23672 -264.092001) (xy 115.282736 -264.074549) (xy 115.330955 -264.064705) (xy 115.38013 -264.062724)
			(xy 115.428985 -264.068656) (xy 115.476256 -264.082348) (xy 115.520718 -264.103446) (xy 115.561221 -264.131402)
			(xy 115.596714 -264.165494) (xy 115.626279 -264.204838) (xy 115.64915 -264.248415) (xy 115.664734 -264.295096)
			(xy 115.672629 -264.343673) (xy 115.673124 -264.36828) (xy 116.94212 -264.36828) (xy 116.94608 -264.319226)
			(xy 116.957857 -264.271442) (xy 116.977148 -264.226166) (xy 117.003451 -264.18457) (xy 117.036086 -264.147733)
			(xy 117.074207 -264.116608) (xy 117.116828 -264.092001) (xy 117.162844 -264.074549) (xy 117.211063 -264.064705)
			(xy 117.260238 -264.062724) (xy 117.309093 -264.068656) (xy 117.356364 -264.082348) (xy 117.400826 -264.103446)
			(xy 117.441329 -264.131402) (xy 117.476822 -264.165494) (xy 117.506387 -264.204838) (xy 117.529258 -264.248415)
			(xy 117.544842 -264.295096) (xy 117.552737 -264.343673) (xy 117.553232 -264.36828) (xy 118.821974 -264.36828)
			(xy 118.825934 -264.319226) (xy 118.837711 -264.271442) (xy 118.857002 -264.226166) (xy 118.883305 -264.18457)
			(xy 118.91594 -264.147733) (xy 118.954061 -264.116608) (xy 118.996682 -264.092001) (xy 119.042698 -264.074549)
			(xy 119.090917 -264.064705) (xy 119.140092 -264.062724) (xy 119.188947 -264.068656) (xy 119.236218 -264.082348)
			(xy 119.28068 -264.103446) (xy 119.321183 -264.131402) (xy 119.356676 -264.165494) (xy 119.386241 -264.204838)
			(xy 119.409112 -264.248415) (xy 119.424696 -264.295096) (xy 119.432591 -264.343673) (xy 119.433086 -264.36828)
			(xy 120.699796 -264.36828) (xy 120.703756 -264.319226) (xy 120.715533 -264.271442) (xy 120.734824 -264.226166)
			(xy 120.761127 -264.18457) (xy 120.793762 -264.147733) (xy 120.831883 -264.116608) (xy 120.874504 -264.092001)
			(xy 120.92052 -264.074549) (xy 120.968739 -264.064705) (xy 121.017914 -264.062724) (xy 121.066769 -264.068656)
			(xy 121.11404 -264.082348) (xy 121.158502 -264.103446) (xy 121.199005 -264.131402) (xy 121.234498 -264.165494)
			(xy 121.264063 -264.204838) (xy 121.286934 -264.248415) (xy 121.302518 -264.295096) (xy 121.310413 -264.343673)
			(xy 121.310867 -264.366248) (xy 122.578888 -264.366248) (xy 122.582848 -264.317194) (xy 122.594625 -264.26941)
			(xy 122.613916 -264.224134) (xy 122.640219 -264.182538) (xy 122.672854 -264.145701) (xy 122.710975 -264.114576)
			(xy 122.753596 -264.089969) (xy 122.799612 -264.072517) (xy 122.847831 -264.062673) (xy 122.897006 -264.060692)
			(xy 122.945861 -264.066624) (xy 122.993132 -264.080316) (xy 123.037594 -264.101414) (xy 123.078097 -264.12937)
			(xy 123.11359 -264.163462) (xy 123.143155 -264.202806) (xy 123.166026 -264.246383) (xy 123.18161 -264.293064)
			(xy 123.189505 -264.341641) (xy 123.19 -264.366248) (xy 124.458996 -264.366248) (xy 124.462956 -264.317194)
			(xy 124.474733 -264.26941) (xy 124.494024 -264.224134) (xy 124.520327 -264.182538) (xy 124.552962 -264.145701)
			(xy 124.591083 -264.114576) (xy 124.633704 -264.089969) (xy 124.67972 -264.072517) (xy 124.727939 -264.062673)
			(xy 124.777114 -264.060692) (xy 124.825969 -264.066624) (xy 124.87324 -264.080316) (xy 124.917702 -264.101414)
			(xy 124.958205 -264.12937) (xy 124.993698 -264.163462) (xy 125.023263 -264.202806) (xy 125.046134 -264.246383)
			(xy 125.061718 -264.293064) (xy 125.069613 -264.341641) (xy 125.070108 -264.366248) (xy 126.33885 -264.366248)
			(xy 126.34281 -264.317194) (xy 126.354587 -264.26941) (xy 126.373878 -264.224134) (xy 126.400181 -264.182538)
			(xy 126.432816 -264.145701) (xy 126.470937 -264.114576) (xy 126.513558 -264.089969) (xy 126.559574 -264.072517)
			(xy 126.607793 -264.062673) (xy 126.656968 -264.060692) (xy 126.705823 -264.066624) (xy 126.753094 -264.080316)
			(xy 126.797556 -264.101414) (xy 126.838059 -264.12937) (xy 126.873552 -264.163462) (xy 126.903117 -264.202806)
			(xy 126.925988 -264.246383) (xy 126.941572 -264.293064) (xy 126.949467 -264.341641) (xy 126.949962 -264.366248)
			(xy 128.208527 -264.366248) (xy 128.212622 -264.31552) (xy 128.224801 -264.266106) (xy 128.244749 -264.219286)
			(xy 128.27195 -264.176272) (xy 128.305698 -264.138178) (xy 128.34512 -264.105991) (xy 128.389194 -264.080545)
			(xy 128.43678 -264.062498) (xy 128.486644 -264.052318) (xy 128.537496 -264.050269) (xy 128.588017 -264.056403)
			(xy 128.636901 -264.070563) (xy 128.68288 -264.09238) (xy 128.724764 -264.12129) (xy 128.761468 -264.156545)
			(xy 128.792041 -264.197231) (xy 128.815692 -264.242294) (xy 128.831808 -264.290568) (xy 128.839972 -264.340802)
			(xy 128.840484 -264.366248) (xy 129.148581 -264.366248) (xy 129.152676 -264.31552) (xy 129.164855 -264.266106)
			(xy 129.184803 -264.219286) (xy 129.212004 -264.176272) (xy 129.245752 -264.138178) (xy 129.285174 -264.105991)
			(xy 129.329248 -264.080545) (xy 129.376834 -264.062498) (xy 129.426698 -264.052318) (xy 129.47755 -264.050269)
			(xy 129.528071 -264.056403) (xy 129.576955 -264.070563) (xy 129.622934 -264.09238) (xy 129.664818 -264.12129)
			(xy 129.701522 -264.156545) (xy 129.732095 -264.197231) (xy 129.755746 -264.242294) (xy 129.771862 -264.290568)
			(xy 129.780026 -264.340802) (xy 129.780538 -264.366248) (xy 130.099066 -264.366248) (xy 130.103026 -264.317194)
			(xy 130.114803 -264.26941) (xy 130.134094 -264.224134) (xy 130.160397 -264.182538) (xy 130.193032 -264.145701)
			(xy 130.231153 -264.114576) (xy 130.273774 -264.089969) (xy 130.31979 -264.072517) (xy 130.368009 -264.062673)
			(xy 130.417184 -264.060692) (xy 130.466039 -264.066624) (xy 130.51331 -264.080316) (xy 130.557772 -264.101414)
			(xy 130.598275 -264.12937) (xy 130.633768 -264.163462) (xy 130.663333 -264.202806) (xy 130.686204 -264.246383)
			(xy 130.701788 -264.293064) (xy 130.709683 -264.341641) (xy 130.710178 -264.366248) (xy 131.028435 -264.366248)
			(xy 131.03253 -264.31552) (xy 131.044709 -264.266106) (xy 131.064657 -264.219286) (xy 131.091858 -264.176272)
			(xy 131.125606 -264.138178) (xy 131.165028 -264.105991) (xy 131.209102 -264.080545) (xy 131.256688 -264.062498)
			(xy 131.306552 -264.052318) (xy 131.357404 -264.050269) (xy 131.407925 -264.056403) (xy 131.456809 -264.070563)
			(xy 131.502788 -264.09238) (xy 131.544672 -264.12129) (xy 131.581376 -264.156545) (xy 131.611949 -264.197231)
			(xy 131.6356 -264.242294) (xy 131.651716 -264.290568) (xy 131.65988 -264.340802) (xy 131.660392 -264.366248)
			(xy 131.65988 -264.391694) (xy 131.651716 -264.441928) (xy 131.6356 -264.490202) (xy 131.611949 -264.535265)
			(xy 131.581376 -264.575951) (xy 131.544672 -264.611206) (xy 131.502788 -264.640116) (xy 131.456809 -264.661933)
			(xy 131.407925 -264.676093) (xy 131.357404 -264.682227) (xy 131.306552 -264.680178) (xy 131.256688 -264.669998)
			(xy 131.209102 -264.651951) (xy 131.165028 -264.626505) (xy 131.125606 -264.594318) (xy 131.091858 -264.556224)
			(xy 131.064657 -264.51321) (xy 131.044709 -264.46639) (xy 131.03253 -264.416976) (xy 131.028435 -264.366248)
			(xy 130.710178 -264.366248) (xy 130.709683 -264.390855) (xy 130.701788 -264.439432) (xy 130.686204 -264.486113)
			(xy 130.663333 -264.52969) (xy 130.633768 -264.569034) (xy 130.598275 -264.603126) (xy 130.557772 -264.631082)
			(xy 130.51331 -264.65218) (xy 130.466039 -264.665872) (xy 130.417184 -264.671804) (xy 130.368009 -264.669823)
			(xy 130.31979 -264.659979) (xy 130.273774 -264.642527) (xy 130.231153 -264.61792) (xy 130.193032 -264.586795)
			(xy 130.160397 -264.549958) (xy 130.134094 -264.508362) (xy 130.114803 -264.463086) (xy 130.103026 -264.415302)
			(xy 130.099066 -264.366248) (xy 129.780538 -264.366248) (xy 129.780026 -264.391694) (xy 129.771862 -264.441928)
			(xy 129.755746 -264.490202) (xy 129.732095 -264.535265) (xy 129.701522 -264.575951) (xy 129.664818 -264.611206)
			(xy 129.622934 -264.640116) (xy 129.576955 -264.661933) (xy 129.528071 -264.676093) (xy 129.47755 -264.682227)
			(xy 129.426698 -264.680178) (xy 129.376834 -264.669998) (xy 129.329248 -264.651951) (xy 129.285174 -264.626505)
			(xy 129.245752 -264.594318) (xy 129.212004 -264.556224) (xy 129.184803 -264.51321) (xy 129.164855 -264.46639)
			(xy 129.152676 -264.416976) (xy 129.148581 -264.366248) (xy 128.840484 -264.366248) (xy 128.839972 -264.391694)
			(xy 128.831808 -264.441928) (xy 128.815692 -264.490202) (xy 128.792041 -264.535265) (xy 128.761468 -264.575951)
			(xy 128.724764 -264.611206) (xy 128.68288 -264.640116) (xy 128.636901 -264.661933) (xy 128.588017 -264.676093)
			(xy 128.537496 -264.682227) (xy 128.486644 -264.680178) (xy 128.43678 -264.669998) (xy 128.389194 -264.651951)
			(xy 128.34512 -264.626505) (xy 128.305698 -264.594318) (xy 128.27195 -264.556224) (xy 128.244749 -264.51321)
			(xy 128.224801 -264.46639) (xy 128.212622 -264.416976) (xy 128.208527 -264.366248) (xy 126.949962 -264.366248)
			(xy 126.949467 -264.390855) (xy 126.941572 -264.439432) (xy 126.925988 -264.486113) (xy 126.903117 -264.52969)
			(xy 126.873552 -264.569034) (xy 126.838059 -264.603126) (xy 126.797556 -264.631082) (xy 126.753094 -264.65218)
			(xy 126.705823 -264.665872) (xy 126.656968 -264.671804) (xy 126.607793 -264.669823) (xy 126.559574 -264.659979)
			(xy 126.513558 -264.642527) (xy 126.470937 -264.61792) (xy 126.432816 -264.586795) (xy 126.400181 -264.549958)
			(xy 126.373878 -264.508362) (xy 126.354587 -264.463086) (xy 126.34281 -264.415302) (xy 126.33885 -264.366248)
			(xy 125.070108 -264.366248) (xy 125.069613 -264.390855) (xy 125.061718 -264.439432) (xy 125.046134 -264.486113)
			(xy 125.023263 -264.52969) (xy 124.993698 -264.569034) (xy 124.958205 -264.603126) (xy 124.917702 -264.631082)
			(xy 124.87324 -264.65218) (xy 124.825969 -264.665872) (xy 124.777114 -264.671804) (xy 124.727939 -264.669823)
			(xy 124.67972 -264.659979) (xy 124.633704 -264.642527) (xy 124.591083 -264.61792) (xy 124.552962 -264.586795)
			(xy 124.520327 -264.549958) (xy 124.494024 -264.508362) (xy 124.474733 -264.463086) (xy 124.462956 -264.415302)
			(xy 124.458996 -264.366248) (xy 123.19 -264.366248) (xy 123.189505 -264.390855) (xy 123.18161 -264.439432)
			(xy 123.166026 -264.486113) (xy 123.143155 -264.52969) (xy 123.11359 -264.569034) (xy 123.078097 -264.603126)
			(xy 123.037594 -264.631082) (xy 122.993132 -264.65218) (xy 122.945861 -264.665872) (xy 122.897006 -264.671804)
			(xy 122.847831 -264.669823) (xy 122.799612 -264.659979) (xy 122.753596 -264.642527) (xy 122.710975 -264.61792)
			(xy 122.672854 -264.586795) (xy 122.640219 -264.549958) (xy 122.613916 -264.508362) (xy 122.594625 -264.463086)
			(xy 122.582848 -264.415302) (xy 122.578888 -264.366248) (xy 121.310867 -264.366248) (xy 121.310908 -264.36828)
			(xy 121.310413 -264.392887) (xy 121.302518 -264.441464) (xy 121.286934 -264.488145) (xy 121.264063 -264.531722)
			(xy 121.234498 -264.571066) (xy 121.199005 -264.605158) (xy 121.158502 -264.633114) (xy 121.11404 -264.654212)
			(xy 121.066769 -264.667904) (xy 121.017914 -264.673836) (xy 120.968739 -264.671855) (xy 120.92052 -264.662011)
			(xy 120.874504 -264.644559) (xy 120.831883 -264.619952) (xy 120.793762 -264.588827) (xy 120.761127 -264.55199)
			(xy 120.734824 -264.510394) (xy 120.715533 -264.465118) (xy 120.703756 -264.417334) (xy 120.699796 -264.36828)
			(xy 119.433086 -264.36828) (xy 119.432591 -264.392887) (xy 119.424696 -264.441464) (xy 119.409112 -264.488145)
			(xy 119.386241 -264.531722) (xy 119.356676 -264.571066) (xy 119.321183 -264.605158) (xy 119.28068 -264.633114)
			(xy 119.236218 -264.654212) (xy 119.188947 -264.667904) (xy 119.140092 -264.673836) (xy 119.090917 -264.671855)
			(xy 119.042698 -264.662011) (xy 118.996682 -264.644559) (xy 118.954061 -264.619952) (xy 118.91594 -264.588827)
			(xy 118.883305 -264.55199) (xy 118.857002 -264.510394) (xy 118.837711 -264.465118) (xy 118.825934 -264.417334)
			(xy 118.821974 -264.36828) (xy 117.553232 -264.36828) (xy 117.552737 -264.392887) (xy 117.544842 -264.441464)
			(xy 117.529258 -264.488145) (xy 117.506387 -264.531722) (xy 117.476822 -264.571066) (xy 117.441329 -264.605158)
			(xy 117.400826 -264.633114) (xy 117.356364 -264.654212) (xy 117.309093 -264.667904) (xy 117.260238 -264.673836)
			(xy 117.211063 -264.671855) (xy 117.162844 -264.662011) (xy 117.116828 -264.644559) (xy 117.074207 -264.619952)
			(xy 117.036086 -264.588827) (xy 117.003451 -264.55199) (xy 116.977148 -264.510394) (xy 116.957857 -264.465118)
			(xy 116.94608 -264.417334) (xy 116.94212 -264.36828) (xy 115.673124 -264.36828) (xy 115.672629 -264.392887)
			(xy 115.664734 -264.441464) (xy 115.64915 -264.488145) (xy 115.626279 -264.531722) (xy 115.596714 -264.571066)
			(xy 115.561221 -264.605158) (xy 115.520718 -264.633114) (xy 115.476256 -264.654212) (xy 115.428985 -264.667904)
			(xy 115.38013 -264.673836) (xy 115.330955 -264.671855) (xy 115.282736 -264.662011) (xy 115.23672 -264.644559)
			(xy 115.194099 -264.619952) (xy 115.155978 -264.588827) (xy 115.123343 -264.55199) (xy 115.09704 -264.510394)
			(xy 115.077749 -264.465118) (xy 115.065972 -264.417334) (xy 115.062012 -264.36828) (xy 108.1532 -264.36828)
			(xy 108.152705 -264.392887) (xy 108.14481 -264.441464) (xy 108.129226 -264.488145) (xy 108.106355 -264.531722)
			(xy 108.07679 -264.571066) (xy 108.041297 -264.605158) (xy 108.000794 -264.633114) (xy 107.956332 -264.654212)
			(xy 107.909061 -264.667904) (xy 107.860206 -264.673836) (xy 107.811031 -264.671855) (xy 107.762812 -264.662011)
			(xy 107.716796 -264.644559) (xy 107.674175 -264.619952) (xy 107.636054 -264.588827) (xy 107.603419 -264.55199)
			(xy 107.577116 -264.510394) (xy 107.557825 -264.465118) (xy 107.546048 -264.417334) (xy 107.542088 -264.36828)
			(xy 106.273346 -264.36828) (xy 106.272851 -264.392887) (xy 106.264956 -264.441464) (xy 106.249372 -264.488145)
			(xy 106.226501 -264.531722) (xy 106.196936 -264.571066) (xy 106.161443 -264.605158) (xy 106.12094 -264.633114)
			(xy 106.076478 -264.654212) (xy 106.029207 -264.667904) (xy 105.980352 -264.673836) (xy 105.931177 -264.671855)
			(xy 105.882958 -264.662011) (xy 105.836942 -264.644559) (xy 105.794321 -264.619952) (xy 105.7562 -264.588827)
			(xy 105.723565 -264.55199) (xy 105.697262 -264.510394) (xy 105.677971 -264.465118) (xy 105.666194 -264.417334)
			(xy 105.662234 -264.36828) (xy 104.393238 -264.36828) (xy 104.392743 -264.392887) (xy 104.384848 -264.441464)
			(xy 104.369264 -264.488145) (xy 104.346393 -264.531722) (xy 104.316828 -264.571066) (xy 104.281335 -264.605158)
			(xy 104.240832 -264.633114) (xy 104.19637 -264.654212) (xy 104.149099 -264.667904) (xy 104.100244 -264.673836)
			(xy 104.051069 -264.671855) (xy 104.00285 -264.662011) (xy 103.956834 -264.644559) (xy 103.914213 -264.619952)
			(xy 103.876092 -264.588827) (xy 103.843457 -264.55199) (xy 103.817154 -264.510394) (xy 103.797863 -264.465118)
			(xy 103.786086 -264.417334) (xy 103.782126 -264.36828) (xy 102.516391 -264.36828) (xy 102.515937 -264.390855)
			(xy 102.508042 -264.439432) (xy 102.492458 -264.486113) (xy 102.469587 -264.52969) (xy 102.440022 -264.569034)
			(xy 102.404529 -264.603126) (xy 102.364026 -264.631082) (xy 102.319564 -264.65218) (xy 102.272293 -264.665872)
			(xy 102.223438 -264.671804) (xy 102.174263 -264.669823) (xy 102.126044 -264.659979) (xy 102.080028 -264.642527)
			(xy 102.037407 -264.61792) (xy 101.999286 -264.586795) (xy 101.966651 -264.549958) (xy 101.940348 -264.508362)
			(xy 101.921057 -264.463086) (xy 101.90928 -264.415302) (xy 101.90532 -264.366248) (xy 101.07168 -264.366248)
			(xy 101.07168 -264.563098) (xy 101.072136 -264.572977) (xy 101.079572 -264.591283) (xy 101.086158 -264.598658)
			(xy 101.086412 -264.598912) (xy 101.343968 -264.856468) (xy 101.349646 -264.862564) (xy 111.234223 -264.862564)
			(xy 111.238253 -264.810066) (xy 111.25025 -264.758798) (xy 111.269933 -264.709963) (xy 111.296839 -264.664704)
			(xy 111.330339 -264.624083) (xy 111.369647 -264.589052) (xy 111.413842 -264.560432) (xy 111.461887 -264.538893)
			(xy 111.512658 -264.524941) (xy 111.564963 -264.518903) (xy 111.617577 -264.52092) (xy 111.669267 -264.530944)
			(xy 111.71882 -264.548742) (xy 111.765076 -264.573895) (xy 111.80695 -264.605814) (xy 111.843462 -264.643752)
			(xy 111.873754 -264.686818) (xy 111.897117 -264.734003) (xy 111.913003 -264.784202) (xy 111.92104 -264.836238)
			(xy 111.921544 -264.862564) (xy 111.92104 -264.88889) (xy 111.913003 -264.940926) (xy 111.897117 -264.991125)
			(xy 111.873754 -265.03831) (xy 111.843462 -265.081376) (xy 111.80695 -265.119314) (xy 111.765076 -265.151233)
			(xy 111.719063 -265.176254) (xy 121.168934 -265.176254) (xy 121.172894 -265.1272) (xy 121.184671 -265.079416)
			(xy 121.203962 -265.03414) (xy 121.230265 -264.992544) (xy 121.2629 -264.955707) (xy 121.301021 -264.924582)
			(xy 121.343642 -264.899975) (xy 121.389658 -264.882523) (xy 121.437877 -264.872679) (xy 121.487052 -264.870698)
			(xy 121.535907 -264.87663) (xy 121.583178 -264.890322) (xy 121.62764 -264.91142) (xy 121.668143 -264.939376)
			(xy 121.703636 -264.973468) (xy 121.733201 -265.012812) (xy 121.756072 -265.056389) (xy 121.771656 -265.10307)
			(xy 121.779551 -265.151647) (xy 121.780046 -265.176254) (xy 123.049042 -265.176254) (xy 123.053002 -265.1272)
			(xy 123.064779 -265.079416) (xy 123.08407 -265.03414) (xy 123.110373 -264.992544) (xy 123.143008 -264.955707)
			(xy 123.181129 -264.924582) (xy 123.22375 -264.899975) (xy 123.269766 -264.882523) (xy 123.317985 -264.872679)
			(xy 123.36716 -264.870698) (xy 123.416015 -264.87663) (xy 123.463286 -264.890322) (xy 123.507748 -264.91142)
			(xy 123.548251 -264.939376) (xy 123.583744 -264.973468) (xy 123.613309 -265.012812) (xy 123.63618 -265.056389)
			(xy 123.651764 -265.10307) (xy 123.659659 -265.151647) (xy 123.660154 -265.176254) (xy 124.928896 -265.176254)
			(xy 124.932856 -265.1272) (xy 124.944633 -265.079416) (xy 124.963924 -265.03414) (xy 124.990227 -264.992544)
			(xy 125.022862 -264.955707) (xy 125.060983 -264.924582) (xy 125.103604 -264.899975) (xy 125.14962 -264.882523)
			(xy 125.197839 -264.872679) (xy 125.247014 -264.870698) (xy 125.295869 -264.87663) (xy 125.34314 -264.890322)
			(xy 125.387602 -264.91142) (xy 125.428105 -264.939376) (xy 125.463598 -264.973468) (xy 125.493163 -265.012812)
			(xy 125.516034 -265.056389) (xy 125.531618 -265.10307) (xy 125.539513 -265.151647) (xy 125.540008 -265.176254)
			(xy 126.809004 -265.176254) (xy 126.812964 -265.1272) (xy 126.824741 -265.079416) (xy 126.844032 -265.03414)
			(xy 126.870335 -264.992544) (xy 126.90297 -264.955707) (xy 126.941091 -264.924582) (xy 126.983712 -264.899975)
			(xy 127.029728 -264.882523) (xy 127.077947 -264.872679) (xy 127.127122 -264.870698) (xy 127.175977 -264.87663)
			(xy 127.223248 -264.890322) (xy 127.26771 -264.91142) (xy 127.308213 -264.939376) (xy 127.343706 -264.973468)
			(xy 127.373271 -265.012812) (xy 127.396142 -265.056389) (xy 127.411726 -265.10307) (xy 127.419621 -265.151647)
			(xy 127.420116 -265.176254) (xy 127.738627 -265.176254) (xy 127.742722 -265.125526) (xy 127.754901 -265.076112)
			(xy 127.774849 -265.029292) (xy 127.80205 -264.986278) (xy 127.835798 -264.948184) (xy 127.87522 -264.915997)
			(xy 127.919294 -264.890551) (xy 127.96688 -264.872504) (xy 128.016744 -264.862324) (xy 128.067596 -264.860275)
			(xy 128.118117 -264.866409) (xy 128.167001 -264.880569) (xy 128.21298 -264.902386) (xy 128.254864 -264.931296)
			(xy 128.291568 -264.966551) (xy 128.322141 -265.007237) (xy 128.345792 -265.0523) (xy 128.361908 -265.100574)
			(xy 128.370072 -265.150808) (xy 128.370584 -265.176254) (xy 128.688858 -265.176254) (xy 128.692818 -265.1272)
			(xy 128.704595 -265.079416) (xy 128.723886 -265.03414) (xy 128.750189 -264.992544) (xy 128.782824 -264.955707)
			(xy 128.820945 -264.924582) (xy 128.863566 -264.899975) (xy 128.909582 -264.882523) (xy 128.957801 -264.872679)
			(xy 129.006976 -264.870698) (xy 129.055831 -264.87663) (xy 129.103102 -264.890322) (xy 129.147564 -264.91142)
			(xy 129.188067 -264.939376) (xy 129.22356 -264.973468) (xy 129.253125 -265.012812) (xy 129.275996 -265.056389)
			(xy 129.29158 -265.10307) (xy 129.299475 -265.151647) (xy 129.29997 -265.176254) (xy 129.628912 -265.176254)
			(xy 129.632872 -265.1272) (xy 129.644649 -265.079416) (xy 129.66394 -265.03414) (xy 129.690243 -264.992544)
			(xy 129.722878 -264.955707) (xy 129.760999 -264.924582) (xy 129.80362 -264.899975) (xy 129.849636 -264.882523)
			(xy 129.897855 -264.872679) (xy 129.94703 -264.870698) (xy 129.995885 -264.87663) (xy 130.043156 -264.890322)
			(xy 130.087618 -264.91142) (xy 130.128121 -264.939376) (xy 130.163614 -264.973468) (xy 130.193179 -265.012812)
			(xy 130.21605 -265.056389) (xy 130.231634 -265.10307) (xy 130.239529 -265.151647) (xy 130.240024 -265.176254)
			(xy 130.568966 -265.176254) (xy 130.572926 -265.1272) (xy 130.584703 -265.079416) (xy 130.603994 -265.03414)
			(xy 130.630297 -264.992544) (xy 130.662932 -264.955707) (xy 130.701053 -264.924582) (xy 130.743674 -264.899975)
			(xy 130.78969 -264.882523) (xy 130.837909 -264.872679) (xy 130.887084 -264.870698) (xy 130.935939 -264.87663)
			(xy 130.98321 -264.890322) (xy 131.027672 -264.91142) (xy 131.068175 -264.939376) (xy 131.103668 -264.973468)
			(xy 131.133233 -265.012812) (xy 131.156104 -265.056389) (xy 131.171688 -265.10307) (xy 131.179583 -265.151647)
			(xy 131.180078 -265.176254) (xy 131.498589 -265.176254) (xy 131.502684 -265.125526) (xy 131.514863 -265.076112)
			(xy 131.534811 -265.029292) (xy 131.562012 -264.986278) (xy 131.59576 -264.948184) (xy 131.635182 -264.915997)
			(xy 131.679256 -264.890551) (xy 131.726842 -264.872504) (xy 131.776706 -264.862324) (xy 131.827558 -264.860275)
			(xy 131.878079 -264.866409) (xy 131.926963 -264.880569) (xy 131.972942 -264.902386) (xy 132.014826 -264.931296)
			(xy 132.05153 -264.966551) (xy 132.082103 -265.007237) (xy 132.105754 -265.0523) (xy 132.12187 -265.100574)
			(xy 132.130034 -265.150808) (xy 132.130546 -265.176254) (xy 132.44882 -265.176254) (xy 132.45278 -265.1272)
			(xy 132.464557 -265.079416) (xy 132.483848 -265.03414) (xy 132.510151 -264.992544) (xy 132.542786 -264.955707)
			(xy 132.580907 -264.924582) (xy 132.623528 -264.899975) (xy 132.669544 -264.882523) (xy 132.717763 -264.872679)
			(xy 132.766938 -264.870698) (xy 132.815793 -264.87663) (xy 132.863064 -264.890322) (xy 132.907526 -264.91142)
			(xy 132.948029 -264.939376) (xy 132.983522 -264.973468) (xy 133.013087 -265.012812) (xy 133.035958 -265.056389)
			(xy 133.051542 -265.10307) (xy 133.059437 -265.151647) (xy 133.059932 -265.176254) (xy 133.388874 -265.176254)
			(xy 133.392834 -265.1272) (xy 133.404611 -265.079416) (xy 133.423902 -265.03414) (xy 133.450205 -264.992544)
			(xy 133.48284 -264.955707) (xy 133.520961 -264.924582) (xy 133.563582 -264.899975) (xy 133.609598 -264.882523)
			(xy 133.657817 -264.872679) (xy 133.706992 -264.870698) (xy 133.755847 -264.87663) (xy 133.803118 -264.890322)
			(xy 133.84758 -264.91142) (xy 133.888083 -264.939376) (xy 133.923576 -264.973468) (xy 133.953141 -265.012812)
			(xy 133.976012 -265.056389) (xy 133.991596 -265.10307) (xy 133.999491 -265.151647) (xy 133.999986 -265.176254)
			(xy 134.328928 -265.176254) (xy 134.332888 -265.1272) (xy 134.344665 -265.079416) (xy 134.363956 -265.03414)
			(xy 134.390259 -264.992544) (xy 134.422894 -264.955707) (xy 134.461015 -264.924582) (xy 134.503636 -264.899975)
			(xy 134.549652 -264.882523) (xy 134.597871 -264.872679) (xy 134.647046 -264.870698) (xy 134.695901 -264.87663)
			(xy 134.743172 -264.890322) (xy 134.787634 -264.91142) (xy 134.828137 -264.939376) (xy 134.86363 -264.973468)
			(xy 134.893195 -265.012812) (xy 134.916066 -265.056389) (xy 134.93165 -265.10307) (xy 134.939545 -265.151647)
			(xy 134.94004 -265.176254) (xy 135.268982 -265.176254) (xy 135.272942 -265.1272) (xy 135.284719 -265.079416)
			(xy 135.30401 -265.03414) (xy 135.330313 -264.992544) (xy 135.362948 -264.955707) (xy 135.401069 -264.924582)
			(xy 135.44369 -264.899975) (xy 135.489706 -264.882523) (xy 135.537925 -264.872679) (xy 135.5871 -264.870698)
			(xy 135.635955 -264.87663) (xy 135.683226 -264.890322) (xy 135.727688 -264.91142) (xy 135.768191 -264.939376)
			(xy 135.803684 -264.973468) (xy 135.833249 -265.012812) (xy 135.85612 -265.056389) (xy 135.871704 -265.10307)
			(xy 135.879599 -265.151647) (xy 135.880094 -265.176254) (xy 136.209036 -265.176254) (xy 136.212996 -265.1272)
			(xy 136.224773 -265.079416) (xy 136.244064 -265.03414) (xy 136.270367 -264.992544) (xy 136.303002 -264.955707)
			(xy 136.341123 -264.924582) (xy 136.383744 -264.899975) (xy 136.42976 -264.882523) (xy 136.477979 -264.872679)
			(xy 136.527154 -264.870698) (xy 136.576009 -264.87663) (xy 136.62328 -264.890322) (xy 136.667742 -264.91142)
			(xy 136.708245 -264.939376) (xy 136.743738 -264.973468) (xy 136.773303 -265.012812) (xy 136.796174 -265.056389)
			(xy 136.811758 -265.10307) (xy 136.819653 -265.151647) (xy 136.820148 -265.176254) (xy 137.148836 -265.176254)
			(xy 137.152796 -265.1272) (xy 137.164573 -265.079416) (xy 137.183864 -265.03414) (xy 137.210167 -264.992544)
			(xy 137.242802 -264.955707) (xy 137.280923 -264.924582) (xy 137.323544 -264.899975) (xy 137.36956 -264.882523)
			(xy 137.417779 -264.872679) (xy 137.466954 -264.870698) (xy 137.515809 -264.87663) (xy 137.56308 -264.890322)
			(xy 137.607542 -264.91142) (xy 137.648045 -264.939376) (xy 137.683538 -264.973468) (xy 137.713103 -265.012812)
			(xy 137.735974 -265.056389) (xy 137.751558 -265.10307) (xy 137.759453 -265.151647) (xy 137.759948 -265.176254)
			(xy 138.08889 -265.176254) (xy 138.09285 -265.1272) (xy 138.104627 -265.079416) (xy 138.123918 -265.03414)
			(xy 138.150221 -264.992544) (xy 138.182856 -264.955707) (xy 138.220977 -264.924582) (xy 138.263598 -264.899975)
			(xy 138.309614 -264.882523) (xy 138.357833 -264.872679) (xy 138.407008 -264.870698) (xy 138.455863 -264.87663)
			(xy 138.503134 -264.890322) (xy 138.547596 -264.91142) (xy 138.588099 -264.939376) (xy 138.623592 -264.973468)
			(xy 138.653157 -265.012812) (xy 138.676028 -265.056389) (xy 138.691612 -265.10307) (xy 138.699507 -265.151647)
			(xy 138.700002 -265.176254) (xy 139.028944 -265.176254) (xy 139.032904 -265.1272) (xy 139.044681 -265.079416)
			(xy 139.063972 -265.03414) (xy 139.090275 -264.992544) (xy 139.12291 -264.955707) (xy 139.161031 -264.924582)
			(xy 139.203652 -264.899975) (xy 139.249668 -264.882523) (xy 139.297887 -264.872679) (xy 139.347062 -264.870698)
			(xy 139.395917 -264.87663) (xy 139.443188 -264.890322) (xy 139.48765 -264.91142) (xy 139.528153 -264.939376)
			(xy 139.563646 -264.973468) (xy 139.593211 -265.012812) (xy 139.616082 -265.056389) (xy 139.631666 -265.10307)
			(xy 139.639561 -265.151647) (xy 139.640056 -265.176254) (xy 139.639561 -265.200861) (xy 139.631666 -265.249438)
			(xy 139.616082 -265.296119) (xy 139.593211 -265.339696) (xy 139.563646 -265.37904) (xy 139.528153 -265.413132)
			(xy 139.48765 -265.441088) (xy 139.443188 -265.462186) (xy 139.395917 -265.475878) (xy 139.347062 -265.48181)
			(xy 139.297887 -265.479829) (xy 139.249668 -265.469985) (xy 139.203652 -265.452533) (xy 139.161031 -265.427926)
			(xy 139.12291 -265.396801) (xy 139.090275 -265.359964) (xy 139.063972 -265.318368) (xy 139.044681 -265.273092)
			(xy 139.032904 -265.225308) (xy 139.028944 -265.176254) (xy 138.700002 -265.176254) (xy 138.699507 -265.200861)
			(xy 138.691612 -265.249438) (xy 138.676028 -265.296119) (xy 138.653157 -265.339696) (xy 138.623592 -265.37904)
			(xy 138.588099 -265.413132) (xy 138.547596 -265.441088) (xy 138.503134 -265.462186) (xy 138.455863 -265.475878)
			(xy 138.407008 -265.48181) (xy 138.357833 -265.479829) (xy 138.309614 -265.469985) (xy 138.263598 -265.452533)
			(xy 138.220977 -265.427926) (xy 138.182856 -265.396801) (xy 138.150221 -265.359964) (xy 138.123918 -265.318368)
			(xy 138.104627 -265.273092) (xy 138.09285 -265.225308) (xy 138.08889 -265.176254) (xy 137.759948 -265.176254)
			(xy 137.759453 -265.200861) (xy 137.751558 -265.249438) (xy 137.735974 -265.296119) (xy 137.713103 -265.339696)
			(xy 137.683538 -265.37904) (xy 137.648045 -265.413132) (xy 137.607542 -265.441088) (xy 137.56308 -265.462186)
			(xy 137.515809 -265.475878) (xy 137.466954 -265.48181) (xy 137.417779 -265.479829) (xy 137.36956 -265.469985)
			(xy 137.323544 -265.452533) (xy 137.280923 -265.427926) (xy 137.242802 -265.396801) (xy 137.210167 -265.359964)
			(xy 137.183864 -265.318368) (xy 137.164573 -265.273092) (xy 137.152796 -265.225308) (xy 137.148836 -265.176254)
			(xy 136.820148 -265.176254) (xy 136.819653 -265.200861) (xy 136.811758 -265.249438) (xy 136.796174 -265.296119)
			(xy 136.773303 -265.339696) (xy 136.743738 -265.37904) (xy 136.708245 -265.413132) (xy 136.667742 -265.441088)
			(xy 136.62328 -265.462186) (xy 136.576009 -265.475878) (xy 136.527154 -265.48181) (xy 136.477979 -265.479829)
			(xy 136.42976 -265.469985) (xy 136.383744 -265.452533) (xy 136.341123 -265.427926) (xy 136.303002 -265.396801)
			(xy 136.270367 -265.359964) (xy 136.244064 -265.318368) (xy 136.224773 -265.273092) (xy 136.212996 -265.225308)
			(xy 136.209036 -265.176254) (xy 135.880094 -265.176254) (xy 135.879599 -265.200861) (xy 135.871704 -265.249438)
			(xy 135.85612 -265.296119) (xy 135.833249 -265.339696) (xy 135.803684 -265.37904) (xy 135.768191 -265.413132)
			(xy 135.727688 -265.441088) (xy 135.683226 -265.462186) (xy 135.635955 -265.475878) (xy 135.5871 -265.48181)
			(xy 135.537925 -265.479829) (xy 135.489706 -265.469985) (xy 135.44369 -265.452533) (xy 135.401069 -265.427926)
			(xy 135.362948 -265.396801) (xy 135.330313 -265.359964) (xy 135.30401 -265.318368) (xy 135.284719 -265.273092)
			(xy 135.272942 -265.225308) (xy 135.268982 -265.176254) (xy 134.94004 -265.176254) (xy 134.939545 -265.200861)
			(xy 134.93165 -265.249438) (xy 134.916066 -265.296119) (xy 134.893195 -265.339696) (xy 134.86363 -265.37904)
			(xy 134.828137 -265.413132) (xy 134.787634 -265.441088) (xy 134.743172 -265.462186) (xy 134.695901 -265.475878)
			(xy 134.647046 -265.48181) (xy 134.597871 -265.479829) (xy 134.549652 -265.469985) (xy 134.503636 -265.452533)
			(xy 134.461015 -265.427926) (xy 134.422894 -265.396801) (xy 134.390259 -265.359964) (xy 134.363956 -265.318368)
			(xy 134.344665 -265.273092) (xy 134.332888 -265.225308) (xy 134.328928 -265.176254) (xy 133.999986 -265.176254)
			(xy 133.999491 -265.200861) (xy 133.991596 -265.249438) (xy 133.976012 -265.296119) (xy 133.953141 -265.339696)
			(xy 133.923576 -265.37904) (xy 133.888083 -265.413132) (xy 133.84758 -265.441088) (xy 133.803118 -265.462186)
			(xy 133.755847 -265.475878) (xy 133.706992 -265.48181) (xy 133.657817 -265.479829) (xy 133.609598 -265.469985)
			(xy 133.563582 -265.452533) (xy 133.520961 -265.427926) (xy 133.48284 -265.396801) (xy 133.450205 -265.359964)
			(xy 133.423902 -265.318368) (xy 133.404611 -265.273092) (xy 133.392834 -265.225308) (xy 133.388874 -265.176254)
			(xy 133.059932 -265.176254) (xy 133.059437 -265.200861) (xy 133.051542 -265.249438) (xy 133.035958 -265.296119)
			(xy 133.013087 -265.339696) (xy 132.983522 -265.37904) (xy 132.948029 -265.413132) (xy 132.907526 -265.441088)
			(xy 132.863064 -265.462186) (xy 132.815793 -265.475878) (xy 132.766938 -265.48181) (xy 132.717763 -265.479829)
			(xy 132.669544 -265.469985) (xy 132.623528 -265.452533) (xy 132.580907 -265.427926) (xy 132.542786 -265.396801)
			(xy 132.510151 -265.359964) (xy 132.483848 -265.318368) (xy 132.464557 -265.273092) (xy 132.45278 -265.225308)
			(xy 132.44882 -265.176254) (xy 132.130546 -265.176254) (xy 132.130034 -265.2017) (xy 132.12187 -265.251934)
			(xy 132.105754 -265.300208) (xy 132.082103 -265.345271) (xy 132.05153 -265.385957) (xy 132.014826 -265.421212)
			(xy 131.972942 -265.450122) (xy 131.926963 -265.471939) (xy 131.878079 -265.486099) (xy 131.827558 -265.492233)
			(xy 131.776706 -265.490184) (xy 131.726842 -265.480004) (xy 131.679256 -265.461957) (xy 131.635182 -265.436511)
			(xy 131.59576 -265.404324) (xy 131.562012 -265.36623) (xy 131.534811 -265.323216) (xy 131.514863 -265.276396)
			(xy 131.502684 -265.226982) (xy 131.498589 -265.176254) (xy 131.180078 -265.176254) (xy 131.179583 -265.200861)
			(xy 131.171688 -265.249438) (xy 131.156104 -265.296119) (xy 131.133233 -265.339696) (xy 131.103668 -265.37904)
			(xy 131.068175 -265.413132) (xy 131.027672 -265.441088) (xy 130.98321 -265.462186) (xy 130.935939 -265.475878)
			(xy 130.887084 -265.48181) (xy 130.837909 -265.479829) (xy 130.78969 -265.469985) (xy 130.743674 -265.452533)
			(xy 130.701053 -265.427926) (xy 130.662932 -265.396801) (xy 130.630297 -265.359964) (xy 130.603994 -265.318368)
			(xy 130.584703 -265.273092) (xy 130.572926 -265.225308) (xy 130.568966 -265.176254) (xy 130.240024 -265.176254)
			(xy 130.239529 -265.200861) (xy 130.231634 -265.249438) (xy 130.21605 -265.296119) (xy 130.193179 -265.339696)
			(xy 130.163614 -265.37904) (xy 130.128121 -265.413132) (xy 130.087618 -265.441088) (xy 130.043156 -265.462186)
			(xy 129.995885 -265.475878) (xy 129.94703 -265.48181) (xy 129.897855 -265.479829) (xy 129.849636 -265.469985)
			(xy 129.80362 -265.452533) (xy 129.760999 -265.427926) (xy 129.722878 -265.396801) (xy 129.690243 -265.359964)
			(xy 129.66394 -265.318368) (xy 129.644649 -265.273092) (xy 129.632872 -265.225308) (xy 129.628912 -265.176254)
			(xy 129.29997 -265.176254) (xy 129.299475 -265.200861) (xy 129.29158 -265.249438) (xy 129.275996 -265.296119)
			(xy 129.253125 -265.339696) (xy 129.22356 -265.37904) (xy 129.188067 -265.413132) (xy 129.147564 -265.441088)
			(xy 129.103102 -265.462186) (xy 129.055831 -265.475878) (xy 129.006976 -265.48181) (xy 128.957801 -265.479829)
			(xy 128.909582 -265.469985) (xy 128.863566 -265.452533) (xy 128.820945 -265.427926) (xy 128.782824 -265.396801)
			(xy 128.750189 -265.359964) (xy 128.723886 -265.318368) (xy 128.704595 -265.273092) (xy 128.692818 -265.225308)
			(xy 128.688858 -265.176254) (xy 128.370584 -265.176254) (xy 128.370072 -265.2017) (xy 128.361908 -265.251934)
			(xy 128.345792 -265.300208) (xy 128.322141 -265.345271) (xy 128.291568 -265.385957) (xy 128.254864 -265.421212)
			(xy 128.21298 -265.450122) (xy 128.167001 -265.471939) (xy 128.118117 -265.486099) (xy 128.067596 -265.492233)
			(xy 128.016744 -265.490184) (xy 127.96688 -265.480004) (xy 127.919294 -265.461957) (xy 127.87522 -265.436511)
			(xy 127.835798 -265.404324) (xy 127.80205 -265.36623) (xy 127.774849 -265.323216) (xy 127.754901 -265.276396)
			(xy 127.742722 -265.226982) (xy 127.738627 -265.176254) (xy 127.420116 -265.176254) (xy 127.419621 -265.200861)
			(xy 127.411726 -265.249438) (xy 127.396142 -265.296119) (xy 127.373271 -265.339696) (xy 127.343706 -265.37904)
			(xy 127.308213 -265.413132) (xy 127.26771 -265.441088) (xy 127.223248 -265.462186) (xy 127.175977 -265.475878)
			(xy 127.127122 -265.48181) (xy 127.077947 -265.479829) (xy 127.029728 -265.469985) (xy 126.983712 -265.452533)
			(xy 126.941091 -265.427926) (xy 126.90297 -265.396801) (xy 126.870335 -265.359964) (xy 126.844032 -265.318368)
			(xy 126.824741 -265.273092) (xy 126.812964 -265.225308) (xy 126.809004 -265.176254) (xy 125.540008 -265.176254)
			(xy 125.539513 -265.200861) (xy 125.531618 -265.249438) (xy 125.516034 -265.296119) (xy 125.493163 -265.339696)
			(xy 125.463598 -265.37904) (xy 125.428105 -265.413132) (xy 125.387602 -265.441088) (xy 125.34314 -265.462186)
			(xy 125.295869 -265.475878) (xy 125.247014 -265.48181) (xy 125.197839 -265.479829) (xy 125.14962 -265.469985)
			(xy 125.103604 -265.452533) (xy 125.060983 -265.427926) (xy 125.022862 -265.396801) (xy 124.990227 -265.359964)
			(xy 124.963924 -265.318368) (xy 124.944633 -265.273092) (xy 124.932856 -265.225308) (xy 124.928896 -265.176254)
			(xy 123.660154 -265.176254) (xy 123.659659 -265.200861) (xy 123.651764 -265.249438) (xy 123.63618 -265.296119)
			(xy 123.613309 -265.339696) (xy 123.583744 -265.37904) (xy 123.548251 -265.413132) (xy 123.507748 -265.441088)
			(xy 123.463286 -265.462186) (xy 123.416015 -265.475878) (xy 123.36716 -265.48181) (xy 123.317985 -265.479829)
			(xy 123.269766 -265.469985) (xy 123.22375 -265.452533) (xy 123.181129 -265.427926) (xy 123.143008 -265.396801)
			(xy 123.110373 -265.359964) (xy 123.08407 -265.318368) (xy 123.064779 -265.273092) (xy 123.053002 -265.225308)
			(xy 123.049042 -265.176254) (xy 121.780046 -265.176254) (xy 121.779551 -265.200861) (xy 121.771656 -265.249438)
			(xy 121.756072 -265.296119) (xy 121.733201 -265.339696) (xy 121.703636 -265.37904) (xy 121.668143 -265.413132)
			(xy 121.62764 -265.441088) (xy 121.583178 -265.462186) (xy 121.535907 -265.475878) (xy 121.487052 -265.48181)
			(xy 121.437877 -265.479829) (xy 121.389658 -265.469985) (xy 121.343642 -265.452533) (xy 121.301021 -265.427926)
			(xy 121.2629 -265.396801) (xy 121.230265 -265.359964) (xy 121.203962 -265.318368) (xy 121.184671 -265.273092)
			(xy 121.172894 -265.225308) (xy 121.168934 -265.176254) (xy 111.719063 -265.176254) (xy 111.71882 -265.176386)
			(xy 111.669267 -265.194184) (xy 111.617577 -265.204208) (xy 111.564963 -265.206225) (xy 111.512658 -265.200187)
			(xy 111.461887 -265.186235) (xy 111.413842 -265.164696) (xy 111.369647 -265.136076) (xy 111.330339 -265.101045)
			(xy 111.296839 -265.060424) (xy 111.269933 -265.015165) (xy 111.25025 -264.96633) (xy 111.238253 -264.915062)
			(xy 111.234223 -264.862564) (xy 101.349646 -264.862564) (xy 101.349871 -264.862806) (xy 101.357415 -264.878384)
			(xy 101.3587 -264.886948) (xy 101.360224 -264.900664) (xy 101.37648 -264.922508) (xy 101.489764 -264.971022)
			(xy 101.519482 -264.965688) (xy 101.530658 -264.95502) (xy 101.547775 -264.939329) (xy 101.585872 -264.912784)
			(xy 101.627554 -264.892323) (xy 101.671855 -264.878417) (xy 101.717753 -264.871388) (xy 101.74097 -264.870946)
			(xy 101.766233 -264.871436) (xy 101.816071 -264.879748) (xy 101.863861 -264.896151) (xy 101.908299 -264.920195)
			(xy 101.948173 -264.951227) (xy 101.982395 -264.988399) (xy 102.010032 -265.030696) (xy 102.030329 -265.076967)
			(xy 102.042733 -265.125946) (xy 102.046906 -265.1763) (xy 102.042733 -265.226654) (xy 102.030329 -265.275634)
			(xy 102.010032 -265.321904) (xy 101.982395 -265.364201) (xy 101.948173 -265.401373) (xy 101.908299 -265.432405)
			(xy 101.863861 -265.456449) (xy 101.816071 -265.472852) (xy 101.766233 -265.481164) (xy 101.74097 -265.481562)
			(xy 101.717754 -265.481126) (xy 101.671858 -265.474087) (xy 101.627558 -265.460176) (xy 101.585877 -265.439715)
			(xy 101.547777 -265.413176) (xy 101.530658 -265.397488) (xy 101.519482 -265.38682) (xy 101.489764 -265.381486)
			(xy 101.389688 -265.424412) (xy 101.38076 -265.428742) (xy 101.366861 -265.442878) (xy 101.359379 -265.461235)
			(xy 101.358954 -265.471148) (xy 101.358954 -265.576812) (xy 101.358527 -265.58688) (xy 101.350805 -265.605477)
			(xy 101.343968 -265.61288) (xy 101.042216 -265.914632) (xy 101.035503 -265.92187) (xy 101.027912 -265.940075)
			(xy 101.027484 -265.949938) (xy 101.027484 -265.98626) (xy 101.90532 -265.98626) (xy 101.90928 -265.937206)
			(xy 101.921057 -265.889422) (xy 101.940348 -265.844146) (xy 101.966651 -265.80255) (xy 101.999286 -265.765713)
			(xy 102.037407 -265.734588) (xy 102.080028 -265.709981) (xy 102.126044 -265.692529) (xy 102.174263 -265.682685)
			(xy 102.223438 -265.680704) (xy 102.272293 -265.686636) (xy 102.319564 -265.700328) (xy 102.364026 -265.721426)
			(xy 102.404529 -265.749382) (xy 102.440022 -265.783474) (xy 102.469587 -265.822818) (xy 102.492458 -265.866395)
			(xy 102.508042 -265.913076) (xy 102.515937 -265.961653) (xy 102.516432 -265.98626) (xy 102.515937 -266.010867)
			(xy 102.508042 -266.059444) (xy 102.492458 -266.106125) (xy 102.469587 -266.149702) (xy 102.440022 -266.189046)
			(xy 102.404529 -266.223138) (xy 102.364026 -266.251094) (xy 102.319564 -266.272192) (xy 102.272293 -266.285884)
			(xy 102.223438 -266.291816) (xy 102.174263 -266.289835) (xy 102.126044 -266.279991) (xy 102.080028 -266.262539)
			(xy 102.037407 -266.237932) (xy 101.999286 -266.206807) (xy 101.966651 -266.16997) (xy 101.940348 -266.128374)
			(xy 101.921057 -266.083098) (xy 101.90928 -266.035314) (xy 101.90532 -265.98626) (xy 101.027484 -265.98626)
			(xy 101.027484 -266.129262) (xy 101.027952 -266.139136) (xy 101.035404 -266.157425) (xy 101.041962 -266.164822)
			(xy 101.042216 -266.165076) (xy 101.440996 -266.563856) (xy 101.441504 -266.564364) (xy 101.448888 -266.570937)
			(xy 101.467187 -266.578367) (xy 101.477064 -266.578842) (xy 101.498146 -266.578842) (xy 101.502694 -266.57872)
			(xy 101.511639 -266.577062) (xy 101.515926 -266.57554) (xy 101.539294 -266.566904) (xy 101.545898 -266.561316)
			(xy 101.566626 -266.544853) (xy 101.612577 -266.518587) (xy 101.662367 -266.500631) (xy 101.714506 -266.491522)
			(xy 101.74097 -266.490958) (xy 101.764964 -266.491426) (xy 101.812361 -266.498929) (xy 101.858001 -266.513753)
			(xy 101.900761 -266.535534) (xy 101.939586 -266.563737) (xy 101.973522 -266.597665) (xy 102.001732 -266.636485)
			(xy 102.023523 -266.67924) (xy 102.038357 -266.724877) (xy 102.045869 -266.772272) (xy 102.046278 -266.796266)
			(xy 102.045878 -266.81797) (xy 102.039694 -266.860935) (xy 102.027488 -266.902591) (xy 102.018846 -266.922504)
			(xy 102.018846 -266.922758) (xy 102.018592 -266.923012) (xy 102.014083 -266.934906) (xy 102.016088 -266.960229)
			(xy 102.022402 -266.971272) (xy 102.06736 -267.041376) (xy 102.072219 -267.048326) (xy 102.085548 -267.058798)
			(xy 102.101558 -267.064364) (xy 102.110032 -267.064744) (xy 103.252016 -267.064744) (xy 103.260504 -267.064436)
			(xy 103.276545 -267.058885) (xy 103.289871 -267.04837) (xy 103.294688 -267.041376) (xy 103.339646 -266.971272)
			(xy 103.343988 -266.964028) (xy 103.348084 -266.947654) (xy 103.346627 -266.930838) (xy 103.343456 -266.923012)
			(xy 103.343202 -266.922758) (xy 103.343202 -266.922504) (xy 103.334554 -266.902593) (xy 103.322342 -266.860937)
			(xy 103.316155 -266.81797) (xy 103.31577 -266.796266) (xy 103.316243 -266.772276) (xy 103.323753 -266.724887)
			(xy 103.338583 -266.679256) (xy 103.360368 -266.636507) (xy 103.388572 -266.597691) (xy 103.4225 -266.563764)
			(xy 103.461317 -266.535562) (xy 103.504067 -266.513779) (xy 103.549699 -266.498951) (xy 103.597088 -266.491442)
			(xy 103.621078 -266.490958) (xy 103.646778 -266.491487) (xy 103.697453 -266.500099) (xy 103.745967 -266.517081)
			(xy 103.790949 -266.541955) (xy 103.831125 -266.574016) (xy 103.848662 -266.592812) (xy 103.856028 -266.60094)
			(xy 103.874824 -266.609576) (xy 103.885492 -266.60983) (xy 103.95712 -266.611862) (xy 103.966877 -266.611663)
			(xy 103.985155 -266.604869) (xy 103.99268 -266.598654) (xy 103.993696 -266.597892) (xy 104.120442 -266.471146)
			(xy 104.127145 -266.463904) (xy 104.134719 -266.445699) (xy 104.135174 -266.43584) (xy 104.135174 -266.398756)
			(xy 104.135052 -266.394208) (xy 104.133396 -266.385263) (xy 104.131872 -266.380976) (xy 104.111298 -266.325858)
			(xy 104.107003 -266.315835) (xy 104.091607 -266.300424) (xy 104.08158 -266.29614) (xy 104.067356 -266.290806)
			(xy 104.060752 -266.290044) (xy 104.035949 -266.287074) (xy 103.987713 -266.274102) (xy 103.942232 -266.253452)
			(xy 103.900718 -266.225676) (xy 103.864279 -266.191512) (xy 103.833885 -266.151874) (xy 103.810349 -266.107817)
			(xy 103.794297 -266.060517) (xy 103.786157 -266.011235) (xy 103.78567 -265.98626) (xy 103.786192 -265.961005)
			(xy 103.794505 -265.911183) (xy 103.810906 -265.863409) (xy 103.834947 -265.818986) (xy 103.865971 -265.779126)
			(xy 103.903133 -265.744916) (xy 103.945419 -265.71729) (xy 103.991675 -265.697) (xy 104.04064 -265.6846)
			(xy 104.090978 -265.680429) (xy 104.141316 -265.6846) (xy 104.190281 -265.697) (xy 104.236537 -265.71729)
			(xy 104.278823 -265.744916) (xy 104.315985 -265.779126) (xy 104.347009 -265.818986) (xy 104.37105 -265.863409)
			(xy 104.387451 -265.911183) (xy 104.395764 -265.961005) (xy 104.396286 -265.98626) (xy 105.665282 -265.98626)
			(xy 105.669242 -265.937206) (xy 105.681019 -265.889422) (xy 105.70031 -265.844146) (xy 105.726613 -265.80255)
			(xy 105.759248 -265.765713) (xy 105.797369 -265.734588) (xy 105.83999 -265.709981) (xy 105.886006 -265.692529)
			(xy 105.934225 -265.682685) (xy 105.9834 -265.680704) (xy 106.032255 -265.686636) (xy 106.079526 -265.700328)
			(xy 106.123988 -265.721426) (xy 106.164491 -265.749382) (xy 106.199984 -265.783474) (xy 106.229549 -265.822818)
			(xy 106.25242 -265.866395) (xy 106.268004 -265.913076) (xy 106.275899 -265.961653) (xy 106.276394 -265.98626)
			(xy 106.275899 -266.010867) (xy 106.268004 -266.059444) (xy 106.25242 -266.106125) (xy 106.229549 -266.149702)
			(xy 106.199984 -266.189046) (xy 106.164491 -266.223138) (xy 106.123988 -266.251094) (xy 106.079526 -266.272192)
			(xy 106.032255 -266.285884) (xy 105.9834 -266.291816) (xy 105.934225 -266.289835) (xy 105.886006 -266.279991)
			(xy 105.83999 -266.262539) (xy 105.797369 -266.237932) (xy 105.759248 -266.206807) (xy 105.726613 -266.16997)
			(xy 105.70031 -266.128374) (xy 105.681019 -266.083098) (xy 105.669242 -266.035314) (xy 105.665282 -265.98626)
			(xy 104.396286 -265.98626) (xy 104.396286 -265.999976) (xy 104.395242 -266.017487) (xy 104.389645 -266.052118)
			(xy 104.38511 -266.069064) (xy 104.381808 -266.080494) (xy 104.38638 -266.103862) (xy 104.44099 -266.175998)
			(xy 104.448584 -266.184982) (xy 104.469629 -266.19543) (xy 104.481376 -266.196064) (xy 105.43413 -266.196064)
			(xy 105.443971 -266.196592) (xy 105.462146 -266.204165) (xy 105.469436 -266.210796) (xy 105.627678 -266.369038)
			(xy 105.628186 -266.369546) (xy 105.635569 -266.376124) (xy 105.653868 -266.383563) (xy 105.663746 -266.384024)
			(xy 105.673398 -266.384024) (xy 106.298492 -267.009118) (xy 106.299 -267.009626) (xy 106.306382 -267.016204)
			(xy 106.324682 -267.023642) (xy 106.33456 -267.024104) (xy 106.995976 -267.024104) (xy 107.004741 -267.023686)
			(xy 107.021226 -267.017703) (xy 107.028234 -267.01242) (xy 107.033314 -267.008356) (xy 107.084114 -266.937998)
			(xy 107.088376 -266.93158) (xy 107.093283 -266.916985) (xy 107.093766 -266.909296) (xy 107.093766 -266.901168)
			(xy 107.089956 -266.888722) (xy 107.089956 -266.888468) (xy 107.08894 -266.884912) (xy 107.082715 -266.863023)
			(xy 107.076083 -266.818004) (xy 107.075732 -266.79525) (xy 107.075732 -266.79271) (xy 107.076469 -266.768905)
			(xy 107.084417 -266.721947) (xy 107.09956 -266.676794) (xy 107.121532 -266.63454) (xy 107.149798 -266.596211)
			(xy 107.183674 -266.562736) (xy 107.222337 -266.534927) (xy 107.264849 -266.513459) (xy 107.310179 -266.498854)
			(xy 107.357227 -266.491464) (xy 107.38104 -266.490958) (xy 107.407516 -266.491527) (xy 107.459672 -266.500667)
			(xy 107.50947 -266.518668) (xy 107.555417 -266.544988) (xy 107.596135 -266.578839) (xy 107.613704 -266.598654)
			(xy 107.620816 -266.607036) (xy 107.639612 -266.61618) (xy 107.723432 -266.619482) (xy 107.733933 -266.619393)
			(xy 107.753482 -266.611785) (xy 107.761278 -266.60475) (xy 107.903518 -266.46251) (xy 107.90682 -266.4587)
			(xy 107.907074 -266.4587) (xy 107.912506 -266.451497) (xy 107.918417 -266.434464) (xy 107.918116 -266.416438)
			(xy 107.915202 -266.4079) (xy 107.882436 -266.323572) (xy 107.878443 -266.314627) (xy 107.865003 -266.3004)
			(xy 107.847231 -266.292203) (xy 107.837478 -266.291314) (xy 107.837224 -266.291314) (xy 107.811376 -266.289607)
			(xy 107.760764 -266.278585) (xy 107.712739 -266.259179) (xy 107.668678 -266.231944) (xy 107.629847 -266.197664)
			(xy 107.597359 -266.15732) (xy 107.572147 -266.112072) (xy 107.554934 -266.063218) (xy 107.546214 -266.012159)
			(xy 107.545632 -265.98626) (xy 107.546106 -265.962272) (xy 107.553617 -265.914887) (xy 107.568448 -265.869261)
			(xy 107.590235 -265.826517) (xy 107.618439 -265.787707) (xy 107.652368 -265.753787) (xy 107.691185 -265.725593)
			(xy 107.733935 -265.703818) (xy 107.779565 -265.688998) (xy 107.826952 -265.681499) (xy 107.85094 -265.680952)
			(xy 107.874765 -265.681413) (xy 107.921837 -265.688821) (xy 107.967187 -265.703451) (xy 108.009713 -265.724949)
			(xy 108.048383 -265.752792) (xy 108.082259 -265.786303) (xy 108.110519 -265.82467) (xy 108.132475 -265.866962)
			(xy 108.147595 -265.91215) (xy 108.155511 -265.959139) (xy 108.156248 -265.982958) (xy 108.156248 -265.985752)
			(xy 108.156248 -265.98626) (xy 109.425244 -265.98626) (xy 109.429204 -265.937206) (xy 109.440981 -265.889422)
			(xy 109.460272 -265.844146) (xy 109.486575 -265.80255) (xy 109.51921 -265.765713) (xy 109.557331 -265.734588)
			(xy 109.599952 -265.709981) (xy 109.645968 -265.692529) (xy 109.694187 -265.682685) (xy 109.743362 -265.680704)
			(xy 109.792217 -265.686636) (xy 109.839488 -265.700328) (xy 109.88395 -265.721426) (xy 109.924453 -265.749382)
			(xy 109.959946 -265.783474) (xy 109.989511 -265.822818) (xy 110.012382 -265.866395) (xy 110.027966 -265.913076)
			(xy 110.035861 -265.961653) (xy 110.036356 -265.98626) (xy 113.178856 -265.98626) (xy 113.182816 -265.937206)
			(xy 113.194593 -265.889422) (xy 113.213884 -265.844146) (xy 113.240187 -265.80255) (xy 113.272822 -265.765713)
			(xy 113.310943 -265.734588) (xy 113.353564 -265.709981) (xy 113.39958 -265.692529) (xy 113.447799 -265.682685)
			(xy 113.496974 -265.680704) (xy 113.545829 -265.686636) (xy 113.5931 -265.700328) (xy 113.637562 -265.721426)
			(xy 113.678065 -265.749382) (xy 113.713558 -265.783474) (xy 113.743123 -265.822818) (xy 113.765994 -265.866395)
			(xy 113.781578 -265.913076) (xy 113.789473 -265.961653) (xy 113.789968 -265.98626) (xy 113.789473 -266.010867)
			(xy 113.781578 -266.059444) (xy 113.765994 -266.106125) (xy 113.743123 -266.149702) (xy 113.713558 -266.189046)
			(xy 113.678065 -266.223138) (xy 113.637562 -266.251094) (xy 113.5931 -266.272192) (xy 113.545829 -266.285884)
			(xy 113.496974 -266.291816) (xy 113.447799 -266.289835) (xy 113.39958 -266.279991) (xy 113.353564 -266.262539)
			(xy 113.310943 -266.237932) (xy 113.272822 -266.206807) (xy 113.240187 -266.16997) (xy 113.213884 -266.128374)
			(xy 113.194593 -266.083098) (xy 113.182816 -266.035314) (xy 113.178856 -265.98626) (xy 110.036356 -265.98626)
			(xy 110.035861 -266.010867) (xy 110.027966 -266.059444) (xy 110.012382 -266.106125) (xy 109.989511 -266.149702)
			(xy 109.959946 -266.189046) (xy 109.924453 -266.223138) (xy 109.88395 -266.251094) (xy 109.839488 -266.272192)
			(xy 109.792217 -266.285884) (xy 109.743362 -266.291816) (xy 109.694187 -266.289835) (xy 109.645968 -266.279991)
			(xy 109.599952 -266.262539) (xy 109.557331 -266.237932) (xy 109.51921 -266.206807) (xy 109.486575 -266.16997)
			(xy 109.460272 -266.128374) (xy 109.440981 -266.083098) (xy 109.429204 -266.035314) (xy 109.425244 -265.98626)
			(xy 108.156248 -265.98626) (xy 108.155764 -266.009557) (xy 108.148615 -266.055603) (xy 108.142024 -266.077954)
			(xy 108.138468 -266.089638) (xy 108.142278 -266.11326) (xy 108.196634 -266.187936) (xy 108.204241 -266.197192)
			(xy 108.225568 -266.208039) (xy 108.237528 -266.208764) (xy 109.18317 -266.208764) (xy 109.193008 -266.209299)
			(xy 109.211173 -266.216882) (xy 109.218476 -266.223496) (xy 109.358938 -266.363958) (xy 109.359446 -266.364466)
			(xy 109.366828 -266.371048) (xy 109.385126 -266.378499) (xy 109.395006 -266.378944) (xy 109.417104 -266.378944)
			(xy 109.426948 -266.379467) (xy 109.445131 -266.387031) (xy 109.45241 -266.393676) (xy 110.095792 -267.037058)
			(xy 110.0963 -267.037566) (xy 110.103684 -267.044139) (xy 110.121983 -267.051571) (xy 110.13186 -267.052044)
			(xy 111.670592 -267.052044) (xy 111.681984 -267.051409) (xy 111.702538 -267.041577) (xy 111.71687 -267.023864)
			(xy 111.720122 -267.012928) (xy 111.726427 -266.988137) (xy 111.745378 -266.940624) (xy 111.771169 -266.896449)
			(xy 111.803228 -266.856589) (xy 111.840845 -266.821926) (xy 111.883189 -266.793228) (xy 111.929322 -266.771129)
			(xy 111.978223 -266.756119) (xy 112.02881 -266.74853) (xy 112.079962 -266.74853) (xy 112.130549 -266.756119)
			(xy 112.17945 -266.771129) (xy 112.225583 -266.793228) (xy 112.267927 -266.821926) (xy 112.305544 -266.856589)
			(xy 112.337603 -266.896449) (xy 112.363394 -266.940624) (xy 112.382345 -266.988137) (xy 112.38865 -267.012928)
			(xy 112.391861 -267.023894) (xy 112.40617 -267.041669) (xy 112.426769 -267.051486) (xy 112.43818 -267.052044)
			(xy 113.57991 -267.052044) (xy 113.582958 -267.052044) (xy 113.592217 -267.051079) (xy 113.60915 -267.043387)
			(xy 113.615978 -267.037058) (xy 113.622074 -267.029438) (xy 113.675414 -266.95019) (xy 113.6777 -266.925298)
			(xy 113.672874 -266.91336) (xy 113.672366 -266.91209) (xy 113.672112 -266.911836) (xy 113.672112 -266.911328)
			(xy 113.661637 -266.883852) (xy 113.650259 -266.826169) (xy 113.649506 -266.796774) (xy 113.649506 -266.791948)
			(xy 113.650319 -266.767959) (xy 113.658501 -266.720666) (xy 113.67398 -266.675235) (xy 113.696374 -266.632784)
			(xy 113.725133 -266.594359) (xy 113.759548 -266.560905) (xy 113.798773 -266.533246) (xy 113.841841 -266.512063)
			(xy 113.887692 -266.497877) (xy 113.91138 -266.494006) (xy 113.918746 -266.49299) (xy 113.92773 -266.492006)
			(xy 113.945776 -266.490988) (xy 113.954814 -266.490958) (xy 113.978951 -266.491416) (xy 114.026625 -266.499012)
			(xy 114.07251 -266.514012) (xy 114.115464 -266.536043) (xy 114.154418 -266.564556) (xy 114.17173 -266.581382)
			(xy 114.171984 -266.581636) (xy 114.179396 -266.58832) (xy 114.197829 -266.595917) (xy 114.217767 -266.595917)
			(xy 114.2362 -266.58832) (xy 114.243612 -266.581636) (xy 114.535712 -266.289536) (xy 114.542948 -266.282818)
			(xy 114.561153 -266.275216) (xy 114.571018 -266.274804) (xy 114.999262 -266.274804) (xy 115.009136 -266.274336)
			(xy 115.027423 -266.266882) (xy 115.034822 -266.260326) (xy 115.035076 -266.260072) (xy 115.05057 -266.244578)
			(xy 115.05819 -266.234926) (xy 115.091718 -266.1793) (xy 115.096449 -266.170496) (xy 115.099457 -266.150758)
			(xy 115.09756 -266.140946) (xy 115.094512 -266.1285) (xy 115.091972 -266.12342) (xy 115.081727 -266.102023)
			(xy 115.067245 -266.056849) (xy 115.059919 -266.009979) (xy 115.05946 -265.98626) (xy 115.059982 -265.961005)
			(xy 115.068295 -265.911183) (xy 115.084696 -265.863409) (xy 115.108737 -265.818986) (xy 115.139761 -265.779126)
			(xy 115.176923 -265.744916) (xy 115.219209 -265.71729) (xy 115.265465 -265.697) (xy 115.31443 -265.6846)
			(xy 115.364768 -265.680429) (xy 115.415106 -265.6846) (xy 115.464071 -265.697) (xy 115.510327 -265.71729)
			(xy 115.552613 -265.744916) (xy 115.589775 -265.779126) (xy 115.620799 -265.818986) (xy 115.64484 -265.863409)
			(xy 115.661241 -265.911183) (xy 115.669554 -265.961005) (xy 115.670076 -265.98626) (xy 116.938818 -265.98626)
			(xy 116.942778 -265.937206) (xy 116.954555 -265.889422) (xy 116.973846 -265.844146) (xy 117.000149 -265.80255)
			(xy 117.032784 -265.765713) (xy 117.070905 -265.734588) (xy 117.113526 -265.709981) (xy 117.159542 -265.692529)
			(xy 117.207761 -265.682685) (xy 117.256936 -265.680704) (xy 117.305791 -265.686636) (xy 117.353062 -265.700328)
			(xy 117.397524 -265.721426) (xy 117.438027 -265.749382) (xy 117.47352 -265.783474) (xy 117.503085 -265.822818)
			(xy 117.525956 -265.866395) (xy 117.54154 -265.913076) (xy 117.549435 -265.961653) (xy 117.54993 -265.98626)
			(xy 117.549435 -266.010867) (xy 117.54154 -266.059444) (xy 117.525956 -266.106125) (xy 117.503085 -266.149702)
			(xy 117.47352 -266.189046) (xy 117.438027 -266.223138) (xy 117.397524 -266.251094) (xy 117.353062 -266.272192)
			(xy 117.305791 -266.285884) (xy 117.256936 -266.291816) (xy 117.207761 -266.289835) (xy 117.159542 -266.279991)
			(xy 117.113526 -266.262539) (xy 117.070905 -266.237932) (xy 117.032784 -266.206807) (xy 117.000149 -266.16997)
			(xy 116.973846 -266.128374) (xy 116.954555 -266.083098) (xy 116.942778 -266.035314) (xy 116.938818 -265.98626)
			(xy 115.670076 -265.98626) (xy 115.669631 -266.00998) (xy 115.662305 -266.056852) (xy 115.647824 -266.102029)
			(xy 115.637564 -266.12342) (xy 115.635024 -266.1285) (xy 115.631976 -266.140946) (xy 115.62998 -266.150755)
			(xy 115.632997 -266.170527) (xy 115.637818 -266.1793) (xy 115.68049 -266.250166) (xy 115.685305 -266.257444)
			(xy 115.698799 -266.268491) (xy 115.715206 -266.274401) (xy 115.723924 -266.274804) (xy 115.81003 -266.274804)
			(xy 115.819871 -266.275333) (xy 115.838042 -266.28291) (xy 115.845336 -266.289536) (xy 116.577618 -267.021818)
			(xy 116.578126 -267.022326) (xy 116.585505 -267.028915) (xy 116.603804 -267.03638) (xy 116.613686 -267.036804)
			(xy 117.334538 -267.036804) (xy 117.346864 -267.03621) (xy 117.368693 -267.024759) (xy 117.376194 -267.01496)
			(xy 117.422168 -266.948412) (xy 117.425522 -266.943292) (xy 117.429883 -266.931858) (xy 117.430804 -266.925806)
			(xy 117.432328 -266.913868) (xy 117.428264 -266.902184) (xy 117.42801 -266.90193) (xy 117.419281 -266.876395)
			(xy 117.409959 -266.823247) (xy 117.409468 -266.796266) (xy 117.409941 -266.772276) (xy 117.417451 -266.724887)
			(xy 117.432281 -266.679256) (xy 117.454066 -266.636506) (xy 117.48227 -266.59769) (xy 117.516198 -266.563763)
			(xy 117.555015 -266.535561) (xy 117.597765 -266.513778) (xy 117.643397 -266.498949) (xy 117.690786 -266.49144)
			(xy 117.714776 -266.490958) (xy 117.741168 -266.491515) (xy 117.793165 -266.500593) (xy 117.842824 -266.518482)
			(xy 117.888665 -266.544649) (xy 117.90934 -266.561062) (xy 117.916452 -266.566904) (xy 117.93347 -266.572746)
			(xy 117.972078 -266.571984) (xy 117.981778 -266.571351) (xy 117.999656 -266.563763) (xy 118.006876 -266.557252)
			(xy 118.274592 -266.289536) (xy 118.281826 -266.282814) (xy 118.300032 -266.275205) (xy 118.309898 -266.274804)
			(xy 118.759224 -266.274804) (xy 118.769101 -266.274343) (xy 118.787398 -266.266899) (xy 118.794784 -266.260326)
			(xy 118.795038 -266.260072) (xy 118.810532 -266.244578) (xy 118.818152 -266.234926) (xy 118.85168 -266.1793)
			(xy 118.856414 -266.170497) (xy 118.859424 -266.150758) (xy 118.857522 -266.140946) (xy 118.854474 -266.1285)
			(xy 118.851934 -266.12342) (xy 118.84169 -266.102022) (xy 118.82721 -266.056848) (xy 118.819885 -266.009979)
			(xy 118.819422 -265.98626) (xy 118.819944 -265.961005) (xy 118.828257 -265.911183) (xy 118.844658 -265.863409)
			(xy 118.868699 -265.818986) (xy 118.899723 -265.779126) (xy 118.936885 -265.744916) (xy 118.979171 -265.71729)
			(xy 119.025427 -265.697) (xy 119.074392 -265.6846) (xy 119.12473 -265.680429) (xy 119.175068 -265.6846)
			(xy 119.224033 -265.697) (xy 119.270289 -265.71729) (xy 119.312575 -265.744916) (xy 119.349737 -265.779126)
			(xy 119.380761 -265.818986) (xy 119.404802 -265.863409) (xy 119.421203 -265.911183) (xy 119.429516 -265.961005)
			(xy 119.430038 -265.98626) (xy 120.699034 -265.98626) (xy 120.702994 -265.937206) (xy 120.714771 -265.889422)
			(xy 120.734062 -265.844146) (xy 120.760365 -265.80255) (xy 120.793 -265.765713) (xy 120.831121 -265.734588)
			(xy 120.873742 -265.709981) (xy 120.919758 -265.692529) (xy 120.967977 -265.682685) (xy 121.017152 -265.680704)
			(xy 121.066007 -265.686636) (xy 121.113278 -265.700328) (xy 121.15774 -265.721426) (xy 121.198243 -265.749382)
			(xy 121.233736 -265.783474) (xy 121.263301 -265.822818) (xy 121.286172 -265.866395) (xy 121.301756 -265.913076)
			(xy 121.309651 -265.961653) (xy 121.310146 -265.98626) (xy 121.309651 -266.010867) (xy 121.301756 -266.059444)
			(xy 121.286172 -266.106125) (xy 121.263301 -266.149702) (xy 121.233736 -266.189046) (xy 121.198243 -266.223138)
			(xy 121.15774 -266.251094) (xy 121.113278 -266.272192) (xy 121.066007 -266.285884) (xy 121.017152 -266.291816)
			(xy 120.967977 -266.289835) (xy 120.919758 -266.279991) (xy 120.873742 -266.262539) (xy 120.831121 -266.237932)
			(xy 120.793 -266.206807) (xy 120.760365 -266.16997) (xy 120.734062 -266.128374) (xy 120.714771 -266.083098)
			(xy 120.702994 -266.035314) (xy 120.699034 -265.98626) (xy 119.430038 -265.98626) (xy 119.429593 -266.00998)
			(xy 119.422266 -266.056852) (xy 119.407783 -266.102028) (xy 119.397526 -266.12342) (xy 119.394986 -266.1285)
			(xy 119.391938 -266.140946) (xy 119.389941 -266.150754) (xy 119.392961 -266.170526) (xy 119.39778 -266.1793)
			(xy 119.440452 -266.250166) (xy 119.445265 -266.257448) (xy 119.458758 -266.268505) (xy 119.475166 -266.274427)
			(xy 119.483886 -266.274804) (xy 119.58955 -266.274804) (xy 119.599389 -266.275337) (xy 119.617555 -266.282919)
			(xy 119.624856 -266.289536) (xy 120.357138 -267.021818) (xy 120.357646 -267.022326) (xy 120.365025 -267.028912)
			(xy 120.383325 -267.036369) (xy 120.393206 -267.036804) (xy 121.0945 -267.036804) (xy 121.10683 -267.036219)
			(xy 121.128674 -267.024777) (xy 121.136156 -267.01496) (xy 121.18213 -266.948412) (xy 121.185486 -266.943293)
			(xy 121.189851 -266.931859) (xy 121.190766 -266.925806) (xy 121.19229 -266.913868) (xy 121.188226 -266.902184)
			(xy 121.187972 -266.90193) (xy 121.180352 -266.877546) (xy 121.175216 -266.857621) (xy 121.169737 -266.81684)
			(xy 121.16943 -266.796266) (xy 121.16987 -266.77269) (xy 121.17712 -266.7261) (xy 121.191444 -266.681177)
			(xy 121.2125 -266.638988) (xy 121.239789 -266.600536) (xy 121.272662 -266.566734) (xy 121.310339 -266.538384)
			(xy 121.351925 -266.516161) (xy 121.396431 -266.500592) (xy 121.442802 -266.492046) (xy 121.466356 -266.490958)
			(xy 121.473976 -266.490958) (xy 121.500163 -266.491409) (xy 121.551796 -266.500162) (xy 121.601181 -266.517587)
			(xy 121.646874 -266.543176) (xy 121.667524 -266.559284) (xy 121.67489 -266.565126) (xy 121.692416 -266.570968)
			(xy 121.768108 -266.567158) (xy 121.777408 -266.566275) (xy 121.794471 -266.558712) (xy 121.801382 -266.552426)
			(xy 122.130312 -266.223496) (xy 122.13755 -266.216782) (xy 122.155755 -266.209187) (xy 122.165618 -266.208764)
			(xy 122.498104 -266.208764) (xy 122.510083 -266.208117) (xy 122.531429 -266.197244) (xy 122.538998 -266.187936)
			(xy 122.593354 -266.11326) (xy 122.597164 -266.089638) (xy 122.593608 -266.077954) (xy 122.586987 -266.05561)
			(xy 122.579839 -266.00956) (xy 122.579384 -265.98626) (xy 122.579384 -265.985752) (xy 122.579384 -265.982958)
			(xy 122.580163 -265.957882) (xy 122.588898 -265.908481) (xy 122.605592 -265.861174) (xy 122.629794 -265.817232)
			(xy 122.660854 -265.777837) (xy 122.697937 -265.744049) (xy 122.740044 -265.716778) (xy 122.786042 -265.696758)
			(xy 122.834694 -265.684525) (xy 122.884692 -265.680411) (xy 122.93469 -265.684525) (xy 122.983342 -265.696758)
			(xy 123.02934 -265.716778) (xy 123.071447 -265.744049) (xy 123.10853 -265.777837) (xy 123.13959 -265.817232)
			(xy 123.163792 -265.861174) (xy 123.180486 -265.908481) (xy 123.189221 -265.957882) (xy 123.19 -265.982958)
			(xy 123.19 -265.985752) (xy 123.19 -265.98626) (xy 124.458996 -265.98626) (xy 124.462956 -265.937206)
			(xy 124.474733 -265.889422) (xy 124.494024 -265.844146) (xy 124.520327 -265.80255) (xy 124.552962 -265.765713)
			(xy 124.591083 -265.734588) (xy 124.633704 -265.709981) (xy 124.67972 -265.692529) (xy 124.727939 -265.682685)
			(xy 124.777114 -265.680704) (xy 124.825969 -265.686636) (xy 124.87324 -265.700328) (xy 124.917702 -265.721426)
			(xy 124.958205 -265.749382) (xy 124.993698 -265.783474) (xy 125.023263 -265.822818) (xy 125.046134 -265.866395)
			(xy 125.061718 -265.913076) (xy 125.069613 -265.961653) (xy 125.070108 -265.98626) (xy 126.33885 -265.98626)
			(xy 126.34281 -265.937206) (xy 126.354587 -265.889422) (xy 126.373878 -265.844146) (xy 126.400181 -265.80255)
			(xy 126.432816 -265.765713) (xy 126.470937 -265.734588) (xy 126.513558 -265.709981) (xy 126.559574 -265.692529)
			(xy 126.607793 -265.682685) (xy 126.656968 -265.680704) (xy 126.705823 -265.686636) (xy 126.753094 -265.700328)
			(xy 126.797556 -265.721426) (xy 126.838059 -265.749382) (xy 126.873552 -265.783474) (xy 126.903117 -265.822818)
			(xy 126.925988 -265.866395) (xy 126.941572 -265.913076) (xy 126.949467 -265.961653) (xy 126.949962 -265.98626)
			(xy 128.208527 -265.98626) (xy 128.212622 -265.935532) (xy 128.224801 -265.886118) (xy 128.244749 -265.839298)
			(xy 128.27195 -265.796284) (xy 128.305698 -265.75819) (xy 128.34512 -265.726003) (xy 128.389194 -265.700557)
			(xy 128.43678 -265.68251) (xy 128.486644 -265.67233) (xy 128.537496 -265.670281) (xy 128.588017 -265.676415)
			(xy 128.636901 -265.690575) (xy 128.68288 -265.712392) (xy 128.724764 -265.741302) (xy 128.761468 -265.776557)
			(xy 128.792041 -265.817243) (xy 128.815692 -265.862306) (xy 128.831808 -265.91058) (xy 128.839972 -265.960814)
			(xy 128.840484 -265.98626) (xy 129.159012 -265.98626) (xy 129.162972 -265.937206) (xy 129.174749 -265.889422)
			(xy 129.19404 -265.844146) (xy 129.220343 -265.80255) (xy 129.252978 -265.765713) (xy 129.291099 -265.734588)
			(xy 129.33372 -265.709981) (xy 129.379736 -265.692529) (xy 129.427955 -265.682685) (xy 129.47713 -265.680704)
			(xy 129.525985 -265.686636) (xy 129.573256 -265.700328) (xy 129.617718 -265.721426) (xy 129.658221 -265.749382)
			(xy 129.693714 -265.783474) (xy 129.723279 -265.822818) (xy 129.74615 -265.866395) (xy 129.761734 -265.913076)
			(xy 129.769629 -265.961653) (xy 129.770124 -265.98626) (xy 131.028435 -265.98626) (xy 131.03253 -265.935532)
			(xy 131.044709 -265.886118) (xy 131.064657 -265.839298) (xy 131.091858 -265.796284) (xy 131.125606 -265.75819)
			(xy 131.165028 -265.726003) (xy 131.209102 -265.700557) (xy 131.256688 -265.68251) (xy 131.306552 -265.67233)
			(xy 131.357404 -265.670281) (xy 131.407925 -265.676415) (xy 131.456809 -265.690575) (xy 131.502788 -265.712392)
			(xy 131.544672 -265.741302) (xy 131.581376 -265.776557) (xy 131.611949 -265.817243) (xy 131.6356 -265.862306)
			(xy 131.651716 -265.91058) (xy 131.65988 -265.960814) (xy 131.660392 -265.98626) (xy 131.97892 -265.98626)
			(xy 131.98288 -265.937206) (xy 131.994657 -265.889422) (xy 132.013948 -265.844146) (xy 132.040251 -265.80255)
			(xy 132.072886 -265.765713) (xy 132.111007 -265.734588) (xy 132.153628 -265.709981) (xy 132.199644 -265.692529)
			(xy 132.247863 -265.682685) (xy 132.297038 -265.680704) (xy 132.345893 -265.686636) (xy 132.393164 -265.700328)
			(xy 132.437626 -265.721426) (xy 132.478129 -265.749382) (xy 132.513622 -265.783474) (xy 132.543187 -265.822818)
			(xy 132.566058 -265.866395) (xy 132.581642 -265.913076) (xy 132.589537 -265.961653) (xy 132.590032 -265.98626)
			(xy 132.918974 -265.98626) (xy 132.922934 -265.937206) (xy 132.934711 -265.889422) (xy 132.954002 -265.844146)
			(xy 132.980305 -265.80255) (xy 133.01294 -265.765713) (xy 133.051061 -265.734588) (xy 133.093682 -265.709981)
			(xy 133.139698 -265.692529) (xy 133.187917 -265.682685) (xy 133.237092 -265.680704) (xy 133.285947 -265.686636)
			(xy 133.333218 -265.700328) (xy 133.37768 -265.721426) (xy 133.418183 -265.749382) (xy 133.453676 -265.783474)
			(xy 133.483241 -265.822818) (xy 133.506112 -265.866395) (xy 133.521696 -265.913076) (xy 133.529591 -265.961653)
			(xy 133.530086 -265.98626) (xy 133.859028 -265.98626) (xy 133.862988 -265.937206) (xy 133.874765 -265.889422)
			(xy 133.894056 -265.844146) (xy 133.920359 -265.80255) (xy 133.952994 -265.765713) (xy 133.991115 -265.734588)
			(xy 134.033736 -265.709981) (xy 134.079752 -265.692529) (xy 134.127971 -265.682685) (xy 134.177146 -265.680704)
			(xy 134.226001 -265.686636) (xy 134.273272 -265.700328) (xy 134.317734 -265.721426) (xy 134.358237 -265.749382)
			(xy 134.39373 -265.783474) (xy 134.423295 -265.822818) (xy 134.446166 -265.866395) (xy 134.46175 -265.913076)
			(xy 134.469645 -265.961653) (xy 134.47014 -265.98626) (xy 134.798828 -265.98626) (xy 134.802788 -265.937206)
			(xy 134.814565 -265.889422) (xy 134.833856 -265.844146) (xy 134.860159 -265.80255) (xy 134.892794 -265.765713)
			(xy 134.930915 -265.734588) (xy 134.973536 -265.709981) (xy 135.019552 -265.692529) (xy 135.067771 -265.682685)
			(xy 135.116946 -265.680704) (xy 135.165801 -265.686636) (xy 135.213072 -265.700328) (xy 135.257534 -265.721426)
			(xy 135.298037 -265.749382) (xy 135.33353 -265.783474) (xy 135.363095 -265.822818) (xy 135.385966 -265.866395)
			(xy 135.40155 -265.913076) (xy 135.409445 -265.961653) (xy 135.40994 -265.98626) (xy 135.738882 -265.98626)
			(xy 135.742842 -265.937206) (xy 135.754619 -265.889422) (xy 135.77391 -265.844146) (xy 135.800213 -265.80255)
			(xy 135.832848 -265.765713) (xy 135.870969 -265.734588) (xy 135.91359 -265.709981) (xy 135.959606 -265.692529)
			(xy 136.007825 -265.682685) (xy 136.057 -265.680704) (xy 136.105855 -265.686636) (xy 136.153126 -265.700328)
			(xy 136.197588 -265.721426) (xy 136.238091 -265.749382) (xy 136.273584 -265.783474) (xy 136.303149 -265.822818)
			(xy 136.32602 -265.866395) (xy 136.341604 -265.913076) (xy 136.349499 -265.961653) (xy 136.349994 -265.98626)
			(xy 137.61899 -265.98626) (xy 137.62295 -265.937206) (xy 137.634727 -265.889422) (xy 137.654018 -265.844146)
			(xy 137.680321 -265.80255) (xy 137.712956 -265.765713) (xy 137.751077 -265.734588) (xy 137.793698 -265.709981)
			(xy 137.839714 -265.692529) (xy 137.887933 -265.682685) (xy 137.937108 -265.680704) (xy 137.985963 -265.686636)
			(xy 138.033234 -265.700328) (xy 138.077696 -265.721426) (xy 138.118199 -265.749382) (xy 138.153692 -265.783474)
			(xy 138.183257 -265.822818) (xy 138.206128 -265.866395) (xy 138.221712 -265.913076) (xy 138.229607 -265.961653)
			(xy 138.230102 -265.98626) (xy 138.559044 -265.98626) (xy 138.563004 -265.937206) (xy 138.574781 -265.889422)
			(xy 138.594072 -265.844146) (xy 138.620375 -265.80255) (xy 138.65301 -265.765713) (xy 138.691131 -265.734588)
			(xy 138.733752 -265.709981) (xy 138.779768 -265.692529) (xy 138.827987 -265.682685) (xy 138.877162 -265.680704)
			(xy 138.926017 -265.686636) (xy 138.973288 -265.700328) (xy 139.01775 -265.721426) (xy 139.058253 -265.749382)
			(xy 139.093746 -265.783474) (xy 139.123311 -265.822818) (xy 139.146182 -265.866395) (xy 139.161766 -265.913076)
			(xy 139.169661 -265.961653) (xy 139.170156 -265.98626) (xy 139.498844 -265.98626) (xy 139.502804 -265.937206)
			(xy 139.514581 -265.889422) (xy 139.533872 -265.844146) (xy 139.560175 -265.80255) (xy 139.59281 -265.765713)
			(xy 139.630931 -265.734588) (xy 139.673552 -265.709981) (xy 139.719568 -265.692529) (xy 139.767787 -265.682685)
			(xy 139.816962 -265.680704) (xy 139.865817 -265.686636) (xy 139.913088 -265.700328) (xy 139.95755 -265.721426)
			(xy 139.998053 -265.749382) (xy 140.033546 -265.783474) (xy 140.063111 -265.822818) (xy 140.085982 -265.866395)
			(xy 140.101566 -265.913076) (xy 140.109461 -265.961653) (xy 140.109956 -265.98626) (xy 140.109461 -266.010867)
			(xy 140.101566 -266.059444) (xy 140.085982 -266.106125) (xy 140.063111 -266.149702) (xy 140.033546 -266.189046)
			(xy 139.998053 -266.223138) (xy 139.95755 -266.251094) (xy 139.913088 -266.272192) (xy 139.865817 -266.285884)
			(xy 139.816962 -266.291816) (xy 139.767787 -266.289835) (xy 139.719568 -266.279991) (xy 139.673552 -266.262539)
			(xy 139.630931 -266.237932) (xy 139.59281 -266.206807) (xy 139.560175 -266.16997) (xy 139.533872 -266.128374)
			(xy 139.514581 -266.083098) (xy 139.502804 -266.035314) (xy 139.498844 -265.98626) (xy 139.170156 -265.98626)
			(xy 139.169661 -266.010867) (xy 139.161766 -266.059444) (xy 139.146182 -266.106125) (xy 139.123311 -266.149702)
			(xy 139.093746 -266.189046) (xy 139.058253 -266.223138) (xy 139.01775 -266.251094) (xy 138.973288 -266.272192)
			(xy 138.926017 -266.285884) (xy 138.877162 -266.291816) (xy 138.827987 -266.289835) (xy 138.779768 -266.279991)
			(xy 138.733752 -266.262539) (xy 138.691131 -266.237932) (xy 138.65301 -266.206807) (xy 138.620375 -266.16997)
			(xy 138.594072 -266.128374) (xy 138.574781 -266.083098) (xy 138.563004 -266.035314) (xy 138.559044 -265.98626)
			(xy 138.230102 -265.98626) (xy 138.229607 -266.010867) (xy 138.221712 -266.059444) (xy 138.206128 -266.106125)
			(xy 138.183257 -266.149702) (xy 138.153692 -266.189046) (xy 138.118199 -266.223138) (xy 138.077696 -266.251094)
			(xy 138.033234 -266.272192) (xy 137.985963 -266.285884) (xy 137.937108 -266.291816) (xy 137.887933 -266.289835)
			(xy 137.839714 -266.279991) (xy 137.793698 -266.262539) (xy 137.751077 -266.237932) (xy 137.712956 -266.206807)
			(xy 137.680321 -266.16997) (xy 137.654018 -266.128374) (xy 137.634727 -266.083098) (xy 137.62295 -266.035314)
			(xy 137.61899 -265.98626) (xy 136.349994 -265.98626) (xy 136.349499 -266.010867) (xy 136.341604 -266.059444)
			(xy 136.32602 -266.106125) (xy 136.303149 -266.149702) (xy 136.273584 -266.189046) (xy 136.238091 -266.223138)
			(xy 136.197588 -266.251094) (xy 136.153126 -266.272192) (xy 136.105855 -266.285884) (xy 136.057 -266.291816)
			(xy 136.007825 -266.289835) (xy 135.959606 -266.279991) (xy 135.91359 -266.262539) (xy 135.870969 -266.237932)
			(xy 135.832848 -266.206807) (xy 135.800213 -266.16997) (xy 135.77391 -266.128374) (xy 135.754619 -266.083098)
			(xy 135.742842 -266.035314) (xy 135.738882 -265.98626) (xy 135.40994 -265.98626) (xy 135.409445 -266.010867)
			(xy 135.40155 -266.059444) (xy 135.385966 -266.106125) (xy 135.363095 -266.149702) (xy 135.33353 -266.189046)
			(xy 135.298037 -266.223138) (xy 135.257534 -266.251094) (xy 135.213072 -266.272192) (xy 135.165801 -266.285884)
			(xy 135.116946 -266.291816) (xy 135.067771 -266.289835) (xy 135.019552 -266.279991) (xy 134.973536 -266.262539)
			(xy 134.930915 -266.237932) (xy 134.892794 -266.206807) (xy 134.860159 -266.16997) (xy 134.833856 -266.128374)
			(xy 134.814565 -266.083098) (xy 134.802788 -266.035314) (xy 134.798828 -265.98626) (xy 134.47014 -265.98626)
			(xy 134.469645 -266.010867) (xy 134.46175 -266.059444) (xy 134.446166 -266.106125) (xy 134.423295 -266.149702)
			(xy 134.39373 -266.189046) (xy 134.358237 -266.223138) (xy 134.317734 -266.251094) (xy 134.273272 -266.272192)
			(xy 134.226001 -266.285884) (xy 134.177146 -266.291816) (xy 134.127971 -266.289835) (xy 134.079752 -266.279991)
			(xy 134.033736 -266.262539) (xy 133.991115 -266.237932) (xy 133.952994 -266.206807) (xy 133.920359 -266.16997)
			(xy 133.894056 -266.128374) (xy 133.874765 -266.083098) (xy 133.862988 -266.035314) (xy 133.859028 -265.98626)
			(xy 133.530086 -265.98626) (xy 133.529591 -266.010867) (xy 133.521696 -266.059444) (xy 133.506112 -266.106125)
			(xy 133.483241 -266.149702) (xy 133.453676 -266.189046) (xy 133.418183 -266.223138) (xy 133.37768 -266.251094)
			(xy 133.333218 -266.272192) (xy 133.285947 -266.285884) (xy 133.237092 -266.291816) (xy 133.187917 -266.289835)
			(xy 133.139698 -266.279991) (xy 133.093682 -266.262539) (xy 133.051061 -266.237932) (xy 133.01294 -266.206807)
			(xy 132.980305 -266.16997) (xy 132.954002 -266.128374) (xy 132.934711 -266.083098) (xy 132.922934 -266.035314)
			(xy 132.918974 -265.98626) (xy 132.590032 -265.98626) (xy 132.589537 -266.010867) (xy 132.581642 -266.059444)
			(xy 132.566058 -266.106125) (xy 132.543187 -266.149702) (xy 132.513622 -266.189046) (xy 132.478129 -266.223138)
			(xy 132.437626 -266.251094) (xy 132.393164 -266.272192) (xy 132.345893 -266.285884) (xy 132.297038 -266.291816)
			(xy 132.247863 -266.289835) (xy 132.199644 -266.279991) (xy 132.153628 -266.262539) (xy 132.111007 -266.237932)
			(xy 132.072886 -266.206807) (xy 132.040251 -266.16997) (xy 132.013948 -266.128374) (xy 131.994657 -266.083098)
			(xy 131.98288 -266.035314) (xy 131.97892 -265.98626) (xy 131.660392 -265.98626) (xy 131.65988 -266.011706)
			(xy 131.651716 -266.06194) (xy 131.6356 -266.110214) (xy 131.611949 -266.155277) (xy 131.581376 -266.195963)
			(xy 131.544672 -266.231218) (xy 131.502788 -266.260128) (xy 131.456809 -266.281945) (xy 131.407925 -266.296105)
			(xy 131.357404 -266.302239) (xy 131.306552 -266.30019) (xy 131.256688 -266.29001) (xy 131.209102 -266.271963)
			(xy 131.165028 -266.246517) (xy 131.125606 -266.21433) (xy 131.091858 -266.176236) (xy 131.064657 -266.133222)
			(xy 131.044709 -266.086402) (xy 131.03253 -266.036988) (xy 131.028435 -265.98626) (xy 129.770124 -265.98626)
			(xy 129.769629 -266.010867) (xy 129.761734 -266.059444) (xy 129.74615 -266.106125) (xy 129.723279 -266.149702)
			(xy 129.693714 -266.189046) (xy 129.658221 -266.223138) (xy 129.617718 -266.251094) (xy 129.573256 -266.272192)
			(xy 129.525985 -266.285884) (xy 129.47713 -266.291816) (xy 129.427955 -266.289835) (xy 129.379736 -266.279991)
			(xy 129.33372 -266.262539) (xy 129.291099 -266.237932) (xy 129.252978 -266.206807) (xy 129.220343 -266.16997)
			(xy 129.19404 -266.128374) (xy 129.174749 -266.083098) (xy 129.162972 -266.035314) (xy 129.159012 -265.98626)
			(xy 128.840484 -265.98626) (xy 128.839972 -266.011706) (xy 128.831808 -266.06194) (xy 128.815692 -266.110214)
			(xy 128.792041 -266.155277) (xy 128.761468 -266.195963) (xy 128.724764 -266.231218) (xy 128.68288 -266.260128)
			(xy 128.636901 -266.281945) (xy 128.588017 -266.296105) (xy 128.537496 -266.302239) (xy 128.486644 -266.30019)
			(xy 128.43678 -266.29001) (xy 128.389194 -266.271963) (xy 128.34512 -266.246517) (xy 128.305698 -266.21433)
			(xy 128.27195 -266.176236) (xy 128.244749 -266.133222) (xy 128.224801 -266.086402) (xy 128.212622 -266.036988)
			(xy 128.208527 -265.98626) (xy 126.949962 -265.98626) (xy 126.949467 -266.010867) (xy 126.941572 -266.059444)
			(xy 126.925988 -266.106125) (xy 126.903117 -266.149702) (xy 126.873552 -266.189046) (xy 126.838059 -266.223138)
			(xy 126.797556 -266.251094) (xy 126.753094 -266.272192) (xy 126.705823 -266.285884) (xy 126.656968 -266.291816)
			(xy 126.607793 -266.289835) (xy 126.559574 -266.279991) (xy 126.513558 -266.262539) (xy 126.470937 -266.237932)
			(xy 126.432816 -266.206807) (xy 126.400181 -266.16997) (xy 126.373878 -266.128374) (xy 126.354587 -266.083098)
			(xy 126.34281 -266.035314) (xy 126.33885 -265.98626) (xy 125.070108 -265.98626) (xy 125.069613 -266.010867)
			(xy 125.061718 -266.059444) (xy 125.046134 -266.106125) (xy 125.023263 -266.149702) (xy 124.993698 -266.189046)
			(xy 124.958205 -266.223138) (xy 124.917702 -266.251094) (xy 124.87324 -266.272192) (xy 124.825969 -266.285884)
			(xy 124.777114 -266.291816) (xy 124.727939 -266.289835) (xy 124.67972 -266.279991) (xy 124.633704 -266.262539)
			(xy 124.591083 -266.237932) (xy 124.552962 -266.206807) (xy 124.520327 -266.16997) (xy 124.494024 -266.128374)
			(xy 124.474733 -266.083098) (xy 124.462956 -266.035314) (xy 124.458996 -265.98626) (xy 123.19 -265.98626)
			(xy 123.189516 -266.009557) (xy 123.182366 -266.055602) (xy 123.175776 -266.077954) (xy 123.17222 -266.089638)
			(xy 123.17603 -266.11326) (xy 123.230386 -266.187936) (xy 123.237989 -266.1972) (xy 123.259316 -266.208067)
			(xy 123.27128 -266.208764) (xy 123.31319 -266.208764) (xy 123.323027 -266.209303) (xy 123.341186 -266.216891)
			(xy 123.348496 -266.223496) (xy 124.146818 -267.021818) (xy 124.147326 -267.022326) (xy 124.154705 -267.028915)
			(xy 124.173004 -267.03638) (xy 124.182886 -267.036804) (xy 124.854462 -267.036804) (xy 124.866785 -267.036205)
			(xy 124.888605 -267.024748) (xy 124.896118 -267.01496) (xy 124.942092 -266.948412) (xy 124.94545 -266.943293)
			(xy 124.949818 -266.93186) (xy 124.950728 -266.925806) (xy 124.952252 -266.913868) (xy 124.948188 -266.902184)
			(xy 124.947934 -266.90193) (xy 124.939204 -266.876395) (xy 124.929882 -266.823248) (xy 124.929392 -266.796266)
			(xy 124.929914 -266.771011) (xy 124.938227 -266.721189) (xy 124.954628 -266.673415) (xy 124.978669 -266.628992)
			(xy 125.009693 -266.589132) (xy 125.046855 -266.554922) (xy 125.089141 -266.527296) (xy 125.135397 -266.507006)
			(xy 125.184362 -266.494606) (xy 125.2347 -266.490435) (xy 125.285038 -266.494606) (xy 125.334003 -266.507006)
			(xy 125.380259 -266.527296) (xy 125.422545 -266.554922) (xy 125.459707 -266.589132) (xy 125.490731 -266.628992)
			(xy 125.514772 -266.673415) (xy 125.531173 -266.721189) (xy 125.539486 -266.771011) (xy 125.540008 -266.796266)
			(xy 125.539497 -266.823245) (xy 125.530167 -266.876388) (xy 125.521466 -266.90193) (xy 125.521212 -266.902184)
			(xy 125.520958 -266.902692) (xy 125.519252 -266.908237) (xy 125.5181 -266.919779) (xy 125.518672 -266.925552)
			(xy 125.520196 -266.938252) (xy 125.573282 -267.01496) (xy 125.580895 -267.024626) (xy 125.602657 -267.036026)
			(xy 125.614938 -267.036804) (xy 125.811788 -267.036804) (xy 125.821658 -267.036392) (xy 125.839895 -267.028838)
			(xy 125.853851 -267.014877) (xy 125.861397 -266.996636) (xy 125.861826 -266.986766) (xy 125.861826 -266.796266)
			(xy 125.862308 -266.771676) (xy 125.870002 -266.723101) (xy 125.885199 -266.676328) (xy 125.907526 -266.632509)
			(xy 125.936434 -266.592721) (xy 125.971209 -266.557946) (xy 126.010997 -266.529038) (xy 126.054816 -266.506711)
			(xy 126.101589 -266.491514) (xy 126.150164 -266.48382) (xy 126.199344 -266.48382) (xy 126.247919 -266.491514)
			(xy 126.294692 -266.506711) (xy 126.338511 -266.529038) (xy 126.378299 -266.557946) (xy 126.413074 -266.592721)
			(xy 126.441982 -266.632509) (xy 126.464309 -266.676328) (xy 126.479506 -266.723101) (xy 126.4872 -266.771676)
			(xy 126.487682 -266.796266) (xy 126.809004 -266.796266) (xy 126.812964 -266.747212) (xy 126.824741 -266.699428)
			(xy 126.844032 -266.654152) (xy 126.870335 -266.612556) (xy 126.90297 -266.575719) (xy 126.941091 -266.544594)
			(xy 126.983712 -266.519987) (xy 127.029728 -266.502535) (xy 127.077947 -266.492691) (xy 127.127122 -266.49071)
			(xy 127.175977 -266.496642) (xy 127.223248 -266.510334) (xy 127.26771 -266.531432) (xy 127.308213 -266.559388)
			(xy 127.343706 -266.59348) (xy 127.373271 -266.632824) (xy 127.396142 -266.676401) (xy 127.411726 -266.723082)
			(xy 127.419621 -266.771659) (xy 127.420116 -266.796266) (xy 127.738627 -266.796266) (xy 127.742722 -266.745538)
			(xy 127.754901 -266.696124) (xy 127.774849 -266.649304) (xy 127.80205 -266.60629) (xy 127.835798 -266.568196)
			(xy 127.87522 -266.536009) (xy 127.919294 -266.510563) (xy 127.96688 -266.492516) (xy 128.016744 -266.482336)
			(xy 128.067596 -266.480287) (xy 128.118117 -266.486421) (xy 128.167001 -266.500581) (xy 128.21298 -266.522398)
			(xy 128.254864 -266.551308) (xy 128.291568 -266.586563) (xy 128.322141 -266.627249) (xy 128.345792 -266.672312)
			(xy 128.361908 -266.720586) (xy 128.370072 -266.77082) (xy 128.370584 -266.796266) (xy 128.688858 -266.796266)
			(xy 128.692818 -266.747212) (xy 128.704595 -266.699428) (xy 128.723886 -266.654152) (xy 128.750189 -266.612556)
			(xy 128.782824 -266.575719) (xy 128.820945 -266.544594) (xy 128.863566 -266.519987) (xy 128.909582 -266.502535)
			(xy 128.957801 -266.492691) (xy 129.006976 -266.49071) (xy 129.055831 -266.496642) (xy 129.103102 -266.510334)
			(xy 129.147564 -266.531432) (xy 129.188067 -266.559388) (xy 129.22356 -266.59348) (xy 129.253125 -266.632824)
			(xy 129.275996 -266.676401) (xy 129.29158 -266.723082) (xy 129.299475 -266.771659) (xy 129.29997 -266.796266)
			(xy 129.618481 -266.796266) (xy 129.622576 -266.745538) (xy 129.634755 -266.696124) (xy 129.654703 -266.649304)
			(xy 129.681904 -266.60629) (xy 129.715652 -266.568196) (xy 129.755074 -266.536009) (xy 129.799148 -266.510563)
			(xy 129.846734 -266.492516) (xy 129.896598 -266.482336) (xy 129.94745 -266.480287) (xy 129.997971 -266.486421)
			(xy 130.046855 -266.500581) (xy 130.092834 -266.522398) (xy 130.134718 -266.551308) (xy 130.171422 -266.586563)
			(xy 130.201995 -266.627249) (xy 130.225646 -266.672312) (xy 130.241762 -266.720586) (xy 130.249926 -266.77082)
			(xy 130.250438 -266.796266) (xy 130.568966 -266.796266) (xy 130.572926 -266.747212) (xy 130.584703 -266.699428)
			(xy 130.603994 -266.654152) (xy 130.630297 -266.612556) (xy 130.662932 -266.575719) (xy 130.701053 -266.544594)
			(xy 130.743674 -266.519987) (xy 130.78969 -266.502535) (xy 130.837909 -266.492691) (xy 130.887084 -266.49071)
			(xy 130.935939 -266.496642) (xy 130.98321 -266.510334) (xy 131.027672 -266.531432) (xy 131.068175 -266.559388)
			(xy 131.103668 -266.59348) (xy 131.133233 -266.632824) (xy 131.156104 -266.676401) (xy 131.171688 -266.723082)
			(xy 131.179583 -266.771659) (xy 131.180078 -266.796266) (xy 131.498589 -266.796266) (xy 131.502684 -266.745538)
			(xy 131.514863 -266.696124) (xy 131.534811 -266.649304) (xy 131.562012 -266.60629) (xy 131.59576 -266.568196)
			(xy 131.635182 -266.536009) (xy 131.679256 -266.510563) (xy 131.726842 -266.492516) (xy 131.776706 -266.482336)
			(xy 131.827558 -266.480287) (xy 131.878079 -266.486421) (xy 131.926963 -266.500581) (xy 131.972942 -266.522398)
			(xy 132.014826 -266.551308) (xy 132.05153 -266.586563) (xy 132.082103 -266.627249) (xy 132.105754 -266.672312)
			(xy 132.12187 -266.720586) (xy 132.130034 -266.77082) (xy 132.130546 -266.796266) (xy 132.438643 -266.796266)
			(xy 132.442738 -266.745538) (xy 132.454917 -266.696124) (xy 132.474865 -266.649304) (xy 132.502066 -266.60629)
			(xy 132.535814 -266.568196) (xy 132.575236 -266.536009) (xy 132.61931 -266.510563) (xy 132.666896 -266.492516)
			(xy 132.71676 -266.482336) (xy 132.767612 -266.480287) (xy 132.818133 -266.486421) (xy 132.867017 -266.500581)
			(xy 132.912996 -266.522398) (xy 132.95488 -266.551308) (xy 132.991584 -266.586563) (xy 133.022157 -266.627249)
			(xy 133.045808 -266.672312) (xy 133.061924 -266.720586) (xy 133.070088 -266.77082) (xy 133.0706 -266.796266)
			(xy 133.388874 -266.796266) (xy 133.392834 -266.747212) (xy 133.404611 -266.699428) (xy 133.423902 -266.654152)
			(xy 133.450205 -266.612556) (xy 133.48284 -266.575719) (xy 133.520961 -266.544594) (xy 133.563582 -266.519987)
			(xy 133.609598 -266.502535) (xy 133.657817 -266.492691) (xy 133.706992 -266.49071) (xy 133.755847 -266.496642)
			(xy 133.803118 -266.510334) (xy 133.84758 -266.531432) (xy 133.888083 -266.559388) (xy 133.923576 -266.59348)
			(xy 133.953141 -266.632824) (xy 133.976012 -266.676401) (xy 133.991596 -266.723082) (xy 133.999491 -266.771659)
			(xy 133.999986 -266.796266) (xy 134.328928 -266.796266) (xy 134.332888 -266.747212) (xy 134.344665 -266.699428)
			(xy 134.363956 -266.654152) (xy 134.390259 -266.612556) (xy 134.422894 -266.575719) (xy 134.461015 -266.544594)
			(xy 134.503636 -266.519987) (xy 134.549652 -266.502535) (xy 134.597871 -266.492691) (xy 134.647046 -266.49071)
			(xy 134.695901 -266.496642) (xy 134.743172 -266.510334) (xy 134.787634 -266.531432) (xy 134.828137 -266.559388)
			(xy 134.86363 -266.59348) (xy 134.893195 -266.632824) (xy 134.916066 -266.676401) (xy 134.93165 -266.723082)
			(xy 134.939545 -266.771659) (xy 134.94004 -266.796266) (xy 135.268982 -266.796266) (xy 135.272942 -266.747212)
			(xy 135.284719 -266.699428) (xy 135.30401 -266.654152) (xy 135.330313 -266.612556) (xy 135.362948 -266.575719)
			(xy 135.401069 -266.544594) (xy 135.44369 -266.519987) (xy 135.489706 -266.502535) (xy 135.537925 -266.492691)
			(xy 135.5871 -266.49071) (xy 135.635955 -266.496642) (xy 135.683226 -266.510334) (xy 135.727688 -266.531432)
			(xy 135.768191 -266.559388) (xy 135.803684 -266.59348) (xy 135.833249 -266.632824) (xy 135.85612 -266.676401)
			(xy 135.871704 -266.723082) (xy 135.879599 -266.771659) (xy 135.880094 -266.796266) (xy 136.209036 -266.796266)
			(xy 136.212996 -266.747212) (xy 136.224773 -266.699428) (xy 136.244064 -266.654152) (xy 136.270367 -266.612556)
			(xy 136.303002 -266.575719) (xy 136.341123 -266.544594) (xy 136.383744 -266.519987) (xy 136.42976 -266.502535)
			(xy 136.477979 -266.492691) (xy 136.527154 -266.49071) (xy 136.576009 -266.496642) (xy 136.62328 -266.510334)
			(xy 136.667742 -266.531432) (xy 136.708245 -266.559388) (xy 136.743738 -266.59348) (xy 136.773303 -266.632824)
			(xy 136.796174 -266.676401) (xy 136.811758 -266.723082) (xy 136.819653 -266.771659) (xy 136.820148 -266.796266)
			(xy 137.148836 -266.796266) (xy 137.152796 -266.747212) (xy 137.164573 -266.699428) (xy 137.183864 -266.654152)
			(xy 137.210167 -266.612556) (xy 137.242802 -266.575719) (xy 137.280923 -266.544594) (xy 137.323544 -266.519987)
			(xy 137.36956 -266.502535) (xy 137.417779 -266.492691) (xy 137.466954 -266.49071) (xy 137.515809 -266.496642)
			(xy 137.56308 -266.510334) (xy 137.607542 -266.531432) (xy 137.648045 -266.559388) (xy 137.683538 -266.59348)
			(xy 137.713103 -266.632824) (xy 137.735974 -266.676401) (xy 137.751558 -266.723082) (xy 137.759453 -266.771659)
			(xy 137.759948 -266.796266) (xy 138.08889 -266.796266) (xy 138.09285 -266.747212) (xy 138.104627 -266.699428)
			(xy 138.123918 -266.654152) (xy 138.150221 -266.612556) (xy 138.182856 -266.575719) (xy 138.220977 -266.544594)
			(xy 138.263598 -266.519987) (xy 138.309614 -266.502535) (xy 138.357833 -266.492691) (xy 138.407008 -266.49071)
			(xy 138.455863 -266.496642) (xy 138.503134 -266.510334) (xy 138.547596 -266.531432) (xy 138.588099 -266.559388)
			(xy 138.623592 -266.59348) (xy 138.653157 -266.632824) (xy 138.676028 -266.676401) (xy 138.691612 -266.723082)
			(xy 138.699507 -266.771659) (xy 138.700002 -266.796266) (xy 139.028944 -266.796266) (xy 139.032904 -266.747212)
			(xy 139.044681 -266.699428) (xy 139.063972 -266.654152) (xy 139.090275 -266.612556) (xy 139.12291 -266.575719)
			(xy 139.161031 -266.544594) (xy 139.203652 -266.519987) (xy 139.249668 -266.502535) (xy 139.297887 -266.492691)
			(xy 139.347062 -266.49071) (xy 139.395917 -266.496642) (xy 139.443188 -266.510334) (xy 139.48765 -266.531432)
			(xy 139.528153 -266.559388) (xy 139.563646 -266.59348) (xy 139.593211 -266.632824) (xy 139.616082 -266.676401)
			(xy 139.631666 -266.723082) (xy 139.639561 -266.771659) (xy 139.640056 -266.796266) (xy 139.639561 -266.820873)
			(xy 139.631666 -266.86945) (xy 139.616082 -266.916131) (xy 139.593211 -266.959708) (xy 139.563646 -266.999052)
			(xy 139.528153 -267.033144) (xy 139.48765 -267.0611) (xy 139.443188 -267.082198) (xy 139.395917 -267.09589)
			(xy 139.347062 -267.101822) (xy 139.297887 -267.099841) (xy 139.249668 -267.089997) (xy 139.203652 -267.072545)
			(xy 139.161031 -267.047938) (xy 139.12291 -267.016813) (xy 139.090275 -266.979976) (xy 139.063972 -266.93838)
			(xy 139.044681 -266.893104) (xy 139.032904 -266.84532) (xy 139.028944 -266.796266) (xy 138.700002 -266.796266)
			(xy 138.699507 -266.820873) (xy 138.691612 -266.86945) (xy 138.676028 -266.916131) (xy 138.653157 -266.959708)
			(xy 138.623592 -266.999052) (xy 138.588099 -267.033144) (xy 138.547596 -267.0611) (xy 138.503134 -267.082198)
			(xy 138.455863 -267.09589) (xy 138.407008 -267.101822) (xy 138.357833 -267.099841) (xy 138.309614 -267.089997)
			(xy 138.263598 -267.072545) (xy 138.220977 -267.047938) (xy 138.182856 -267.016813) (xy 138.150221 -266.979976)
			(xy 138.123918 -266.93838) (xy 138.104627 -266.893104) (xy 138.09285 -266.84532) (xy 138.08889 -266.796266)
			(xy 137.759948 -266.796266) (xy 137.759453 -266.820873) (xy 137.751558 -266.86945) (xy 137.735974 -266.916131)
			(xy 137.713103 -266.959708) (xy 137.683538 -266.999052) (xy 137.648045 -267.033144) (xy 137.607542 -267.0611)
			(xy 137.56308 -267.082198) (xy 137.515809 -267.09589) (xy 137.466954 -267.101822) (xy 137.417779 -267.099841)
			(xy 137.36956 -267.089997) (xy 137.323544 -267.072545) (xy 137.280923 -267.047938) (xy 137.242802 -267.016813)
			(xy 137.210167 -266.979976) (xy 137.183864 -266.93838) (xy 137.164573 -266.893104) (xy 137.152796 -266.84532)
			(xy 137.148836 -266.796266) (xy 136.820148 -266.796266) (xy 136.819653 -266.820873) (xy 136.811758 -266.86945)
			(xy 136.796174 -266.916131) (xy 136.773303 -266.959708) (xy 136.743738 -266.999052) (xy 136.708245 -267.033144)
			(xy 136.667742 -267.0611) (xy 136.62328 -267.082198) (xy 136.576009 -267.09589) (xy 136.527154 -267.101822)
			(xy 136.477979 -267.099841) (xy 136.42976 -267.089997) (xy 136.383744 -267.072545) (xy 136.341123 -267.047938)
			(xy 136.303002 -267.016813) (xy 136.270367 -266.979976) (xy 136.244064 -266.93838) (xy 136.224773 -266.893104)
			(xy 136.212996 -266.84532) (xy 136.209036 -266.796266) (xy 135.880094 -266.796266) (xy 135.879599 -266.820873)
			(xy 135.871704 -266.86945) (xy 135.85612 -266.916131) (xy 135.833249 -266.959708) (xy 135.803684 -266.999052)
			(xy 135.768191 -267.033144) (xy 135.727688 -267.0611) (xy 135.683226 -267.082198) (xy 135.635955 -267.09589)
			(xy 135.5871 -267.101822) (xy 135.537925 -267.099841) (xy 135.489706 -267.089997) (xy 135.44369 -267.072545)
			(xy 135.401069 -267.047938) (xy 135.362948 -267.016813) (xy 135.330313 -266.979976) (xy 135.30401 -266.93838)
			(xy 135.284719 -266.893104) (xy 135.272942 -266.84532) (xy 135.268982 -266.796266) (xy 134.94004 -266.796266)
			(xy 134.939545 -266.820873) (xy 134.93165 -266.86945) (xy 134.916066 -266.916131) (xy 134.893195 -266.959708)
			(xy 134.86363 -266.999052) (xy 134.828137 -267.033144) (xy 134.787634 -267.0611) (xy 134.743172 -267.082198)
			(xy 134.695901 -267.09589) (xy 134.647046 -267.101822) (xy 134.597871 -267.099841) (xy 134.549652 -267.089997)
			(xy 134.503636 -267.072545) (xy 134.461015 -267.047938) (xy 134.422894 -267.016813) (xy 134.390259 -266.979976)
			(xy 134.363956 -266.93838) (xy 134.344665 -266.893104) (xy 134.332888 -266.84532) (xy 134.328928 -266.796266)
			(xy 133.999986 -266.796266) (xy 133.999491 -266.820873) (xy 133.991596 -266.86945) (xy 133.976012 -266.916131)
			(xy 133.953141 -266.959708) (xy 133.923576 -266.999052) (xy 133.888083 -267.033144) (xy 133.84758 -267.0611)
			(xy 133.803118 -267.082198) (xy 133.755847 -267.09589) (xy 133.706992 -267.101822) (xy 133.657817 -267.099841)
			(xy 133.609598 -267.089997) (xy 133.563582 -267.072545) (xy 133.520961 -267.047938) (xy 133.48284 -267.016813)
			(xy 133.450205 -266.979976) (xy 133.423902 -266.93838) (xy 133.404611 -266.893104) (xy 133.392834 -266.84532)
			(xy 133.388874 -266.796266) (xy 133.0706 -266.796266) (xy 133.070088 -266.821712) (xy 133.061924 -266.871946)
			(xy 133.045808 -266.92022) (xy 133.022157 -266.965283) (xy 132.991584 -267.005969) (xy 132.95488 -267.041224)
			(xy 132.912996 -267.070134) (xy 132.867017 -267.091951) (xy 132.818133 -267.106111) (xy 132.767612 -267.112245)
			(xy 132.71676 -267.110196) (xy 132.666896 -267.100016) (xy 132.61931 -267.081969) (xy 132.575236 -267.056523)
			(xy 132.535814 -267.024336) (xy 132.502066 -266.986242) (xy 132.474865 -266.943228) (xy 132.454917 -266.896408)
			(xy 132.442738 -266.846994) (xy 132.438643 -266.796266) (xy 132.130546 -266.796266) (xy 132.130034 -266.821712)
			(xy 132.12187 -266.871946) (xy 132.105754 -266.92022) (xy 132.082103 -266.965283) (xy 132.05153 -267.005969)
			(xy 132.014826 -267.041224) (xy 131.972942 -267.070134) (xy 131.926963 -267.091951) (xy 131.878079 -267.106111)
			(xy 131.827558 -267.112245) (xy 131.776706 -267.110196) (xy 131.726842 -267.100016) (xy 131.679256 -267.081969)
			(xy 131.635182 -267.056523) (xy 131.59576 -267.024336) (xy 131.562012 -266.986242) (xy 131.534811 -266.943228)
			(xy 131.514863 -266.896408) (xy 131.502684 -266.846994) (xy 131.498589 -266.796266) (xy 131.180078 -266.796266)
			(xy 131.179583 -266.820873) (xy 131.171688 -266.86945) (xy 131.156104 -266.916131) (xy 131.133233 -266.959708)
			(xy 131.103668 -266.999052) (xy 131.068175 -267.033144) (xy 131.027672 -267.0611) (xy 130.98321 -267.082198)
			(xy 130.935939 -267.09589) (xy 130.887084 -267.101822) (xy 130.837909 -267.099841) (xy 130.78969 -267.089997)
			(xy 130.743674 -267.072545) (xy 130.701053 -267.047938) (xy 130.662932 -267.016813) (xy 130.630297 -266.979976)
			(xy 130.603994 -266.93838) (xy 130.584703 -266.893104) (xy 130.572926 -266.84532) (xy 130.568966 -266.796266)
			(xy 130.250438 -266.796266) (xy 130.249926 -266.821712) (xy 130.241762 -266.871946) (xy 130.225646 -266.92022)
			(xy 130.201995 -266.965283) (xy 130.171422 -267.005969) (xy 130.134718 -267.041224) (xy 130.092834 -267.070134)
			(xy 130.046855 -267.091951) (xy 129.997971 -267.106111) (xy 129.94745 -267.112245) (xy 129.896598 -267.110196)
			(xy 129.846734 -267.100016) (xy 129.799148 -267.081969) (xy 129.755074 -267.056523) (xy 129.715652 -267.024336)
			(xy 129.681904 -266.986242) (xy 129.654703 -266.943228) (xy 129.634755 -266.896408) (xy 129.622576 -266.846994)
			(xy 129.618481 -266.796266) (xy 129.29997 -266.796266) (xy 129.299475 -266.820873) (xy 129.29158 -266.86945)
			(xy 129.275996 -266.916131) (xy 129.253125 -266.959708) (xy 129.22356 -266.999052) (xy 129.188067 -267.033144)
			(xy 129.147564 -267.0611) (xy 129.103102 -267.082198) (xy 129.055831 -267.09589) (xy 129.006976 -267.101822)
			(xy 128.957801 -267.099841) (xy 128.909582 -267.089997) (xy 128.863566 -267.072545) (xy 128.820945 -267.047938)
			(xy 128.782824 -267.016813) (xy 128.750189 -266.979976) (xy 128.723886 -266.93838) (xy 128.704595 -266.893104)
			(xy 128.692818 -266.84532) (xy 128.688858 -266.796266) (xy 128.370584 -266.796266) (xy 128.370072 -266.821712)
			(xy 128.361908 -266.871946) (xy 128.345792 -266.92022) (xy 128.322141 -266.965283) (xy 128.291568 -267.005969)
			(xy 128.254864 -267.041224) (xy 128.21298 -267.070134) (xy 128.167001 -267.091951) (xy 128.118117 -267.106111)
			(xy 128.067596 -267.112245) (xy 128.016744 -267.110196) (xy 127.96688 -267.100016) (xy 127.919294 -267.081969)
			(xy 127.87522 -267.056523) (xy 127.835798 -267.024336) (xy 127.80205 -266.986242) (xy 127.774849 -266.943228)
			(xy 127.754901 -266.896408) (xy 127.742722 -266.846994) (xy 127.738627 -266.796266) (xy 127.420116 -266.796266)
			(xy 127.419621 -266.820873) (xy 127.411726 -266.86945) (xy 127.396142 -266.916131) (xy 127.373271 -266.959708)
			(xy 127.343706 -266.999052) (xy 127.308213 -267.033144) (xy 127.26771 -267.0611) (xy 127.223248 -267.082198)
			(xy 127.175977 -267.09589) (xy 127.127122 -267.101822) (xy 127.077947 -267.099841) (xy 127.029728 -267.089997)
			(xy 126.983712 -267.072545) (xy 126.941091 -267.047938) (xy 126.90297 -267.016813) (xy 126.870335 -266.979976)
			(xy 126.844032 -266.93838) (xy 126.824741 -266.893104) (xy 126.812964 -266.84532) (xy 126.809004 -266.796266)
			(xy 126.487682 -266.796266) (xy 126.487682 -267.204952) (xy 126.488199 -267.215881) (xy 126.497284 -267.235761)
			(xy 126.505208 -267.243306) (xy 126.569978 -267.29944) (xy 126.590806 -267.305536) (xy 126.601982 -267.304012)
			(xy 126.612594 -267.302602) (xy 126.633949 -267.301079) (xy 126.644654 -267.300964) (xy 126.646686 -267.300964)
			(xy 126.670576 -267.301582) (xy 126.71773 -267.309333) (xy 126.763101 -267.324336) (xy 126.80558 -267.346223)
			(xy 126.844132 -267.374461) (xy 126.877813 -267.408359) (xy 126.905803 -267.447091) (xy 126.927418 -267.48971)
			(xy 126.942129 -267.535176) (xy 126.949577 -267.582379) (xy 126.949962 -267.606272) (xy 126.949583 -267.627974)
			(xy 126.943439 -267.67094) (xy 126.931271 -267.712602) (xy 126.913325 -267.752121) (xy 126.901956 -267.77061)
			(xy 126.898146 -267.776706) (xy 126.893828 -267.791184) (xy 126.891689 -267.800003) (xy 126.893062 -267.818085)
			(xy 126.900609 -267.834574) (xy 126.906782 -267.841222) (xy 126.981458 -267.915898) (xy 126.981966 -267.916406)
			(xy 126.989346 -267.922991) (xy 127.007645 -267.930444) (xy 127.017526 -267.930884) (xy 128.186942 -267.930884)
			(xy 128.187704 -267.930884) (xy 128.199798 -267.930021) (xy 128.221149 -267.918608) (xy 128.228598 -267.90904)
			(xy 128.231646 -267.90396) (xy 128.272794 -267.827506) (xy 128.273556 -267.826236) (xy 128.273556 -267.825982)
			(xy 128.277139 -267.817976) (xy 128.279189 -267.800569) (xy 128.27522 -267.783497) (xy 128.270762 -267.775944)
			(xy 128.26873 -267.772642) (xy 128.267968 -267.771626) (xy 128.267714 -267.770864) (xy 128.26619 -267.768832)
			(xy 128.251537 -267.744277) (xy 128.230675 -267.691043) (xy 128.22007 -267.63486) (xy 128.219454 -267.606272)
			(xy 128.219454 -267.599668) (xy 128.220485 -267.57477) (xy 128.229636 -267.525789) (xy 128.246618 -267.478944)
			(xy 128.27098 -267.435477) (xy 128.302075 -267.396541) (xy 128.339079 -267.363171) (xy 128.381009 -267.33625)
			(xy 128.426754 -267.316495) (xy 128.475099 -267.304427) (xy 128.524762 -267.300369) (xy 128.574425 -267.304427)
			(xy 128.62277 -267.316495) (xy 128.668515 -267.33625) (xy 128.710445 -267.363171) (xy 128.747449 -267.396541)
			(xy 128.778544 -267.435477) (xy 128.802906 -267.478944) (xy 128.819888 -267.525789) (xy 128.829039 -267.57477)
			(xy 128.83007 -267.599668) (xy 128.83007 -267.606272) (xy 128.829475 -267.633866) (xy 128.819569 -267.688159)
			(xy 128.800091 -267.739797) (xy 128.786382 -267.763752) (xy 128.782572 -267.769848) (xy 128.779016 -267.783056)
			(xy 128.779016 -267.819124) (xy 128.77918 -267.825134) (xy 128.782 -267.836819) (xy 128.784604 -267.842238)
			(xy 128.784858 -267.842746) (xy 128.817878 -267.904214) (xy 128.81991 -267.90777) (xy 128.827283 -267.917955)
			(xy 128.849272 -267.930087) (xy 128.86182 -267.930884) (xy 129.126996 -267.930884) (xy 129.127758 -267.930884)
			(xy 129.140117 -267.930103) (xy 129.161833 -267.91826) (xy 129.16916 -267.908278) (xy 129.1717 -267.904214)
			(xy 129.210816 -267.831062) (xy 129.213903 -267.824848) (xy 129.217 -267.811329) (xy 129.216912 -267.804392)
			(xy 129.216658 -267.801344) (xy 129.200829 -267.780338) (xy 129.175656 -267.734159) (xy 129.158495 -267.684444)
			(xy 129.149821 -267.63257) (xy 129.149348 -267.606272) (xy 129.149834 -267.581482) (xy 129.15759 -267.532514)
			(xy 129.172911 -267.485361) (xy 129.19542 -267.441186) (xy 129.224562 -267.401075) (xy 129.259619 -267.366018)
			(xy 129.29973 -267.336876) (xy 129.343905 -267.314367) (xy 129.391058 -267.299046) (xy 129.440026 -267.29129)
			(xy 129.489606 -267.29129) (xy 129.538574 -267.299046) (xy 129.585727 -267.314367) (xy 129.629902 -267.336876)
			(xy 129.670013 -267.366018) (xy 129.70507 -267.401075) (xy 129.734212 -267.441186) (xy 129.756721 -267.485361)
			(xy 129.772042 -267.532514) (xy 129.779798 -267.581482) (xy 129.780284 -267.606272) (xy 130.099066 -267.606272)
			(xy 130.103026 -267.557218) (xy 130.114803 -267.509434) (xy 130.134094 -267.464158) (xy 130.160397 -267.422562)
			(xy 130.193032 -267.385725) (xy 130.231153 -267.3546) (xy 130.273774 -267.329993) (xy 130.31979 -267.312541)
			(xy 130.368009 -267.302697) (xy 130.417184 -267.300716) (xy 130.466039 -267.306648) (xy 130.51331 -267.32034)
			(xy 130.557772 -267.341438) (xy 130.598275 -267.369394) (xy 130.633768 -267.403486) (xy 130.663333 -267.44283)
			(xy 130.686204 -267.486407) (xy 130.701788 -267.533088) (xy 130.709683 -267.581665) (xy 130.710178 -267.606272)
			(xy 131.038866 -267.606272) (xy 131.042826 -267.557218) (xy 131.054603 -267.509434) (xy 131.073894 -267.464158)
			(xy 131.100197 -267.422562) (xy 131.132832 -267.385725) (xy 131.170953 -267.3546) (xy 131.213574 -267.329993)
			(xy 131.25959 -267.312541) (xy 131.307809 -267.302697) (xy 131.356984 -267.300716) (xy 131.405839 -267.306648)
			(xy 131.45311 -267.32034) (xy 131.497572 -267.341438) (xy 131.538075 -267.369394) (xy 131.573568 -267.403486)
			(xy 131.603133 -267.44283) (xy 131.626004 -267.486407) (xy 131.641588 -267.533088) (xy 131.649483 -267.581665)
			(xy 131.649978 -267.606272) (xy 131.97892 -267.606272) (xy 131.98288 -267.557218) (xy 131.994657 -267.509434)
			(xy 132.013948 -267.464158) (xy 132.040251 -267.422562) (xy 132.072886 -267.385725) (xy 132.111007 -267.3546)
			(xy 132.153628 -267.329993) (xy 132.199644 -267.312541) (xy 132.247863 -267.302697) (xy 132.297038 -267.300716)
			(xy 132.345893 -267.306648) (xy 132.393164 -267.32034) (xy 132.437626 -267.341438) (xy 132.478129 -267.369394)
			(xy 132.513622 -267.403486) (xy 132.543187 -267.44283) (xy 132.566058 -267.486407) (xy 132.581642 -267.533088)
			(xy 132.589537 -267.581665) (xy 132.590032 -267.606272) (xy 132.908543 -267.606272) (xy 132.912638 -267.555544)
			(xy 132.924817 -267.50613) (xy 132.944765 -267.45931) (xy 132.971966 -267.416296) (xy 133.005714 -267.378202)
			(xy 133.045136 -267.346015) (xy 133.08921 -267.320569) (xy 133.136796 -267.302522) (xy 133.18666 -267.292342)
			(xy 133.237512 -267.290293) (xy 133.288033 -267.296427) (xy 133.336917 -267.310587) (xy 133.382896 -267.332404)
			(xy 133.42478 -267.361314) (xy 133.461484 -267.396569) (xy 133.492057 -267.437255) (xy 133.515708 -267.482318)
			(xy 133.531824 -267.530592) (xy 133.539988 -267.580826) (xy 133.5405 -267.606272) (xy 133.859028 -267.606272)
			(xy 133.862988 -267.557218) (xy 133.874765 -267.509434) (xy 133.894056 -267.464158) (xy 133.920359 -267.422562)
			(xy 133.952994 -267.385725) (xy 133.991115 -267.3546) (xy 134.033736 -267.329993) (xy 134.079752 -267.312541)
			(xy 134.127971 -267.302697) (xy 134.177146 -267.300716) (xy 134.226001 -267.306648) (xy 134.273272 -267.32034)
			(xy 134.317734 -267.341438) (xy 134.358237 -267.369394) (xy 134.39373 -267.403486) (xy 134.423295 -267.44283)
			(xy 134.446166 -267.486407) (xy 134.46175 -267.533088) (xy 134.469645 -267.581665) (xy 134.47014 -267.606272)
			(xy 134.798828 -267.606272) (xy 134.802788 -267.557218) (xy 134.814565 -267.509434) (xy 134.833856 -267.464158)
			(xy 134.860159 -267.422562) (xy 134.892794 -267.385725) (xy 134.930915 -267.3546) (xy 134.973536 -267.329993)
			(xy 135.019552 -267.312541) (xy 135.067771 -267.302697) (xy 135.116946 -267.300716) (xy 135.165801 -267.306648)
			(xy 135.213072 -267.32034) (xy 135.257534 -267.341438) (xy 135.298037 -267.369394) (xy 135.33353 -267.403486)
			(xy 135.363095 -267.44283) (xy 135.385966 -267.486407) (xy 135.40155 -267.533088) (xy 135.409445 -267.581665)
			(xy 135.40994 -267.606272) (xy 135.738882 -267.606272) (xy 135.742842 -267.557218) (xy 135.754619 -267.509434)
			(xy 135.77391 -267.464158) (xy 135.800213 -267.422562) (xy 135.832848 -267.385725) (xy 135.870969 -267.3546)
			(xy 135.91359 -267.329993) (xy 135.959606 -267.312541) (xy 136.007825 -267.302697) (xy 136.057 -267.300716)
			(xy 136.105855 -267.306648) (xy 136.153126 -267.32034) (xy 136.197588 -267.341438) (xy 136.238091 -267.369394)
			(xy 136.273584 -267.403486) (xy 136.303149 -267.44283) (xy 136.32602 -267.486407) (xy 136.341604 -267.533088)
			(xy 136.349499 -267.581665) (xy 136.349994 -267.606272) (xy 136.678936 -267.606272) (xy 136.682896 -267.557218)
			(xy 136.694673 -267.509434) (xy 136.713964 -267.464158) (xy 136.740267 -267.422562) (xy 136.772902 -267.385725)
			(xy 136.811023 -267.3546) (xy 136.853644 -267.329993) (xy 136.89966 -267.312541) (xy 136.947879 -267.302697)
			(xy 136.997054 -267.300716) (xy 137.045909 -267.306648) (xy 137.09318 -267.32034) (xy 137.137642 -267.341438)
			(xy 137.178145 -267.369394) (xy 137.213638 -267.403486) (xy 137.243203 -267.44283) (xy 137.266074 -267.486407)
			(xy 137.281658 -267.533088) (xy 137.289553 -267.581665) (xy 137.290048 -267.606272) (xy 137.61899 -267.606272)
			(xy 137.62295 -267.557218) (xy 137.634727 -267.509434) (xy 137.654018 -267.464158) (xy 137.680321 -267.422562)
			(xy 137.712956 -267.385725) (xy 137.751077 -267.3546) (xy 137.793698 -267.329993) (xy 137.839714 -267.312541)
			(xy 137.887933 -267.302697) (xy 137.937108 -267.300716) (xy 137.985963 -267.306648) (xy 138.033234 -267.32034)
			(xy 138.077696 -267.341438) (xy 138.118199 -267.369394) (xy 138.153692 -267.403486) (xy 138.183257 -267.44283)
			(xy 138.206128 -267.486407) (xy 138.221712 -267.533088) (xy 138.229607 -267.581665) (xy 138.230102 -267.606272)
			(xy 138.559044 -267.606272) (xy 138.563004 -267.557218) (xy 138.574781 -267.509434) (xy 138.594072 -267.464158)
			(xy 138.620375 -267.422562) (xy 138.65301 -267.385725) (xy 138.691131 -267.3546) (xy 138.733752 -267.329993)
			(xy 138.779768 -267.312541) (xy 138.827987 -267.302697) (xy 138.877162 -267.300716) (xy 138.926017 -267.306648)
			(xy 138.973288 -267.32034) (xy 139.01775 -267.341438) (xy 139.058253 -267.369394) (xy 139.093746 -267.403486)
			(xy 139.123311 -267.44283) (xy 139.146182 -267.486407) (xy 139.161766 -267.533088) (xy 139.169661 -267.581665)
			(xy 139.170156 -267.606272) (xy 139.498844 -267.606272) (xy 139.502804 -267.557218) (xy 139.514581 -267.509434)
			(xy 139.533872 -267.464158) (xy 139.560175 -267.422562) (xy 139.59281 -267.385725) (xy 139.630931 -267.3546)
			(xy 139.673552 -267.329993) (xy 139.719568 -267.312541) (xy 139.767787 -267.302697) (xy 139.816962 -267.300716)
			(xy 139.865817 -267.306648) (xy 139.913088 -267.32034) (xy 139.95755 -267.341438) (xy 139.998053 -267.369394)
			(xy 140.033546 -267.403486) (xy 140.063111 -267.44283) (xy 140.085982 -267.486407) (xy 140.101566 -267.533088)
			(xy 140.109461 -267.581665) (xy 140.109956 -267.606272) (xy 140.109461 -267.630879) (xy 140.101566 -267.679456)
			(xy 140.085982 -267.726137) (xy 140.063111 -267.769714) (xy 140.033546 -267.809058) (xy 139.998053 -267.84315)
			(xy 139.95755 -267.871106) (xy 139.913088 -267.892204) (xy 139.865817 -267.905896) (xy 139.816962 -267.911828)
			(xy 139.767787 -267.909847) (xy 139.719568 -267.900003) (xy 139.673552 -267.882551) (xy 139.630931 -267.857944)
			(xy 139.59281 -267.826819) (xy 139.560175 -267.789982) (xy 139.533872 -267.748386) (xy 139.514581 -267.70311)
			(xy 139.502804 -267.655326) (xy 139.498844 -267.606272) (xy 139.170156 -267.606272) (xy 139.169661 -267.630879)
			(xy 139.161766 -267.679456) (xy 139.146182 -267.726137) (xy 139.123311 -267.769714) (xy 139.093746 -267.809058)
			(xy 139.058253 -267.84315) (xy 139.01775 -267.871106) (xy 138.973288 -267.892204) (xy 138.926017 -267.905896)
			(xy 138.877162 -267.911828) (xy 138.827987 -267.909847) (xy 138.779768 -267.900003) (xy 138.733752 -267.882551)
			(xy 138.691131 -267.857944) (xy 138.65301 -267.826819) (xy 138.620375 -267.789982) (xy 138.594072 -267.748386)
			(xy 138.574781 -267.70311) (xy 138.563004 -267.655326) (xy 138.559044 -267.606272) (xy 138.230102 -267.606272)
			(xy 138.229607 -267.630879) (xy 138.221712 -267.679456) (xy 138.206128 -267.726137) (xy 138.183257 -267.769714)
			(xy 138.153692 -267.809058) (xy 138.118199 -267.84315) (xy 138.077696 -267.871106) (xy 138.033234 -267.892204)
			(xy 137.985963 -267.905896) (xy 137.937108 -267.911828) (xy 137.887933 -267.909847) (xy 137.839714 -267.900003)
			(xy 137.793698 -267.882551) (xy 137.751077 -267.857944) (xy 137.712956 -267.826819) (xy 137.680321 -267.789982)
			(xy 137.654018 -267.748386) (xy 137.634727 -267.70311) (xy 137.62295 -267.655326) (xy 137.61899 -267.606272)
			(xy 137.290048 -267.606272) (xy 137.289553 -267.630879) (xy 137.281658 -267.679456) (xy 137.266074 -267.726137)
			(xy 137.243203 -267.769714) (xy 137.213638 -267.809058) (xy 137.178145 -267.84315) (xy 137.137642 -267.871106)
			(xy 137.09318 -267.892204) (xy 137.045909 -267.905896) (xy 136.997054 -267.911828) (xy 136.947879 -267.909847)
			(xy 136.89966 -267.900003) (xy 136.853644 -267.882551) (xy 136.811023 -267.857944) (xy 136.772902 -267.826819)
			(xy 136.740267 -267.789982) (xy 136.713964 -267.748386) (xy 136.694673 -267.70311) (xy 136.682896 -267.655326)
			(xy 136.678936 -267.606272) (xy 136.349994 -267.606272) (xy 136.349499 -267.630879) (xy 136.341604 -267.679456)
			(xy 136.32602 -267.726137) (xy 136.303149 -267.769714) (xy 136.273584 -267.809058) (xy 136.238091 -267.84315)
			(xy 136.197588 -267.871106) (xy 136.153126 -267.892204) (xy 136.105855 -267.905896) (xy 136.057 -267.911828)
			(xy 136.007825 -267.909847) (xy 135.959606 -267.900003) (xy 135.91359 -267.882551) (xy 135.870969 -267.857944)
			(xy 135.832848 -267.826819) (xy 135.800213 -267.789982) (xy 135.77391 -267.748386) (xy 135.754619 -267.70311)
			(xy 135.742842 -267.655326) (xy 135.738882 -267.606272) (xy 135.40994 -267.606272) (xy 135.409445 -267.630879)
			(xy 135.40155 -267.679456) (xy 135.385966 -267.726137) (xy 135.363095 -267.769714) (xy 135.33353 -267.809058)
			(xy 135.298037 -267.84315) (xy 135.257534 -267.871106) (xy 135.213072 -267.892204) (xy 135.165801 -267.905896)
			(xy 135.116946 -267.911828) (xy 135.067771 -267.909847) (xy 135.019552 -267.900003) (xy 134.973536 -267.882551)
			(xy 134.930915 -267.857944) (xy 134.892794 -267.826819) (xy 134.860159 -267.789982) (xy 134.833856 -267.748386)
			(xy 134.814565 -267.70311) (xy 134.802788 -267.655326) (xy 134.798828 -267.606272) (xy 134.47014 -267.606272)
			(xy 134.469645 -267.630879) (xy 134.46175 -267.679456) (xy 134.446166 -267.726137) (xy 134.423295 -267.769714)
			(xy 134.39373 -267.809058) (xy 134.358237 -267.84315) (xy 134.317734 -267.871106) (xy 134.273272 -267.892204)
			(xy 134.226001 -267.905896) (xy 134.177146 -267.911828) (xy 134.127971 -267.909847) (xy 134.079752 -267.900003)
			(xy 134.033736 -267.882551) (xy 133.991115 -267.857944) (xy 133.952994 -267.826819) (xy 133.920359 -267.789982)
			(xy 133.894056 -267.748386) (xy 133.874765 -267.70311) (xy 133.862988 -267.655326) (xy 133.859028 -267.606272)
			(xy 133.5405 -267.606272) (xy 133.539988 -267.631718) (xy 133.531824 -267.681952) (xy 133.515708 -267.730226)
			(xy 133.492057 -267.775289) (xy 133.461484 -267.815975) (xy 133.42478 -267.85123) (xy 133.382896 -267.88014)
			(xy 133.336917 -267.901957) (xy 133.288033 -267.916117) (xy 133.237512 -267.922251) (xy 133.18666 -267.920202)
			(xy 133.136796 -267.910022) (xy 133.08921 -267.891975) (xy 133.045136 -267.866529) (xy 133.005714 -267.834342)
			(xy 132.971966 -267.796248) (xy 132.944765 -267.753234) (xy 132.924817 -267.706414) (xy 132.912638 -267.657)
			(xy 132.908543 -267.606272) (xy 132.590032 -267.606272) (xy 132.589537 -267.630879) (xy 132.581642 -267.679456)
			(xy 132.566058 -267.726137) (xy 132.543187 -267.769714) (xy 132.513622 -267.809058) (xy 132.478129 -267.84315)
			(xy 132.437626 -267.871106) (xy 132.393164 -267.892204) (xy 132.345893 -267.905896) (xy 132.297038 -267.911828)
			(xy 132.247863 -267.909847) (xy 132.199644 -267.900003) (xy 132.153628 -267.882551) (xy 132.111007 -267.857944)
			(xy 132.072886 -267.826819) (xy 132.040251 -267.789982) (xy 132.013948 -267.748386) (xy 131.994657 -267.70311)
			(xy 131.98288 -267.655326) (xy 131.97892 -267.606272) (xy 131.649978 -267.606272) (xy 131.649483 -267.630879)
			(xy 131.641588 -267.679456) (xy 131.626004 -267.726137) (xy 131.603133 -267.769714) (xy 131.573568 -267.809058)
			(xy 131.538075 -267.84315) (xy 131.497572 -267.871106) (xy 131.45311 -267.892204) (xy 131.405839 -267.905896)
			(xy 131.356984 -267.911828) (xy 131.307809 -267.909847) (xy 131.25959 -267.900003) (xy 131.213574 -267.882551)
			(xy 131.170953 -267.857944) (xy 131.132832 -267.826819) (xy 131.100197 -267.789982) (xy 131.073894 -267.748386)
			(xy 131.054603 -267.70311) (xy 131.042826 -267.655326) (xy 131.038866 -267.606272) (xy 130.710178 -267.606272)
			(xy 130.709683 -267.630879) (xy 130.701788 -267.679456) (xy 130.686204 -267.726137) (xy 130.663333 -267.769714)
			(xy 130.633768 -267.809058) (xy 130.598275 -267.84315) (xy 130.557772 -267.871106) (xy 130.51331 -267.892204)
			(xy 130.466039 -267.905896) (xy 130.417184 -267.911828) (xy 130.368009 -267.909847) (xy 130.31979 -267.900003)
			(xy 130.273774 -267.882551) (xy 130.231153 -267.857944) (xy 130.193032 -267.826819) (xy 130.160397 -267.789982)
			(xy 130.134094 -267.748386) (xy 130.114803 -267.70311) (xy 130.103026 -267.655326) (xy 130.099066 -267.606272)
			(xy 129.780284 -267.606272) (xy 129.779877 -267.629436) (xy 129.773104 -267.675265) (xy 129.759699 -267.719611)
			(xy 129.739952 -267.761518) (xy 129.727452 -267.781024) (xy 129.723388 -267.787628) (xy 129.71907 -267.801598)
			(xy 129.71907 -267.819124) (xy 129.719234 -267.825135) (xy 129.722051 -267.83682) (xy 129.724658 -267.842238)
			(xy 129.724912 -267.842746) (xy 129.757932 -267.904214) (xy 129.759964 -267.90777) (xy 129.767334 -267.917963)
			(xy 129.789322 -267.930114) (xy 129.801874 -267.930884) (xy 129.85623 -267.930884) (xy 129.866071 -267.931412)
			(xy 129.884244 -267.938987) (xy 129.891536 -267.945616) (xy 130.116072 -268.170152) (xy 130.119628 -268.1732)
			(xy 130.121152 -268.17447) (xy 130.121914 -268.174978) (xy 130.136888 -268.186975) (xy 130.16402 -268.214106)
			(xy 130.176016 -268.22908) (xy 130.176524 -268.229842) (xy 130.177794 -268.231366) (xy 130.180842 -268.234922)
			(xy 130.613658 -268.667738) (xy 130.614166 -268.668246) (xy 130.621547 -268.674827) (xy 130.639847 -268.682274)
			(xy 130.649726 -268.682724) (xy 131.057396 -268.682724)
		)
		(stroke
			(width 0)
			(type solid)
		)
		(fill yes)
		(layer "In6.Cu")
		(net "PVDD11_S3_P1")
	)
	(gr_poly
		(pts
			(xy 456.648058 -440.624976) (xy 456.659687 -440.624402) (xy 456.680585 -440.614189) (xy 456.694897 -440.595854)
			(xy 456.697842 -440.58459) (xy 456.721972 -440.469528) (xy 456.705462 -440.437778) (xy 456.688952 -440.430412)
			(xy 456.595863 -440.389194) (xy 456.412583 -440.300509) (xy 456.232863 -440.204813) (xy 456.056973 -440.102248)
			(xy 455.885175 -439.992967) (xy 455.717725 -439.877134) (xy 455.554873 -439.754922) (xy 455.396862 -439.626512)
			(xy 455.243927 -439.492095) (xy 455.096296 -439.351874) (xy 454.954191 -439.206056) (xy 454.817822 -439.05486)
			(xy 454.687393 -438.898511) (xy 454.563099 -438.737241) (xy 454.445125 -438.571292) (xy 454.333648 -438.400912)
			(xy 454.228833 -438.226354) (xy 454.130836 -438.047878) (xy 454.039805 -437.865752) (xy 453.955874 -437.680246)
			(xy 453.879169 -437.491637) (xy 453.809805 -437.300207) (xy 453.747885 -437.106242) (xy 453.6935 -436.91003)
			(xy 453.646734 -436.711864) (xy 453.607654 -436.51204) (xy 453.576319 -436.310856) (xy 453.552777 -436.108612)
			(xy 453.537062 -435.90561) (xy 453.529198 -435.702153) (xy 453.528684 -435.600348) (xy 453.529191 -435.496851)
			(xy 453.537316 -435.290017) (xy 453.553554 -435.083661) (xy 453.577881 -434.878102) (xy 453.610259 -434.673657)
			(xy 453.650639 -434.47064) (xy 453.698957 -434.269365) (xy 453.75514 -434.070142) (xy 453.819102 -433.873278)
			(xy 453.890742 -433.679077) (xy 453.969951 -433.487838) (xy 454.056608 -433.299857) (xy 454.150577 -433.115422)
			(xy 454.251714 -432.934819) (xy 454.359864 -432.758325) (xy 454.474859 -432.586213) (xy 454.596523 -432.418749)
			(xy 454.724667 -432.25619) (xy 454.859094 -432.098787) (xy 454.999597 -431.946783) (xy 455.14596 -431.800412)
			(xy 455.297955 -431.6599) (xy 455.45535 -431.525464) (xy 455.617902 -431.39731) (xy 455.785359 -431.275637)
			(xy 455.957464 -431.160631) (xy 456.133951 -431.052471) (xy 456.314549 -430.951323) (xy 456.498978 -430.857343)
			(xy 456.686954 -430.770676) (xy 456.878188 -430.691455) (xy 457.072385 -430.619803) (xy 457.269245 -430.55583)
			(xy 457.468465 -430.499636) (xy 457.669737 -430.451305) (xy 457.872751 -430.410914) (xy 458.077195 -430.378523)
			(xy 458.282753 -430.354184) (xy 458.489108 -430.337934) (xy 458.695941 -430.329797) (xy 458.799438 -430.32934)
			(xy 458.8002 -430.32934) (xy 458.90319 -430.329838) (xy 459.109014 -430.337885) (xy 459.314366 -430.353967)
			(xy 459.518933 -430.378059) (xy 459.722402 -430.410125) (xy 459.924464 -430.450115) (xy 460.124809 -430.497969)
			(xy 460.323132 -430.553613) (xy 460.519129 -430.616962) (xy 460.712502 -430.68792) (xy 460.902955 -430.766378)
			(xy 461.090197 -430.852217) (xy 461.273943 -430.945306) (xy 461.453912 -431.045502) (xy 461.629829 -431.152652)
			(xy 461.801426 -431.266593) (xy 461.968441 -431.387151) (xy 462.130618 -431.514142) (xy 462.28771 -431.647371)
			(xy 462.439478 -431.786636) (xy 462.585689 -431.931724) (xy 462.72612 -432.082413) (xy 462.860557 -432.238473)
			(xy 462.988794 -432.399666) (xy 463.110636 -432.565746) (xy 463.225897 -432.73646) (xy 463.334401 -432.911546)
			(xy 463.435981 -433.090737) (xy 463.530484 -433.273759) (xy 463.617764 -433.460334) (xy 463.697689 -433.650177)
			(xy 463.734404 -433.746402) (xy 463.741008 -433.763928) (xy 463.772758 -433.781962) (xy 463.889344 -433.760626)
			(xy 463.897997 -433.75867) (xy 463.913312 -433.749744) (xy 463.92466 -433.736126) (xy 463.930675 -433.719452)
			(xy 463.931 -433.710588) (xy 463.931 -408.086052) (xy 463.931432 -408.075986) (xy 463.939159 -408.057394)
			(xy 463.945986 -408.049984) (xy 466.986874 -405.009096) (xy 466.993723 -405.001698) (xy 467.00146 -404.9831)
			(xy 467.00186 -404.973028) (xy 467.00186 -376.167396) (xy 467.001435 -376.157327) (xy 466.993715 -376.138727)
			(xy 466.986874 -376.131328) (xy 466.29828 -375.442734) (xy 466.291168 -375.435368) (xy 466.272372 -375.427748)
			(xy 442.32449 -375.427748) (xy 442.314422 -375.428174) (xy 442.295824 -375.435897) (xy 442.288422 -375.442734)
			(xy 440.937396 -376.79376) (xy 440.930706 -376.801168) (xy 440.92311 -376.819604) (xy 440.922664 -376.829574)
			(xy 440.922664 -383.388882) (xy 441.915547 -383.388882) (xy 441.919279 -383.335628) (xy 441.930398 -383.283415)
			(xy 441.948686 -383.233261) (xy 441.973787 -383.186146) (xy 442.005209 -383.14299) (xy 442.042341 -383.104634)
			(xy 442.063124 -383.08788) (xy 442.071895 -383.080327) (xy 442.082072 -383.059561) (xy 442.082682 -383.048002)
			(xy 442.082682 -382.967738) (xy 442.082096 -382.956172) (xy 442.071913 -382.9354) (xy 442.063124 -382.92786)
			(xy 442.042313 -382.911141) (xy 442.005185 -382.872782) (xy 441.973767 -382.829623) (xy 441.948671 -382.782505)
			(xy 441.930388 -382.73235) (xy 441.919274 -382.680135) (xy 441.915547 -382.626882) (xy 441.919279 -382.573628)
			(xy 441.930398 -382.521415) (xy 441.948686 -382.471261) (xy 441.973787 -382.424146) (xy 442.005209 -382.38099)
			(xy 442.042341 -382.342634) (xy 442.063124 -382.32588) (xy 442.071895 -382.318327) (xy 442.082072 -382.297561)
			(xy 442.082682 -382.286002) (xy 442.082682 -382.205738) (xy 442.082096 -382.194172) (xy 442.071913 -382.1734)
			(xy 442.063124 -382.16586) (xy 442.040626 -382.147685) (xy 442.000891 -382.105663) (xy 441.967953 -382.058125)
			(xy 441.942567 -382.00616) (xy 441.925314 -381.950959) (xy 441.91659 -381.893787) (xy 441.916058 -381.86487)
			(xy 441.916544 -381.837619) (xy 441.9243 -381.783671) (xy 441.939655 -381.731376) (xy 441.962297 -381.681799)
			(xy 441.991763 -381.635949) (xy 442.027454 -381.594758) (xy 442.068645 -381.559067) (xy 442.114495 -381.529601)
			(xy 442.164072 -381.506959) (xy 442.216367 -381.491604) (xy 442.270315 -381.483848) (xy 442.324817 -381.483848)
			(xy 442.378765 -381.491604) (xy 442.43106 -381.506959) (xy 442.480637 -381.529601) (xy 442.526487 -381.559067)
			(xy 442.567678 -381.594758) (xy 442.603369 -381.635949) (xy 442.632835 -381.681799) (xy 442.655477 -381.731376)
			(xy 442.670832 -381.783671) (xy 442.678588 -381.837619) (xy 442.679074 -381.86487) (xy 442.678544 -381.893787)
			(xy 442.669819 -381.950958) (xy 442.652564 -382.006157) (xy 442.627174 -382.058119) (xy 442.594232 -382.105653)
			(xy 442.554493 -382.14767) (xy 442.532008 -382.16586) (xy 442.52327 -382.173445) (xy 442.513073 -382.194186)
			(xy 442.51245 -382.205738) (xy 442.51245 -382.286002) (xy 442.513002 -382.297573) (xy 442.523208 -382.318345)
			(xy 442.532008 -382.32588) (xy 442.552763 -382.342668) (xy 442.589896 -382.381016) (xy 442.62132 -382.424166)
			(xy 442.646422 -382.471275) (xy 442.664711 -382.521424) (xy 442.675831 -382.573632) (xy 442.679563 -382.626882)
			(xy 442.675836 -382.680131) (xy 442.664721 -382.732341) (xy 442.646437 -382.782491) (xy 442.621339 -382.829603)
			(xy 442.589919 -382.872756) (xy 442.55279 -382.911107) (xy 442.532008 -382.92786) (xy 442.52327 -382.935445)
			(xy 442.513073 -382.956186) (xy 442.51245 -382.967738) (xy 442.51245 -383.048002) (xy 442.513002 -383.059573)
			(xy 442.523208 -383.080345) (xy 442.532008 -383.08788) (xy 442.552763 -383.104668) (xy 442.589896 -383.143016)
			(xy 442.62132 -383.186166) (xy 442.646422 -383.233275) (xy 442.664711 -383.283424) (xy 442.675831 -383.335632)
			(xy 442.679563 -383.388882) (xy 445.725547 -383.388882) (xy 445.729279 -383.335628) (xy 445.740398 -383.283415)
			(xy 445.758686 -383.233261) (xy 445.783787 -383.186146) (xy 445.815209 -383.14299) (xy 445.852341 -383.104634)
			(xy 445.873124 -383.08788) (xy 445.881895 -383.080327) (xy 445.892072 -383.059561) (xy 445.892682 -383.048002)
			(xy 445.892682 -382.967738) (xy 445.892096 -382.956172) (xy 445.881913 -382.9354) (xy 445.873124 -382.92786)
			(xy 445.852313 -382.911141) (xy 445.815185 -382.872782) (xy 445.783767 -382.829623) (xy 445.758671 -382.782505)
			(xy 445.740388 -382.73235) (xy 445.729274 -382.680135) (xy 445.725547 -382.626882) (xy 445.729279 -382.573628)
			(xy 445.740398 -382.521415) (xy 445.758686 -382.471261) (xy 445.783787 -382.424146) (xy 445.815209 -382.38099)
			(xy 445.852341 -382.342634) (xy 445.873124 -382.32588) (xy 445.881895 -382.318327) (xy 445.892072 -382.297561)
			(xy 445.892682 -382.286002) (xy 445.892682 -382.205738) (xy 445.892096 -382.194172) (xy 445.881913 -382.1734)
			(xy 445.873124 -382.16586) (xy 445.850626 -382.147685) (xy 445.810891 -382.105663) (xy 445.777953 -382.058125)
			(xy 445.752567 -382.00616) (xy 445.735314 -381.950959) (xy 445.72659 -381.893787) (xy 445.726058 -381.86487)
			(xy 445.726544 -381.837619) (xy 445.7343 -381.783671) (xy 445.749655 -381.731376) (xy 445.772297 -381.681799)
			(xy 445.801763 -381.635949) (xy 445.837454 -381.594758) (xy 445.878645 -381.559067) (xy 445.924495 -381.529601)
			(xy 445.974072 -381.506959) (xy 446.026367 -381.491604) (xy 446.080315 -381.483848) (xy 446.134817 -381.483848)
			(xy 446.188765 -381.491604) (xy 446.24106 -381.506959) (xy 446.290637 -381.529601) (xy 446.336487 -381.559067)
			(xy 446.377678 -381.594758) (xy 446.413369 -381.635949) (xy 446.442835 -381.681799) (xy 446.465477 -381.731376)
			(xy 446.480832 -381.783671) (xy 446.488588 -381.837619) (xy 446.489074 -381.86487) (xy 446.488544 -381.893787)
			(xy 446.479819 -381.950958) (xy 446.462564 -382.006157) (xy 446.437174 -382.058119) (xy 446.404232 -382.105653)
			(xy 446.364493 -382.14767) (xy 446.342008 -382.16586) (xy 446.33327 -382.173445) (xy 446.323073 -382.194186)
			(xy 446.32245 -382.205738) (xy 446.32245 -382.286002) (xy 446.323002 -382.297573) (xy 446.333208 -382.318345)
			(xy 446.342008 -382.32588) (xy 446.362763 -382.342668) (xy 446.399896 -382.381016) (xy 446.43132 -382.424166)
			(xy 446.456422 -382.471275) (xy 446.474711 -382.521424) (xy 446.485831 -382.573632) (xy 446.489563 -382.626882)
			(xy 446.485836 -382.680131) (xy 446.474721 -382.732341) (xy 446.456437 -382.782491) (xy 446.431339 -382.829603)
			(xy 446.399919 -382.872756) (xy 446.36279 -382.911107) (xy 446.342008 -382.92786) (xy 446.33327 -382.935445)
			(xy 446.323073 -382.956186) (xy 446.32245 -382.967738) (xy 446.32245 -383.048002) (xy 446.323002 -383.059573)
			(xy 446.333208 -383.080345) (xy 446.342008 -383.08788) (xy 446.362763 -383.104668) (xy 446.399896 -383.143016)
			(xy 446.43132 -383.186166) (xy 446.456422 -383.233275) (xy 446.474711 -383.283424) (xy 446.485831 -383.335632)
			(xy 446.489563 -383.388882) (xy 447.681347 -383.388882) (xy 447.685079 -383.335628) (xy 447.696198 -383.283415)
			(xy 447.714486 -383.233261) (xy 447.739587 -383.186146) (xy 447.771009 -383.14299) (xy 447.808141 -383.104634)
			(xy 447.828924 -383.08788) (xy 447.837695 -383.080327) (xy 447.847872 -383.059561) (xy 447.848482 -383.048002)
			(xy 447.848482 -382.967738) (xy 447.847896 -382.956172) (xy 447.837713 -382.9354) (xy 447.828924 -382.92786)
			(xy 447.808113 -382.911141) (xy 447.770985 -382.872782) (xy 447.739567 -382.829623) (xy 447.714471 -382.782505)
			(xy 447.696188 -382.73235) (xy 447.685074 -382.680135) (xy 447.681347 -382.626882) (xy 447.685079 -382.573628)
			(xy 447.696198 -382.521415) (xy 447.714486 -382.471261) (xy 447.739587 -382.424146) (xy 447.771009 -382.38099)
			(xy 447.808141 -382.342634) (xy 447.828924 -382.32588) (xy 447.837695 -382.318327) (xy 447.847872 -382.297561)
			(xy 447.848482 -382.286002) (xy 447.848482 -382.205738) (xy 447.847896 -382.194172) (xy 447.837713 -382.1734)
			(xy 447.828924 -382.16586) (xy 447.806426 -382.147685) (xy 447.766691 -382.105663) (xy 447.733753 -382.058125)
			(xy 447.708367 -382.00616) (xy 447.691114 -381.950959) (xy 447.68239 -381.893787) (xy 447.681858 -381.86487)
			(xy 447.682344 -381.837619) (xy 447.6901 -381.783671) (xy 447.705455 -381.731376) (xy 447.728097 -381.681799)
			(xy 447.757563 -381.635949) (xy 447.793254 -381.594758) (xy 447.834445 -381.559067) (xy 447.880295 -381.529601)
			(xy 447.929872 -381.506959) (xy 447.982167 -381.491604) (xy 448.036115 -381.483848) (xy 448.090617 -381.483848)
			(xy 448.144565 -381.491604) (xy 448.19686 -381.506959) (xy 448.246437 -381.529601) (xy 448.292287 -381.559067)
			(xy 448.333478 -381.594758) (xy 448.369169 -381.635949) (xy 448.398635 -381.681799) (xy 448.421277 -381.731376)
			(xy 448.436632 -381.783671) (xy 448.444388 -381.837619) (xy 448.444874 -381.86487) (xy 448.444344 -381.893787)
			(xy 448.435619 -381.950958) (xy 448.418364 -382.006157) (xy 448.392974 -382.058119) (xy 448.360032 -382.105653)
			(xy 448.320293 -382.14767) (xy 448.297808 -382.16586) (xy 448.28907 -382.173445) (xy 448.278873 -382.194186)
			(xy 448.27825 -382.205738) (xy 448.27825 -382.286002) (xy 448.278802 -382.297573) (xy 448.289008 -382.318345)
			(xy 448.297808 -382.32588) (xy 448.318563 -382.342668) (xy 448.355696 -382.381016) (xy 448.38712 -382.424166)
			(xy 448.412222 -382.471275) (xy 448.430511 -382.521424) (xy 448.441631 -382.573632) (xy 448.445363 -382.626882)
			(xy 448.441636 -382.680131) (xy 448.430521 -382.732341) (xy 448.412237 -382.782491) (xy 448.387139 -382.829603)
			(xy 448.355719 -382.872756) (xy 448.31859 -382.911107) (xy 448.297808 -382.92786) (xy 448.28907 -382.935445)
			(xy 448.278873 -382.956186) (xy 448.27825 -382.967738) (xy 448.27825 -383.048002) (xy 448.278802 -383.059573)
			(xy 448.289008 -383.080345) (xy 448.297808 -383.08788) (xy 448.318563 -383.104668) (xy 448.355696 -383.143016)
			(xy 448.38712 -383.186166) (xy 448.412222 -383.233275) (xy 448.430511 -383.283424) (xy 448.441631 -383.335632)
			(xy 448.445363 -383.388882) (xy 451.491347 -383.388882) (xy 451.495079 -383.335628) (xy 451.506198 -383.283415)
			(xy 451.524486 -383.233261) (xy 451.549587 -383.186146) (xy 451.581009 -383.14299) (xy 451.618141 -383.104634)
			(xy 451.638924 -383.08788) (xy 451.647695 -383.080327) (xy 451.657872 -383.059561) (xy 451.658482 -383.048002)
			(xy 451.658482 -382.967738) (xy 451.657896 -382.956172) (xy 451.647713 -382.9354) (xy 451.638924 -382.92786)
			(xy 451.618113 -382.911141) (xy 451.580985 -382.872782) (xy 451.549567 -382.829623) (xy 451.524471 -382.782505)
			(xy 451.506188 -382.73235) (xy 451.495074 -382.680135) (xy 451.491347 -382.626882) (xy 451.495079 -382.573628)
			(xy 451.506198 -382.521415) (xy 451.524486 -382.471261) (xy 451.549587 -382.424146) (xy 451.581009 -382.38099)
			(xy 451.618141 -382.342634) (xy 451.638924 -382.32588) (xy 451.647695 -382.318327) (xy 451.657872 -382.297561)
			(xy 451.658482 -382.286002) (xy 451.658482 -382.205738) (xy 451.657896 -382.194172) (xy 451.647713 -382.1734)
			(xy 451.638924 -382.16586) (xy 451.616426 -382.147685) (xy 451.576691 -382.105663) (xy 451.543753 -382.058125)
			(xy 451.518367 -382.00616) (xy 451.501114 -381.950959) (xy 451.49239 -381.893787) (xy 451.491858 -381.86487)
			(xy 451.492344 -381.837619) (xy 451.5001 -381.783671) (xy 451.515455 -381.731376) (xy 451.538097 -381.681799)
			(xy 451.567563 -381.635949) (xy 451.603254 -381.594758) (xy 451.644445 -381.559067) (xy 451.690295 -381.529601)
			(xy 451.739872 -381.506959) (xy 451.792167 -381.491604) (xy 451.846115 -381.483848) (xy 451.900617 -381.483848)
			(xy 451.954565 -381.491604) (xy 452.00686 -381.506959) (xy 452.056437 -381.529601) (xy 452.102287 -381.559067)
			(xy 452.143478 -381.594758) (xy 452.179169 -381.635949) (xy 452.208635 -381.681799) (xy 452.231277 -381.731376)
			(xy 452.246632 -381.783671) (xy 452.254388 -381.837619) (xy 452.254874 -381.86487) (xy 452.254344 -381.893787)
			(xy 452.245619 -381.950958) (xy 452.228364 -382.006157) (xy 452.202974 -382.058119) (xy 452.170032 -382.105653)
			(xy 452.130293 -382.14767) (xy 452.107808 -382.16586) (xy 452.09907 -382.173445) (xy 452.088873 -382.194186)
			(xy 452.08825 -382.205738) (xy 452.08825 -382.286002) (xy 452.088802 -382.297573) (xy 452.099008 -382.318345)
			(xy 452.107808 -382.32588) (xy 452.128563 -382.342668) (xy 452.165696 -382.381016) (xy 452.19712 -382.424166)
			(xy 452.222222 -382.471275) (xy 452.240511 -382.521424) (xy 452.251631 -382.573632) (xy 452.255363 -382.626882)
			(xy 452.251636 -382.680131) (xy 452.240521 -382.732341) (xy 452.222237 -382.782491) (xy 452.197139 -382.829603)
			(xy 452.165719 -382.872756) (xy 452.12859 -382.911107) (xy 452.107808 -382.92786) (xy 452.09907 -382.935445)
			(xy 452.088873 -382.956186) (xy 452.08825 -382.967738) (xy 452.08825 -383.048002) (xy 452.088802 -383.059573)
			(xy 452.099008 -383.080345) (xy 452.107808 -383.08788) (xy 452.128563 -383.104668) (xy 452.165696 -383.143016)
			(xy 452.19712 -383.186166) (xy 452.222222 -383.233275) (xy 452.240511 -383.283424) (xy 452.251631 -383.335632)
			(xy 452.255363 -383.388882) (xy 453.777347 -383.388882) (xy 453.781079 -383.335628) (xy 453.792198 -383.283415)
			(xy 453.810486 -383.233261) (xy 453.835587 -383.186146) (xy 453.867009 -383.14299) (xy 453.904141 -383.104634)
			(xy 453.924924 -383.08788) (xy 453.933695 -383.080327) (xy 453.943872 -383.059561) (xy 453.944482 -383.048002)
			(xy 453.944482 -382.967738) (xy 453.943896 -382.956172) (xy 453.933713 -382.9354) (xy 453.924924 -382.92786)
			(xy 453.904113 -382.911141) (xy 453.866985 -382.872782) (xy 453.835567 -382.829623) (xy 453.810471 -382.782505)
			(xy 453.792188 -382.73235) (xy 453.781074 -382.680135) (xy 453.777347 -382.626882) (xy 453.781079 -382.573628)
			(xy 453.792198 -382.521415) (xy 453.810486 -382.471261) (xy 453.835587 -382.424146) (xy 453.867009 -382.38099)
			(xy 453.904141 -382.342634) (xy 453.924924 -382.32588) (xy 453.933695 -382.318327) (xy 453.943872 -382.297561)
			(xy 453.944482 -382.286002) (xy 453.944482 -382.205738) (xy 453.943896 -382.194172) (xy 453.933713 -382.1734)
			(xy 453.924924 -382.16586) (xy 453.902426 -382.147685) (xy 453.862691 -382.105663) (xy 453.829753 -382.058125)
			(xy 453.804367 -382.00616) (xy 453.787114 -381.950959) (xy 453.77839 -381.893787) (xy 453.777858 -381.86487)
			(xy 453.778344 -381.837619) (xy 453.7861 -381.783671) (xy 453.801455 -381.731376) (xy 453.824097 -381.681799)
			(xy 453.853563 -381.635949) (xy 453.889254 -381.594758) (xy 453.930445 -381.559067) (xy 453.976295 -381.529601)
			(xy 454.025872 -381.506959) (xy 454.078167 -381.491604) (xy 454.132115 -381.483848) (xy 454.186617 -381.483848)
			(xy 454.240565 -381.491604) (xy 454.29286 -381.506959) (xy 454.342437 -381.529601) (xy 454.388287 -381.559067)
			(xy 454.429478 -381.594758) (xy 454.465169 -381.635949) (xy 454.494635 -381.681799) (xy 454.517277 -381.731376)
			(xy 454.532632 -381.783671) (xy 454.540388 -381.837619) (xy 454.540874 -381.86487) (xy 454.540344 -381.893787)
			(xy 454.531619 -381.950958) (xy 454.514364 -382.006157) (xy 454.488974 -382.058119) (xy 454.456032 -382.105653)
			(xy 454.416293 -382.14767) (xy 454.393808 -382.16586) (xy 454.38507 -382.173445) (xy 454.374873 -382.194186)
			(xy 454.37425 -382.205738) (xy 454.37425 -382.286002) (xy 454.374802 -382.297573) (xy 454.385008 -382.318345)
			(xy 454.393808 -382.32588) (xy 454.414563 -382.342668) (xy 454.451696 -382.381016) (xy 454.48312 -382.424166)
			(xy 454.508222 -382.471275) (xy 454.526511 -382.521424) (xy 454.537631 -382.573632) (xy 454.541363 -382.626882)
			(xy 454.537636 -382.680131) (xy 454.526521 -382.732341) (xy 454.508237 -382.782491) (xy 454.483139 -382.829603)
			(xy 454.451719 -382.872756) (xy 454.41459 -382.911107) (xy 454.393808 -382.92786) (xy 454.38507 -382.935445)
			(xy 454.374873 -382.956186) (xy 454.37425 -382.967738) (xy 454.37425 -383.048002) (xy 454.374802 -383.059573)
			(xy 454.385008 -383.080345) (xy 454.393808 -383.08788) (xy 454.414563 -383.104668) (xy 454.451696 -383.143016)
			(xy 454.48312 -383.186166) (xy 454.508222 -383.233275) (xy 454.526511 -383.283424) (xy 454.537631 -383.335632)
			(xy 454.541363 -383.388882) (xy 457.587347 -383.388882) (xy 457.591079 -383.335628) (xy 457.602198 -383.283415)
			(xy 457.620486 -383.233261) (xy 457.645587 -383.186146) (xy 457.677009 -383.14299) (xy 457.714141 -383.104634)
			(xy 457.734924 -383.08788) (xy 457.743695 -383.080327) (xy 457.753872 -383.059561) (xy 457.754482 -383.048002)
			(xy 457.754482 -382.967738) (xy 457.753896 -382.956172) (xy 457.743713 -382.9354) (xy 457.734924 -382.92786)
			(xy 457.714113 -382.911141) (xy 457.676985 -382.872782) (xy 457.645567 -382.829623) (xy 457.620471 -382.782505)
			(xy 457.602188 -382.73235) (xy 457.591074 -382.680135) (xy 457.587347 -382.626882) (xy 457.591079 -382.573628)
			(xy 457.602198 -382.521415) (xy 457.620486 -382.471261) (xy 457.645587 -382.424146) (xy 457.677009 -382.38099)
			(xy 457.714141 -382.342634) (xy 457.734924 -382.32588) (xy 457.743695 -382.318327) (xy 457.753872 -382.297561)
			(xy 457.754482 -382.286002) (xy 457.754482 -382.205738) (xy 457.753896 -382.194172) (xy 457.743713 -382.1734)
			(xy 457.734924 -382.16586) (xy 457.712426 -382.147685) (xy 457.672691 -382.105663) (xy 457.639753 -382.058125)
			(xy 457.614367 -382.00616) (xy 457.597114 -381.950959) (xy 457.58839 -381.893787) (xy 457.587858 -381.86487)
			(xy 457.588344 -381.837619) (xy 457.5961 -381.783671) (xy 457.611455 -381.731376) (xy 457.634097 -381.681799)
			(xy 457.663563 -381.635949) (xy 457.699254 -381.594758) (xy 457.740445 -381.559067) (xy 457.786295 -381.529601)
			(xy 457.835872 -381.506959) (xy 457.888167 -381.491604) (xy 457.942115 -381.483848) (xy 457.996617 -381.483848)
			(xy 458.050565 -381.491604) (xy 458.10286 -381.506959) (xy 458.152437 -381.529601) (xy 458.198287 -381.559067)
			(xy 458.239478 -381.594758) (xy 458.275169 -381.635949) (xy 458.304635 -381.681799) (xy 458.327277 -381.731376)
			(xy 458.342632 -381.783671) (xy 458.350388 -381.837619) (xy 458.350874 -381.86487) (xy 458.350344 -381.893787)
			(xy 458.341619 -381.950958) (xy 458.324364 -382.006157) (xy 458.298974 -382.058119) (xy 458.266032 -382.105653)
			(xy 458.226293 -382.14767) (xy 458.203808 -382.16586) (xy 458.19507 -382.173445) (xy 458.184873 -382.194186)
			(xy 458.18425 -382.205738) (xy 458.18425 -382.286002) (xy 458.184802 -382.297573) (xy 458.195008 -382.318345)
			(xy 458.203808 -382.32588) (xy 458.224563 -382.342668) (xy 458.261696 -382.381016) (xy 458.29312 -382.424166)
			(xy 458.318222 -382.471275) (xy 458.336511 -382.521424) (xy 458.347631 -382.573632) (xy 458.351363 -382.626882)
			(xy 458.347636 -382.680131) (xy 458.336521 -382.732341) (xy 458.318237 -382.782491) (xy 458.293139 -382.829603)
			(xy 458.261719 -382.872756) (xy 458.22459 -382.911107) (xy 458.203808 -382.92786) (xy 458.19507 -382.935445)
			(xy 458.184873 -382.956186) (xy 458.18425 -382.967738) (xy 458.18425 -383.048002) (xy 458.184802 -383.059573)
			(xy 458.195008 -383.080345) (xy 458.203808 -383.08788) (xy 458.224563 -383.104668) (xy 458.261696 -383.143016)
			(xy 458.29312 -383.186166) (xy 458.318222 -383.233275) (xy 458.336511 -383.283424) (xy 458.347631 -383.335632)
			(xy 458.351363 -383.388882) (xy 459.873347 -383.388882) (xy 459.877079 -383.335628) (xy 459.888198 -383.283415)
			(xy 459.906486 -383.233261) (xy 459.931587 -383.186146) (xy 459.963009 -383.14299) (xy 460.000141 -383.104634)
			(xy 460.020924 -383.08788) (xy 460.029695 -383.080327) (xy 460.039872 -383.059561) (xy 460.040482 -383.048002)
			(xy 460.040482 -382.967738) (xy 460.039896 -382.956172) (xy 460.029713 -382.9354) (xy 460.020924 -382.92786)
			(xy 460.000113 -382.911141) (xy 459.962985 -382.872782) (xy 459.931567 -382.829623) (xy 459.906471 -382.782505)
			(xy 459.888188 -382.73235) (xy 459.877074 -382.680135) (xy 459.873347 -382.626882) (xy 459.877079 -382.573628)
			(xy 459.888198 -382.521415) (xy 459.906486 -382.471261) (xy 459.931587 -382.424146) (xy 459.963009 -382.38099)
			(xy 460.000141 -382.342634) (xy 460.020924 -382.32588) (xy 460.029695 -382.318327) (xy 460.039872 -382.297561)
			(xy 460.040482 -382.286002) (xy 460.040482 -382.205738) (xy 460.039896 -382.194172) (xy 460.029713 -382.1734)
			(xy 460.020924 -382.16586) (xy 459.998426 -382.147685) (xy 459.958691 -382.105663) (xy 459.925753 -382.058125)
			(xy 459.900367 -382.00616) (xy 459.883114 -381.950959) (xy 459.87439 -381.893787) (xy 459.873858 -381.86487)
			(xy 459.874344 -381.837619) (xy 459.8821 -381.783671) (xy 459.897455 -381.731376) (xy 459.920097 -381.681799)
			(xy 459.949563 -381.635949) (xy 459.985254 -381.594758) (xy 460.026445 -381.559067) (xy 460.072295 -381.529601)
			(xy 460.121872 -381.506959) (xy 460.174167 -381.491604) (xy 460.228115 -381.483848) (xy 460.282617 -381.483848)
			(xy 460.336565 -381.491604) (xy 460.38886 -381.506959) (xy 460.438437 -381.529601) (xy 460.484287 -381.559067)
			(xy 460.525478 -381.594758) (xy 460.561169 -381.635949) (xy 460.590635 -381.681799) (xy 460.613277 -381.731376)
			(xy 460.628632 -381.783671) (xy 460.636388 -381.837619) (xy 460.636874 -381.86487) (xy 460.636344 -381.893787)
			(xy 460.627619 -381.950958) (xy 460.610364 -382.006157) (xy 460.584974 -382.058119) (xy 460.552032 -382.105653)
			(xy 460.512293 -382.14767) (xy 460.489808 -382.16586) (xy 460.48107 -382.173445) (xy 460.470873 -382.194186)
			(xy 460.47025 -382.205738) (xy 460.47025 -382.286002) (xy 460.470802 -382.297573) (xy 460.481008 -382.318345)
			(xy 460.489808 -382.32588) (xy 460.510563 -382.342668) (xy 460.547696 -382.381016) (xy 460.57912 -382.424166)
			(xy 460.604222 -382.471275) (xy 460.622511 -382.521424) (xy 460.633631 -382.573632) (xy 460.637363 -382.626882)
			(xy 460.633636 -382.680131) (xy 460.622521 -382.732341) (xy 460.604237 -382.782491) (xy 460.579139 -382.829603)
			(xy 460.547719 -382.872756) (xy 460.51059 -382.911107) (xy 460.489808 -382.92786) (xy 460.48107 -382.935445)
			(xy 460.470873 -382.956186) (xy 460.47025 -382.967738) (xy 460.47025 -383.048002) (xy 460.470802 -383.059573)
			(xy 460.481008 -383.080345) (xy 460.489808 -383.08788) (xy 460.510563 -383.104668) (xy 460.547696 -383.143016)
			(xy 460.57912 -383.186166) (xy 460.604222 -383.233275) (xy 460.622511 -383.283424) (xy 460.633631 -383.335632)
			(xy 460.637363 -383.388882) (xy 463.683347 -383.388882) (xy 463.687079 -383.335628) (xy 463.698198 -383.283415)
			(xy 463.716486 -383.233261) (xy 463.741587 -383.186146) (xy 463.773009 -383.14299) (xy 463.810141 -383.104634)
			(xy 463.830924 -383.08788) (xy 463.839695 -383.080327) (xy 463.849872 -383.059561) (xy 463.850482 -383.048002)
			(xy 463.850482 -382.967738) (xy 463.849896 -382.956172) (xy 463.839713 -382.9354) (xy 463.830924 -382.92786)
			(xy 463.810113 -382.911141) (xy 463.772985 -382.872782) (xy 463.741567 -382.829623) (xy 463.716471 -382.782505)
			(xy 463.698188 -382.73235) (xy 463.687074 -382.680135) (xy 463.683347 -382.626882) (xy 463.687079 -382.573628)
			(xy 463.698198 -382.521415) (xy 463.716486 -382.471261) (xy 463.741587 -382.424146) (xy 463.773009 -382.38099)
			(xy 463.810141 -382.342634) (xy 463.830924 -382.32588) (xy 463.839695 -382.318327) (xy 463.849872 -382.297561)
			(xy 463.850482 -382.286002) (xy 463.850482 -382.205738) (xy 463.849896 -382.194172) (xy 463.839713 -382.1734)
			(xy 463.830924 -382.16586) (xy 463.808426 -382.147685) (xy 463.768691 -382.105663) (xy 463.735753 -382.058125)
			(xy 463.710367 -382.00616) (xy 463.693114 -381.950959) (xy 463.68439 -381.893787) (xy 463.683858 -381.86487)
			(xy 463.684344 -381.837619) (xy 463.6921 -381.783671) (xy 463.707455 -381.731376) (xy 463.730097 -381.681799)
			(xy 463.759563 -381.635949) (xy 463.795254 -381.594758) (xy 463.836445 -381.559067) (xy 463.882295 -381.529601)
			(xy 463.931872 -381.506959) (xy 463.984167 -381.491604) (xy 464.038115 -381.483848) (xy 464.092617 -381.483848)
			(xy 464.146565 -381.491604) (xy 464.19886 -381.506959) (xy 464.248437 -381.529601) (xy 464.294287 -381.559067)
			(xy 464.335478 -381.594758) (xy 464.371169 -381.635949) (xy 464.400635 -381.681799) (xy 464.423277 -381.731376)
			(xy 464.438632 -381.783671) (xy 464.446388 -381.837619) (xy 464.446874 -381.86487) (xy 464.446344 -381.893787)
			(xy 464.437619 -381.950958) (xy 464.420364 -382.006157) (xy 464.394974 -382.058119) (xy 464.362032 -382.105653)
			(xy 464.322293 -382.14767) (xy 464.299808 -382.16586) (xy 464.29107 -382.173445) (xy 464.280873 -382.194186)
			(xy 464.28025 -382.205738) (xy 464.28025 -382.286002) (xy 464.280802 -382.297573) (xy 464.291008 -382.318345)
			(xy 464.299808 -382.32588) (xy 464.320563 -382.342668) (xy 464.357696 -382.381016) (xy 464.38912 -382.424166)
			(xy 464.414222 -382.471275) (xy 464.432511 -382.521424) (xy 464.443631 -382.573632) (xy 464.447363 -382.626882)
			(xy 464.443636 -382.680131) (xy 464.432521 -382.732341) (xy 464.414237 -382.782491) (xy 464.389139 -382.829603)
			(xy 464.357719 -382.872756) (xy 464.32059 -382.911107) (xy 464.299808 -382.92786) (xy 464.29107 -382.935445)
			(xy 464.280873 -382.956186) (xy 464.28025 -382.967738) (xy 464.28025 -383.048002) (xy 464.280802 -383.059573)
			(xy 464.291008 -383.080345) (xy 464.299808 -383.08788) (xy 464.320563 -383.104668) (xy 464.357696 -383.143016)
			(xy 464.38912 -383.186166) (xy 464.414222 -383.233275) (xy 464.432511 -383.283424) (xy 464.443631 -383.335632)
			(xy 464.447363 -383.388882) (xy 464.443636 -383.442131) (xy 464.432521 -383.494341) (xy 464.414237 -383.544491)
			(xy 464.389139 -383.591603) (xy 464.357719 -383.634756) (xy 464.32059 -383.673107) (xy 464.299808 -383.68986)
			(xy 464.29107 -383.697445) (xy 464.280873 -383.718186) (xy 464.28025 -383.729738) (xy 464.28025 -383.810002)
			(xy 464.280802 -383.821573) (xy 464.291008 -383.842345) (xy 464.299808 -383.84988) (xy 464.322284 -383.86808)
			(xy 464.362019 -383.910098) (xy 464.394959 -383.957631) (xy 464.420348 -384.009591) (xy 464.437606 -384.064787)
			(xy 464.446338 -384.121955) (xy 464.446874 -384.15087) (xy 464.446388 -384.178121) (xy 464.438632 -384.232069)
			(xy 464.423277 -384.284364) (xy 464.400635 -384.333941) (xy 464.371169 -384.379791) (xy 464.335478 -384.420982)
			(xy 464.294287 -384.456673) (xy 464.248437 -384.486139) (xy 464.19886 -384.508781) (xy 464.146565 -384.524136)
			(xy 464.092617 -384.531892) (xy 464.038115 -384.531892) (xy 463.984167 -384.524136) (xy 463.931872 -384.508781)
			(xy 463.882295 -384.486139) (xy 463.836445 -384.456673) (xy 463.795254 -384.420982) (xy 463.759563 -384.379791)
			(xy 463.730097 -384.333941) (xy 463.707455 -384.284364) (xy 463.6921 -384.232069) (xy 463.684344 -384.178121)
			(xy 463.683858 -384.15087) (xy 463.684405 -384.121954) (xy 463.693125 -384.064783) (xy 463.710376 -384.009584)
			(xy 463.735762 -383.957622) (xy 463.768702 -383.910087) (xy 463.80844 -383.86807) (xy 463.830924 -383.84988)
			(xy 463.839695 -383.842327) (xy 463.849872 -383.821561) (xy 463.850482 -383.810002) (xy 463.850482 -383.729738)
			(xy 463.849896 -383.718172) (xy 463.839713 -383.6974) (xy 463.830924 -383.68986) (xy 463.810113 -383.673141)
			(xy 463.772985 -383.634782) (xy 463.741567 -383.591623) (xy 463.716471 -383.544505) (xy 463.698188 -383.49435)
			(xy 463.687074 -383.442135) (xy 463.683347 -383.388882) (xy 460.637363 -383.388882) (xy 460.633636 -383.442131)
			(xy 460.622521 -383.494341) (xy 460.604237 -383.544491) (xy 460.579139 -383.591603) (xy 460.547719 -383.634756)
			(xy 460.51059 -383.673107) (xy 460.489808 -383.68986) (xy 460.48107 -383.697445) (xy 460.470873 -383.718186)
			(xy 460.47025 -383.729738) (xy 460.47025 -383.810002) (xy 460.470802 -383.821573) (xy 460.481008 -383.842345)
			(xy 460.489808 -383.84988) (xy 460.512284 -383.86808) (xy 460.552019 -383.910098) (xy 460.584959 -383.957631)
			(xy 460.610348 -384.009591) (xy 460.627606 -384.064787) (xy 460.636338 -384.121955) (xy 460.636874 -384.15087)
			(xy 460.636388 -384.178121) (xy 460.628632 -384.232069) (xy 460.613277 -384.284364) (xy 460.590635 -384.333941)
			(xy 460.561169 -384.379791) (xy 460.525478 -384.420982) (xy 460.484287 -384.456673) (xy 460.438437 -384.486139)
			(xy 460.38886 -384.508781) (xy 460.336565 -384.524136) (xy 460.282617 -384.531892) (xy 460.228115 -384.531892)
			(xy 460.174167 -384.524136) (xy 460.121872 -384.508781) (xy 460.072295 -384.486139) (xy 460.026445 -384.456673)
			(xy 459.985254 -384.420982) (xy 459.949563 -384.379791) (xy 459.920097 -384.333941) (xy 459.897455 -384.284364)
			(xy 459.8821 -384.232069) (xy 459.874344 -384.178121) (xy 459.873858 -384.15087) (xy 459.874405 -384.121954)
			(xy 459.883125 -384.064783) (xy 459.900376 -384.009584) (xy 459.925762 -383.957622) (xy 459.958702 -383.910087)
			(xy 459.99844 -383.86807) (xy 460.020924 -383.84988) (xy 460.029695 -383.842327) (xy 460.039872 -383.821561)
			(xy 460.040482 -383.810002) (xy 460.040482 -383.729738) (xy 460.039896 -383.718172) (xy 460.029713 -383.6974)
			(xy 460.020924 -383.68986) (xy 460.000113 -383.673141) (xy 459.962985 -383.634782) (xy 459.931567 -383.591623)
			(xy 459.906471 -383.544505) (xy 459.888188 -383.49435) (xy 459.877074 -383.442135) (xy 459.873347 -383.388882)
			(xy 458.351363 -383.388882) (xy 458.347636 -383.442131) (xy 458.336521 -383.494341) (xy 458.318237 -383.544491)
			(xy 458.293139 -383.591603) (xy 458.261719 -383.634756) (xy 458.22459 -383.673107) (xy 458.203808 -383.68986)
			(xy 458.19507 -383.697445) (xy 458.184873 -383.718186) (xy 458.18425 -383.729738) (xy 458.18425 -383.810002)
			(xy 458.184802 -383.821573) (xy 458.195008 -383.842345) (xy 458.203808 -383.84988) (xy 458.226284 -383.86808)
			(xy 458.266019 -383.910098) (xy 458.298959 -383.957631) (xy 458.324348 -384.009591) (xy 458.341606 -384.064787)
			(xy 458.350338 -384.121955) (xy 458.350874 -384.15087) (xy 458.350388 -384.178121) (xy 458.342632 -384.232069)
			(xy 458.327277 -384.284364) (xy 458.304635 -384.333941) (xy 458.275169 -384.379791) (xy 458.239478 -384.420982)
			(xy 458.198287 -384.456673) (xy 458.152437 -384.486139) (xy 458.10286 -384.508781) (xy 458.050565 -384.524136)
			(xy 457.996617 -384.531892) (xy 457.942115 -384.531892) (xy 457.888167 -384.524136) (xy 457.835872 -384.508781)
			(xy 457.786295 -384.486139) (xy 457.740445 -384.456673) (xy 457.699254 -384.420982) (xy 457.663563 -384.379791)
			(xy 457.634097 -384.333941) (xy 457.611455 -384.284364) (xy 457.5961 -384.232069) (xy 457.588344 -384.178121)
			(xy 457.587858 -384.15087) (xy 457.588405 -384.121954) (xy 457.597125 -384.064783) (xy 457.614376 -384.009584)
			(xy 457.639762 -383.957622) (xy 457.672702 -383.910087) (xy 457.71244 -383.86807) (xy 457.734924 -383.84988)
			(xy 457.743695 -383.842327) (xy 457.753872 -383.821561) (xy 457.754482 -383.810002) (xy 457.754482 -383.729738)
			(xy 457.753896 -383.718172) (xy 457.743713 -383.6974) (xy 457.734924 -383.68986) (xy 457.714113 -383.673141)
			(xy 457.676985 -383.634782) (xy 457.645567 -383.591623) (xy 457.620471 -383.544505) (xy 457.602188 -383.49435)
			(xy 457.591074 -383.442135) (xy 457.587347 -383.388882) (xy 454.541363 -383.388882) (xy 454.537636 -383.442131)
			(xy 454.526521 -383.494341) (xy 454.508237 -383.544491) (xy 454.483139 -383.591603) (xy 454.451719 -383.634756)
			(xy 454.41459 -383.673107) (xy 454.393808 -383.68986) (xy 454.38507 -383.697445) (xy 454.374873 -383.718186)
			(xy 454.37425 -383.729738) (xy 454.37425 -383.810002) (xy 454.374802 -383.821573) (xy 454.385008 -383.842345)
			(xy 454.393808 -383.84988) (xy 454.416284 -383.86808) (xy 454.456019 -383.910098) (xy 454.488959 -383.957631)
			(xy 454.514348 -384.009591) (xy 454.531606 -384.064787) (xy 454.540338 -384.121955) (xy 454.540874 -384.15087)
			(xy 454.540388 -384.178121) (xy 454.532632 -384.232069) (xy 454.517277 -384.284364) (xy 454.494635 -384.333941)
			(xy 454.465169 -384.379791) (xy 454.429478 -384.420982) (xy 454.388287 -384.456673) (xy 454.342437 -384.486139)
			(xy 454.29286 -384.508781) (xy 454.240565 -384.524136) (xy 454.186617 -384.531892) (xy 454.132115 -384.531892)
			(xy 454.078167 -384.524136) (xy 454.025872 -384.508781) (xy 453.976295 -384.486139) (xy 453.930445 -384.456673)
			(xy 453.889254 -384.420982) (xy 453.853563 -384.379791) (xy 453.824097 -384.333941) (xy 453.801455 -384.284364)
			(xy 453.7861 -384.232069) (xy 453.778344 -384.178121) (xy 453.777858 -384.15087) (xy 453.778405 -384.121954)
			(xy 453.787125 -384.064783) (xy 453.804376 -384.009584) (xy 453.829762 -383.957622) (xy 453.862702 -383.910087)
			(xy 453.90244 -383.86807) (xy 453.924924 -383.84988) (xy 453.933695 -383.842327) (xy 453.943872 -383.821561)
			(xy 453.944482 -383.810002) (xy 453.944482 -383.729738) (xy 453.943896 -383.718172) (xy 453.933713 -383.6974)
			(xy 453.924924 -383.68986) (xy 453.904113 -383.673141) (xy 453.866985 -383.634782) (xy 453.835567 -383.591623)
			(xy 453.810471 -383.544505) (xy 453.792188 -383.49435) (xy 453.781074 -383.442135) (xy 453.777347 -383.388882)
			(xy 452.255363 -383.388882) (xy 452.251636 -383.442131) (xy 452.240521 -383.494341) (xy 452.222237 -383.544491)
			(xy 452.197139 -383.591603) (xy 452.165719 -383.634756) (xy 452.12859 -383.673107) (xy 452.107808 -383.68986)
			(xy 452.09907 -383.697445) (xy 452.088873 -383.718186) (xy 452.08825 -383.729738) (xy 452.08825 -383.810002)
			(xy 452.088802 -383.821573) (xy 452.099008 -383.842345) (xy 452.107808 -383.84988) (xy 452.130284 -383.86808)
			(xy 452.170019 -383.910098) (xy 452.202959 -383.957631) (xy 452.228348 -384.009591) (xy 452.245606 -384.064787)
			(xy 452.254338 -384.121955) (xy 452.254874 -384.15087) (xy 452.254388 -384.178121) (xy 452.246632 -384.232069)
			(xy 452.231277 -384.284364) (xy 452.208635 -384.333941) (xy 452.179169 -384.379791) (xy 452.143478 -384.420982)
			(xy 452.102287 -384.456673) (xy 452.056437 -384.486139) (xy 452.00686 -384.508781) (xy 451.954565 -384.524136)
			(xy 451.900617 -384.531892) (xy 451.846115 -384.531892) (xy 451.792167 -384.524136) (xy 451.739872 -384.508781)
			(xy 451.690295 -384.486139) (xy 451.644445 -384.456673) (xy 451.603254 -384.420982) (xy 451.567563 -384.379791)
			(xy 451.538097 -384.333941) (xy 451.515455 -384.284364) (xy 451.5001 -384.232069) (xy 451.492344 -384.178121)
			(xy 451.491858 -384.15087) (xy 451.492405 -384.121954) (xy 451.501125 -384.064783) (xy 451.518376 -384.009584)
			(xy 451.543762 -383.957622) (xy 451.576702 -383.910087) (xy 451.61644 -383.86807) (xy 451.638924 -383.84988)
			(xy 451.647695 -383.842327) (xy 451.657872 -383.821561) (xy 451.658482 -383.810002) (xy 451.658482 -383.729738)
			(xy 451.657896 -383.718172) (xy 451.647713 -383.6974) (xy 451.638924 -383.68986) (xy 451.618113 -383.673141)
			(xy 451.580985 -383.634782) (xy 451.549567 -383.591623) (xy 451.524471 -383.544505) (xy 451.506188 -383.49435)
			(xy 451.495074 -383.442135) (xy 451.491347 -383.388882) (xy 448.445363 -383.388882) (xy 448.441636 -383.442131)
			(xy 448.430521 -383.494341) (xy 448.412237 -383.544491) (xy 448.387139 -383.591603) (xy 448.355719 -383.634756)
			(xy 448.31859 -383.673107) (xy 448.297808 -383.68986) (xy 448.28907 -383.697445) (xy 448.278873 -383.718186)
			(xy 448.27825 -383.729738) (xy 448.27825 -383.810002) (xy 448.278802 -383.821573) (xy 448.289008 -383.842345)
			(xy 448.297808 -383.84988) (xy 448.320284 -383.86808) (xy 448.360019 -383.910098) (xy 448.392959 -383.957631)
			(xy 448.418348 -384.009591) (xy 448.435606 -384.064787) (xy 448.444338 -384.121955) (xy 448.444874 -384.15087)
			(xy 448.444388 -384.178121) (xy 448.436632 -384.232069) (xy 448.421277 -384.284364) (xy 448.398635 -384.333941)
			(xy 448.369169 -384.379791) (xy 448.333478 -384.420982) (xy 448.292287 -384.456673) (xy 448.246437 -384.486139)
			(xy 448.19686 -384.508781) (xy 448.144565 -384.524136) (xy 448.090617 -384.531892) (xy 448.036115 -384.531892)
			(xy 447.982167 -384.524136) (xy 447.929872 -384.508781) (xy 447.880295 -384.486139) (xy 447.834445 -384.456673)
			(xy 447.793254 -384.420982) (xy 447.757563 -384.379791) (xy 447.728097 -384.333941) (xy 447.705455 -384.284364)
			(xy 447.6901 -384.232069) (xy 447.682344 -384.178121) (xy 447.681858 -384.15087) (xy 447.682405 -384.121954)
			(xy 447.691125 -384.064783) (xy 447.708376 -384.009584) (xy 447.733762 -383.957622) (xy 447.766702 -383.910087)
			(xy 447.80644 -383.86807) (xy 447.828924 -383.84988) (xy 447.837695 -383.842327) (xy 447.847872 -383.821561)
			(xy 447.848482 -383.810002) (xy 447.848482 -383.729738) (xy 447.847896 -383.718172) (xy 447.837713 -383.6974)
			(xy 447.828924 -383.68986) (xy 447.808113 -383.673141) (xy 447.770985 -383.634782) (xy 447.739567 -383.591623)
			(xy 447.714471 -383.544505) (xy 447.696188 -383.49435) (xy 447.685074 -383.442135) (xy 447.681347 -383.388882)
			(xy 446.489563 -383.388882) (xy 446.485836 -383.442131) (xy 446.474721 -383.494341) (xy 446.456437 -383.544491)
			(xy 446.431339 -383.591603) (xy 446.399919 -383.634756) (xy 446.36279 -383.673107) (xy 446.342008 -383.68986)
			(xy 446.33327 -383.697445) (xy 446.323073 -383.718186) (xy 446.32245 -383.729738) (xy 446.32245 -383.810002)
			(xy 446.323002 -383.821573) (xy 446.333208 -383.842345) (xy 446.342008 -383.84988) (xy 446.364484 -383.86808)
			(xy 446.404219 -383.910098) (xy 446.437159 -383.957631) (xy 446.462548 -384.009591) (xy 446.479806 -384.064787)
			(xy 446.488538 -384.121955) (xy 446.489074 -384.15087) (xy 446.488588 -384.178121) (xy 446.480832 -384.232069)
			(xy 446.465477 -384.284364) (xy 446.442835 -384.333941) (xy 446.413369 -384.379791) (xy 446.377678 -384.420982)
			(xy 446.336487 -384.456673) (xy 446.290637 -384.486139) (xy 446.24106 -384.508781) (xy 446.188765 -384.524136)
			(xy 446.134817 -384.531892) (xy 446.080315 -384.531892) (xy 446.026367 -384.524136) (xy 445.974072 -384.508781)
			(xy 445.924495 -384.486139) (xy 445.878645 -384.456673) (xy 445.837454 -384.420982) (xy 445.801763 -384.379791)
			(xy 445.772297 -384.333941) (xy 445.749655 -384.284364) (xy 445.7343 -384.232069) (xy 445.726544 -384.178121)
			(xy 445.726058 -384.15087) (xy 445.726605 -384.121954) (xy 445.735325 -384.064783) (xy 445.752576 -384.009584)
			(xy 445.777962 -383.957622) (xy 445.810902 -383.910087) (xy 445.85064 -383.86807) (xy 445.873124 -383.84988)
			(xy 445.881895 -383.842327) (xy 445.892072 -383.821561) (xy 445.892682 -383.810002) (xy 445.892682 -383.729738)
			(xy 445.892096 -383.718172) (xy 445.881913 -383.6974) (xy 445.873124 -383.68986) (xy 445.852313 -383.673141)
			(xy 445.815185 -383.634782) (xy 445.783767 -383.591623) (xy 445.758671 -383.544505) (xy 445.740388 -383.49435)
			(xy 445.729274 -383.442135) (xy 445.725547 -383.388882) (xy 442.679563 -383.388882) (xy 442.675836 -383.442131)
			(xy 442.664721 -383.494341) (xy 442.646437 -383.544491) (xy 442.621339 -383.591603) (xy 442.589919 -383.634756)
			(xy 442.55279 -383.673107) (xy 442.532008 -383.68986) (xy 442.52327 -383.697445) (xy 442.513073 -383.718186)
			(xy 442.51245 -383.729738) (xy 442.51245 -383.810002) (xy 442.513002 -383.821573) (xy 442.523208 -383.842345)
			(xy 442.532008 -383.84988) (xy 442.554484 -383.86808) (xy 442.594219 -383.910098) (xy 442.627159 -383.957631)
			(xy 442.652548 -384.009591) (xy 442.669806 -384.064787) (xy 442.678538 -384.121955) (xy 442.679074 -384.15087)
			(xy 442.678588 -384.178121) (xy 442.670832 -384.232069) (xy 442.655477 -384.284364) (xy 442.632835 -384.333941)
			(xy 442.603369 -384.379791) (xy 442.567678 -384.420982) (xy 442.526487 -384.456673) (xy 442.480637 -384.486139)
			(xy 442.43106 -384.508781) (xy 442.378765 -384.524136) (xy 442.324817 -384.531892) (xy 442.270315 -384.531892)
			(xy 442.216367 -384.524136) (xy 442.164072 -384.508781) (xy 442.114495 -384.486139) (xy 442.068645 -384.456673)
			(xy 442.027454 -384.420982) (xy 441.991763 -384.379791) (xy 441.962297 -384.333941) (xy 441.939655 -384.284364)
			(xy 441.9243 -384.232069) (xy 441.916544 -384.178121) (xy 441.916058 -384.15087) (xy 441.916605 -384.121954)
			(xy 441.925325 -384.064783) (xy 441.942576 -384.009584) (xy 441.967962 -383.957622) (xy 442.000902 -383.910087)
			(xy 442.04064 -383.86807) (xy 442.063124 -383.84988) (xy 442.071895 -383.842327) (xy 442.082072 -383.821561)
			(xy 442.082682 -383.810002) (xy 442.082682 -383.729738) (xy 442.082096 -383.718172) (xy 442.071913 -383.6974)
			(xy 442.063124 -383.68986) (xy 442.042313 -383.673141) (xy 442.005185 -383.634782) (xy 441.973767 -383.591623)
			(xy 441.948671 -383.544505) (xy 441.930388 -383.49435) (xy 441.919274 -383.442135) (xy 441.915547 -383.388882)
			(xy 440.922664 -383.388882) (xy 440.922664 -385.039108) (xy 447.973196 -385.039108) (xy 447.973663 -385.011855)
			(xy 447.981419 -384.957904) (xy 447.996774 -384.905606) (xy 448.019416 -384.856026) (xy 448.048883 -384.810172)
			(xy 448.084577 -384.76898) (xy 448.125769 -384.733286) (xy 448.171622 -384.703818) (xy 448.221202 -384.681175)
			(xy 448.2735 -384.66582) (xy 448.327451 -384.658063) (xy 448.354704 -384.6576) (xy 448.383621 -384.658116)
			(xy 448.440792 -384.666845) (xy 448.495991 -384.684104) (xy 448.547953 -384.709496) (xy 448.595487 -384.74244)
			(xy 448.637504 -384.782181) (xy 448.655694 -384.804666) (xy 448.663251 -384.813432) (xy 448.684014 -384.82361)
			(xy 448.695572 -384.824224) (xy 448.775836 -384.824224) (xy 448.787403 -384.823643) (xy 448.808176 -384.813459)
			(xy 448.815714 -384.804666) (xy 448.833889 -384.782169) (xy 448.875913 -384.742436) (xy 448.923451 -384.7095)
			(xy 448.975416 -384.684114) (xy 449.030616 -384.66686) (xy 449.087787 -384.658134) (xy 449.116704 -384.6576)
			(xy 449.145443 -384.658121) (xy 449.20227 -384.666744) (xy 449.257161 -384.683795) (xy 449.308873 -384.708887)
			(xy 449.356235 -384.741453) (xy 449.377562 -384.760724) (xy 449.384674 -384.767328) (xy 449.4022 -384.77444)
			(xy 449.491608 -384.77444) (xy 449.509134 -384.767328) (xy 449.516246 -384.760724) (xy 449.537569 -384.741449)
			(xy 449.584933 -384.708884) (xy 449.636645 -384.683792) (xy 449.691537 -384.666743) (xy 449.748365 -384.658121)
			(xy 449.777104 -384.6576) (xy 449.804357 -384.658052) (xy 449.858309 -384.665809) (xy 449.910608 -384.681166)
			(xy 449.960188 -384.70381) (xy 450.006042 -384.733279) (xy 450.047235 -384.768974) (xy 450.082928 -384.810168)
			(xy 450.112396 -384.856022) (xy 450.135038 -384.905604) (xy 450.150393 -384.957903) (xy 450.158149 -385.011855)
			(xy 450.158612 -385.039108) (xy 450.158178 -385.06581) (xy 450.150724 -385.11869) (xy 450.135962 -385.170013)
			(xy 450.114183 -385.218773) (xy 450.085811 -385.264017) (xy 450.06895 -385.284726) (xy 450.062854 -385.292092)
			(xy 450.056758 -385.310126) (xy 450.060568 -385.397756) (xy 450.068188 -385.415282) (xy 450.074792 -385.421886)
			(xy 450.095606 -385.443472) (xy 450.130859 -385.491977) (xy 450.158087 -385.545401) (xy 450.176618 -385.602428)
			(xy 450.185997 -385.661653) (xy 450.186552 -385.691634) (xy 450.186008 -385.720693) (xy 450.177172 -385.778134)
			(xy 450.159725 -385.833571) (xy 450.134071 -385.88572) (xy 450.100803 -385.933374) (xy 450.081142 -385.954778)
			(xy 450.074538 -385.96189) (xy 450.067172 -385.979924) (xy 450.067172 -386.06984) (xy 450.074538 -386.087874)
			(xy 450.081142 -386.094986) (xy 450.100804 -386.116391) (xy 450.134085 -386.164037) (xy 450.159743 -386.216185)
			(xy 450.177186 -386.271625) (xy 450.186007 -386.329071) (xy 450.186552 -386.35813) (xy 450.186034 -386.386232)
			(xy 450.18508 -386.392674) (xy 450.3547 -386.392674) (xy 450.355208 -386.363935) (xy 450.363834 -386.307106)
			(xy 450.380888 -386.252216) (xy 450.405983 -386.200504) (xy 450.438552 -386.153142) (xy 450.457824 -386.131816)
			(xy 450.464428 -386.124704) (xy 450.47154 -386.107178) (xy 450.47154 -386.01777) (xy 450.464428 -386.000244)
			(xy 450.457824 -385.993132) (xy 450.438527 -385.971828) (xy 450.405963 -385.924461) (xy 450.380873 -385.872746)
			(xy 450.363825 -385.817852) (xy 450.355205 -385.761021) (xy 450.355207 -385.703541) (xy 450.363833 -385.646711)
			(xy 450.380887 -385.591819) (xy 450.405982 -385.540106) (xy 450.438551 -385.492743) (xy 450.457824 -385.471416)
			(xy 450.464428 -385.464304) (xy 450.47154 -385.446778) (xy 450.47154 -385.35737) (xy 450.464428 -385.339844)
			(xy 450.457824 -385.332732) (xy 450.438539 -385.311418) (xy 450.405975 -385.264052) (xy 450.380885 -385.212337)
			(xy 450.363838 -385.157444) (xy 450.355219 -385.100614) (xy 450.3547 -385.071874) (xy 450.355154 -385.044622)
			(xy 450.362914 -384.990672) (xy 450.378273 -384.938377) (xy 450.400917 -384.888799) (xy 450.430387 -384.842948)
			(xy 450.466082 -384.801758) (xy 450.507275 -384.766067) (xy 450.553129 -384.736601) (xy 450.602709 -384.713961)
			(xy 450.655006 -384.698607) (xy 450.708956 -384.690851) (xy 450.736208 -384.690366) (xy 450.764947 -384.690894)
			(xy 450.821773 -384.699517) (xy 450.876664 -384.716566) (xy 450.928376 -384.741657) (xy 450.975739 -384.77422)
			(xy 450.997066 -384.79349) (xy 451.004178 -384.800094) (xy 451.021704 -384.807206) (xy 451.111112 -384.807206)
			(xy 451.128638 -384.800094) (xy 451.13575 -384.79349) (xy 451.157082 -384.774224) (xy 451.204442 -384.741656)
			(xy 451.256152 -384.716561) (xy 451.311042 -384.69951) (xy 451.367869 -384.690887) (xy 451.396608 -384.690366)
			(xy 451.42367 -384.690813) (xy 451.477248 -384.69848) (xy 451.529203 -384.713646) (xy 451.578493 -384.736004)
			(xy 451.624126 -384.765107) (xy 451.665187 -384.800369) (xy 451.683374 -384.820414) (xy 451.690944 -384.828277)
			(xy 451.710823 -384.83723) (xy 451.721728 -384.837686) (xy 451.797928 -384.837686) (xy 451.808828 -384.83722)
			(xy 451.828698 -384.828258) (xy 451.836282 -384.820414) (xy 451.854456 -384.800357) (xy 451.895516 -384.765093)
			(xy 451.941151 -384.735992) (xy 451.990445 -384.71364) (xy 452.042405 -384.698487) (xy 452.095986 -384.690836)
			(xy 452.123048 -384.690366) (xy 452.150299 -384.690833) (xy 452.204246 -384.698595) (xy 452.25654 -384.713955)
			(xy 452.306115 -384.7366) (xy 452.351964 -384.766069) (xy 452.393153 -384.801762) (xy 452.428844 -384.842953)
			(xy 452.45831 -384.888804) (xy 452.480952 -384.938381) (xy 452.496309 -384.990675) (xy 452.504068 -385.044623)
			(xy 452.504556 -385.071874) (xy 452.504001 -385.100612) (xy 452.495384 -385.157437) (xy 452.47834 -385.212327)
			(xy 452.453256 -385.264039) (xy 452.420699 -385.311403) (xy 452.401432 -385.332732) (xy 452.394828 -385.339844)
			(xy 452.387716 -385.35737) (xy 452.387716 -385.446778) (xy 452.394828 -385.464304) (xy 452.401432 -385.471416)
			(xy 452.420675 -385.492766) (xy 452.453236 -385.540126) (xy 452.478325 -385.591835) (xy 452.495374 -385.646721)
			(xy 452.503998 -385.703544) (xy 452.504001 -385.761018) (xy 452.495383 -385.817842) (xy 452.478339 -385.87273)
			(xy 452.453255 -385.924441) (xy 452.420698 -385.971804) (xy 452.401432 -385.993132) (xy 452.394828 -386.000244)
			(xy 452.387716 -386.01777) (xy 452.387716 -386.107178) (xy 452.394828 -386.124704) (xy 452.401432 -386.131816)
			(xy 452.420675 -386.153166) (xy 452.453236 -386.200526) (xy 452.478325 -386.252235) (xy 452.495374 -386.307121)
			(xy 452.503998 -386.363944) (xy 452.504001 -386.421418) (xy 452.495383 -386.478242) (xy 452.478339 -386.53313)
			(xy 452.453255 -386.584841) (xy 452.420698 -386.632204) (xy 452.401432 -386.653532) (xy 452.394574 -386.660898)
			(xy 452.387716 -386.678678) (xy 452.388478 -386.768848) (xy 452.395844 -386.786882) (xy 452.402956 -386.793994)
			(xy 452.423192 -386.815485) (xy 452.457414 -386.86358) (xy 452.48382 -386.916372) (xy 452.50178 -386.972601)
			(xy 452.510866 -387.030926) (xy 452.511414 -387.06044) (xy 452.510909 -387.087809) (xy 452.5031 -387.141986)
			(xy 452.48762 -387.194489) (xy 452.464787 -387.244236) (xy 452.435071 -387.290205) (xy 452.417434 -387.311138)
			(xy 452.411338 -387.31825) (xy 452.404988 -387.335268) (xy 452.404988 -387.420612) (xy 452.411338 -387.43763)
			(xy 452.417434 -387.444742) (xy 452.435065 -387.465681) (xy 452.464777 -387.511652) (xy 452.487614 -387.561398)
			(xy 452.503107 -387.613897) (xy 452.503953 -387.619748) (xy 455.361802 -387.619748) (xy 455.362294 -387.591008)
			(xy 455.370924 -387.534179) (xy 455.387981 -387.479288) (xy 455.41308 -387.427577) (xy 455.445652 -387.380216)
			(xy 455.464926 -387.35889) (xy 455.47153 -387.351778) (xy 455.478642 -387.334252) (xy 455.478642 -387.244844)
			(xy 455.47153 -387.227318) (xy 455.464926 -387.220206) (xy 455.445703 -387.198838) (xy 455.413136 -387.151483)
			(xy 455.388041 -387.099778) (xy 455.370988 -387.044893) (xy 455.362361 -386.988071) (xy 455.362355 -386.930599)
			(xy 455.370972 -386.873775) (xy 455.388016 -386.818888) (xy 455.4131 -386.767178) (xy 455.445659 -386.719817)
			(xy 455.464926 -386.69849) (xy 455.47153 -386.691378) (xy 455.478642 -386.673852) (xy 455.478642 -386.584444)
			(xy 455.47153 -386.566918) (xy 455.464926 -386.559806) (xy 455.445703 -386.538438) (xy 455.413136 -386.491083)
			(xy 455.388041 -386.439378) (xy 455.370988 -386.384493) (xy 455.362361 -386.327671) (xy 455.362355 -386.270199)
			(xy 455.370972 -386.213375) (xy 455.388016 -386.158488) (xy 455.4131 -386.106778) (xy 455.445659 -386.059417)
			(xy 455.464926 -386.03809) (xy 455.47153 -386.030978) (xy 455.478642 -386.013452) (xy 455.478642 -385.924044)
			(xy 455.47153 -385.906518) (xy 455.464926 -385.899406) (xy 455.445629 -385.878102) (xy 455.413066 -385.830734)
			(xy 455.387979 -385.779016) (xy 455.370935 -385.72412) (xy 455.362319 -385.667289) (xy 455.361802 -385.638548)
			(xy 455.3623 -385.611296) (xy 455.370051 -385.557346) (xy 455.385401 -385.505048) (xy 455.408039 -385.455467)
			(xy 455.437503 -385.409613) (xy 455.473193 -385.36842) (xy 455.514383 -385.332725) (xy 455.560234 -385.303257)
			(xy 455.609812 -385.280614) (xy 455.662108 -385.265259) (xy 455.716058 -385.257503) (xy 455.74331 -385.25704)
			(xy 455.769625 -385.257509) (xy 455.821757 -385.264732) (xy 455.8724 -385.279054) (xy 455.920594 -385.300203)
			(xy 455.965422 -385.327778) (xy 456.006034 -385.361253) (xy 456.041657 -385.399994) (xy 456.057 -385.421378)
			(xy 456.064112 -385.431538) (xy 456.085448 -385.442968) (xy 456.193144 -385.444492) (xy 456.214988 -385.43357)
			(xy 456.222354 -385.423664) (xy 456.240463 -385.399945) (xy 456.2828 -385.357892) (xy 456.33117 -385.322946)
			(xy 456.384392 -385.295959) (xy 456.441168 -385.277591) (xy 456.500112 -385.26829) (xy 456.529948 -385.267708)
			(xy 456.557716 -385.26821) (xy 456.612668 -385.276252) (xy 456.665873 -385.292172) (xy 456.71621 -385.315634)
			(xy 456.762615 -385.346145) (xy 456.783694 -385.364228) (xy 456.790552 -385.370324) (xy 456.807824 -385.377182)
			(xy 456.89393 -385.377436) (xy 456.911202 -385.370832) (xy 456.918314 -385.364736) (xy 456.939286 -385.346929)
			(xy 456.985399 -385.316922) (xy 457.035341 -385.293845) (xy 457.088079 -385.278176) (xy 457.14252 -385.27024)
			(xy 457.170028 -385.26974) (xy 457.197284 -385.270129) (xy 457.25124 -385.277891) (xy 457.303542 -385.293253)
			(xy 457.353126 -385.315902) (xy 457.398981 -385.345378) (xy 457.440175 -385.381079) (xy 457.475868 -385.42228)
			(xy 457.505334 -385.468141) (xy 457.527974 -385.517729) (xy 457.543325 -385.570034) (xy 457.551076 -385.623992)
			(xy 457.551536 -385.651248) (xy 457.551032 -385.679988) (xy 457.542403 -385.736815) (xy 457.525348 -385.791706)
			(xy 457.500252 -385.843417) (xy 457.467684 -385.890779) (xy 457.448412 -385.912106) (xy 457.441808 -385.919218)
			(xy 457.434696 -385.936744) (xy 457.434696 -386.026152) (xy 457.441808 -386.043678) (xy 457.448412 -386.05079)
			(xy 457.467729 -386.072076) (xy 457.500289 -386.119447) (xy 457.525376 -386.171165) (xy 457.542421 -386.226062)
			(xy 457.551038 -386.282894) (xy 457.551033 -386.340376) (xy 457.542405 -386.397206) (xy 457.52535 -386.4521)
			(xy 457.500254 -386.503814) (xy 457.467685 -386.551178) (xy 457.448412 -386.572506) (xy 457.441808 -386.579618)
			(xy 457.434696 -386.597144) (xy 457.434696 -386.686552) (xy 457.441808 -386.704078) (xy 457.448412 -386.71119)
			(xy 457.467729 -386.732476) (xy 457.500289 -386.779847) (xy 457.525376 -386.831565) (xy 457.542421 -386.886462)
			(xy 457.551038 -386.943294) (xy 457.551033 -387.000776) (xy 457.542405 -387.057606) (xy 457.52535 -387.1125)
			(xy 457.500254 -387.164214) (xy 457.467685 -387.211578) (xy 457.448412 -387.232906) (xy 457.441808 -387.240018)
			(xy 457.434696 -387.257544) (xy 457.434696 -387.258347) (xy 458.670706 -387.258347) (xy 458.670706 -387.203853)
			(xy 458.678461 -387.149912) (xy 458.693813 -387.097625) (xy 458.716449 -387.048054) (xy 458.74591 -387.002209)
			(xy 458.781594 -386.961023) (xy 458.822777 -386.925334) (xy 458.868619 -386.895869) (xy 458.918187 -386.873227)
			(xy 458.970473 -386.857869) (xy 459.024413 -386.850109) (xy 459.05166 -386.84962) (xy 459.080399 -386.850129)
			(xy 459.137226 -386.858758) (xy 459.192116 -386.875813) (xy 459.243828 -386.900907) (xy 459.291191 -386.933473)
			(xy 459.312518 -386.952744) (xy 459.31963 -386.959348) (xy 459.337156 -386.96646) (xy 459.426564 -386.96646)
			(xy 459.44409 -386.959348) (xy 459.451202 -386.952744) (xy 459.472546 -386.933493) (xy 459.519904 -386.900924)
			(xy 459.571611 -386.875828) (xy 459.626498 -386.858772) (xy 459.683322 -386.850144) (xy 459.71206 -386.84962)
			(xy 459.739317 -386.850024) (xy 459.793276 -386.857777) (xy 459.845583 -386.873131) (xy 459.895171 -386.895773)
			(xy 459.941033 -386.925242) (xy 459.982234 -386.960938) (xy 460.017934 -387.002135) (xy 460.047408 -387.047993)
			(xy 460.070055 -387.09758) (xy 460.085414 -387.149885) (xy 460.093173 -387.203843) (xy 460.093173 -387.258357)
			(xy 460.087696 -387.296447) (xy 460.851306 -387.296447) (xy 460.851306 -387.241953) (xy 460.859061 -387.188014)
			(xy 460.874412 -387.135727) (xy 460.897048 -387.086157) (xy 460.926507 -387.040312) (xy 460.962191 -386.999126)
			(xy 461.003372 -386.963437) (xy 461.049213 -386.933972) (xy 461.09878 -386.91133) (xy 461.151065 -386.895971)
			(xy 461.205003 -386.88821) (xy 461.23225 -386.88772) (xy 461.260989 -386.888235) (xy 461.317816 -386.896863)
			(xy 461.372706 -386.913916) (xy 461.424417 -386.939009) (xy 461.47178 -386.971574) (xy 461.493108 -386.990844)
			(xy 461.50022 -386.997448) (xy 461.517746 -387.00456) (xy 461.607154 -387.00456) (xy 461.62468 -386.997448)
			(xy 461.631792 -386.990844) (xy 461.653099 -386.971551) (xy 461.700467 -386.938987) (xy 461.752183 -386.913899)
			(xy 461.807078 -386.896854) (xy 461.86391 -386.888237) (xy 461.89265 -386.88772) (xy 461.919907 -386.888124)
			(xy 461.973868 -386.895875) (xy 462.026175 -386.911228) (xy 462.075765 -386.933869) (xy 462.121628 -386.963338)
			(xy 462.16283 -386.999035) (xy 462.198532 -387.040232) (xy 462.228007 -387.086091) (xy 462.250654 -387.135678)
			(xy 462.266014 -387.187983) (xy 462.273773 -387.241943) (xy 462.273773 -387.296457) (xy 462.266014 -387.350416)
			(xy 462.255395 -387.386576) (xy 462.824828 -387.386576) (xy 462.828899 -387.330954) (xy 462.841025 -387.276517)
			(xy 462.860948 -387.224426) (xy 462.888244 -387.175791) (xy 462.92233 -387.131648) (xy 462.962479 -387.092939)
			(xy 463.007837 -387.060488) (xy 463.057437 -387.034987) (xy 463.110221 -387.01698) (xy 463.165064 -387.00685)
			(xy 463.220798 -387.004813) (xy 463.276235 -387.010913) (xy 463.330192 -387.025019) (xy 463.381521 -387.046831)
			(xy 463.429127 -387.075885) (xy 463.471995 -387.11156) (xy 463.509212 -387.153097) (xy 463.539985 -387.19961)
			(xy 463.563657 -387.250107) (xy 463.579725 -387.303514) (xy 463.587845 -387.35869) (xy 463.588354 -387.386576)
			(xy 463.587845 -387.414462) (xy 463.579725 -387.469638) (xy 463.563657 -387.523045) (xy 463.539985 -387.573542)
			(xy 463.509212 -387.620055) (xy 463.471995 -387.661592) (xy 463.429127 -387.697267) (xy 463.381521 -387.726321)
			(xy 463.330192 -387.748133) (xy 463.276235 -387.762239) (xy 463.220798 -387.768339) (xy 463.165064 -387.766302)
			(xy 463.110221 -387.756172) (xy 463.057437 -387.738165) (xy 463.007837 -387.712664) (xy 462.962479 -387.680213)
			(xy 462.92233 -387.641504) (xy 462.888244 -387.597361) (xy 462.860948 -387.548726) (xy 462.841025 -387.496635)
			(xy 462.828899 -387.442198) (xy 462.824828 -387.386576) (xy 462.255395 -387.386576) (xy 462.250654 -387.402722)
			(xy 462.228007 -387.452309) (xy 462.198532 -387.498168) (xy 462.16283 -387.539365) (xy 462.121628 -387.575062)
			(xy 462.075765 -387.604531) (xy 462.026175 -387.627172) (xy 461.973868 -387.642525) (xy 461.919907 -387.650276)
			(xy 461.89265 -387.650736) (xy 461.86391 -387.650233) (xy 461.807083 -387.641604) (xy 461.752192 -387.624548)
			(xy 461.700481 -387.599453) (xy 461.653119 -387.566884) (xy 461.631792 -387.547612) (xy 461.62468 -387.541008)
			(xy 461.607154 -387.533896) (xy 461.517746 -387.533896) (xy 461.50022 -387.541008) (xy 461.493108 -387.547612)
			(xy 461.471794 -387.566898) (xy 461.424429 -387.599464) (xy 461.372715 -387.624555) (xy 461.317821 -387.641601)
			(xy 461.26099 -387.650219) (xy 461.23225 -387.650736) (xy 461.205003 -387.65019) (xy 461.151065 -387.642429)
			(xy 461.09878 -387.62707) (xy 461.049213 -387.604428) (xy 461.003372 -387.574963) (xy 460.962191 -387.539274)
			(xy 460.926507 -387.498088) (xy 460.897048 -387.452243) (xy 460.874412 -387.402673) (xy 460.859061 -387.350386)
			(xy 460.851306 -387.296447) (xy 460.087696 -387.296447) (xy 460.085414 -387.312315) (xy 460.070055 -387.36462)
			(xy 460.047408 -387.414207) (xy 460.017934 -387.460065) (xy 459.982234 -387.501262) (xy 459.941033 -387.536958)
			(xy 459.895171 -387.566427) (xy 459.845583 -387.589069) (xy 459.793276 -387.604423) (xy 459.739317 -387.612176)
			(xy 459.71206 -387.612636) (xy 459.683321 -387.612127) (xy 459.626493 -387.603499) (xy 459.571603 -387.586445)
			(xy 459.519891 -387.561351) (xy 459.472529 -387.528783) (xy 459.451202 -387.509512) (xy 459.44409 -387.502908)
			(xy 459.426564 -387.495796) (xy 459.337156 -387.495796) (xy 459.31963 -387.502908) (xy 459.312518 -387.509512)
			(xy 459.2912 -387.528793) (xy 459.243836 -387.56136) (xy 459.192123 -387.586451) (xy 459.137229 -387.603499)
			(xy 459.0804 -387.612118) (xy 459.05166 -387.612636) (xy 459.024413 -387.612091) (xy 458.970473 -387.604331)
			(xy 458.918187 -387.588973) (xy 458.868619 -387.566331) (xy 458.822777 -387.536866) (xy 458.781594 -387.501177)
			(xy 458.74591 -387.459991) (xy 458.716449 -387.414146) (xy 458.693813 -387.364575) (xy 458.678461 -387.312288)
			(xy 458.670706 -387.258347) (xy 457.434696 -387.258347) (xy 457.434696 -387.346952) (xy 457.441808 -387.364478)
			(xy 457.448412 -387.37159) (xy 457.467697 -387.392905) (xy 457.500263 -387.440269) (xy 457.525354 -387.491984)
			(xy 457.542401 -387.546878) (xy 457.551018 -387.603708) (xy 457.551536 -387.632448) (xy 457.551061 -387.659007)
			(xy 457.543703 -387.711613) (xy 457.529123 -387.762691) (xy 457.507601 -387.811254) (xy 457.479554 -387.856364)
			(xy 457.46289 -387.87705) (xy 457.45654 -387.884416) (xy 457.450698 -387.90245) (xy 457.454508 -387.989826)
			(xy 457.462128 -388.007098) (xy 457.468732 -388.013956) (xy 457.489405 -388.035575) (xy 457.524504 -388.084004)
			(xy 457.542741 -388.119874) (xy 457.846428 -388.119874) (xy 457.850499 -388.064252) (xy 457.862625 -388.009815)
			(xy 457.882548 -387.957724) (xy 457.909844 -387.909089) (xy 457.94393 -387.864946) (xy 457.984079 -387.826237)
			(xy 458.029437 -387.793786) (xy 458.079037 -387.768285) (xy 458.131821 -387.750278) (xy 458.186664 -387.740148)
			(xy 458.242398 -387.738111) (xy 458.297835 -387.744211) (xy 458.351792 -387.758317) (xy 458.403121 -387.780129)
			(xy 458.450727 -387.809183) (xy 458.493595 -387.844858) (xy 458.530812 -387.886395) (xy 458.561585 -387.932908)
			(xy 458.585257 -387.983405) (xy 458.601325 -388.036812) (xy 458.609445 -388.091988) (xy 458.609954 -388.119874)
			(xy 458.609445 -388.14776) (xy 458.601325 -388.202936) (xy 458.585257 -388.256343) (xy 458.561585 -388.30684)
			(xy 458.530812 -388.353353) (xy 458.493595 -388.39489) (xy 458.450727 -388.430565) (xy 458.403121 -388.459619)
			(xy 458.351792 -388.481431) (xy 458.297835 -388.495537) (xy 458.242398 -388.501637) (xy 458.186664 -388.4996)
			(xy 458.131821 -388.48947) (xy 458.079037 -388.471463) (xy 458.029437 -388.445962) (xy 457.984079 -388.413511)
			(xy 457.94393 -388.374802) (xy 457.909844 -388.330659) (xy 457.882548 -388.282024) (xy 457.862625 -388.229933)
			(xy 457.850499 -388.175496) (xy 457.846428 -388.119874) (xy 457.542741 -388.119874) (xy 457.551611 -388.137319)
			(xy 457.570061 -388.194213) (xy 457.5794 -388.253291) (xy 457.579984 -388.283196) (xy 457.579541 -388.31045)
			(xy 457.571784 -388.364403) (xy 457.556427 -388.416702) (xy 457.533783 -388.466284) (xy 457.504313 -388.512138)
			(xy 457.468618 -388.553332) (xy 457.427422 -388.589025) (xy 457.381567 -388.618493) (xy 457.331984 -388.641134)
			(xy 457.279683 -388.656488) (xy 457.22573 -388.664242) (xy 457.198476 -388.664704) (xy 457.171906 -388.664233)
			(xy 457.119283 -388.656837) (xy 457.068197 -388.642205) (xy 457.019637 -388.620622) (xy 456.974545 -388.592504)
			(xy 456.953874 -388.575804) (xy 456.946508 -388.569708) (xy 456.928982 -388.563866) (xy 456.84186 -388.566914)
			(xy 456.824842 -388.57428) (xy 456.817984 -388.580884) (xy 456.796502 -388.600972) (xy 456.748506 -388.634959)
			(xy 456.695863 -388.66118) (xy 456.639821 -388.679013) (xy 456.581706 -388.688037) (xy 456.5523 -388.68858)
			(xy 456.524869 -388.688153) (xy 456.470576 -388.680275) (xy 456.417969 -388.66471) (xy 456.36813 -388.641778)
			(xy 456.322085 -388.611952) (xy 456.280781 -388.575844) (xy 456.245068 -388.534198) (xy 456.229974 -388.511288)
			(xy 456.223116 -388.500366) (xy 456.200764 -388.48792) (xy 456.09002 -388.486142) (xy 456.067414 -388.497826)
			(xy 456.060048 -388.508748) (xy 456.044731 -388.530502) (xy 456.009069 -388.569982) (xy 455.968269 -388.604127)
			(xy 455.923123 -388.632275) (xy 455.874505 -388.65388) (xy 455.823358 -388.668523) (xy 455.770673 -388.675922)
			(xy 455.744072 -388.676388) (xy 455.716819 -388.675948) (xy 455.662869 -388.668187) (xy 455.610572 -388.652828)
			(xy 455.560993 -388.630182) (xy 455.515142 -388.600711) (xy 455.473952 -388.565014) (xy 455.43826 -388.523819)
			(xy 455.408795 -388.477965) (xy 455.386156 -388.428383) (xy 455.370802 -388.376084) (xy 455.363048 -388.322133)
			(xy 455.362564 -388.29488) (xy 455.363074 -388.265401) (xy 455.372148 -388.207146) (xy 455.390076 -388.15098)
			(xy 455.416433 -388.098241) (xy 455.450589 -388.050185) (xy 455.470768 -388.028688) (xy 455.47788 -388.021322)
			(xy 455.485246 -388.003034) (xy 455.485246 -387.912102) (xy 455.477626 -387.893814) (xy 455.470768 -387.886702)
			(xy 455.450437 -387.865202) (xy 455.416059 -387.817042) (xy 455.389529 -387.764151) (xy 455.371483 -387.707798)
			(xy 455.362355 -387.649334) (xy 455.361802 -387.619748) (xy 452.503953 -387.619748) (xy 452.510938 -387.668071)
			(xy 452.511414 -387.69544) (xy 452.510874 -387.723834) (xy 452.502458 -387.779995) (xy 452.485804 -387.834286)
			(xy 452.46128 -387.885505) (xy 452.429428 -387.932519) (xy 452.410576 -387.953758) (xy 452.404226 -387.960616)
			(xy 452.397368 -387.977888) (xy 452.396098 -388.064248) (xy 452.402194 -388.08152) (xy 452.408544 -388.088632)
			(xy 452.425852 -388.109521) (xy 452.455038 -388.155246) (xy 452.47745 -388.204647) (xy 452.492635 -388.256725)
			(xy 452.500286 -388.310429) (xy 452.500746 -388.337552) (xy 452.50026 -388.364803) (xy 452.492504 -388.418751)
			(xy 452.477149 -388.471046) (xy 452.454507 -388.520623) (xy 452.425041 -388.566473) (xy 452.38935 -388.607664)
			(xy 452.348159 -388.643355) (xy 452.302309 -388.672821) (xy 452.252732 -388.695463) (xy 452.200437 -388.710818)
			(xy 452.146489 -388.718574) (xy 452.091987 -388.718574) (xy 452.038039 -388.710818) (xy 451.985744 -388.695463)
			(xy 451.936167 -388.672821) (xy 451.890317 -388.643355) (xy 451.849126 -388.607664) (xy 451.813435 -388.566473)
			(xy 451.783969 -388.520623) (xy 451.761327 -388.471046) (xy 451.745972 -388.418751) (xy 451.738216 -388.364803)
			(xy 451.73773 -388.337552) (xy 451.738128 -388.312092) (xy 451.744897 -388.261624) (xy 451.758321 -388.212505)
			(xy 451.778162 -388.16561) (xy 451.804066 -388.121772) (xy 451.835573 -388.08177) (xy 451.853554 -388.06374)
			(xy 451.860334 -388.056435) (xy 451.86817 -388.038128) (xy 451.868794 -388.02818) (xy 451.869556 -387.996176)
			(xy 451.869232 -387.98619) (xy 451.861915 -387.967623) (xy 451.855332 -387.960108) (xy 451.84314 -387.9469)
			(xy 451.835578 -387.93903) (xy 451.815692 -387.930084) (xy 451.804786 -387.929628) (xy 451.728586 -387.929628)
			(xy 451.717691 -387.930128) (xy 451.697822 -387.939068) (xy 451.690232 -387.9469) (xy 451.672054 -387.966953)
			(xy 451.630995 -388.002217) (xy 451.58536 -388.031318) (xy 451.536067 -388.05367) (xy 451.484108 -388.068825)
			(xy 451.430528 -388.076477) (xy 451.403466 -388.076948) (xy 451.374727 -388.076432) (xy 451.3179 -388.067806)
			(xy 451.263009 -388.050753) (xy 451.211298 -388.02566) (xy 451.163935 -387.993095) (xy 451.142608 -387.973824)
			(xy 451.135496 -387.96722) (xy 451.11797 -387.960108) (xy 451.028562 -387.960108) (xy 451.011036 -387.96722)
			(xy 451.003924 -387.973824) (xy 450.982605 -387.993105) (xy 450.935242 -388.025671) (xy 450.883528 -388.050762)
			(xy 450.828635 -388.06781) (xy 450.771806 -388.076429) (xy 450.743066 -388.076948) (xy 450.715816 -388.076454)
			(xy 450.66187 -388.068694) (xy 450.609578 -388.053336) (xy 450.560004 -388.030694) (xy 450.514155 -388.001228)
			(xy 450.472966 -387.965538) (xy 450.437275 -387.92435) (xy 450.407809 -387.878502) (xy 450.385166 -387.828927)
			(xy 450.369807 -387.776635) (xy 450.362046 -387.72269) (xy 450.361558 -387.69544) (xy 450.362033 -387.66807)
			(xy 450.369847 -387.613891) (xy 450.385333 -387.561387) (xy 450.408173 -387.51164) (xy 450.437897 -387.465673)
			(xy 450.455538 -387.444742) (xy 450.461634 -387.43763) (xy 450.467984 -387.420612) (xy 450.467984 -387.335268)
			(xy 450.461634 -387.31825) (xy 450.455538 -387.311138) (xy 450.437909 -387.290198) (xy 450.408194 -387.244228)
			(xy 450.385356 -387.194482) (xy 450.369863 -387.141983) (xy 450.362033 -387.087809) (xy 450.361558 -387.06044)
			(xy 450.362056 -387.0317) (xy 450.370687 -386.974872) (xy 450.387744 -386.919982) (xy 450.41284 -386.86827)
			(xy 450.44541 -386.820909) (xy 450.464682 -386.799582) (xy 450.47154 -386.792216) (xy 450.478398 -386.774436)
			(xy 450.477636 -386.684266) (xy 450.47027 -386.666232) (xy 450.463158 -386.65912) (xy 450.442931 -386.637621)
			(xy 450.408707 -386.589528) (xy 450.382299 -386.536738) (xy 450.364337 -386.480511) (xy 450.35525 -386.422187)
			(xy 450.3547 -386.392674) (xy 450.18508 -386.392674) (xy 450.177797 -386.441828) (xy 450.16149 -386.495614)
			(xy 450.137467 -386.546424) (xy 450.106249 -386.59316) (xy 450.06851 -386.634808) (xy 450.047106 -386.653024)
			(xy 450.03847 -386.660136) (xy 450.028818 -386.680202) (xy 450.027294 -386.780532) (xy 450.036438 -386.800598)
			(xy 450.045074 -386.808218) (xy 450.065287 -386.826445) (xy 450.100884 -386.867614) (xy 450.130271 -386.913424)
			(xy 450.152851 -386.962944) (xy 450.168167 -387.015169) (xy 450.175906 -387.069041) (xy 450.176392 -387.096254)
			(xy 450.175903 -387.124994) (xy 450.167272 -387.181823) (xy 450.150214 -387.236714) (xy 450.125115 -387.288426)
			(xy 450.092542 -387.335786) (xy 450.073268 -387.357112) (xy 450.066664 -387.364224) (xy 450.059552 -387.38175)
			(xy 450.059552 -387.471158) (xy 450.066664 -387.488684) (xy 450.073268 -387.495796) (xy 450.092565 -387.5171)
			(xy 450.125128 -387.564468) (xy 450.150215 -387.616186) (xy 450.167259 -387.671082) (xy 450.175875 -387.727913)
			(xy 450.176392 -387.756654) (xy 450.175902 -387.783906) (xy 450.168151 -387.837857) (xy 450.1528 -387.890156)
			(xy 450.130161 -387.939737) (xy 450.100697 -387.985591) (xy 450.065006 -388.026784) (xy 450.023815 -388.062479)
			(xy 449.977963 -388.091947) (xy 449.928384 -388.114589) (xy 449.876087 -388.129944) (xy 449.822136 -388.1377)
			(xy 449.794884 -388.138162) (xy 449.769022 -388.137724) (xy 449.717771 -388.13074) (xy 449.667935 -388.11689)
			(xy 449.620431 -388.096427) (xy 449.57613 -388.069728) (xy 449.535847 -388.037283) (xy 449.51777 -388.018782)
			(xy 449.510244 -388.011554) (xy 449.491108 -388.003288) (xy 449.480686 -388.00278) (xy 449.448682 -388.00278)
			(xy 449.43825 -388.003245) (xy 449.419097 -388.011514) (xy 449.411598 -388.018782) (xy 449.407534 -388.0231)
			(xy 449.400168 -388.030466) (xy 449.392802 -388.04977) (xy 449.39585 -388.14375) (xy 449.404486 -388.162546)
			(xy 449.41236 -388.169404) (xy 449.431867 -388.187546) (xy 449.466085 -388.228374) (xy 449.494285 -388.27357)
			(xy 449.515917 -388.322252) (xy 449.530559 -388.373472) (xy 449.537926 -388.426232) (xy 449.538344 -388.452868)
			(xy 449.537792 -388.480117) (xy 449.530041 -388.53406) (xy 449.514692 -388.586352) (xy 449.492057 -388.635926)
			(xy 449.462597 -388.681775) (xy 449.426913 -388.722965) (xy 449.385729 -388.758657) (xy 449.339886 -388.788124)
			(xy 449.290315 -388.810768) (xy 449.238027 -388.826126) (xy 449.184085 -388.833887) (xy 449.156836 -388.834376)
			(xy 449.12792 -388.833841) (xy 449.070749 -388.825117) (xy 449.01555 -388.807863) (xy 448.963588 -388.782474)
			(xy 448.916054 -388.749533) (xy 448.874036 -388.709794) (xy 448.855846 -388.68731) (xy 448.848258 -388.678575)
			(xy 448.827519 -388.668376) (xy 448.815968 -388.667752) (xy 448.735704 -388.667752) (xy 448.724134 -388.668307)
			(xy 448.703362 -388.678511) (xy 448.695826 -388.68731) (xy 448.677623 -388.709783) (xy 448.635605 -388.749519)
			(xy 448.588073 -388.782458) (xy 448.536114 -388.807848) (xy 448.480919 -388.825107) (xy 448.423751 -388.833839)
			(xy 448.394836 -388.834376) (xy 448.367583 -388.833911) (xy 448.31363 -388.826158) (xy 448.26133 -388.810805)
			(xy 448.211748 -388.788164) (xy 448.165893 -388.758697) (xy 448.124699 -388.723003) (xy 448.089005 -388.68181)
			(xy 448.059537 -388.635955) (xy 448.036896 -388.586374) (xy 448.021543 -388.534074) (xy 448.013789 -388.480121)
			(xy 448.013328 -388.452868) (xy 448.013848 -388.423354) (xy 448.022944 -388.36503) (xy 448.040916 -388.308804)
			(xy 448.067333 -388.256017) (xy 448.101565 -388.207928) (xy 448.121786 -388.186422) (xy 448.129152 -388.179056)
			(xy 448.136518 -388.159752) (xy 448.13347 -388.065772) (xy 448.124834 -388.046976) (xy 448.11696 -388.040118)
			(xy 448.097468 -388.021961) (xy 448.063247 -387.981136) (xy 448.035045 -387.935944) (xy 448.013411 -387.887265)
			(xy 447.998766 -387.836047) (xy 447.991395 -387.783289) (xy 447.990976 -387.756654) (xy 447.991478 -387.727914)
			(xy 448.000107 -387.671086) (xy 448.017162 -387.616196) (xy 448.042259 -387.564484) (xy 448.074828 -387.517122)
			(xy 448.0941 -387.495796) (xy 448.100704 -387.488684) (xy 448.107816 -387.471158) (xy 448.107816 -387.38175)
			(xy 448.100704 -387.364224) (xy 448.0941 -387.357112) (xy 448.074818 -387.335794) (xy 448.042251 -387.288431)
			(xy 448.01716 -387.236717) (xy 448.000112 -387.181824) (xy 447.991494 -387.124994) (xy 447.990976 -387.096254)
			(xy 447.991473 -387.068151) (xy 447.999713 -387.012554) (xy 448.016023 -386.958767) (xy 448.04005 -386.907956)
			(xy 448.071273 -386.861222) (xy 448.109016 -386.819575) (xy 448.130422 -386.80136) (xy 448.139058 -386.794248)
			(xy 448.14871 -386.774182) (xy 448.150234 -386.673852) (xy 448.14109 -386.653786) (xy 448.132454 -386.646166)
			(xy 448.112239 -386.627941) (xy 448.076641 -386.586772) (xy 448.047253 -386.540963) (xy 448.024673 -386.491442)
			(xy 448.009359 -386.439215) (xy 448.001621 -386.385343) (xy 448.001136 -386.35813) (xy 448.001696 -386.329072)
			(xy 448.010524 -386.27163) (xy 448.027966 -386.216192) (xy 448.053618 -386.164043) (xy 448.086885 -386.11639)
			(xy 448.106546 -386.094986) (xy 448.11315 -386.087874) (xy 448.120516 -386.06984) (xy 448.120516 -385.979924)
			(xy 448.11315 -385.96189) (xy 448.106546 -385.954778) (xy 448.086865 -385.93339) (xy 448.053587 -385.885739)
			(xy 448.027932 -385.833586) (xy 448.010495 -385.778143) (xy 448.001679 -385.720695) (xy 448.001136 -385.691634)
			(xy 448.001606 -385.664934) (xy 448.009054 -385.612055) (xy 448.023807 -385.560733) (xy 448.045578 -385.511973)
			(xy 448.073941 -385.466727) (xy 448.090798 -385.446016) (xy 448.096894 -385.43865) (xy 448.10299 -385.420616)
			(xy 448.09918 -385.332986) (xy 448.09156 -385.31546) (xy 448.084956 -385.308856) (xy 448.064171 -385.287243)
			(xy 448.028912 -385.238746) (xy 448.001679 -385.185329) (xy 447.98314 -385.128308) (xy 447.973755 -385.069088)
			(xy 447.973196 -385.039108) (xy 440.922664 -385.039108) (xy 440.922664 -386.394706) (xy 442.279024 -386.394706)
			(xy 442.279461 -386.367452) (xy 442.287218 -386.313498) (xy 442.302575 -386.261198) (xy 442.325219 -386.211616)
			(xy 442.354689 -386.165761) (xy 442.390386 -386.124568) (xy 442.431582 -386.088874) (xy 442.477439 -386.059407)
			(xy 442.527022 -386.036766) (xy 442.579324 -386.021412) (xy 442.633278 -386.013659) (xy 442.660532 -386.013198)
			(xy 442.687801 -386.013699) (xy 442.741781 -386.02148) (xy 442.794103 -386.036866) (xy 442.843704 -386.059542)
			(xy 442.889571 -386.089047) (xy 442.930772 -386.124781) (xy 442.966467 -386.166015) (xy 442.981588 -386.188712)
			(xy 442.989127 -386.198999) (xy 443.011525 -386.21113) (xy 443.02426 -386.211826) (xy 443.055756 -386.211826)
			(xy 443.06422 -386.211559) (xy 443.080231 -386.20607) (xy 443.093566 -386.195646) (xy 443.098428 -386.188712)
			(xy 443.118748 -386.16001) (xy 443.12459 -386.152644) (xy 443.129924 -386.134356) (xy 443.123066 -386.04698)
			(xy 443.114938 -386.029708) (xy 443.107826 -386.023358) (xy 443.089012 -386.005256) (xy 443.056035 -385.96478)
			(xy 443.028882 -385.920186) (xy 443.008061 -385.872308) (xy 442.993959 -385.822039) (xy 442.986841 -385.770317)
			(xy 442.986414 -385.744212) (xy 442.986867 -385.716958) (xy 442.994622 -385.663006) (xy 443.009978 -385.610707)
			(xy 443.032621 -385.561125) (xy 443.06209 -385.515271) (xy 443.097785 -385.474077) (xy 443.138979 -385.438384)
			(xy 443.184834 -385.408916) (xy 443.234416 -385.386275) (xy 443.286716 -385.37092) (xy 443.340668 -385.363166)
			(xy 443.367922 -385.362704) (xy 443.394158 -385.363146) (xy 443.446135 -385.370344) (xy 443.496634 -385.384602)
			(xy 443.5447 -385.405649) (xy 443.589427 -385.433089) (xy 443.629968 -385.466403) (xy 443.648084 -385.485386)
			(xy 443.65545 -385.493006) (xy 443.6745 -385.501642) (xy 443.769496 -385.502404) (xy 443.7888 -385.494276)
			(xy 443.796166 -385.486656) (xy 443.814239 -385.468464) (xy 443.854381 -385.436556) (xy 443.898434 -385.41031)
			(xy 443.945606 -385.390201) (xy 443.995046 -385.37659) (xy 444.045863 -385.369723) (xy 444.071502 -385.369308)
			(xy 444.097485 -385.369722) (xy 444.148968 -385.376788) (xy 444.199017 -385.390774) (xy 444.246704 -385.411422)
			(xy 444.291149 -385.43835) (xy 444.331529 -385.471061) (xy 444.349632 -385.489704) (xy 444.357159 -385.496931)
			(xy 444.376294 -385.505198) (xy 444.386716 -385.505706) (xy 444.460884 -385.505706) (xy 444.471315 -385.505227)
			(xy 444.490468 -385.496968) (xy 444.497968 -385.489704) (xy 444.516083 -385.471073) (xy 444.556457 -385.438359)
			(xy 444.600899 -385.41143) (xy 444.648585 -385.390784) (xy 444.698633 -385.376803) (xy 444.750116 -385.369748)
			(xy 444.776098 -385.369308) (xy 444.803352 -385.369757) (xy 444.857304 -385.377514) (xy 444.909603 -385.392871)
			(xy 444.959184 -385.415514) (xy 445.005038 -385.444984) (xy 445.046231 -385.480679) (xy 445.081925 -385.521873)
			(xy 445.111392 -385.567728) (xy 445.134034 -385.61731) (xy 445.149389 -385.66961) (xy 445.157144 -385.723562)
			(xy 445.157606 -385.750816) (xy 445.157128 -385.77795) (xy 445.149441 -385.831671) (xy 445.134212 -385.883758)
			(xy 445.111748 -385.933158) (xy 445.082504 -385.978871) (xy 445.06515 -385.999736) (xy 445.059054 -386.006848)
			(xy 445.052704 -386.02412) (xy 445.053974 -386.110226) (xy 445.060832 -386.127244) (xy 445.066928 -386.134356)
			(xy 445.085435 -386.155533) (xy 445.116711 -386.202273) (xy 445.140793 -386.253095) (xy 445.157162 -386.3069)
			(xy 445.165462 -386.362523) (xy 445.165988 -386.390642) (xy 445.165412 -386.419767) (xy 445.156552 -386.477339)
			(xy 445.139044 -386.532895) (xy 445.113296 -386.585145) (xy 445.079906 -386.632874) (xy 445.039649 -386.674974)
			(xy 445.01689 -386.693156) (xy 445.007492 -386.700268) (xy 444.997078 -386.721604) (xy 444.997586 -386.826252)
			(xy 445.008 -386.847588) (xy 445.017652 -386.8547) (xy 445.040752 -386.872847) (xy 445.081617 -386.915042)
			(xy 445.115533 -386.963003) (xy 445.141697 -387.015595) (xy 445.159491 -387.071575) (xy 445.168495 -387.129622)
			(xy 445.169036 -387.158992) (xy 445.168581 -387.186363) (xy 445.160763 -387.240543) (xy 445.145272 -387.293047)
			(xy 445.122427 -387.342794) (xy 445.092699 -387.388759) (xy 445.075056 -387.40969) (xy 445.06896 -387.416802)
			(xy 445.06261 -387.43382) (xy 445.06261 -387.519164) (xy 445.06896 -387.536182) (xy 445.075056 -387.543294)
			(xy 445.09269 -387.564233) (xy 445.122416 -387.610199) (xy 445.145263 -387.659944) (xy 445.16076 -387.712446)
			(xy 445.16859 -387.766624) (xy 445.168591 -387.821364) (xy 445.160763 -387.875543) (xy 445.145267 -387.928044)
			(xy 445.122422 -387.97779) (xy 445.092697 -388.023758) (xy 445.075056 -388.04469) (xy 445.06896 -388.051802)
			(xy 445.06261 -388.06882) (xy 445.06261 -388.154164) (xy 445.06896 -388.171182) (xy 445.075056 -388.178294)
			(xy 445.092699 -388.199223) (xy 445.122412 -388.245196) (xy 445.145248 -388.294944) (xy 445.160738 -388.347446)
			(xy 445.168564 -388.401623) (xy 445.169036 -388.428992) (xy 445.168515 -388.456242) (xy 445.16076 -388.510187)
			(xy 445.145407 -388.562479) (xy 445.122769 -388.612055) (xy 445.093306 -388.657904) (xy 445.057619 -388.699093)
			(xy 445.016432 -388.734785) (xy 444.970586 -388.764252) (xy 444.921013 -388.786895) (xy 444.868722 -388.802253)
			(xy 444.814778 -388.810012) (xy 444.787528 -388.8105) (xy 444.761546 -388.810064) (xy 444.710064 -388.803002)
			(xy 444.660016 -388.78902) (xy 444.612328 -388.768376) (xy 444.567883 -388.741452) (xy 444.527502 -388.708746)
			(xy 444.509398 -388.690104) (xy 444.501859 -388.682891) (xy 444.482733 -388.674616) (xy 444.472314 -388.674102)
			(xy 444.398146 -388.674102) (xy 444.387711 -388.674541) (xy 444.368558 -388.682828) (xy 444.361062 -388.690104)
			(xy 444.342982 -388.70877) (xy 444.3026 -388.741481) (xy 444.258151 -388.768405) (xy 444.210458 -388.789045)
			(xy 444.160404 -388.803018) (xy 444.108916 -388.810065) (xy 444.082932 -388.8105) (xy 444.05568 -388.810015)
			(xy 444.001729 -388.802262) (xy 443.949431 -388.78691) (xy 443.899851 -388.76427) (xy 443.853997 -388.734805)
			(xy 443.812804 -388.699113) (xy 443.777109 -388.657922) (xy 443.747641 -388.612071) (xy 443.724999 -388.562491)
			(xy 443.709643 -388.510194) (xy 443.701887 -388.456244) (xy 443.701424 -388.428992) (xy 443.70188 -388.401621)
			(xy 443.709699 -388.347442) (xy 443.72519 -388.294938) (xy 443.748034 -388.245191) (xy 443.777762 -388.199225)
			(xy 443.795404 -388.178294) (xy 443.8015 -388.171182) (xy 443.80785 -388.154164) (xy 443.80785 -388.06882)
			(xy 443.8015 -388.051802) (xy 443.795404 -388.04469) (xy 443.777747 -388.023772) (xy 443.748038 -387.977795)
			(xy 443.725205 -387.928044) (xy 443.709718 -387.875541) (xy 443.701895 -387.821362) (xy 443.701424 -387.793992)
			(xy 443.701952 -387.764514) (xy 443.711023 -387.70626) (xy 443.728948 -387.650095) (xy 443.7553 -387.597356)
			(xy 443.789452 -387.549299) (xy 443.809628 -387.5278) (xy 443.816159 -387.520463) (xy 443.823606 -387.502304)
			(xy 443.824106 -387.492494) (xy 443.824106 -387.439154) (xy 443.81039 -387.425946) (xy 443.802262 -387.417564)
			(xy 443.780672 -387.40969) (xy 443.678818 -387.419596) (xy 443.65926 -387.431534) (xy 443.65291 -387.441186)
			(xy 443.637716 -387.463474) (xy 443.602042 -387.503932) (xy 443.561022 -387.538959) (xy 443.515476 -387.567856)
			(xy 443.466313 -387.590047) (xy 443.414513 -387.605089) (xy 443.36111 -387.612682) (xy 443.33414 -387.613144)
			(xy 443.3054 -387.612645) (xy 443.248572 -387.604015) (xy 443.193682 -387.586958) (xy 443.141971 -387.561861)
			(xy 443.094609 -387.529292) (xy 443.073282 -387.51002) (xy 443.06617 -387.503416) (xy 443.048644 -387.496304)
			(xy 442.959236 -387.496304) (xy 442.94171 -387.503416) (xy 442.934598 -387.51002) (xy 442.913248 -387.529265)
			(xy 442.865893 -387.561836) (xy 442.814187 -387.586934) (xy 442.759301 -387.603991) (xy 442.702478 -387.61262)
			(xy 442.67374 -387.613144) (xy 442.64649 -387.612608) (xy 442.592543 -387.604857) (xy 442.540249 -387.589508)
			(xy 442.490671 -387.566873) (xy 442.44482 -387.537412) (xy 442.403628 -387.501726) (xy 442.367933 -387.460541)
			(xy 442.338464 -387.414695) (xy 442.315819 -387.365122) (xy 442.300459 -387.312831) (xy 442.292698 -387.258886)
			(xy 442.292232 -387.231636) (xy 442.292795 -387.203509) (xy 442.30105 -387.147864) (xy 442.317387 -387.094035)
			(xy 442.341452 -387.043188) (xy 442.372723 -386.996426) (xy 442.410521 -386.954764) (xy 442.454028 -386.919103)
			(xy 442.477906 -386.90423) (xy 442.489844 -386.897118) (xy 442.503052 -386.87375) (xy 442.50102 -386.757926)
			(xy 442.487304 -386.734812) (xy 442.475112 -386.728208) (xy 442.450014 -386.713677) (xy 442.404186 -386.678139)
			(xy 442.364263 -386.636074) (xy 442.331165 -386.588453) (xy 442.305654 -386.536372) (xy 442.288319 -386.481031)
			(xy 442.279557 -386.423703) (xy 442.279024 -386.394706) (xy 440.922664 -386.394706) (xy 440.922664 -388.079996)
			(xy 440.922206 -388.104587) (xy 440.916805 -388.13867) (xy 441.467492 -388.13867) (xy 441.471563 -388.083048)
			(xy 441.483689 -388.028611) (xy 441.503612 -387.97652) (xy 441.530908 -387.927885) (xy 441.564994 -387.883742)
			(xy 441.605143 -387.845033) (xy 441.650501 -387.812582) (xy 441.700101 -387.787081) (xy 441.752885 -387.769074)
			(xy 441.807728 -387.758944) (xy 441.863462 -387.756907) (xy 441.918899 -387.763007) (xy 441.972856 -387.777113)
			(xy 442.024185 -387.798925) (xy 442.071791 -387.827979) (xy 442.114659 -387.863654) (xy 442.151876 -387.905191)
			(xy 442.182649 -387.951704) (xy 442.206321 -388.002201) (xy 442.222389 -388.055608) (xy 442.230509 -388.110784)
			(xy 442.231018 -388.13867) (xy 442.230509 -388.166556) (xy 442.222389 -388.221732) (xy 442.206321 -388.275139)
			(xy 442.182649 -388.325636) (xy 442.151876 -388.372149) (xy 442.114659 -388.413686) (xy 442.071791 -388.449361)
			(xy 442.024185 -388.478415) (xy 441.972856 -388.500227) (xy 441.918899 -388.514333) (xy 441.863462 -388.520433)
			(xy 441.807728 -388.518396) (xy 441.752885 -388.508266) (xy 441.700101 -388.490259) (xy 441.650501 -388.464758)
			(xy 441.605143 -388.432307) (xy 441.564994 -388.393598) (xy 441.530908 -388.349455) (xy 441.503612 -388.30082)
			(xy 441.483689 -388.248729) (xy 441.471563 -388.194292) (xy 441.467492 -388.13867) (xy 440.916805 -388.13867)
			(xy 440.914509 -388.153162) (xy 440.899305 -388.199935) (xy 440.876968 -388.243751) (xy 440.848048 -388.283531)
			(xy 440.83097 -388.30123) (xy 438.667652 -390.464548) (xy 438.660843 -390.471893) (xy 438.65312 -390.490357)
			(xy 438.652666 -390.500362) (xy 438.652666 -391.015728) (xy 438.670954 -391.04189) (xy 438.686194 -391.047224)
			(xy 438.71334 -391.057532) (xy 438.7644 -391.085179) (xy 438.810683 -391.120242) (xy 438.851121 -391.161911)
			(xy 438.884781 -391.209224) (xy 438.898284 -391.23493) (xy 438.898284 -391.235438) (xy 438.902921 -391.243591)
			(xy 438.916868 -391.25611) (xy 438.934379 -391.262787) (xy 438.94375 -391.263124) (xy 439.034428 -391.263124)
			(xy 439.043853 -391.262741) (xy 439.061424 -391.255912) (xy 439.075334 -391.24319) (xy 439.079894 -391.23493)
			(xy 439.092117 -391.211536) (xy 439.122043 -391.168058) (xy 439.157678 -391.129121) (xy 439.198342 -391.09547)
			(xy 439.243257 -391.067747) (xy 439.291566 -391.046482) (xy 439.342345 -391.032081) (xy 439.394625 -391.024819)
			(xy 439.421016 -391.024364) (xy 439.448268 -391.024851) (xy 439.502218 -391.03261) (xy 439.554515 -391.047968)
			(xy 439.604094 -391.070611) (xy 439.649946 -391.10008) (xy 439.691137 -391.135774) (xy 439.726829 -391.176967)
			(xy 439.756296 -391.22282) (xy 439.778938 -391.2724) (xy 439.794294 -391.324697) (xy 439.80205 -391.378647)
			(xy 439.80205 -391.433153) (xy 439.794294 -391.487103) (xy 439.778938 -391.5394) (xy 439.756296 -391.58898)
			(xy 439.726829 -391.634833) (xy 439.691137 -391.676026) (xy 439.649946 -391.71172) (xy 439.604094 -391.741189)
			(xy 439.554515 -391.763832) (xy 439.502218 -391.77919) (xy 439.448269 -391.786949) (xy 439.421016 -391.78738)
			(xy 439.394663 -391.78693) (xy 439.34246 -391.779667) (xy 439.291753 -391.76529) (xy 439.243506 -391.744073)
			(xy 439.198638 -391.716419) (xy 439.158001 -391.682854) (xy 439.122369 -391.644018) (xy 439.09242 -391.600648)
			(xy 439.080148 -391.577322) (xy 439.080148 -391.576814) (xy 439.075503 -391.568674) (xy 439.061551 -391.556186)
			(xy 439.044046 -391.549539) (xy 439.034682 -391.549128) (xy 438.944004 -391.549128) (xy 438.934578 -391.549507)
			(xy 438.917004 -391.556333) (xy 438.903095 -391.569059) (xy 438.898538 -391.577322) (xy 438.885016 -391.603081)
			(xy 438.851356 -391.650528) (xy 438.810882 -391.692315) (xy 438.764533 -391.727472) (xy 438.713383 -391.755184)
			(xy 438.686194 -391.765536) (xy 438.670954 -391.77087) (xy 438.652666 -391.797032) (xy 438.652666 -391.888218)
			(xy 438.652239 -391.898286) (xy 438.644516 -391.916883) (xy 438.63768 -391.924286) (xy 433.026312 -397.535654)
			(xy 433.018946 -397.542766) (xy 433.011326 -397.561562) (xy 433.011326 -397.835628) (xy 440.404248 -397.835628)
			(xy 440.408319 -397.780006) (xy 440.420445 -397.725569) (xy 440.440368 -397.673478) (xy 440.467664 -397.624843)
			(xy 440.50175 -397.5807) (xy 440.541899 -397.541991) (xy 440.587257 -397.50954) (xy 440.636857 -397.484039)
			(xy 440.689641 -397.466032) (xy 440.744484 -397.455902) (xy 440.800218 -397.453865) (xy 440.855655 -397.459965)
			(xy 440.909612 -397.474071) (xy 440.960941 -397.495883) (xy 441.008547 -397.524937) (xy 441.051415 -397.560612)
			(xy 441.088632 -397.602149) (xy 441.119405 -397.648662) (xy 441.143077 -397.699159) (xy 441.159145 -397.752566)
			(xy 441.167265 -397.807742) (xy 441.167774 -397.835628) (xy 441.167265 -397.863514) (xy 441.159145 -397.91869)
			(xy 441.145926 -397.962628) (xy 449.472048 -397.962628) (xy 449.476119 -397.907006) (xy 449.488245 -397.852569)
			(xy 449.508168 -397.800478) (xy 449.535464 -397.751843) (xy 449.56955 -397.7077) (xy 449.609699 -397.668991)
			(xy 449.655057 -397.63654) (xy 449.704657 -397.611039) (xy 449.757441 -397.593032) (xy 449.812284 -397.582902)
			(xy 449.868018 -397.580865) (xy 449.923455 -397.586965) (xy 449.977412 -397.601071) (xy 450.028741 -397.622883)
			(xy 450.076347 -397.651937) (xy 450.119215 -397.687612) (xy 450.156432 -397.729149) (xy 450.187205 -397.775662)
			(xy 450.210877 -397.826159) (xy 450.226945 -397.879566) (xy 450.235065 -397.934742) (xy 450.235574 -397.962628)
			(xy 450.235065 -397.990514) (xy 450.226945 -398.04569) (xy 450.210877 -398.099097) (xy 450.187205 -398.149594)
			(xy 450.156432 -398.196107) (xy 450.119215 -398.237644) (xy 450.076347 -398.273319) (xy 450.028741 -398.302373)
			(xy 449.977412 -398.324185) (xy 449.923455 -398.338291) (xy 449.868018 -398.344391) (xy 449.812284 -398.342354)
			(xy 449.757441 -398.332224) (xy 449.704657 -398.314217) (xy 449.655057 -398.288716) (xy 449.609699 -398.256265)
			(xy 449.56955 -398.217556) (xy 449.535464 -398.173413) (xy 449.508168 -398.124778) (xy 449.488245 -398.072687)
			(xy 449.476119 -398.01825) (xy 449.472048 -397.962628) (xy 441.145926 -397.962628) (xy 441.143077 -397.972097)
			(xy 441.119405 -398.022594) (xy 441.088632 -398.069107) (xy 441.051415 -398.110644) (xy 441.008547 -398.146319)
			(xy 440.960941 -398.175373) (xy 440.909612 -398.197185) (xy 440.855655 -398.211291) (xy 440.800218 -398.217391)
			(xy 440.744484 -398.215354) (xy 440.689641 -398.205224) (xy 440.636857 -398.187217) (xy 440.587257 -398.161716)
			(xy 440.541899 -398.129265) (xy 440.50175 -398.090556) (xy 440.467664 -398.046413) (xy 440.440368 -397.997778)
			(xy 440.420445 -397.945687) (xy 440.408319 -397.89125) (xy 440.404248 -397.835628) (xy 433.011326 -397.835628)
			(xy 433.011326 -398.737328) (xy 440.397136 -398.737328) (xy 440.401207 -398.681706) (xy 440.413333 -398.627269)
			(xy 440.433256 -398.575178) (xy 440.460552 -398.526543) (xy 440.494638 -398.4824) (xy 440.534787 -398.443691)
			(xy 440.580145 -398.41124) (xy 440.629745 -398.385739) (xy 440.682529 -398.367732) (xy 440.737372 -398.357602)
			(xy 440.793106 -398.355565) (xy 440.848543 -398.361665) (xy 440.9025 -398.375771) (xy 440.953829 -398.397583)
			(xy 441.001435 -398.426637) (xy 441.044303 -398.462312) (xy 441.08152 -398.503849) (xy 441.112293 -398.550362)
			(xy 441.135965 -398.600859) (xy 441.152033 -398.654266) (xy 441.160153 -398.709442) (xy 441.160662 -398.737328)
			(xy 441.160153 -398.765214) (xy 441.152033 -398.82039) (xy 441.138814 -398.864328) (xy 449.475858 -398.864328)
			(xy 449.479929 -398.808706) (xy 449.492055 -398.754269) (xy 449.511978 -398.702178) (xy 449.539274 -398.653543)
			(xy 449.57336 -398.6094) (xy 449.613509 -398.570691) (xy 449.658867 -398.53824) (xy 449.708467 -398.512739)
			(xy 449.761251 -398.494732) (xy 449.816094 -398.484602) (xy 449.871828 -398.482565) (xy 449.927265 -398.488665)
			(xy 449.981222 -398.502771) (xy 450.032551 -398.524583) (xy 450.080157 -398.553637) (xy 450.123025 -398.589312)
			(xy 450.160242 -398.630849) (xy 450.191015 -398.677362) (xy 450.214687 -398.727859) (xy 450.230755 -398.781266)
			(xy 450.238875 -398.836442) (xy 450.239384 -398.864328) (xy 450.238875 -398.892214) (xy 450.230755 -398.94739)
			(xy 450.214687 -399.000797) (xy 450.191015 -399.051294) (xy 450.160242 -399.097807) (xy 450.123025 -399.139344)
			(xy 450.080157 -399.175019) (xy 450.032551 -399.204073) (xy 449.981222 -399.225885) (xy 449.927265 -399.239991)
			(xy 449.871828 -399.246091) (xy 449.816094 -399.244054) (xy 449.761251 -399.233924) (xy 449.708467 -399.215917)
			(xy 449.658867 -399.190416) (xy 449.613509 -399.157965) (xy 449.57336 -399.119256) (xy 449.539274 -399.075113)
			(xy 449.511978 -399.026478) (xy 449.492055 -398.974387) (xy 449.479929 -398.91995) (xy 449.475858 -398.864328)
			(xy 441.138814 -398.864328) (xy 441.135965 -398.873797) (xy 441.112293 -398.924294) (xy 441.08152 -398.970807)
			(xy 441.044303 -399.012344) (xy 441.001435 -399.048019) (xy 440.953829 -399.077073) (xy 440.9025 -399.098885)
			(xy 440.848543 -399.112991) (xy 440.793106 -399.119091) (xy 440.737372 -399.117054) (xy 440.682529 -399.106924)
			(xy 440.629745 -399.088917) (xy 440.580145 -399.063416) (xy 440.534787 -399.030965) (xy 440.494638 -398.992256)
			(xy 440.460552 -398.948113) (xy 440.433256 -398.899478) (xy 440.413333 -398.847387) (xy 440.401207 -398.79295)
			(xy 440.397136 -398.737328) (xy 433.011326 -398.737328) (xy 433.011326 -399.2834) (xy 445.415396 -399.2834)
			(xy 445.419379 -399.230248) (xy 445.431241 -399.178283) (xy 445.450715 -399.128667) (xy 445.477367 -399.082508)
			(xy 445.510601 -399.040836) (xy 445.549675 -399.004584) (xy 445.593717 -398.974561) (xy 445.641741 -398.951438)
			(xy 445.692675 -398.935731) (xy 445.745381 -398.927791) (xy 445.772032 -398.92732) (xy 445.798392 -398.927815)
			(xy 445.850533 -398.9356) (xy 445.900956 -398.950994) (xy 445.948554 -398.973661) (xy 445.992286 -399.003103)
			(xy 446.012062 -399.020538) (xy 446.019174 -399.026888) (xy 446.036954 -399.033746) (xy 446.12433 -399.033746)
			(xy 446.14211 -399.026888) (xy 446.149222 -399.020538) (xy 446.169016 -399.003127) (xy 446.212754 -398.973702)
			(xy 446.260349 -398.95104) (xy 446.310763 -398.935634) (xy 446.362895 -398.92782) (xy 446.389252 -398.92732)
			(xy 446.415612 -398.927803) (xy 446.467754 -398.935591) (xy 446.518177 -398.950988) (xy 446.565775 -398.973657)
			(xy 446.609506 -399.003102) (xy 446.629282 -399.020538) (xy 446.636394 -399.026888) (xy 446.654174 -399.033746)
			(xy 446.74155 -399.033746) (xy 446.75933 -399.026888) (xy 446.766442 -399.020538) (xy 446.786228 -399.003117)
			(xy 446.829969 -398.973694) (xy 446.877566 -398.951034) (xy 446.927981 -398.93563) (xy 446.980115 -398.927819)
			(xy 447.006472 -398.92732) (xy 447.031468 -398.927745) (xy 447.080968 -398.93474) (xy 447.129005 -398.948582)
			(xy 447.174638 -398.968999) (xy 447.21697 -398.995592) (xy 447.236342 -399.011394) (xy 447.243454 -399.01749)
			(xy 447.259964 -399.023586) (xy 447.344038 -399.023586) (xy 447.360548 -399.01749) (xy 447.36766 -399.011394)
			(xy 447.387032 -398.995591) (xy 447.42936 -398.968989) (xy 447.474992 -398.948567) (xy 447.523031 -398.934727)
			(xy 447.572533 -398.92774) (xy 447.59753 -398.92732) (xy 447.624436 -398.927823) (xy 447.677639 -398.9359)
			(xy 447.72902 -398.951895) (xy 447.777406 -398.975444) (xy 447.821695 -399.00601) (xy 447.841624 -399.024094)
			(xy 447.848736 -399.030698) (xy 447.865754 -399.03781) (xy 447.953384 -399.039588) (xy 447.970656 -399.033238)
			(xy 447.978022 -399.026888) (xy 447.998965 -399.009317) (xy 448.044897 -398.979676) (xy 448.094591 -398.956895)
			(xy 448.147027 -398.941443) (xy 448.201133 -398.933634) (xy 448.228466 -398.933162) (xy 448.255718 -398.933683)
			(xy 448.309669 -398.941435) (xy 448.361966 -398.956787) (xy 448.411547 -398.979426) (xy 448.457401 -399.008891)
			(xy 448.498594 -399.044582) (xy 448.534289 -399.085772) (xy 448.563758 -399.131623) (xy 448.586401 -399.181202)
			(xy 448.601757 -399.233498) (xy 448.608933 -399.2834) (xy 454.494221 -399.2834) (xy 454.498203 -399.230259)
			(xy 454.51006 -399.178305) (xy 454.529528 -399.128698) (xy 454.556171 -399.082546) (xy 454.589394 -399.040881)
			(xy 454.628456 -399.004632) (xy 454.672484 -398.974609) (xy 454.720494 -398.951483) (xy 454.771415 -398.93577)
			(xy 454.824109 -398.927821) (xy 454.850754 -398.92732) (xy 454.877114 -398.927802) (xy 454.929257 -398.93559)
			(xy 454.979679 -398.950987) (xy 455.027277 -398.973657) (xy 455.071008 -399.003102) (xy 455.090784 -399.020538)
			(xy 455.097896 -399.026888) (xy 455.115676 -399.033746) (xy 455.203052 -399.033746) (xy 455.220832 -399.026888)
			(xy 455.227944 -399.020538) (xy 455.247729 -399.003116) (xy 455.29147 -398.973694) (xy 455.339067 -398.951033)
			(xy 455.389482 -398.93563) (xy 455.441616 -398.927819) (xy 455.467974 -398.92732) (xy 455.494335 -398.92779)
			(xy 455.546478 -398.935581) (xy 455.5969 -398.950981) (xy 455.644498 -398.973653) (xy 455.688228 -399.003101)
			(xy 455.708004 -399.020538) (xy 455.715116 -399.026888) (xy 455.732896 -399.033746) (xy 455.820272 -399.033746)
			(xy 455.838052 -399.026888) (xy 455.845164 -399.020538) (xy 455.864941 -399.003107) (xy 455.908684 -398.973685)
			(xy 455.956283 -398.951027) (xy 456.0067 -398.935626) (xy 456.058836 -398.927817) (xy 456.085194 -398.92732)
			(xy 456.11019 -398.927733) (xy 456.159691 -398.93473) (xy 456.207729 -398.948575) (xy 456.253361 -398.968996)
			(xy 456.295692 -398.995591) (xy 456.315064 -399.011394) (xy 456.322176 -399.01749) (xy 456.338686 -399.023586)
			(xy 456.42276 -399.023586) (xy 456.43927 -399.01749) (xy 456.446382 -399.011394) (xy 456.465746 -398.995581)
			(xy 456.508076 -398.96898) (xy 456.55371 -398.94856) (xy 456.601751 -398.934722) (xy 456.651255 -398.927738)
			(xy 456.676252 -398.92732) (xy 456.701833 -398.927781) (xy 456.75247 -398.935097) (xy 456.801538 -398.949585)
			(xy 456.848027 -398.970947) (xy 456.89098 -398.998743) (xy 456.929513 -399.032401) (xy 456.946508 -399.051526)
			(xy 456.952858 -399.059146) (xy 456.97013 -399.068036) (xy 457.059792 -399.076926) (xy 457.078334 -399.071338)
			(xy 457.086208 -399.065242) (xy 457.106427 -399.049888) (xy 457.150186 -399.024146) (xy 457.196972 -399.004433)
			(xy 457.245959 -398.991098) (xy 457.296281 -398.984375) (xy 457.321666 -398.983962) (xy 457.348918 -398.984483)
			(xy 457.402869 -398.992235) (xy 457.455166 -399.007587) (xy 457.504747 -399.030226) (xy 457.550601 -399.059691)
			(xy 457.591794 -399.095382) (xy 457.627489 -399.136572) (xy 457.656958 -399.182423) (xy 457.679601 -399.232002)
			(xy 457.694957 -399.284298) (xy 457.702715 -399.338248) (xy 457.702715 -399.392752) (xy 457.694957 -399.446702)
			(xy 457.679601 -399.498998) (xy 457.656958 -399.548577) (xy 457.627489 -399.594428) (xy 457.591794 -399.635618)
			(xy 457.550601 -399.671309) (xy 457.504747 -399.700774) (xy 457.455166 -399.723413) (xy 457.402869 -399.738765)
			(xy 457.348918 -399.746517) (xy 457.321666 -399.746978) (xy 457.292465 -399.746417) (xy 457.234744 -399.737518)
			(xy 457.179057 -399.719918) (xy 457.126706 -399.694029) (xy 457.078917 -399.660458) (xy 457.036808 -399.619989)
			(xy 457.018644 -399.597118) (xy 457.012548 -399.589244) (xy 456.996038 -399.579338) (xy 456.906884 -399.565622)
			(xy 456.888088 -399.56994) (xy 456.87996 -399.575528) (xy 456.857414 -399.59061) (xy 456.808731 -399.61453)
			(xy 456.756986 -399.630793) (xy 456.703373 -399.639024) (xy 456.676252 -399.639536) (xy 456.651257 -399.639084)
			(xy 456.601759 -399.632094) (xy 456.553722 -399.618257) (xy 456.508089 -399.597846) (xy 456.465756 -399.57126)
			(xy 456.446382 -399.555462) (xy 456.43927 -399.549366) (xy 456.42276 -399.54327) (xy 456.338686 -399.54327)
			(xy 456.322176 -399.549366) (xy 456.315064 -399.555462) (xy 456.29569 -399.571262) (xy 456.253362 -399.597863)
			(xy 456.207731 -399.618285) (xy 456.159692 -399.632126) (xy 456.11019 -399.639114) (xy 456.085194 -399.639536)
			(xy 456.058833 -399.639071) (xy 456.006691 -399.631277) (xy 455.956269 -399.615875) (xy 455.908672 -399.593202)
			(xy 455.86494 -399.563754) (xy 455.845164 -399.546318) (xy 455.838052 -399.539968) (xy 455.820272 -399.53311)
			(xy 455.732896 -399.53311) (xy 455.715116 -399.539968) (xy 455.708004 -399.546318) (xy 455.688233 -399.563757)
			(xy 455.644489 -399.593179) (xy 455.596888 -399.615836) (xy 455.54647 -399.631236) (xy 455.494333 -399.639041)
			(xy 455.467974 -399.639536) (xy 455.441615 -399.639023) (xy 455.389475 -399.63124) (xy 455.339054 -399.615849)
			(xy 455.291455 -399.593187) (xy 455.247722 -399.56375) (xy 455.227944 -399.546318) (xy 455.220832 -399.539968)
			(xy 455.203052 -399.53311) (xy 455.115676 -399.53311) (xy 455.097896 -399.539968) (xy 455.090784 -399.546318)
			(xy 455.070981 -399.563719) (xy 455.027246 -399.593146) (xy 454.979653 -399.615811) (xy 454.929242 -399.631219)
			(xy 454.87711 -399.639035) (xy 454.850754 -399.639536) (xy 454.824109 -399.638979) (xy 454.771415 -399.63103)
			(xy 454.720494 -399.615317) (xy 454.672484 -399.592191) (xy 454.628456 -399.562168) (xy 454.589394 -399.525919)
			(xy 454.556171 -399.484254) (xy 454.529528 -399.438102) (xy 454.51006 -399.388495) (xy 454.498203 -399.336541)
			(xy 454.494221 -399.2834) (xy 448.608933 -399.2834) (xy 448.609515 -399.287448) (xy 448.609515 -399.341952)
			(xy 448.601757 -399.395902) (xy 448.586401 -399.448198) (xy 448.563758 -399.497777) (xy 448.534289 -399.543628)
			(xy 448.498594 -399.584818) (xy 448.457401 -399.620509) (xy 448.411547 -399.649974) (xy 448.361966 -399.672613)
			(xy 448.309669 -399.687965) (xy 448.255718 -399.695717) (xy 448.228466 -399.696178) (xy 448.202545 -399.69574)
			(xy 448.151182 -399.688705) (xy 448.101244 -399.674782) (xy 448.05365 -399.654229) (xy 448.009276 -399.627422)
			(xy 447.968939 -399.594855) (xy 447.950844 -399.57629) (xy 447.94424 -399.569178) (xy 447.927476 -399.561304)
			(xy 447.840354 -399.554446) (xy 447.822574 -399.559526) (xy 447.814954 -399.565622) (xy 447.79142 -399.582994)
			(xy 447.739865 -399.610621) (xy 447.684487 -399.629448) (xy 447.626776 -399.638967) (xy 447.59753 -399.639536)
			(xy 447.572535 -399.639096) (xy 447.523036 -399.632103) (xy 447.474999 -399.618264) (xy 447.429367 -399.59785)
			(xy 447.387033 -399.571261) (xy 447.36766 -399.555462) (xy 447.360548 -399.549366) (xy 447.344038 -399.54327)
			(xy 447.259964 -399.54327) (xy 447.243454 -399.549366) (xy 447.236342 -399.555462) (xy 447.216976 -399.571273)
			(xy 447.174646 -399.597872) (xy 447.129012 -399.618291) (xy 447.080972 -399.63213) (xy 447.031469 -399.639116)
			(xy 447.006472 -399.639536) (xy 446.980113 -399.639024) (xy 446.927973 -399.631241) (xy 446.877551 -399.61585)
			(xy 446.829953 -399.593188) (xy 446.78622 -399.56375) (xy 446.766442 -399.546318) (xy 446.75933 -399.539968)
			(xy 446.74155 -399.53311) (xy 446.654174 -399.53311) (xy 446.636394 -399.539968) (xy 446.629282 -399.546318)
			(xy 446.60948 -399.56372) (xy 446.565744 -399.593147) (xy 446.518152 -399.615812) (xy 446.46774 -399.63122)
			(xy 446.415608 -399.639035) (xy 446.389252 -399.639536) (xy 446.362893 -399.639036) (xy 446.310752 -399.63125)
			(xy 446.26033 -399.615856) (xy 446.212732 -399.593191) (xy 446.168999 -399.563751) (xy 446.149222 -399.546318)
			(xy 446.14211 -399.539968) (xy 446.12433 -399.53311) (xy 446.036954 -399.53311) (xy 446.019174 -399.539968)
			(xy 446.012062 -399.546318) (xy 445.992268 -399.563729) (xy 445.94853 -399.593155) (xy 445.900935 -399.615818)
			(xy 445.850522 -399.631224) (xy 445.798389 -399.639036) (xy 445.772032 -399.639536) (xy 445.745381 -399.639009)
			(xy 445.692675 -399.631069) (xy 445.641741 -399.615362) (xy 445.593716 -399.592239) (xy 445.549675 -399.562216)
			(xy 445.510601 -399.525964) (xy 445.477367 -399.484292) (xy 445.450715 -399.438133) (xy 445.431241 -399.388517)
			(xy 445.419379 -399.336552) (xy 445.415396 -399.2834) (xy 433.011326 -399.2834) (xy 433.011326 -400.15287)
			(xy 447.338958 -400.15287) (xy 447.33945 -400.12562) (xy 447.34721 -400.071674) (xy 447.362567 -400.019381)
			(xy 447.385209 -399.969806) (xy 447.414675 -399.923958) (xy 447.450366 -399.882769) (xy 447.491554 -399.847078)
			(xy 447.537403 -399.817611) (xy 447.586978 -399.794968) (xy 447.63927 -399.77961) (xy 447.693216 -399.77185)
			(xy 447.720466 -399.771362) (xy 447.749383 -399.771881) (xy 447.806555 -399.780607) (xy 447.861755 -399.797863)
			(xy 447.913718 -399.823254) (xy 447.961251 -399.856199) (xy 448.003267 -399.895941) (xy 448.021456 -399.918428)
			(xy 448.029036 -399.92717) (xy 448.049781 -399.937363) (xy 448.061334 -399.937986) (xy 448.141598 -399.937986)
			(xy 448.153166 -399.937419) (xy 448.173937 -399.927222) (xy 448.181476 -399.918428) (xy 448.199688 -399.895962)
			(xy 448.241702 -399.856224) (xy 448.289233 -399.823282) (xy 448.34119 -399.797891) (xy 448.396384 -399.780631)
			(xy 448.453551 -399.771899) (xy 448.482466 -399.771362) (xy 448.509717 -399.771887) (xy 448.563664 -399.779638)
			(xy 448.615959 -399.794989) (xy 448.665537 -399.817625) (xy 448.711389 -399.847087) (xy 448.752581 -399.882774)
			(xy 448.788275 -399.92396) (xy 448.817744 -399.969807) (xy 448.840389 -400.019381) (xy 448.855748 -400.071674)
			(xy 448.863509 -400.125619) (xy 448.863649 -400.13382) (xy 449.300598 -400.13382) (xy 449.304669 -400.078198)
			(xy 449.316795 -400.023761) (xy 449.336718 -399.97167) (xy 449.364014 -399.923035) (xy 449.3981 -399.878892)
			(xy 449.438249 -399.840183) (xy 449.483607 -399.807732) (xy 449.533207 -399.782231) (xy 449.585991 -399.764224)
			(xy 449.640834 -399.754094) (xy 449.696568 -399.752057) (xy 449.752005 -399.758157) (xy 449.805962 -399.772263)
			(xy 449.857291 -399.794075) (xy 449.904897 -399.823129) (xy 449.947765 -399.858804) (xy 449.984982 -399.900341)
			(xy 450.015755 -399.946854) (xy 450.039427 -399.997351) (xy 450.055495 -400.050758) (xy 450.063615 -400.105934)
			(xy 450.064124 -400.13382) (xy 450.063615 -400.161706) (xy 450.057439 -400.20367) (xy 456.432158 -400.20367)
			(xy 456.43265 -400.17642) (xy 456.44041 -400.122474) (xy 456.455767 -400.070181) (xy 456.478409 -400.020606)
			(xy 456.507875 -399.974758) (xy 456.543566 -399.933569) (xy 456.584754 -399.897878) (xy 456.630603 -399.868411)
			(xy 456.680178 -399.845768) (xy 456.73247 -399.83041) (xy 456.786416 -399.82265) (xy 456.813666 -399.822162)
			(xy 456.842583 -399.822681) (xy 456.899755 -399.831407) (xy 456.954955 -399.848663) (xy 457.006918 -399.874054)
			(xy 457.054451 -399.906999) (xy 457.096467 -399.946741) (xy 457.114656 -399.969228) (xy 457.122236 -399.97797)
			(xy 457.142981 -399.988163) (xy 457.154534 -399.988786) (xy 457.234798 -399.988786) (xy 457.246366 -399.988219)
			(xy 457.267137 -399.978022) (xy 457.274676 -399.969228) (xy 457.292888 -399.946762) (xy 457.334902 -399.907024)
			(xy 457.382433 -399.874082) (xy 457.43439 -399.848691) (xy 457.489584 -399.831431) (xy 457.546751 -399.822699)
			(xy 457.575666 -399.822162) (xy 457.602917 -399.822687) (xy 457.656864 -399.830438) (xy 457.709159 -399.845789)
			(xy 457.758737 -399.868425) (xy 457.804589 -399.897887) (xy 457.845781 -399.933574) (xy 457.881475 -399.97476)
			(xy 457.910944 -400.020607) (xy 457.933589 -400.070181) (xy 457.948948 -400.122474) (xy 457.956709 -400.176419)
			(xy 457.957174 -400.20367) (xy 457.956772 -400.22936) (xy 457.949869 -400.280274) (xy 457.936196 -400.329801)
			(xy 457.916 -400.377046) (xy 457.889648 -400.421154) (xy 457.857616 -400.461326) (xy 457.820483 -400.496838)
			(xy 457.799948 -400.51228) (xy 457.788772 -400.520408) (xy 457.777596 -400.545808) (xy 457.791566 -400.661378)
			(xy 457.80833 -400.683476) (xy 457.821284 -400.688556) (xy 457.847233 -400.699707) (xy 457.895816 -400.728508)
			(xy 457.939623 -400.764156) (xy 457.977696 -400.805872) (xy 458.009205 -400.852744) (xy 458.03346 -400.903748)
			(xy 458.049932 -400.95777) (xy 458.058262 -401.013631) (xy 458.058774 -401.04187) (xy 458.058317 -401.069124)
			(xy 458.050563 -401.123077) (xy 458.035209 -401.175377) (xy 458.012567 -401.224959) (xy 457.983099 -401.270814)
			(xy 457.947405 -401.312008) (xy 457.906211 -401.347702) (xy 457.860355 -401.377169) (xy 457.810773 -401.39981)
			(xy 457.758473 -401.415164) (xy 457.70452 -401.422917) (xy 457.677266 -401.423378) (xy 457.64835 -401.422821)
			(xy 457.591181 -401.414101) (xy 457.535982 -401.396851) (xy 457.48402 -401.371467) (xy 457.436485 -401.33853)
			(xy 457.394467 -401.298795) (xy 457.376276 -401.276312) (xy 457.368718 -401.267546) (xy 457.347957 -401.257364)
			(xy 457.336398 -401.256754) (xy 457.256134 -401.256754) (xy 457.244566 -401.257325) (xy 457.223794 -401.267517)
			(xy 457.216256 -401.276312) (xy 457.198093 -401.298819) (xy 457.156067 -401.338552) (xy 457.108526 -401.371488)
			(xy 457.056559 -401.396872) (xy 457.001357 -401.414123) (xy 456.944184 -401.422846) (xy 456.915266 -401.423378)
			(xy 456.888013 -401.422954) (xy 456.834061 -401.415192) (xy 456.781763 -401.399831) (xy 456.732184 -401.377184)
			(xy 456.686332 -401.347711) (xy 456.645142 -401.312013) (xy 456.609451 -401.270816) (xy 456.579986 -401.22496)
			(xy 456.557347 -401.175377) (xy 456.541995 -401.123076) (xy 456.534242 -401.069124) (xy 456.533758 -401.04187)
			(xy 456.534176 -401.01618) (xy 456.541075 -400.965267) (xy 456.554745 -400.915739) (xy 456.574937 -400.868494)
			(xy 456.601286 -400.824386) (xy 456.633317 -400.784213) (xy 456.670449 -400.748702) (xy 456.690984 -400.73326)
			(xy 456.70216 -400.725132) (xy 456.713336 -400.699732) (xy 456.699366 -400.584162) (xy 456.682602 -400.562064)
			(xy 456.669648 -400.556984) (xy 456.643698 -400.545835) (xy 456.595119 -400.517029) (xy 456.551316 -400.481379)
			(xy 456.513245 -400.439663) (xy 456.481737 -400.392791) (xy 456.457481 -400.341788) (xy 456.441006 -400.287767)
			(xy 456.432673 -400.231908) (xy 456.432158 -400.20367) (xy 450.057439 -400.20367) (xy 450.055495 -400.216882)
			(xy 450.039427 -400.270289) (xy 450.015755 -400.320786) (xy 449.984982 -400.367299) (xy 449.947765 -400.408836)
			(xy 449.904897 -400.444511) (xy 449.857291 -400.473565) (xy 449.805962 -400.495377) (xy 449.752005 -400.509483)
			(xy 449.696568 -400.515583) (xy 449.640834 -400.513546) (xy 449.585991 -400.503416) (xy 449.533207 -400.485409)
			(xy 449.483607 -400.459908) (xy 449.438249 -400.427457) (xy 449.3981 -400.388748) (xy 449.364014 -400.344605)
			(xy 449.336718 -400.29597) (xy 449.316795 -400.243879) (xy 449.304669 -400.189442) (xy 449.300598 -400.13382)
			(xy 448.863649 -400.13382) (xy 448.863974 -400.15287) (xy 448.863572 -400.17856) (xy 448.856669 -400.229474)
			(xy 448.842996 -400.279001) (xy 448.8228 -400.326246) (xy 448.796448 -400.370354) (xy 448.764416 -400.410526)
			(xy 448.727283 -400.446038) (xy 448.706748 -400.46148) (xy 448.695572 -400.469608) (xy 448.684396 -400.495008)
			(xy 448.698366 -400.610578) (xy 448.71513 -400.632676) (xy 448.728084 -400.637756) (xy 448.754033 -400.648907)
			(xy 448.802616 -400.677708) (xy 448.846423 -400.713356) (xy 448.884496 -400.755072) (xy 448.916005 -400.801944)
			(xy 448.94026 -400.852948) (xy 448.956732 -400.90697) (xy 448.965062 -400.962831) (xy 448.965574 -400.99107)
			(xy 448.965117 -401.018324) (xy 448.957363 -401.072277) (xy 448.953672 -401.084848) (xy 452.907696 -401.084848)
			(xy 452.907696 -401.030352) (xy 452.915451 -400.976411) (xy 452.930803 -400.924123) (xy 452.95344 -400.874551)
			(xy 452.9829 -400.828705) (xy 453.018585 -400.787518) (xy 453.059768 -400.751828) (xy 453.10561 -400.722362)
			(xy 453.155179 -400.699719) (xy 453.207466 -400.684361) (xy 453.261406 -400.676599) (xy 453.288654 -400.67611)
			(xy 453.314407 -400.676537) (xy 453.365442 -400.683484) (xy 453.415079 -400.697231) (xy 453.462417 -400.717528)
			(xy 453.506596 -400.744006) (xy 453.546812 -400.776185) (xy 453.582336 -400.813479) (xy 453.597772 -400.834098)
			(xy 453.603868 -400.842226) (xy 453.620632 -400.85264) (xy 453.711056 -400.867626) (xy 453.73036 -400.863308)
			(xy 453.738742 -400.857466) (xy 453.763002 -400.840983) (xy 453.815524 -400.814883) (xy 453.871423 -400.797134)
			(xy 453.929381 -400.788154) (xy 453.958706 -400.787616) (xy 453.985959 -400.788054) (xy 454.039909 -400.795812)
			(xy 454.092206 -400.811169) (xy 454.141786 -400.833811) (xy 454.187639 -400.86328) (xy 454.228831 -400.898974)
			(xy 454.264524 -400.940166) (xy 454.293991 -400.986019) (xy 454.316634 -401.035599) (xy 454.331989 -401.087897)
			(xy 454.339746 -401.141847) (xy 454.339746 -401.196353) (xy 454.331989 -401.250303) (xy 454.316634 -401.302601)
			(xy 454.293991 -401.352181) (xy 454.264524 -401.398034) (xy 454.228831 -401.439226) (xy 454.187639 -401.47492)
			(xy 454.141786 -401.504389) (xy 454.092206 -401.527031) (xy 454.039909 -401.542388) (xy 453.985959 -401.550146)
			(xy 453.958706 -401.550632) (xy 453.932954 -401.550184) (xy 453.881919 -401.543244) (xy 453.832281 -401.529503)
			(xy 453.784942 -401.50921) (xy 453.740763 -401.482734) (xy 453.700546 -401.450557) (xy 453.665023 -401.413263)
			(xy 453.649588 -401.392644) (xy 453.643492 -401.384516) (xy 453.626728 -401.374102) (xy 453.536304 -401.359116)
			(xy 453.517 -401.363434) (xy 453.508618 -401.369276) (xy 453.484365 -401.385769) (xy 453.431841 -401.411869)
			(xy 453.375939 -401.429615) (xy 453.317979 -401.438591) (xy 453.288654 -401.439126) (xy 453.261406 -401.438601)
			(xy 453.207466 -401.430839) (xy 453.155179 -401.415481) (xy 453.10561 -401.392838) (xy 453.059768 -401.363372)
			(xy 453.018585 -401.327682) (xy 452.9829 -401.286495) (xy 452.95344 -401.240649) (xy 452.930803 -401.191077)
			(xy 452.915451 -401.138789) (xy 452.907696 -401.084848) (xy 448.953672 -401.084848) (xy 448.942009 -401.124577)
			(xy 448.919367 -401.174159) (xy 448.889899 -401.220014) (xy 448.854205 -401.261208) (xy 448.813011 -401.296902)
			(xy 448.767155 -401.326369) (xy 448.717573 -401.34901) (xy 448.665273 -401.364364) (xy 448.61132 -401.372117)
			(xy 448.584066 -401.372578) (xy 448.55515 -401.372021) (xy 448.497981 -401.363301) (xy 448.442782 -401.346051)
			(xy 448.39082 -401.320667) (xy 448.343285 -401.28773) (xy 448.301267 -401.247995) (xy 448.283076 -401.225512)
			(xy 448.275518 -401.216746) (xy 448.254757 -401.206564) (xy 448.243198 -401.205954) (xy 448.162934 -401.205954)
			(xy 448.151366 -401.206525) (xy 448.130594 -401.216717) (xy 448.123056 -401.225512) (xy 448.104893 -401.248019)
			(xy 448.062867 -401.287752) (xy 448.015326 -401.320688) (xy 447.963359 -401.346072) (xy 447.908157 -401.363323)
			(xy 447.850984 -401.372046) (xy 447.822066 -401.372578) (xy 447.794813 -401.372154) (xy 447.740861 -401.364392)
			(xy 447.688563 -401.349031) (xy 447.638984 -401.326384) (xy 447.593132 -401.296911) (xy 447.551942 -401.261213)
			(xy 447.516251 -401.220016) (xy 447.486786 -401.17416) (xy 447.464147 -401.124577) (xy 447.448795 -401.072276)
			(xy 447.441042 -401.018324) (xy 447.440558 -400.99107) (xy 447.440976 -400.96538) (xy 447.447875 -400.914467)
			(xy 447.461545 -400.864939) (xy 447.481737 -400.817694) (xy 447.508086 -400.773586) (xy 447.540117 -400.733413)
			(xy 447.577249 -400.697902) (xy 447.597784 -400.68246) (xy 447.60896 -400.674332) (xy 447.620136 -400.648932)
			(xy 447.606166 -400.533362) (xy 447.589402 -400.511264) (xy 447.576448 -400.506184) (xy 447.550498 -400.495035)
			(xy 447.501919 -400.466229) (xy 447.458116 -400.430579) (xy 447.420045 -400.388863) (xy 447.388537 -400.341991)
			(xy 447.364281 -400.290988) (xy 447.347806 -400.236967) (xy 447.339473 -400.181108) (xy 447.338958 -400.15287)
			(xy 433.011326 -400.15287) (xy 433.011326 -400.214592) (xy 433.011748 -400.224662) (xy 433.019463 -400.243266)
			(xy 433.026312 -400.25066) (xy 434.217572 -401.44192) (xy 440.397898 -401.44192) (xy 440.401969 -401.386298)
			(xy 440.414095 -401.331861) (xy 440.434018 -401.27977) (xy 440.461314 -401.231135) (xy 440.4954 -401.186992)
			(xy 440.535549 -401.148283) (xy 440.580907 -401.115832) (xy 440.630507 -401.090331) (xy 440.683291 -401.072324)
			(xy 440.738134 -401.062194) (xy 440.793868 -401.060157) (xy 440.849305 -401.066257) (xy 440.903262 -401.080363)
			(xy 440.954591 -401.102175) (xy 441.002197 -401.131229) (xy 441.025147 -401.150328) (xy 444.513714 -401.150328)
			(xy 444.517785 -401.094706) (xy 444.529911 -401.040269) (xy 444.549834 -400.988178) (xy 444.57713 -400.939543)
			(xy 444.611216 -400.8954) (xy 444.651365 -400.856691) (xy 444.696723 -400.82424) (xy 444.746323 -400.798739)
			(xy 444.799107 -400.780732) (xy 444.85395 -400.770602) (xy 444.909684 -400.768565) (xy 444.965121 -400.774665)
			(xy 445.019078 -400.788771) (xy 445.070407 -400.810583) (xy 445.118013 -400.839637) (xy 445.160881 -400.875312)
			(xy 445.198098 -400.916849) (xy 445.228871 -400.963362) (xy 445.252543 -401.013859) (xy 445.268611 -401.067266)
			(xy 445.276731 -401.122442) (xy 445.27724 -401.150328) (xy 445.276731 -401.178214) (xy 445.268611 -401.23339)
			(xy 445.252543 -401.286797) (xy 445.228871 -401.337294) (xy 445.198098 -401.383807) (xy 445.160881 -401.425344)
			(xy 445.118013 -401.461019) (xy 445.070407 -401.490073) (xy 445.019078 -401.511885) (xy 444.965121 -401.525991)
			(xy 444.909684 -401.532091) (xy 444.85395 -401.530054) (xy 444.799107 -401.519924) (xy 444.746323 -401.501917)
			(xy 444.696723 -401.476416) (xy 444.651365 -401.443965) (xy 444.611216 -401.405256) (xy 444.57713 -401.361113)
			(xy 444.549834 -401.312478) (xy 444.529911 -401.260387) (xy 444.517785 -401.20595) (xy 444.513714 -401.150328)
			(xy 441.025147 -401.150328) (xy 441.045065 -401.166904) (xy 441.082282 -401.208441) (xy 441.113055 -401.254954)
			(xy 441.136727 -401.305451) (xy 441.152795 -401.358858) (xy 441.160915 -401.414034) (xy 441.161424 -401.44192)
			(xy 441.160915 -401.469806) (xy 441.152795 -401.524982) (xy 441.136727 -401.578389) (xy 441.113055 -401.628886)
			(xy 441.082282 -401.675399) (xy 441.045065 -401.716936) (xy 441.002197 -401.752611) (xy 440.954591 -401.781665)
			(xy 440.903262 -401.803477) (xy 440.849305 -401.817583) (xy 440.793868 -401.823683) (xy 440.738134 -401.821646)
			(xy 440.683291 -401.811516) (xy 440.630507 -401.793509) (xy 440.580907 -401.768008) (xy 440.535549 -401.735557)
			(xy 440.4954 -401.696848) (xy 440.461314 -401.652705) (xy 440.434018 -401.60407) (xy 440.414095 -401.551979)
			(xy 440.401969 -401.497542) (xy 440.397898 -401.44192) (xy 434.217572 -401.44192) (xy 434.51272 -401.737068)
			(xy 434.520118 -401.743915) (xy 434.538716 -401.751647) (xy 434.548788 -401.752054) (xy 435.677564 -401.752054)
			(xy 435.687628 -401.75249) (xy 435.70621 -401.760227) (xy 435.713632 -401.76704) (xy 436.366412 -402.41982)
			(xy 440.683648 -402.41982) (xy 440.687719 -402.364198) (xy 440.699845 -402.309761) (xy 440.719768 -402.25767)
			(xy 440.747064 -402.209035) (xy 440.78115 -402.164892) (xy 440.821299 -402.126183) (xy 440.866657 -402.093732)
			(xy 440.916257 -402.068231) (xy 440.969041 -402.050224) (xy 441.023884 -402.040094) (xy 441.079618 -402.038057)
			(xy 441.135055 -402.044157) (xy 441.189012 -402.058263) (xy 441.240341 -402.080075) (xy 441.287947 -402.109129)
			(xy 441.330815 -402.144804) (xy 441.360569 -402.178012) (xy 443.299848 -402.178012) (xy 443.303919 -402.12239)
			(xy 443.316045 -402.067953) (xy 443.335968 -402.015862) (xy 443.363264 -401.967227) (xy 443.39735 -401.923084)
			(xy 443.437499 -401.884375) (xy 443.482857 -401.851924) (xy 443.532457 -401.826423) (xy 443.585241 -401.808416)
			(xy 443.640084 -401.798286) (xy 443.695818 -401.796249) (xy 443.751255 -401.802349) (xy 443.805212 -401.816455)
			(xy 443.856541 -401.838267) (xy 443.904147 -401.867321) (xy 443.947015 -401.902996) (xy 443.984232 -401.944533)
			(xy 444.015005 -401.991046) (xy 444.038677 -402.041543) (xy 444.054745 -402.09495) (xy 444.062865 -402.150126)
			(xy 444.063374 -402.178012) (xy 444.06291 -402.203412) (xy 445.01003 -402.203412) (xy 445.014101 -402.14779)
			(xy 445.026227 -402.093353) (xy 445.04615 -402.041262) (xy 445.073446 -401.992627) (xy 445.107532 -401.948484)
			(xy 445.147681 -401.909775) (xy 445.193039 -401.877324) (xy 445.242639 -401.851823) (xy 445.295423 -401.833816)
			(xy 445.350266 -401.823686) (xy 445.406 -401.821649) (xy 445.461437 -401.827749) (xy 445.515394 -401.841855)
			(xy 445.566723 -401.863667) (xy 445.582363 -401.873212) (xy 451.885048 -401.873212) (xy 451.889119 -401.81759)
			(xy 451.901245 -401.763153) (xy 451.921168 -401.711062) (xy 451.948464 -401.662427) (xy 451.98255 -401.618284)
			(xy 452.022699 -401.579575) (xy 452.068057 -401.547124) (xy 452.117657 -401.521623) (xy 452.170441 -401.503616)
			(xy 452.225284 -401.493486) (xy 452.281018 -401.491449) (xy 452.336455 -401.497549) (xy 452.390412 -401.511655)
			(xy 452.441741 -401.533467) (xy 452.489347 -401.562521) (xy 452.532215 -401.598196) (xy 452.569432 -401.639733)
			(xy 452.600205 -401.686246) (xy 452.623877 -401.736743) (xy 452.639945 -401.79015) (xy 452.648065 -401.845326)
			(xy 452.648574 -401.873212) (xy 452.648065 -401.901098) (xy 452.639945 -401.956274) (xy 452.623877 -402.009681)
			(xy 452.600205 -402.060178) (xy 452.569432 -402.106691) (xy 452.532215 -402.148228) (xy 452.526947 -402.152612)
			(xy 454.098658 -402.152612) (xy 454.102729 -402.09699) (xy 454.114855 -402.042553) (xy 454.134778 -401.990462)
			(xy 454.162074 -401.941827) (xy 454.19616 -401.897684) (xy 454.236309 -401.858975) (xy 454.281667 -401.826524)
			(xy 454.331267 -401.801023) (xy 454.384051 -401.783016) (xy 454.438894 -401.772886) (xy 454.494628 -401.770849)
			(xy 454.550065 -401.776949) (xy 454.604022 -401.791055) (xy 454.655351 -401.812867) (xy 454.702957 -401.841921)
			(xy 454.745825 -401.877596) (xy 454.783042 -401.919133) (xy 454.813815 -401.965646) (xy 454.837487 -402.016143)
			(xy 454.853555 -402.06955) (xy 454.861675 -402.124726) (xy 454.862184 -402.152612) (xy 454.861675 -402.180498)
			(xy 454.853555 -402.235674) (xy 454.837487 -402.289081) (xy 454.813815 -402.339578) (xy 454.783042 -402.386091)
			(xy 454.745825 -402.427628) (xy 454.702957 -402.463303) (xy 454.655351 -402.492357) (xy 454.604022 -402.514169)
			(xy 454.550065 -402.528275) (xy 454.494628 -402.534375) (xy 454.438894 -402.532338) (xy 454.384051 -402.522208)
			(xy 454.331267 -402.504201) (xy 454.281667 -402.4787) (xy 454.236309 -402.446249) (xy 454.19616 -402.40754)
			(xy 454.162074 -402.363397) (xy 454.134778 -402.314762) (xy 454.114855 -402.262671) (xy 454.102729 -402.208234)
			(xy 454.098658 -402.152612) (xy 452.526947 -402.152612) (xy 452.489347 -402.183903) (xy 452.441741 -402.212957)
			(xy 452.390412 -402.234769) (xy 452.336455 -402.248875) (xy 452.281018 -402.254975) (xy 452.225284 -402.252938)
			(xy 452.170441 -402.242808) (xy 452.117657 -402.224801) (xy 452.068057 -402.1993) (xy 452.022699 -402.166849)
			(xy 451.98255 -402.12814) (xy 451.948464 -402.083997) (xy 451.921168 -402.035362) (xy 451.901245 -401.983271)
			(xy 451.889119 -401.928834) (xy 451.885048 -401.873212) (xy 445.582363 -401.873212) (xy 445.614329 -401.892721)
			(xy 445.657197 -401.928396) (xy 445.694414 -401.969933) (xy 445.725187 -402.016446) (xy 445.748859 -402.066943)
			(xy 445.764927 -402.12035) (xy 445.773047 -402.175526) (xy 445.773556 -402.203412) (xy 445.773047 -402.231298)
			(xy 445.764927 -402.286474) (xy 445.748859 -402.339881) (xy 445.725187 -402.390378) (xy 445.694414 -402.436891)
			(xy 445.657197 -402.478428) (xy 445.614329 -402.514103) (xy 445.566723 -402.543157) (xy 445.515394 -402.564969)
			(xy 445.461437 -402.579075) (xy 445.406 -402.585175) (xy 445.350266 -402.583138) (xy 445.295423 -402.573008)
			(xy 445.242639 -402.555001) (xy 445.193039 -402.5295) (xy 445.147681 -402.497049) (xy 445.107532 -402.45834)
			(xy 445.073446 -402.414197) (xy 445.04615 -402.365562) (xy 445.026227 -402.313471) (xy 445.014101 -402.259034)
			(xy 445.01003 -402.203412) (xy 444.06291 -402.203412) (xy 444.062865 -402.205898) (xy 444.054745 -402.261074)
			(xy 444.038677 -402.314481) (xy 444.015005 -402.364978) (xy 443.984232 -402.411491) (xy 443.947015 -402.453028)
			(xy 443.904147 -402.488703) (xy 443.856541 -402.517757) (xy 443.805212 -402.539569) (xy 443.751255 -402.553675)
			(xy 443.695818 -402.559775) (xy 443.640084 -402.557738) (xy 443.585241 -402.547608) (xy 443.532457 -402.529601)
			(xy 443.482857 -402.5041) (xy 443.437499 -402.471649) (xy 443.39735 -402.43294) (xy 443.363264 -402.388797)
			(xy 443.335968 -402.340162) (xy 443.316045 -402.288071) (xy 443.303919 -402.233634) (xy 443.299848 -402.178012)
			(xy 441.360569 -402.178012) (xy 441.368032 -402.186341) (xy 441.398805 -402.232854) (xy 441.422477 -402.283351)
			(xy 441.438545 -402.336758) (xy 441.446665 -402.391934) (xy 441.447174 -402.41982) (xy 441.446665 -402.447706)
			(xy 441.438545 -402.502882) (xy 441.422477 -402.556289) (xy 441.398805 -402.606786) (xy 441.368032 -402.653299)
			(xy 441.330815 -402.694836) (xy 441.32275 -402.701548) (xy 450.670706 -402.701548) (xy 450.670706 -402.647052)
			(xy 450.678461 -402.59311) (xy 450.693814 -402.540821) (xy 450.716452 -402.491249) (xy 450.745914 -402.445404)
			(xy 450.7816 -402.404217) (xy 450.822784 -402.368528) (xy 450.868628 -402.339063) (xy 450.918199 -402.316423)
			(xy 450.970487 -402.301067) (xy 451.024428 -402.293308) (xy 451.051676 -402.29282) (xy 451.080593 -402.293348)
			(xy 451.137764 -402.302074) (xy 451.192963 -402.31933) (xy 451.244925 -402.344719) (xy 451.292459 -402.377661)
			(xy 451.334476 -402.417401) (xy 451.352666 -402.439886) (xy 451.360249 -402.448626) (xy 451.380992 -402.458822)
			(xy 451.392544 -402.459444) (xy 451.472808 -402.459444) (xy 451.48438 -402.458898) (xy 451.505151 -402.448688)
			(xy 451.512686 -402.439886) (xy 451.530881 -402.417406) (xy 451.572901 -402.377672) (xy 451.620435 -402.344732)
			(xy 451.672395 -402.319344) (xy 451.727592 -402.302086) (xy 451.78476 -402.293356) (xy 451.813676 -402.29282)
			(xy 451.840932 -402.293225) (xy 451.89489 -402.30098) (xy 451.947194 -402.316335) (xy 451.996781 -402.338978)
			(xy 452.042641 -402.368448) (xy 452.083839 -402.404144) (xy 452.119538 -402.44534) (xy 452.149011 -402.491198)
			(xy 452.171656 -402.540783) (xy 452.187015 -402.593087) (xy 452.194773 -402.647044) (xy 452.194773 -402.701556)
			(xy 452.187015 -402.755513) (xy 452.171656 -402.807817) (xy 452.149011 -402.857402) (xy 452.119538 -402.90326)
			(xy 452.083839 -402.944456) (xy 452.042641 -402.980152) (xy 451.996781 -403.009622) (xy 451.947194 -403.032265)
			(xy 451.89489 -403.04762) (xy 451.840932 -403.055375) (xy 451.813676 -403.055836) (xy 451.78476 -403.055287)
			(xy 451.727589 -403.046568) (xy 451.67239 -403.029318) (xy 451.620427 -403.003932) (xy 451.572893 -402.970992)
			(xy 451.530876 -402.931254) (xy 451.512686 -402.90877) (xy 451.505131 -402.900001) (xy 451.484367 -402.889823)
			(xy 451.472808 -402.889212) (xy 451.392544 -402.889212) (xy 451.380979 -402.889803) (xy 451.360207 -402.899983)
			(xy 451.352666 -402.90877) (xy 451.334487 -402.931264) (xy 451.292465 -402.970999) (xy 451.244928 -403.003938)
			(xy 451.192965 -403.029325) (xy 451.137765 -403.046579) (xy 451.080593 -403.055304) (xy 451.051676 -403.055836)
			(xy 451.024428 -403.055292) (xy 450.970487 -403.047533) (xy 450.918199 -403.032177) (xy 450.868628 -403.009537)
			(xy 450.822784 -402.980072) (xy 450.7816 -402.944383) (xy 450.745914 -402.903196) (xy 450.716452 -402.857351)
			(xy 450.693814 -402.807779) (xy 450.678461 -402.75549) (xy 450.670706 -402.701548) (xy 441.32275 -402.701548)
			(xy 441.287947 -402.730511) (xy 441.240341 -402.759565) (xy 441.189012 -402.781377) (xy 441.135055 -402.795483)
			(xy 441.079618 -402.801583) (xy 441.023884 -402.799546) (xy 440.969041 -402.789416) (xy 440.916257 -402.771409)
			(xy 440.866657 -402.745908) (xy 440.821299 -402.713457) (xy 440.78115 -402.674748) (xy 440.747064 -402.630605)
			(xy 440.719768 -402.58197) (xy 440.699845 -402.529879) (xy 440.687719 -402.475442) (xy 440.683648 -402.41982)
			(xy 436.366412 -402.41982) (xy 437.223662 -403.27707) (xy 443.122048 -403.27707) (xy 443.126119 -403.221448)
			(xy 443.138245 -403.167011) (xy 443.158168 -403.11492) (xy 443.185464 -403.066285) (xy 443.21955 -403.022142)
			(xy 443.259699 -402.983433) (xy 443.305057 -402.950982) (xy 443.354657 -402.925481) (xy 443.407441 -402.907474)
			(xy 443.462284 -402.897344) (xy 443.518018 -402.895307) (xy 443.573455 -402.901407) (xy 443.627412 -402.915513)
			(xy 443.678741 -402.937325) (xy 443.726347 -402.966379) (xy 443.769215 -403.002054) (xy 443.806432 -403.043591)
			(xy 443.837205 -403.090104) (xy 443.860877 -403.140601) (xy 443.876945 -403.194008) (xy 443.885065 -403.249184)
			(xy 443.885574 -403.27707) (xy 443.885065 -403.304956) (xy 443.876945 -403.360132) (xy 443.860877 -403.413539)
			(xy 443.837205 -403.464036) (xy 443.806432 -403.510549) (xy 443.769215 -403.552086) (xy 443.726347 -403.587761)
			(xy 443.678741 -403.616815) (xy 443.627412 -403.638627) (xy 443.573455 -403.652733) (xy 443.518018 -403.658833)
			(xy 443.462284 -403.656796) (xy 443.407441 -403.646666) (xy 443.354657 -403.628659) (xy 443.305057 -403.603158)
			(xy 443.259699 -403.570707) (xy 443.21955 -403.531998) (xy 443.185464 -403.487855) (xy 443.158168 -403.43922)
			(xy 443.138245 -403.387129) (xy 443.126119 -403.332692) (xy 443.122048 -403.27707) (xy 437.223662 -403.27707)
			(xy 438.63768 -404.691088) (xy 438.644531 -404.698485) (xy 438.652273 -404.717083) (xy 438.652666 -404.727156)
			(xy 438.652666 -406.209246) (xy 448.698112 -406.209246) (xy 448.698678 -406.179635) (xy 448.707823 -406.121123)
			(xy 448.7259 -406.064727) (xy 448.752476 -406.011803) (xy 448.786911 -405.963621) (xy 448.828378 -405.92134)
			(xy 448.875882 -405.885974) (xy 448.90182 -405.87168) (xy 448.913621 -405.865041) (xy 448.933432 -405.846593)
			(xy 448.947695 -405.823585) (xy 448.955406 -405.797636) (xy 448.956023 -405.770573) (xy 448.949502 -405.7443)
			(xy 448.936302 -405.720666) (xy 448.917353 -405.701334) (xy 448.905884 -405.694134) (xy 448.881637 -405.679373)
			(xy 448.837444 -405.643748) (xy 448.799017 -405.601968) (xy 448.767207 -405.554953) (xy 448.742716 -405.503744)
			(xy 448.726084 -405.449471) (xy 448.717679 -405.393332) (xy 448.717162 -405.36495) (xy 448.717648 -405.337699)
			(xy 448.725404 -405.283751) (xy 448.740759 -405.231456) (xy 448.763401 -405.181879) (xy 448.792867 -405.136029)
			(xy 448.828558 -405.094838) (xy 448.869749 -405.059147) (xy 448.915599 -405.029681) (xy 448.965176 -405.007039)
			(xy 449.017471 -404.991684) (xy 449.071419 -404.983928) (xy 449.125921 -404.983928) (xy 449.179869 -404.991684)
			(xy 449.232164 -405.007039) (xy 449.281741 -405.029681) (xy 449.327591 -405.059147) (xy 449.368782 -405.094838)
			(xy 449.404473 -405.136029) (xy 449.433939 -405.181879) (xy 449.456581 -405.231456) (xy 449.471936 -405.283751)
			(xy 449.479692 -405.337699) (xy 449.480178 -405.36495) (xy 449.479614 -405.394561) (xy 449.47047 -405.453073)
			(xy 449.452392 -405.509469) (xy 449.425817 -405.562394) (xy 449.391381 -405.610576) (xy 449.349913 -405.652857)
			(xy 449.302409 -405.688222) (xy 449.27647 -405.702516) (xy 449.264673 -405.709161) (xy 449.244864 -405.727609)
			(xy 449.230603 -405.750616) (xy 449.222893 -405.776563) (xy 449.222275 -405.803624) (xy 449.228795 -405.829896)
			(xy 449.241992 -405.853529) (xy 449.260939 -405.872861) (xy 449.272406 -405.880062) (xy 449.296649 -405.894829)
			(xy 449.340843 -405.930453) (xy 449.37927 -405.972232) (xy 449.41108 -406.019245) (xy 449.435572 -406.070453)
			(xy 449.452205 -406.124726) (xy 449.46061 -406.180864) (xy 449.461128 -406.209246) (xy 449.460642 -406.236497)
			(xy 449.452886 -406.290445) (xy 449.437531 -406.34274) (xy 449.433305 -406.351994) (xy 456.067414 -406.351994)
			(xy 456.067927 -406.323785) (xy 456.076229 -406.267981) (xy 456.092666 -406.214011) (xy 456.116878 -406.163053)
			(xy 456.148338 -406.11622) (xy 456.186356 -406.074536) (xy 456.230104 -406.038912) (xy 456.254104 -406.02408)
			(xy 456.266496 -406.016145) (xy 456.286401 -405.994487) (xy 456.299322 -405.968061) (xy 456.30419 -405.939051)
			(xy 456.300602 -405.909854) (xy 456.288857 -405.882886) (xy 456.269923 -405.860373) (xy 456.257914 -405.851868)
			(xy 456.235704 -405.836632) (xy 456.195365 -405.800945) (xy 456.160445 -405.759942) (xy 456.131636 -405.714436)
			(xy 456.109511 -405.665331) (xy 456.09451 -405.613604) (xy 456.08693 -405.560281) (xy 456.086464 -405.533352)
			(xy 456.08695 -405.506101) (xy 456.094706 -405.452153) (xy 456.110061 -405.399858) (xy 456.132703 -405.350281)
			(xy 456.162169 -405.304431) (xy 456.19786 -405.26324) (xy 456.239051 -405.227549) (xy 456.284901 -405.198083)
			(xy 456.334478 -405.175441) (xy 456.386773 -405.160086) (xy 456.440721 -405.15233) (xy 456.495223 -405.15233)
			(xy 456.549171 -405.160086) (xy 456.601466 -405.175441) (xy 456.651043 -405.198083) (xy 456.696893 -405.227549)
			(xy 456.738084 -405.26324) (xy 456.773775 -405.304431) (xy 456.803241 -405.350281) (xy 456.825883 -405.399858)
			(xy 456.841238 -405.452153) (xy 456.848994 -405.506101) (xy 456.84948 -405.533352) (xy 456.848927 -405.56156)
			(xy 456.840633 -405.617362) (xy 456.824203 -405.671331) (xy 456.799998 -405.722289) (xy 456.768544 -405.769122)
			(xy 456.730531 -405.810808) (xy 456.686788 -405.846434) (xy 456.66279 -405.861266) (xy 456.650449 -405.869273)
			(xy 456.630548 -405.890916) (xy 456.617626 -405.917326) (xy 456.612753 -405.946321) (xy 456.61633 -405.975505)
			(xy 456.628062 -406.002465) (xy 456.646979 -406.024973) (xy 456.65898 -406.033478) (xy 456.68121 -406.048686)
			(xy 456.721549 -406.084377) (xy 456.756468 -406.125386) (xy 456.785275 -406.170896) (xy 456.807396 -406.220005)
			(xy 456.822393 -406.271737) (xy 456.829967 -406.325063) (xy 456.83043 -406.351994) (xy 456.829944 -406.379245)
			(xy 456.822188 -406.433193) (xy 456.806833 -406.485488) (xy 456.784191 -406.535065) (xy 456.754725 -406.580915)
			(xy 456.719034 -406.622106) (xy 456.677843 -406.657797) (xy 456.631993 -406.687263) (xy 456.582416 -406.709905)
			(xy 456.530121 -406.72526) (xy 456.476173 -406.733016) (xy 456.421671 -406.733016) (xy 456.367723 -406.72526)
			(xy 456.315428 -406.709905) (xy 456.265851 -406.687263) (xy 456.220001 -406.657797) (xy 456.17881 -406.622106)
			(xy 456.143119 -406.580915) (xy 456.113653 -406.535065) (xy 456.091011 -406.485488) (xy 456.075656 -406.433193)
			(xy 456.0679 -406.379245) (xy 456.067414 -406.351994) (xy 449.433305 -406.351994) (xy 449.414889 -406.392317)
			(xy 449.385423 -406.438167) (xy 449.349732 -406.479358) (xy 449.308541 -406.515049) (xy 449.262691 -406.544515)
			(xy 449.213114 -406.567157) (xy 449.160819 -406.582512) (xy 449.106871 -406.590268) (xy 449.052369 -406.590268)
			(xy 448.998421 -406.582512) (xy 448.946126 -406.567157) (xy 448.896549 -406.544515) (xy 448.850699 -406.515049)
			(xy 448.809508 -406.479358) (xy 448.773817 -406.438167) (xy 448.744351 -406.392317) (xy 448.721709 -406.34274)
			(xy 448.706354 -406.290445) (xy 448.698598 -406.236497) (xy 448.698112 -406.209246) (xy 438.652666 -406.209246)
			(xy 438.652666 -406.931622) (xy 439.08929 -406.931622) (xy 439.093361 -406.876) (xy 439.105487 -406.821563)
			(xy 439.12541 -406.769472) (xy 439.152706 -406.720837) (xy 439.186792 -406.676694) (xy 439.226941 -406.637985)
			(xy 439.272299 -406.605534) (xy 439.321899 -406.580033) (xy 439.374683 -406.562026) (xy 439.429526 -406.551896)
			(xy 439.48526 -406.549859) (xy 439.540697 -406.555959) (xy 439.594654 -406.570065) (xy 439.645983 -406.591877)
			(xy 439.693589 -406.620931) (xy 439.736457 -406.656606) (xy 439.773674 -406.698143) (xy 439.804447 -406.744656)
			(xy 439.828119 -406.795153) (xy 439.844187 -406.84856) (xy 439.852307 -406.903736) (xy 439.852816 -406.931622)
			(xy 439.852307 -406.959508) (xy 439.844187 -407.014684) (xy 439.828119 -407.068091) (xy 439.804447 -407.118588)
			(xy 439.773674 -407.165101) (xy 439.742543 -407.199846) (xy 448.698112 -407.199846) (xy 448.698598 -407.172595)
			(xy 448.706354 -407.118647) (xy 448.721709 -407.066352) (xy 448.744351 -407.016775) (xy 448.773817 -406.970925)
			(xy 448.809508 -406.929734) (xy 448.850699 -406.894043) (xy 448.896549 -406.864577) (xy 448.946126 -406.841935)
			(xy 448.998421 -406.82658) (xy 449.052369 -406.818824) (xy 449.106871 -406.818824) (xy 449.160819 -406.82658)
			(xy 449.213114 -406.841935) (xy 449.262691 -406.864577) (xy 449.308541 -406.894043) (xy 449.349732 -406.929734)
			(xy 449.385423 -406.970925) (xy 449.414889 -407.016775) (xy 449.437531 -407.066352) (xy 449.452886 -407.118647)
			(xy 449.460642 -407.172595) (xy 449.461128 -407.199846) (xy 449.460563 -407.228837) (xy 449.451777 -407.286151)
			(xy 449.43798 -407.330148) (xy 456.075796 -407.330148) (xy 456.076282 -407.302897) (xy 456.084038 -407.248949)
			(xy 456.099393 -407.196654) (xy 456.122035 -407.147077) (xy 456.151501 -407.101227) (xy 456.187192 -407.060036)
			(xy 456.228383 -407.024345) (xy 456.274233 -406.994879) (xy 456.32381 -406.972237) (xy 456.376105 -406.956882)
			(xy 456.430053 -406.949126) (xy 456.484555 -406.949126) (xy 456.538503 -406.956882) (xy 456.590798 -406.972237)
			(xy 456.640375 -406.994879) (xy 456.686225 -407.024345) (xy 456.727416 -407.060036) (xy 456.763107 -407.101227)
			(xy 456.792573 -407.147077) (xy 456.815215 -407.196654) (xy 456.83057 -407.248949) (xy 456.838326 -407.302897)
			(xy 456.838812 -407.330148) (xy 456.838291 -407.35901) (xy 456.829609 -407.416078) (xy 456.812419 -407.471184)
			(xy 456.787116 -407.523067) (xy 456.754278 -407.570541) (xy 456.714656 -407.612519) (xy 456.669156 -407.648043)
			(xy 456.644248 -407.662634) (xy 456.632498 -407.669733) (xy 456.61303 -407.689076) (xy 456.599416 -407.712904)
			(xy 456.592637 -407.739497) (xy 456.593184 -407.766935) (xy 456.601016 -407.793237) (xy 456.615569 -407.816504)
			(xy 456.635792 -407.835056) (xy 456.647804 -407.841704) (xy 456.670957 -407.854001) (xy 456.713937 -407.884023)
			(xy 456.752403 -407.919644) (xy 456.785633 -407.960193) (xy 456.813001 -408.004909) (xy 456.833993 -408.05295)
			(xy 456.848213 -408.103411) (xy 456.855393 -408.155343) (xy 456.85583 -408.181556) (xy 456.855344 -408.208807)
			(xy 456.847588 -408.262755) (xy 456.832233 -408.31505) (xy 456.809591 -408.364627) (xy 456.780125 -408.410477)
			(xy 456.744434 -408.451668) (xy 456.703243 -408.487359) (xy 456.657393 -408.516825) (xy 456.607816 -408.539467)
			(xy 456.555521 -408.554822) (xy 456.501573 -408.562578) (xy 456.447071 -408.562578) (xy 456.393123 -408.554822)
			(xy 456.340828 -408.539467) (xy 456.291251 -408.516825) (xy 456.245401 -408.487359) (xy 456.20421 -408.451668)
			(xy 456.168519 -408.410477) (xy 456.139053 -408.364627) (xy 456.116411 -408.31505) (xy 456.101056 -408.262755)
			(xy 456.0933 -408.208807) (xy 456.092814 -408.181556) (xy 456.093325 -408.152693) (xy 456.102008 -408.095624)
			(xy 456.119198 -408.040518) (xy 456.144503 -407.988634) (xy 456.177343 -407.94116) (xy 456.216967 -407.899183)
			(xy 456.262469 -407.863661) (xy 456.287378 -407.84907) (xy 456.299122 -407.841963) (xy 456.318584 -407.822619)
			(xy 456.332195 -407.798793) (xy 456.338971 -407.772203) (xy 456.338425 -407.744769) (xy 456.330596 -407.718469)
			(xy 456.316048 -407.695203) (xy 456.295831 -407.67665) (xy 456.283822 -407.67) (xy 456.260676 -407.657689)
			(xy 456.217696 -407.62767) (xy 456.179228 -407.592052) (xy 456.145997 -407.551504) (xy 456.118628 -407.50679)
			(xy 456.097635 -407.458752) (xy 456.083415 -407.408292) (xy 456.076233 -407.356361) (xy 456.075796 -407.330148)
			(xy 449.43798 -407.330148) (xy 449.434427 -407.341477) (xy 449.408913 -407.393546) (xy 449.375822 -407.441159)
			(xy 449.335914 -407.483223) (xy 449.290106 -407.51877) (xy 449.26504 -407.533348) (xy 449.25296 -407.540612)
			(xy 449.233005 -407.560503) (xy 449.219245 -407.585089) (xy 449.212726 -407.6125) (xy 449.213945 -407.640649)
			(xy 449.222808 -407.667394) (xy 449.238641 -407.690699) (xy 449.260239 -407.708792) (xy 449.272914 -407.714958)
			(xy 449.29783 -407.726553) (xy 449.344309 -407.755877) (xy 449.386098 -407.791567) (xy 449.422332 -407.832886)
			(xy 449.452262 -407.878977) (xy 449.475267 -407.928886) (xy 449.490871 -407.98158) (xy 449.498752 -408.035968)
			(xy 449.499228 -408.063446) (xy 449.498742 -408.090697) (xy 449.490986 -408.144645) (xy 449.475631 -408.19694)
			(xy 449.452989 -408.246517) (xy 449.423523 -408.292367) (xy 449.387832 -408.333558) (xy 449.346641 -408.369249)
			(xy 449.300791 -408.398715) (xy 449.251214 -408.421357) (xy 449.198919 -408.436712) (xy 449.144971 -408.444468)
			(xy 449.090469 -408.444468) (xy 449.036521 -408.436712) (xy 448.984226 -408.421357) (xy 448.934649 -408.398715)
			(xy 448.888799 -408.369249) (xy 448.847608 -408.333558) (xy 448.811917 -408.292367) (xy 448.782451 -408.246517)
			(xy 448.759809 -408.19694) (xy 448.744454 -408.144645) (xy 448.736698 -408.090697) (xy 448.736212 -408.063446)
			(xy 448.73675 -408.034453) (xy 448.745539 -407.977138) (xy 448.762892 -407.92181) (xy 448.788409 -407.869741)
			(xy 448.821505 -407.822128) (xy 448.861418 -407.780065) (xy 448.907232 -407.74452) (xy 448.9323 -407.729944)
			(xy 448.944382 -407.722687) (xy 448.964329 -407.702791) (xy 448.978083 -407.678204) (xy 448.984598 -407.650795)
			(xy 448.983379 -407.622649) (xy 448.974518 -407.595905) (xy 448.95869 -407.5726) (xy 448.937098 -407.554503)
			(xy 448.924426 -407.548334) (xy 448.899516 -407.536726) (xy 448.853036 -407.507406) (xy 448.811245 -407.471718)
			(xy 448.775009 -407.430402) (xy 448.745078 -407.384313) (xy 448.722072 -407.334405) (xy 448.706468 -407.281711)
			(xy 448.698588 -407.227324) (xy 448.698112 -407.199846) (xy 439.742543 -407.199846) (xy 439.736457 -407.206638)
			(xy 439.693589 -407.242313) (xy 439.645983 -407.271367) (xy 439.594654 -407.293179) (xy 439.540697 -407.307285)
			(xy 439.48526 -407.313385) (xy 439.429526 -407.311348) (xy 439.374683 -407.301218) (xy 439.321899 -407.283211)
			(xy 439.272299 -407.25771) (xy 439.226941 -407.225259) (xy 439.186792 -407.18655) (xy 439.152706 -407.142407)
			(xy 439.12541 -407.093772) (xy 439.105487 -407.041681) (xy 439.093361 -406.987244) (xy 439.08929 -406.931622)
			(xy 438.652666 -406.931622) (xy 438.652666 -410.578554) (xy 446.710306 -410.578554) (xy 446.714377 -410.522932)
			(xy 446.726503 -410.468495) (xy 446.746426 -410.416404) (xy 446.773722 -410.367769) (xy 446.807808 -410.323626)
			(xy 446.847957 -410.284917) (xy 446.893315 -410.252466) (xy 446.942915 -410.226965) (xy 446.995699 -410.208958)
			(xy 447.050542 -410.198828) (xy 447.106276 -410.196791) (xy 447.161713 -410.202891) (xy 447.21567 -410.216997)
			(xy 447.266999 -410.238809) (xy 447.314605 -410.267863) (xy 447.357473 -410.303538) (xy 447.39469 -410.345075)
			(xy 447.425463 -410.391588) (xy 447.449135 -410.442085) (xy 447.465203 -410.495492) (xy 447.473323 -410.550668)
			(xy 447.473832 -410.578554) (xy 447.599306 -410.578554) (xy 447.603377 -410.522932) (xy 447.615503 -410.468495)
			(xy 447.635426 -410.416404) (xy 447.662722 -410.367769) (xy 447.696808 -410.323626) (xy 447.736957 -410.284917)
			(xy 447.782315 -410.252466) (xy 447.831915 -410.226965) (xy 447.884699 -410.208958) (xy 447.939542 -410.198828)
			(xy 447.995276 -410.196791) (xy 448.050713 -410.202891) (xy 448.10467 -410.216997) (xy 448.155999 -410.238809)
			(xy 448.203605 -410.267863) (xy 448.246473 -410.303538) (xy 448.28369 -410.345075) (xy 448.314463 -410.391588)
			(xy 448.338135 -410.442085) (xy 448.354203 -410.495492) (xy 448.362323 -410.550668) (xy 448.362832 -410.578554)
			(xy 448.488306 -410.578554) (xy 448.492377 -410.522932) (xy 448.504503 -410.468495) (xy 448.524426 -410.416404)
			(xy 448.551722 -410.367769) (xy 448.585808 -410.323626) (xy 448.625957 -410.284917) (xy 448.671315 -410.252466)
			(xy 448.720915 -410.226965) (xy 448.773699 -410.208958) (xy 448.828542 -410.198828) (xy 448.884276 -410.196791)
			(xy 448.939713 -410.202891) (xy 448.99367 -410.216997) (xy 449.044999 -410.238809) (xy 449.092605 -410.267863)
			(xy 449.135473 -410.303538) (xy 449.17269 -410.345075) (xy 449.203463 -410.391588) (xy 449.227135 -410.442085)
			(xy 449.243203 -410.495492) (xy 449.251323 -410.550668) (xy 449.251832 -410.578554) (xy 449.251323 -410.60644)
			(xy 449.243203 -410.661616) (xy 449.227135 -410.715023) (xy 449.203463 -410.76552) (xy 449.17269 -410.812033)
			(xy 449.135473 -410.85357) (xy 449.092605 -410.889245) (xy 449.071044 -410.902404) (xy 451.091808 -410.902404)
			(xy 451.092365 -410.87228) (xy 451.101847 -410.812782) (xy 451.12056 -410.755513) (xy 451.14804 -410.701897)
			(xy 451.183603 -410.653264) (xy 451.204584 -410.63164) (xy 451.21195 -410.624528) (xy 451.21957 -410.605732)
			(xy 451.21957 -410.513276) (xy 451.21195 -410.49448) (xy 451.204584 -410.487368) (xy 451.183608 -410.465739)
			(xy 451.14804 -410.417111) (xy 451.12056 -410.363495) (xy 451.10185 -410.306226) (xy 451.092377 -410.246728)
			(xy 451.091808 -410.216604) (xy 451.092259 -410.189351) (xy 451.100016 -410.135398) (xy 451.115372 -410.083099)
			(xy 451.138015 -410.033518) (xy 451.167485 -409.987664) (xy 451.20318 -409.946471) (xy 451.244374 -409.910777)
			(xy 451.290229 -409.88131) (xy 451.339811 -409.858668) (xy 451.39211 -409.843313) (xy 451.446063 -409.835558)
			(xy 451.473316 -409.835096) (xy 451.503441 -409.835643) (xy 451.562939 -409.845128) (xy 451.620207 -409.863844)
			(xy 451.673824 -409.891325) (xy 451.722457 -409.92689) (xy 451.74408 -409.947872) (xy 451.751192 -409.955238)
			(xy 451.769988 -409.962858) (xy 451.862444 -409.962858) (xy 451.88124 -409.955238) (xy 451.888352 -409.947872)
			(xy 451.909987 -409.926903) (xy 451.958612 -409.89133) (xy 452.012225 -409.863847) (xy 452.069494 -409.845136)
			(xy 452.128992 -409.835665) (xy 452.159116 -409.835096) (xy 452.186487 -409.835554) (xy 452.240666 -409.843374)
			(xy 452.293169 -409.858865) (xy 452.342916 -409.881708) (xy 452.388882 -409.911434) (xy 452.409814 -409.929076)
			(xy 452.416926 -409.935172) (xy 452.433944 -409.941522) (xy 452.519288 -409.941522) (xy 452.536306 -409.935172)
			(xy 452.543418 -409.929076) (xy 452.564367 -409.911458) (xy 452.610336 -409.881744) (xy 452.660079 -409.858904)
			(xy 452.712576 -409.843408) (xy 452.766748 -409.835574) (xy 452.794116 -409.835096) (xy 452.821368 -409.835563)
			(xy 452.875316 -409.843322) (xy 452.927612 -409.858679) (xy 452.977189 -409.881322) (xy 453.02304 -409.910791)
			(xy 453.06423 -409.946484) (xy 453.099921 -409.987676) (xy 453.129387 -410.033528) (xy 453.152028 -410.083107)
			(xy 453.167383 -410.135403) (xy 453.175139 -410.189352) (xy 453.175624 -410.216604) (xy 453.175063 -410.246728)
			(xy 453.165581 -410.306225) (xy 453.146868 -410.363493) (xy 453.11939 -410.41711) (xy 453.083828 -410.465744)
			(xy 453.062848 -410.487368) (xy 453.055482 -410.49448) (xy 453.047862 -410.513276) (xy 453.047862 -410.6037)
			(xy 454.780648 -410.6037) (xy 454.784719 -410.548078) (xy 454.796845 -410.493641) (xy 454.816768 -410.44155)
			(xy 454.844064 -410.392915) (xy 454.87815 -410.348772) (xy 454.918299 -410.310063) (xy 454.963657 -410.277612)
			(xy 455.013257 -410.252111) (xy 455.066041 -410.234104) (xy 455.120884 -410.223974) (xy 455.176618 -410.221937)
			(xy 455.232055 -410.228037) (xy 455.286012 -410.242143) (xy 455.337341 -410.263955) (xy 455.384947 -410.293009)
			(xy 455.427815 -410.328684) (xy 455.465032 -410.370221) (xy 455.495805 -410.416734) (xy 455.519477 -410.467231)
			(xy 455.535545 -410.520638) (xy 455.543665 -410.575814) (xy 455.544174 -410.6037) (xy 455.669648 -410.6037)
			(xy 455.673719 -410.548078) (xy 455.685845 -410.493641) (xy 455.705768 -410.44155) (xy 455.733064 -410.392915)
			(xy 455.76715 -410.348772) (xy 455.807299 -410.310063) (xy 455.852657 -410.277612) (xy 455.902257 -410.252111)
			(xy 455.955041 -410.234104) (xy 456.009884 -410.223974) (xy 456.065618 -410.221937) (xy 456.121055 -410.228037)
			(xy 456.175012 -410.242143) (xy 456.226341 -410.263955) (xy 456.273947 -410.293009) (xy 456.316815 -410.328684)
			(xy 456.354032 -410.370221) (xy 456.384805 -410.416734) (xy 456.408477 -410.467231) (xy 456.424545 -410.520638)
			(xy 456.432665 -410.575814) (xy 456.433174 -410.6037) (xy 456.558648 -410.6037) (xy 456.562719 -410.548078)
			(xy 456.574845 -410.493641) (xy 456.594768 -410.44155) (xy 456.622064 -410.392915) (xy 456.65615 -410.348772)
			(xy 456.696299 -410.310063) (xy 456.741657 -410.277612) (xy 456.791257 -410.252111) (xy 456.844041 -410.234104)
			(xy 456.898884 -410.223974) (xy 456.954618 -410.221937) (xy 457.010055 -410.228037) (xy 457.064012 -410.242143)
			(xy 457.115341 -410.263955) (xy 457.162947 -410.293009) (xy 457.205815 -410.328684) (xy 457.243032 -410.370221)
			(xy 457.273805 -410.416734) (xy 457.297477 -410.467231) (xy 457.313545 -410.520638) (xy 457.321665 -410.575814)
			(xy 457.322174 -410.6037) (xy 457.321665 -410.631586) (xy 457.313545 -410.686762) (xy 457.297477 -410.740169)
			(xy 457.273805 -410.790666) (xy 457.243032 -410.837179) (xy 457.205815 -410.878716) (xy 457.162947 -410.914391)
			(xy 457.115341 -410.943445) (xy 457.064012 -410.965257) (xy 457.010055 -410.979363) (xy 456.954618 -410.985463)
			(xy 456.898884 -410.983426) (xy 456.844041 -410.973296) (xy 456.791257 -410.955289) (xy 456.741657 -410.929788)
			(xy 456.696299 -410.897337) (xy 456.65615 -410.858628) (xy 456.622064 -410.814485) (xy 456.594768 -410.76585)
			(xy 456.574845 -410.713759) (xy 456.562719 -410.659322) (xy 456.558648 -410.6037) (xy 456.433174 -410.6037)
			(xy 456.432665 -410.631586) (xy 456.424545 -410.686762) (xy 456.408477 -410.740169) (xy 456.384805 -410.790666)
			(xy 456.354032 -410.837179) (xy 456.316815 -410.878716) (xy 456.273947 -410.914391) (xy 456.226341 -410.943445)
			(xy 456.175012 -410.965257) (xy 456.121055 -410.979363) (xy 456.065618 -410.985463) (xy 456.009884 -410.983426)
			(xy 455.955041 -410.973296) (xy 455.902257 -410.955289) (xy 455.852657 -410.929788) (xy 455.807299 -410.897337)
			(xy 455.76715 -410.858628) (xy 455.733064 -410.814485) (xy 455.705768 -410.76585) (xy 455.685845 -410.713759)
			(xy 455.673719 -410.659322) (xy 455.669648 -410.6037) (xy 455.544174 -410.6037) (xy 455.543665 -410.631586)
			(xy 455.535545 -410.686762) (xy 455.519477 -410.740169) (xy 455.495805 -410.790666) (xy 455.465032 -410.837179)
			(xy 455.427815 -410.878716) (xy 455.384947 -410.914391) (xy 455.337341 -410.943445) (xy 455.286012 -410.965257)
			(xy 455.232055 -410.979363) (xy 455.176618 -410.985463) (xy 455.120884 -410.983426) (xy 455.066041 -410.973296)
			(xy 455.013257 -410.955289) (xy 454.963657 -410.929788) (xy 454.918299 -410.897337) (xy 454.87815 -410.858628)
			(xy 454.844064 -410.814485) (xy 454.816768 -410.76585) (xy 454.796845 -410.713759) (xy 454.784719 -410.659322)
			(xy 454.780648 -410.6037) (xy 453.047862 -410.6037) (xy 453.047862 -410.605732) (xy 453.055482 -410.624528)
			(xy 453.062848 -410.63164) (xy 453.083816 -410.653277) (xy 453.119388 -410.701901) (xy 453.146871 -410.755515)
			(xy 453.165582 -410.812783) (xy 453.175055 -410.87228) (xy 453.175624 -410.902404) (xy 453.175126 -410.929655)
			(xy 453.167369 -410.983601) (xy 453.152015 -411.035895) (xy 453.129374 -411.085471) (xy 453.099909 -411.13132)
			(xy 453.064219 -411.17251) (xy 453.02303 -411.208202) (xy 452.977181 -411.237668) (xy 452.927606 -411.26031)
			(xy 452.875313 -411.275667) (xy 452.821367 -411.283425) (xy 452.794116 -411.283912) (xy 452.766746 -411.283434)
			(xy 452.712568 -411.275618) (xy 452.660065 -411.260132) (xy 452.610318 -411.237293) (xy 452.56435 -411.207572)
			(xy 452.543418 -411.189932) (xy 452.536306 -411.183836) (xy 452.519288 -411.177486) (xy 452.433944 -411.177486)
			(xy 452.416926 -411.183836) (xy 452.409814 -411.189932) (xy 452.388892 -411.207583) (xy 452.342916 -411.237292)
			(xy 452.293166 -411.260125) (xy 452.240663 -411.275613) (xy 452.186486 -411.283439) (xy 452.159116 -411.283912)
			(xy 452.128992 -411.283342) (xy 452.069496 -411.273862) (xy 452.012227 -411.255152) (xy 451.95861 -411.227675)
			(xy 451.909976 -411.192116) (xy 451.888352 -411.171136) (xy 451.88124 -411.16377) (xy 451.862444 -411.15615)
			(xy 451.769988 -411.15615) (xy 451.751192 -411.16377) (xy 451.74408 -411.171136) (xy 451.722432 -411.192091)
			(xy 451.673811 -411.227665) (xy 451.6202 -411.255151) (xy 451.562935 -411.273865) (xy 451.503439 -411.283341)
			(xy 451.473316 -411.283912) (xy 451.446064 -411.28343) (xy 451.392114 -411.275675) (xy 451.339816 -411.260321)
			(xy 451.290237 -411.237681) (xy 451.244384 -411.208215) (xy 451.203191 -411.172523) (xy 451.167497 -411.131332)
			(xy 451.138029 -411.085481) (xy 451.115386 -411.035902) (xy 451.100029 -410.983606) (xy 451.092272 -410.929656)
			(xy 451.091808 -410.902404) (xy 449.071044 -410.902404) (xy 449.044999 -410.918299) (xy 448.99367 -410.940111)
			(xy 448.939713 -410.954217) (xy 448.884276 -410.960317) (xy 448.828542 -410.95828) (xy 448.773699 -410.94815)
			(xy 448.720915 -410.930143) (xy 448.671315 -410.904642) (xy 448.625957 -410.872191) (xy 448.585808 -410.833482)
			(xy 448.551722 -410.789339) (xy 448.524426 -410.740704) (xy 448.504503 -410.688613) (xy 448.492377 -410.634176)
			(xy 448.488306 -410.578554) (xy 448.362832 -410.578554) (xy 448.362323 -410.60644) (xy 448.354203 -410.661616)
			(xy 448.338135 -410.715023) (xy 448.314463 -410.76552) (xy 448.28369 -410.812033) (xy 448.246473 -410.85357)
			(xy 448.203605 -410.889245) (xy 448.155999 -410.918299) (xy 448.10467 -410.940111) (xy 448.050713 -410.954217)
			(xy 447.995276 -410.960317) (xy 447.939542 -410.95828) (xy 447.884699 -410.94815) (xy 447.831915 -410.930143)
			(xy 447.782315 -410.904642) (xy 447.736957 -410.872191) (xy 447.696808 -410.833482) (xy 447.662722 -410.789339)
			(xy 447.635426 -410.740704) (xy 447.615503 -410.688613) (xy 447.603377 -410.634176) (xy 447.599306 -410.578554)
			(xy 447.473832 -410.578554) (xy 447.473323 -410.60644) (xy 447.465203 -410.661616) (xy 447.449135 -410.715023)
			(xy 447.425463 -410.76552) (xy 447.39469 -410.812033) (xy 447.357473 -410.85357) (xy 447.314605 -410.889245)
			(xy 447.266999 -410.918299) (xy 447.21567 -410.940111) (xy 447.161713 -410.954217) (xy 447.106276 -410.960317)
			(xy 447.050542 -410.95828) (xy 446.995699 -410.94815) (xy 446.942915 -410.930143) (xy 446.893315 -410.904642)
			(xy 446.847957 -410.872191) (xy 446.807808 -410.833482) (xy 446.773722 -410.789339) (xy 446.746426 -410.740704)
			(xy 446.726503 -410.688613) (xy 446.714377 -410.634176) (xy 446.710306 -410.578554) (xy 438.652666 -410.578554)
			(xy 438.652666 -415.147252) (xy 449.363338 -415.147252) (xy 449.363825 -415.119882) (xy 449.371637 -415.065704)
			(xy 449.38712 -415.013201) (xy 449.409957 -414.963453) (xy 449.439678 -414.917486) (xy 449.457318 -414.896554)
			(xy 449.463414 -414.889442) (xy 449.469764 -414.872424) (xy 449.469764 -414.78708) (xy 449.463414 -414.770062)
			(xy 449.457318 -414.76295) (xy 449.439692 -414.742008) (xy 449.409977 -414.696038) (xy 449.387139 -414.646293)
			(xy 449.371645 -414.593795) (xy 449.363813 -414.539621) (xy 449.363338 -414.512252) (xy 449.363733 -414.484997)
			(xy 449.371498 -414.431044) (xy 449.386861 -414.378745) (xy 449.409511 -414.329164) (xy 449.438987 -414.283312)
			(xy 449.474688 -414.242121) (xy 449.515887 -414.20643) (xy 449.561747 -414.176966) (xy 449.611333 -414.154328)
			(xy 449.663636 -414.138978) (xy 449.717591 -414.131227) (xy 449.744846 -414.130744) (xy 449.774968 -414.13135)
			(xy 449.834463 -414.140823) (xy 449.89173 -414.159526) (xy 449.945348 -414.186993) (xy 449.993984 -414.222544)
			(xy 450.01561 -414.24352) (xy 450.022722 -414.250886) (xy 450.041518 -414.258506) (xy 450.133974 -414.258506)
			(xy 450.15277 -414.250886) (xy 450.159882 -414.24352) (xy 450.181495 -414.222527) (xy 450.230127 -414.186959)
			(xy 450.283746 -414.159481) (xy 450.341019 -414.140776) (xy 450.400521 -414.13131) (xy 450.430646 -414.130744)
			(xy 450.457896 -414.131235) (xy 450.511841 -414.138996) (xy 450.564133 -414.154355) (xy 450.613707 -414.176998)
			(xy 450.659555 -414.206465) (xy 450.700743 -414.242155) (xy 450.736434 -414.283343) (xy 450.765901 -414.329191)
			(xy 450.788544 -414.378765) (xy 450.803903 -414.431057) (xy 450.811665 -414.485002) (xy 450.812154 -414.512252)
			(xy 450.811597 -414.541729) (xy 450.802533 -414.599982) (xy 450.784616 -414.656147) (xy 450.75827 -414.708887)
			(xy 450.724123 -414.756945) (xy 450.70395 -414.778444) (xy 450.697396 -414.785764) (xy 450.689964 -414.803936)
			(xy 450.689472 -414.81375) (xy 450.689472 -414.86709) (xy 450.702426 -414.879536) (xy 450.710329 -414.886933)
			(xy 450.730463 -414.894828) (xy 450.741288 -414.894776) (xy 450.7738 -414.892998) (xy 450.784574 -414.891856)
			(xy 450.803779 -414.881872) (xy 450.810884 -414.873694) (xy 450.829064 -414.851551) (xy 450.870964 -414.812479)
			(xy 450.918237 -414.780112) (xy 450.969818 -414.755179) (xy 451.024548 -414.738242) (xy 451.081196 -414.729679)
			(xy 451.109842 -414.729168) (xy 451.139964 -414.72977) (xy 451.199459 -414.739243) (xy 451.256727 -414.757946)
			(xy 451.310345 -414.785415) (xy 451.35898 -414.820968) (xy 451.380606 -414.841944) (xy 451.387718 -414.84931)
			(xy 451.406514 -414.85693) (xy 451.49897 -414.85693) (xy 451.517766 -414.84931) (xy 451.524878 -414.841944)
			(xy 451.546497 -414.820957) (xy 451.595126 -414.785388) (xy 451.648744 -414.757908) (xy 451.706016 -414.739202)
			(xy 451.765517 -414.729734) (xy 451.795642 -414.729168) (xy 451.821941 -414.729585) (xy 451.87404 -414.73681)
			(xy 451.92465 -414.751129) (xy 451.972811 -414.772271) (xy 452.017608 -414.799834) (xy 452.058189 -414.833295)
			(xy 452.076312 -414.852358) (xy 452.083424 -414.859978) (xy 452.101712 -414.86836) (xy 452.194168 -414.871662)
			(xy 452.213218 -414.864804) (xy 452.220584 -414.857692) (xy 452.241902 -414.838411) (xy 452.289266 -414.805844)
			(xy 452.340979 -414.780753) (xy 452.395873 -414.763705) (xy 452.452702 -414.755087) (xy 452.481442 -414.754568)
			(xy 452.510242 -414.755066) (xy 452.567191 -414.763698) (xy 452.622196 -414.78079) (xy 452.674009 -414.805954)
			(xy 452.721451 -414.838618) (xy 452.742808 -414.857946) (xy 452.74992 -414.864804) (xy 452.767954 -414.871916)
			(xy 452.85787 -414.871154) (xy 452.875904 -414.864042) (xy 452.883016 -414.857184) (xy 452.904484 -414.837172)
			(xy 452.9524 -414.803287) (xy 453.004938 -414.777135) (xy 453.060861 -414.759334) (xy 453.118849 -414.750304)
			(xy 453.148192 -414.749742) (xy 453.17451 -414.750141) (xy 453.226647 -414.75737) (xy 453.277297 -414.771693)
			(xy 453.325499 -414.792837) (xy 453.370339 -414.820403) (xy 453.410968 -414.853867) (xy 453.429116 -414.872932)
			(xy 453.43626 -414.879989) (xy 453.454426 -414.888492) (xy 453.464422 -414.889442) (xy 453.51827 -414.891474)
			(xy 453.52462 -414.885124) (xy 453.531732 -414.878012) (xy 453.539352 -414.859724) (xy 453.540368 -414.76803)
			(xy 453.533002 -414.749742) (xy 453.52589 -414.742376) (xy 453.505877 -414.720922) (xy 453.472052 -414.672985)
			(xy 453.44596 -414.620436) (xy 453.428217 -414.564514) (xy 453.419239 -414.506535) (xy 453.418702 -414.4772)
			(xy 453.419188 -414.449949) (xy 453.426944 -414.396001) (xy 453.442299 -414.343706) (xy 453.464941 -414.294129)
			(xy 453.494407 -414.248279) (xy 453.530098 -414.207088) (xy 453.571289 -414.171397) (xy 453.617139 -414.141931)
			(xy 453.666716 -414.119289) (xy 453.719011 -414.103934) (xy 453.772959 -414.096178) (xy 453.827461 -414.096178)
			(xy 453.881409 -414.103934) (xy 453.933704 -414.119289) (xy 453.983281 -414.141931) (xy 454.029131 -414.171397)
			(xy 454.070322 -414.207088) (xy 454.106013 -414.248279) (xy 454.135479 -414.294129) (xy 454.158121 -414.343706)
			(xy 454.173476 -414.396001) (xy 454.181232 -414.449949) (xy 454.181718 -414.4772) (xy 454.181157 -414.507324)
			(xy 454.171675 -414.566821) (xy 454.152962 -414.62409) (xy 454.125484 -414.677707) (xy 454.089923 -414.72634)
			(xy 454.068942 -414.747964) (xy 454.06183 -414.755076) (xy 454.05421 -414.773364) (xy 454.053194 -414.865058)
			(xy 454.06056 -414.883346) (xy 454.067672 -414.890712) (xy 454.087673 -414.912177) (xy 454.121501 -414.960111)
			(xy 454.147596 -415.012656) (xy 454.165342 -415.068577) (xy 454.174322 -415.126554) (xy 454.17486 -415.155888)
			(xy 454.174371 -415.183386) (xy 454.166481 -415.237812) (xy 454.150863 -415.290544) (xy 454.12784 -415.340488)
			(xy 454.097888 -415.386612) (xy 454.080118 -415.407602) (xy 454.073768 -415.414714) (xy 454.067418 -415.43224)
			(xy 454.068688 -415.519362) (xy 454.075546 -415.536634) (xy 454.081896 -415.543746) (xy 454.100923 -415.565062)
			(xy 454.133149 -415.612242) (xy 454.157985 -415.663697) (xy 454.174875 -415.718278) (xy 454.183443 -415.774767)
			(xy 454.184004 -415.803334) (xy 454.183554 -415.830586) (xy 454.175793 -415.884535) (xy 454.160433 -415.936831)
			(xy 454.137788 -415.986409) (xy 454.108317 -416.032259) (xy 454.072622 -416.073449) (xy 454.031429 -416.10914)
			(xy 453.985575 -416.138606) (xy 453.935995 -416.161246) (xy 453.883698 -416.176601) (xy 453.829748 -416.184357)
			(xy 453.802496 -416.184842) (xy 453.776975 -416.18445) (xy 453.726387 -416.177654) (xy 453.677158 -416.164171)
			(xy 453.630167 -416.144242) (xy 453.586254 -416.118222) (xy 453.546205 -416.086578) (xy 453.528176 -416.06851)
			(xy 453.521572 -416.061652) (xy 453.5043 -416.053778) (xy 453.416162 -416.048698) (xy 453.398128 -416.05454)
			(xy 453.390762 -416.06089) (xy 453.37018 -416.077259) (xy 453.325366 -416.104777) (xy 453.277195 -416.125875)
			(xy 453.226582 -416.140152) (xy 453.174487 -416.147338) (xy 453.148192 -416.147758) (xy 453.119392 -416.14726)
			(xy 453.062442 -416.138631) (xy 453.007436 -416.12154) (xy 452.955623 -416.096376) (xy 452.908182 -416.06371)
			(xy 452.886826 -416.04438) (xy 452.879714 -416.037522) (xy 452.86168 -416.03041) (xy 452.771764 -416.031172)
			(xy 452.75373 -416.038284) (xy 452.746618 -416.045142) (xy 452.725182 -416.06519) (xy 452.677257 -416.099069)
			(xy 452.62471 -416.125214) (xy 452.568781 -416.143006) (xy 452.510787 -416.152027) (xy 452.481442 -416.152584)
			(xy 452.45132 -416.151977) (xy 452.391826 -416.142503) (xy 452.334559 -416.1238) (xy 452.280941 -416.096333)
			(xy 452.232305 -416.060783) (xy 452.210678 -416.039808) (xy 452.203566 -416.032442) (xy 452.18477 -416.024822)
			(xy 452.092314 -416.024822) (xy 452.073518 -416.032442) (xy 452.066406 -416.039808) (xy 452.046782 -416.05891)
			(xy 452.003043 -416.091863) (xy 451.955042 -416.118223) (xy 451.903764 -416.137449) (xy 451.850264 -416.149145)
			(xy 451.795642 -416.15307) (xy 451.74102 -416.149145) (xy 451.68752 -416.137449) (xy 451.636242 -416.118223)
			(xy 451.588241 -416.091863) (xy 451.544502 -416.05891) (xy 451.524878 -416.039808) (xy 451.517766 -416.032442)
			(xy 451.49897 -416.024822) (xy 451.406514 -416.024822) (xy 451.387718 -416.032442) (xy 451.380606 -416.039808)
			(xy 451.359003 -416.060812) (xy 451.310368 -416.096377) (xy 451.256746 -416.123852) (xy 451.199471 -416.142555)
			(xy 451.139968 -416.152019) (xy 451.109842 -416.152584) (xy 451.080711 -416.152045) (xy 451.023129 -416.14317)
			(xy 450.967568 -416.125637) (xy 450.915322 -416.099853) (xy 450.867607 -416.06642) (xy 450.84619 -416.046666)
			(xy 450.838824 -416.039808) (xy 450.820282 -416.032442) (xy 450.728588 -416.033966) (xy 450.710554 -416.04184)
			(xy 450.703188 -416.049206) (xy 450.681532 -416.070516) (xy 450.632677 -416.106631) (xy 450.578715 -416.134546)
			(xy 450.521011 -416.153554) (xy 450.461023 -416.163175) (xy 450.430646 -416.16376) (xy 450.403392 -416.163302)
			(xy 450.349438 -416.15555) (xy 450.297138 -416.140197) (xy 450.247554 -416.117557) (xy 450.201699 -416.088089)
			(xy 450.160504 -416.052394) (xy 450.12481 -416.0112) (xy 450.095343 -415.965344) (xy 450.072702 -415.915761)
			(xy 450.05735 -415.86346) (xy 450.049598 -415.809506) (xy 450.049138 -415.782252) (xy 450.0497 -415.752775)
			(xy 450.058762 -415.694522) (xy 450.076679 -415.638357) (xy 450.103024 -415.585618) (xy 450.137169 -415.537559)
			(xy 450.157342 -415.51606) (xy 450.163893 -415.508738) (xy 450.171327 -415.490568) (xy 450.17182 -415.480754)
			(xy 450.17182 -415.427414) (xy 450.159882 -415.415984) (xy 450.15277 -415.408618) (xy 450.133974 -415.400998)
			(xy 450.041518 -415.400998) (xy 450.022722 -415.408618) (xy 450.01561 -415.415984) (xy 449.994001 -415.436982)
			(xy 449.945368 -415.472548) (xy 449.891748 -415.500026) (xy 449.834474 -415.51873) (xy 449.774971 -415.528195)
			(xy 449.744846 -415.52876) (xy 449.717592 -415.528302) (xy 449.663638 -415.52055) (xy 449.611338 -415.505197)
			(xy 449.561754 -415.482557) (xy 449.515899 -415.453089) (xy 449.474704 -415.417394) (xy 449.43901 -415.3762)
			(xy 449.409543 -415.330344) (xy 449.386902 -415.280761) (xy 449.37155 -415.22846) (xy 449.363798 -415.174506)
			(xy 449.363338 -415.147252) (xy 438.652666 -415.147252) (xy 438.652666 -415.933382) (xy 438.652227 -415.943445)
			(xy 438.644488 -415.962025) (xy 438.63768 -415.96945) (xy 437.360314 -417.246816) (xy 437.352948 -417.253928)
			(xy 437.345328 -417.272724) (xy 437.345328 -418.436044) (xy 438.118756 -418.436044) (xy 438.122827 -418.380422)
			(xy 438.134953 -418.325985) (xy 438.154876 -418.273894) (xy 438.182172 -418.225259) (xy 438.216258 -418.181116)
			(xy 438.256407 -418.142407) (xy 438.301765 -418.109956) (xy 438.351365 -418.084455) (xy 438.404149 -418.066448)
			(xy 438.458992 -418.056318) (xy 438.514726 -418.054281) (xy 438.570163 -418.060381) (xy 438.62412 -418.074487)
			(xy 438.675449 -418.096299) (xy 438.723055 -418.125353) (xy 438.765923 -418.161028) (xy 438.80314 -418.202565)
			(xy 438.833913 -418.249078) (xy 438.857585 -418.299575) (xy 438.873653 -418.352982) (xy 438.881773 -418.408158)
			(xy 438.882282 -418.436044) (xy 439.134756 -418.436044) (xy 439.138827 -418.380422) (xy 439.150953 -418.325985)
			(xy 439.170876 -418.273894) (xy 439.198172 -418.225259) (xy 439.232258 -418.181116) (xy 439.272407 -418.142407)
			(xy 439.317765 -418.109956) (xy 439.367365 -418.084455) (xy 439.420149 -418.066448) (xy 439.474992 -418.056318)
			(xy 439.530726 -418.054281) (xy 439.586163 -418.060381) (xy 439.64012 -418.074487) (xy 439.691449 -418.096299)
			(xy 439.739055 -418.125353) (xy 439.781923 -418.161028) (xy 439.816684 -418.199824) (xy 448.144898 -418.199824)
			(xy 448.148969 -418.144202) (xy 448.161095 -418.089765) (xy 448.181018 -418.037674) (xy 448.208314 -417.989039)
			(xy 448.2424 -417.944896) (xy 448.282549 -417.906187) (xy 448.327907 -417.873736) (xy 448.377507 -417.848235)
			(xy 448.430291 -417.830228) (xy 448.485134 -417.820098) (xy 448.540868 -417.818061) (xy 448.596305 -417.824161)
			(xy 448.650262 -417.838267) (xy 448.701591 -417.860079) (xy 448.749197 -417.889133) (xy 448.792065 -417.924808)
			(xy 448.829282 -417.966345) (xy 448.860055 -418.012858) (xy 448.883727 -418.063355) (xy 448.899795 -418.116762)
			(xy 448.907915 -418.171938) (xy 448.908424 -418.199824) (xy 448.907915 -418.22771) (xy 448.899795 -418.282886)
			(xy 448.883727 -418.336293) (xy 448.860055 -418.38679) (xy 448.829282 -418.433303) (xy 448.792065 -418.47484)
			(xy 448.749197 -418.510515) (xy 448.701591 -418.539569) (xy 448.650262 -418.561381) (xy 448.596305 -418.575487)
			(xy 448.540868 -418.581587) (xy 448.485134 -418.57955) (xy 448.430291 -418.56942) (xy 448.377507 -418.551413)
			(xy 448.327907 -418.525912) (xy 448.282549 -418.493461) (xy 448.2424 -418.454752) (xy 448.208314 -418.410609)
			(xy 448.181018 -418.361974) (xy 448.161095 -418.309883) (xy 448.148969 -418.255446) (xy 448.144898 -418.199824)
			(xy 439.816684 -418.199824) (xy 439.81914 -418.202565) (xy 439.849913 -418.249078) (xy 439.873585 -418.299575)
			(xy 439.889653 -418.352982) (xy 439.897773 -418.408158) (xy 439.898282 -418.436044) (xy 439.897773 -418.46393)
			(xy 439.889653 -418.519106) (xy 439.873585 -418.572513) (xy 439.849913 -418.62301) (xy 439.81914 -418.669523)
			(xy 439.781923 -418.71106) (xy 439.739055 -418.746735) (xy 439.691449 -418.775789) (xy 439.64012 -418.797601)
			(xy 439.586163 -418.811707) (xy 439.530726 -418.817807) (xy 439.474992 -418.81577) (xy 439.420149 -418.80564)
			(xy 439.367365 -418.787633) (xy 439.317765 -418.762132) (xy 439.272407 -418.729681) (xy 439.232258 -418.690972)
			(xy 439.198172 -418.646829) (xy 439.170876 -418.598194) (xy 439.150953 -418.546103) (xy 439.138827 -418.491666)
			(xy 439.134756 -418.436044) (xy 438.882282 -418.436044) (xy 438.881773 -418.46393) (xy 438.873653 -418.519106)
			(xy 438.857585 -418.572513) (xy 438.833913 -418.62301) (xy 438.80314 -418.669523) (xy 438.765923 -418.71106)
			(xy 438.723055 -418.746735) (xy 438.675449 -418.775789) (xy 438.62412 -418.797601) (xy 438.570163 -418.811707)
			(xy 438.514726 -418.817807) (xy 438.458992 -418.81577) (xy 438.404149 -418.80564) (xy 438.351365 -418.787633)
			(xy 438.301765 -418.762132) (xy 438.256407 -418.729681) (xy 438.216258 -418.690972) (xy 438.182172 -418.646829)
			(xy 438.154876 -418.598194) (xy 438.134953 -418.546103) (xy 438.122827 -418.491666) (xy 438.118756 -418.436044)
			(xy 437.345328 -418.436044) (xy 437.345328 -419.59911) (xy 440.425584 -419.59911) (xy 440.429655 -419.543488)
			(xy 440.441781 -419.489051) (xy 440.461704 -419.43696) (xy 440.489 -419.388325) (xy 440.523086 -419.344182)
			(xy 440.563235 -419.305473) (xy 440.608593 -419.273022) (xy 440.658193 -419.247521) (xy 440.710977 -419.229514)
			(xy 440.76582 -419.219384) (xy 440.821554 -419.217347) (xy 440.876991 -419.223447) (xy 440.930948 -419.237553)
			(xy 440.982277 -419.259365) (xy 441.029883 -419.288419) (xy 441.072751 -419.324094) (xy 441.109968 -419.365631)
			(xy 441.140741 -419.412144) (xy 441.140751 -419.412166) (xy 442.711584 -419.412166) (xy 442.715655 -419.356544)
			(xy 442.727781 -419.302107) (xy 442.747704 -419.250016) (xy 442.775 -419.201381) (xy 442.809086 -419.157238)
			(xy 442.849235 -419.118529) (xy 442.894593 -419.086078) (xy 442.944193 -419.060577) (xy 442.996977 -419.04257)
			(xy 443.05182 -419.03244) (xy 443.107554 -419.030403) (xy 443.162991 -419.036503) (xy 443.216948 -419.050609)
			(xy 443.268277 -419.072421) (xy 443.315883 -419.101475) (xy 443.358751 -419.13715) (xy 443.395968 -419.178687)
			(xy 443.426741 -419.2252) (xy 443.450413 -419.275697) (xy 443.466481 -419.329104) (xy 443.474601 -419.38428)
			(xy 443.47511 -419.412166) (xy 443.474601 -419.440052) (xy 443.466481 -419.495228) (xy 443.450413 -419.548635)
			(xy 443.427823 -419.596824) (xy 448.925948 -419.596824) (xy 448.930019 -419.541202) (xy 448.942145 -419.486765)
			(xy 448.962068 -419.434674) (xy 448.989364 -419.386039) (xy 449.02345 -419.341896) (xy 449.063599 -419.303187)
			(xy 449.108957 -419.270736) (xy 449.158557 -419.245235) (xy 449.211341 -419.227228) (xy 449.266184 -419.217098)
			(xy 449.321918 -419.215061) (xy 449.377355 -419.221161) (xy 449.431312 -419.235267) (xy 449.482641 -419.257079)
			(xy 449.530247 -419.286133) (xy 449.573115 -419.321808) (xy 449.610332 -419.363345) (xy 449.641105 -419.409858)
			(xy 449.664777 -419.460355) (xy 449.680845 -419.513762) (xy 449.688965 -419.568938) (xy 449.689474 -419.596824)
			(xy 449.688965 -419.62471) (xy 449.680845 -419.679886) (xy 449.664777 -419.733293) (xy 449.641105 -419.78379)
			(xy 449.610332 -419.830303) (xy 449.573115 -419.87184) (xy 449.530247 -419.907515) (xy 449.482641 -419.936569)
			(xy 449.431312 -419.958381) (xy 449.377355 -419.972487) (xy 449.321918 -419.978587) (xy 449.266184 -419.97655)
			(xy 449.211341 -419.96642) (xy 449.158557 -419.948413) (xy 449.108957 -419.922912) (xy 449.063599 -419.890461)
			(xy 449.02345 -419.851752) (xy 448.989364 -419.807609) (xy 448.962068 -419.758974) (xy 448.942145 -419.706883)
			(xy 448.930019 -419.652446) (xy 448.925948 -419.596824) (xy 443.427823 -419.596824) (xy 443.426741 -419.599132)
			(xy 443.395968 -419.645645) (xy 443.358751 -419.687182) (xy 443.315883 -419.722857) (xy 443.268277 -419.751911)
			(xy 443.216948 -419.773723) (xy 443.162991 -419.787829) (xy 443.107554 -419.793929) (xy 443.05182 -419.791892)
			(xy 442.996977 -419.781762) (xy 442.944193 -419.763755) (xy 442.894593 -419.738254) (xy 442.849235 -419.705803)
			(xy 442.809086 -419.667094) (xy 442.775 -419.622951) (xy 442.747704 -419.574316) (xy 442.727781 -419.522225)
			(xy 442.715655 -419.467788) (xy 442.711584 -419.412166) (xy 441.140751 -419.412166) (xy 441.164413 -419.462641)
			(xy 441.180481 -419.516048) (xy 441.188601 -419.571224) (xy 441.18911 -419.59911) (xy 441.188601 -419.626996)
			(xy 441.180481 -419.682172) (xy 441.164413 -419.735579) (xy 441.140741 -419.786076) (xy 441.109968 -419.832589)
			(xy 441.072751 -419.874126) (xy 441.029883 -419.909801) (xy 440.982277 -419.938855) (xy 440.930948 -419.960667)
			(xy 440.876991 -419.974773) (xy 440.821554 -419.980873) (xy 440.76582 -419.978836) (xy 440.710977 -419.968706)
			(xy 440.658193 -419.950699) (xy 440.608593 -419.925198) (xy 440.563235 -419.892747) (xy 440.523086 -419.854038)
			(xy 440.489 -419.809895) (xy 440.461704 -419.76126) (xy 440.441781 -419.709169) (xy 440.429655 -419.654732)
			(xy 440.425584 -419.59911) (xy 437.345328 -419.59911) (xy 437.345328 -420.23411) (xy 444.235584 -420.23411)
			(xy 444.239655 -420.178488) (xy 444.251781 -420.124051) (xy 444.271704 -420.07196) (xy 444.299 -420.023325)
			(xy 444.333086 -419.979182) (xy 444.373235 -419.940473) (xy 444.418593 -419.908022) (xy 444.468193 -419.882521)
			(xy 444.520977 -419.864514) (xy 444.57582 -419.854384) (xy 444.631554 -419.852347) (xy 444.686991 -419.858447)
			(xy 444.740948 -419.872553) (xy 444.792277 -419.894365) (xy 444.839883 -419.923419) (xy 444.882751 -419.959094)
			(xy 444.919968 -420.000631) (xy 444.950741 -420.047144) (xy 444.974413 -420.097641) (xy 444.990481 -420.151048)
			(xy 444.998601 -420.206224) (xy 444.99911 -420.23411) (xy 445.505584 -420.23411) (xy 445.509655 -420.178488)
			(xy 445.521781 -420.124051) (xy 445.541704 -420.07196) (xy 445.569 -420.023325) (xy 445.603086 -419.979182)
			(xy 445.643235 -419.940473) (xy 445.688593 -419.908022) (xy 445.738193 -419.882521) (xy 445.790977 -419.864514)
			(xy 445.84582 -419.854384) (xy 445.901554 -419.852347) (xy 445.956991 -419.858447) (xy 446.010948 -419.872553)
			(xy 446.062277 -419.894365) (xy 446.109883 -419.923419) (xy 446.152751 -419.959094) (xy 446.189968 -420.000631)
			(xy 446.220741 -420.047144) (xy 446.244413 -420.097641) (xy 446.260481 -420.151048) (xy 446.268601 -420.206224)
			(xy 446.26911 -420.23411) (xy 446.268601 -420.261996) (xy 446.260481 -420.317172) (xy 446.244413 -420.370579)
			(xy 446.220741 -420.421076) (xy 446.189968 -420.467589) (xy 446.152751 -420.509126) (xy 446.109883 -420.544801)
			(xy 446.062277 -420.573855) (xy 446.010948 -420.595667) (xy 445.956991 -420.609773) (xy 445.901554 -420.615873)
			(xy 445.84582 -420.613836) (xy 445.790977 -420.603706) (xy 445.738193 -420.585699) (xy 445.688593 -420.560198)
			(xy 445.643235 -420.527747) (xy 445.603086 -420.489038) (xy 445.569 -420.444895) (xy 445.541704 -420.39626)
			(xy 445.521781 -420.344169) (xy 445.509655 -420.289732) (xy 445.505584 -420.23411) (xy 444.99911 -420.23411)
			(xy 444.998601 -420.261996) (xy 444.990481 -420.317172) (xy 444.974413 -420.370579) (xy 444.950741 -420.421076)
			(xy 444.919968 -420.467589) (xy 444.882751 -420.509126) (xy 444.839883 -420.544801) (xy 444.792277 -420.573855)
			(xy 444.740948 -420.595667) (xy 444.686991 -420.609773) (xy 444.631554 -420.615873) (xy 444.57582 -420.613836)
			(xy 444.520977 -420.603706) (xy 444.468193 -420.585699) (xy 444.418593 -420.560198) (xy 444.373235 -420.527747)
			(xy 444.333086 -420.489038) (xy 444.299 -420.444895) (xy 444.271704 -420.39626) (xy 444.251781 -420.344169)
			(xy 444.239655 -420.289732) (xy 444.235584 -420.23411) (xy 437.345328 -420.23411) (xy 437.345328 -420.86911)
			(xy 440.180982 -420.86911) (xy 440.185053 -420.813488) (xy 440.197179 -420.759051) (xy 440.217102 -420.70696)
			(xy 440.244398 -420.658325) (xy 440.278484 -420.614182) (xy 440.318633 -420.575473) (xy 440.363991 -420.543022)
			(xy 440.413591 -420.517521) (xy 440.466375 -420.499514) (xy 440.521218 -420.489384) (xy 440.576952 -420.487347)
			(xy 440.632389 -420.493447) (xy 440.686346 -420.507553) (xy 440.737675 -420.529365) (xy 440.785281 -420.558419)
			(xy 440.828149 -420.594094) (xy 440.865366 -420.635631) (xy 440.896139 -420.682144) (xy 440.919811 -420.732641)
			(xy 440.92266 -420.74211) (xy 442.838584 -420.74211) (xy 442.842655 -420.686488) (xy 442.854781 -420.632051)
			(xy 442.874704 -420.57996) (xy 442.902 -420.531325) (xy 442.936086 -420.487182) (xy 442.976235 -420.448473)
			(xy 443.021593 -420.416022) (xy 443.071193 -420.390521) (xy 443.123977 -420.372514) (xy 443.17882 -420.362384)
			(xy 443.234554 -420.360347) (xy 443.289991 -420.366447) (xy 443.343948 -420.380553) (xy 443.395277 -420.402365)
			(xy 443.442883 -420.431419) (xy 443.485751 -420.467094) (xy 443.522968 -420.508631) (xy 443.553741 -420.555144)
			(xy 443.577413 -420.605641) (xy 443.593481 -420.659048) (xy 443.601601 -420.714224) (xy 443.60211 -420.74211)
			(xy 443.601601 -420.769996) (xy 443.593481 -420.825172) (xy 443.577413 -420.878579) (xy 443.553741 -420.929076)
			(xy 443.522968 -420.975589) (xy 443.504581 -420.99611) (xy 450.196458 -420.99611) (xy 450.196941 -420.968612)
			(xy 450.204832 -420.914185) (xy 450.220451 -420.861453) (xy 450.243476 -420.811509) (xy 450.27343 -420.765386)
			(xy 450.2912 -420.744396) (xy 450.29755 -420.737284) (xy 450.3039 -420.720266) (xy 450.3039 -420.634668)
			(xy 450.29755 -420.61765) (xy 450.2912 -420.610538) (xy 450.273442 -420.589537) (xy 450.243486 -420.543417)
			(xy 450.220458 -420.493476) (xy 450.204835 -420.440747) (xy 450.19694 -420.386321) (xy 450.196458 -420.358824)
			(xy 450.196944 -420.331573) (xy 450.2047 -420.277625) (xy 450.220055 -420.22533) (xy 450.242697 -420.175753)
			(xy 450.272163 -420.129903) (xy 450.307854 -420.088712) (xy 450.349045 -420.053021) (xy 450.394895 -420.023555)
			(xy 450.444472 -420.000913) (xy 450.496767 -419.985558) (xy 450.550715 -419.977802) (xy 450.605217 -419.977802)
			(xy 450.659165 -419.985558) (xy 450.71146 -420.000913) (xy 450.761037 -420.023555) (xy 450.806887 -420.053021)
			(xy 450.848078 -420.088712) (xy 450.883769 -420.129903) (xy 450.913235 -420.175753) (xy 450.935877 -420.22533)
			(xy 450.951232 -420.277625) (xy 450.958988 -420.331573) (xy 450.959474 -420.358824) (xy 450.959003 -420.386322)
			(xy 450.951108 -420.44075) (xy 450.935486 -420.493481) (xy 450.912458 -420.543425) (xy 450.882503 -420.589548)
			(xy 450.864732 -420.610538) (xy 450.858382 -420.61765) (xy 450.852032 -420.634668) (xy 450.852032 -420.720266)
			(xy 450.858382 -420.737284) (xy 450.864732 -420.744396) (xy 450.882511 -420.76538) (xy 450.912463 -420.811505)
			(xy 450.935486 -420.861451) (xy 450.951105 -420.914183) (xy 450.958995 -420.968611) (xy 450.959474 -420.99611)
			(xy 450.958988 -421.023361) (xy 450.951232 -421.077309) (xy 450.935877 -421.129604) (xy 450.913235 -421.179181)
			(xy 450.883769 -421.225031) (xy 450.848078 -421.266222) (xy 450.806887 -421.301913) (xy 450.761037 -421.331379)
			(xy 450.71146 -421.354021) (xy 450.659165 -421.369376) (xy 450.605217 -421.377132) (xy 450.550715 -421.377132)
			(xy 450.496767 -421.369376) (xy 450.444472 -421.354021) (xy 450.394895 -421.331379) (xy 450.349045 -421.301913)
			(xy 450.307854 -421.266222) (xy 450.272163 -421.225031) (xy 450.242697 -421.179181) (xy 450.220055 -421.129604)
			(xy 450.2047 -421.077309) (xy 450.196944 -421.023361) (xy 450.196458 -420.99611) (xy 443.504581 -420.99611)
			(xy 443.485751 -421.017126) (xy 443.442883 -421.052801) (xy 443.395277 -421.081855) (xy 443.343948 -421.103667)
			(xy 443.289991 -421.117773) (xy 443.234554 -421.123873) (xy 443.17882 -421.121836) (xy 443.123977 -421.111706)
			(xy 443.071193 -421.093699) (xy 443.021593 -421.068198) (xy 442.976235 -421.035747) (xy 442.936086 -420.997038)
			(xy 442.902 -420.952895) (xy 442.874704 -420.90426) (xy 442.854781 -420.852169) (xy 442.842655 -420.797732)
			(xy 442.838584 -420.74211) (xy 440.92266 -420.74211) (xy 440.935879 -420.786048) (xy 440.943999 -420.841224)
			(xy 440.944508 -420.86911) (xy 440.943999 -420.896996) (xy 440.935879 -420.952172) (xy 440.919811 -421.005579)
			(xy 440.896139 -421.056076) (xy 440.865366 -421.102589) (xy 440.828149 -421.144126) (xy 440.785281 -421.179801)
			(xy 440.737675 -421.208855) (xy 440.686346 -421.230667) (xy 440.632389 -421.244773) (xy 440.576952 -421.250873)
			(xy 440.521218 -421.248836) (xy 440.466375 -421.238706) (xy 440.413591 -421.220699) (xy 440.363991 -421.195198)
			(xy 440.318633 -421.162747) (xy 440.278484 -421.124038) (xy 440.244398 -421.079895) (xy 440.217102 -421.03126)
			(xy 440.197179 -420.979169) (xy 440.185053 -420.924732) (xy 440.180982 -420.86911) (xy 437.345328 -420.86911)
			(xy 437.345328 -423.215562) (xy 440.204098 -423.215562) (xy 440.204539 -423.188278) (xy 440.212331 -423.134267)
			(xy 440.227736 -423.081918) (xy 440.25044 -423.032296) (xy 440.279981 -422.986414) (xy 440.315756 -422.945208)
			(xy 440.357035 -422.909517) (xy 440.402977 -422.880069) (xy 440.427618 -422.868344) (xy 440.44102 -422.861668)
			(xy 440.463477 -422.841883) (xy 440.479241 -422.816442) (xy 440.486961 -422.787526) (xy 440.485975 -422.757613)
			(xy 440.476368 -422.729268) (xy 440.458964 -422.70492) (xy 440.44743 -422.69537) (xy 440.424753 -422.677154)
			(xy 440.384614 -422.63506) (xy 440.351326 -422.587363) (xy 440.325662 -422.535167) (xy 440.308214 -422.479682)
			(xy 440.299387 -422.422192) (xy 440.29884 -422.39311) (xy 440.299326 -422.365859) (xy 440.307082 -422.311911)
			(xy 440.322437 -422.259616) (xy 440.345079 -422.210039) (xy 440.374545 -422.164189) (xy 440.410236 -422.122998)
			(xy 440.451427 -422.087307) (xy 440.497277 -422.057841) (xy 440.546854 -422.035199) (xy 440.599149 -422.019844)
			(xy 440.653097 -422.012088) (xy 440.707599 -422.012088) (xy 440.761547 -422.019844) (xy 440.813842 -422.035199)
			(xy 440.863419 -422.057841) (xy 440.909269 -422.087307) (xy 440.95046 -422.122998) (xy 440.986151 -422.164189)
			(xy 441.015617 -422.210039) (xy 441.038259 -422.259616) (xy 441.053614 -422.311911) (xy 441.06137 -422.365859)
			(xy 441.061856 -422.39311) (xy 441.061419 -422.420395) (xy 441.05363 -422.474406) (xy 441.038226 -422.526757)
			(xy 441.015522 -422.57638) (xy 440.98598 -422.622263) (xy 440.950204 -422.663469) (xy 440.908923 -422.699159)
			(xy 440.862979 -422.728605) (xy 440.838336 -422.740328) (xy 440.824956 -422.747048) (xy 440.802492 -422.76682)
			(xy 440.797971 -422.77411) (xy 448.661534 -422.77411) (xy 448.665605 -422.718488) (xy 448.677731 -422.664051)
			(xy 448.697654 -422.61196) (xy 448.72495 -422.563325) (xy 448.759036 -422.519182) (xy 448.799185 -422.480473)
			(xy 448.844543 -422.448022) (xy 448.894143 -422.422521) (xy 448.946927 -422.404514) (xy 449.00177 -422.394384)
			(xy 449.057504 -422.392347) (xy 449.112941 -422.398447) (xy 449.166898 -422.412553) (xy 449.218227 -422.434365)
			(xy 449.265833 -422.463419) (xy 449.308701 -422.499094) (xy 449.345918 -422.540631) (xy 449.376691 -422.587144)
			(xy 449.400363 -422.637641) (xy 449.416431 -422.691048) (xy 449.424551 -422.746224) (xy 449.42506 -422.77411)
			(xy 449.424551 -422.801996) (xy 449.416431 -422.857172) (xy 449.400363 -422.910579) (xy 449.376691 -422.961076)
			(xy 449.345918 -423.007589) (xy 449.308701 -423.049126) (xy 449.265833 -423.084801) (xy 449.218227 -423.113855)
			(xy 449.166898 -423.135667) (xy 449.112941 -423.149773) (xy 449.057504 -423.155873) (xy 449.00177 -423.153836)
			(xy 448.946927 -423.143706) (xy 448.894143 -423.125699) (xy 448.844543 -423.100198) (xy 448.799185 -423.067747)
			(xy 448.759036 -423.029038) (xy 448.72495 -422.984895) (xy 448.697654 -422.93626) (xy 448.677731 -422.884169)
			(xy 448.665605 -422.829732) (xy 448.661534 -422.77411) (xy 440.797971 -422.77411) (xy 440.786721 -422.792252)
			(xy 440.778996 -422.821163) (xy 440.779978 -422.851072) (xy 440.789584 -422.879414) (xy 440.80699 -422.903756)
			(xy 440.818524 -422.913302) (xy 440.841247 -422.931463) (xy 440.881381 -422.97357) (xy 440.914661 -423.021279)
			(xy 440.940317 -423.073485) (xy 440.957756 -423.128979) (xy 440.966572 -423.186477) (xy 440.967114 -423.215562)
			(xy 440.966628 -423.242813) (xy 440.958872 -423.296761) (xy 440.943517 -423.349056) (xy 440.920875 -423.398633)
			(xy 440.891409 -423.444483) (xy 440.855718 -423.485674) (xy 440.814527 -423.521365) (xy 440.768677 -423.550831)
			(xy 440.755743 -423.556738) (xy 456.285335 -423.556738) (xy 456.285335 -423.427598) (xy 456.293285 -423.298703)
			(xy 456.309155 -423.170543) (xy 456.332884 -423.043602) (xy 456.364383 -422.918363) (xy 456.403532 -422.7953)
			(xy 456.450183 -422.674881) (xy 456.504158 -422.557562) (xy 456.565253 -422.443788) (xy 456.633236 -422.333991)
			(xy 456.70785 -422.228588) (xy 456.788811 -422.127978) (xy 456.875811 -422.032543) (xy 456.968522 -421.942644)
			(xy 457.066592 -421.858623) (xy 457.169647 -421.780799) (xy 457.277298 -421.709467) (xy 457.389137 -421.644897)
			(xy 457.504738 -421.587335) (xy 457.623663 -421.536998) (xy 457.745462 -421.494078) (xy 457.869672 -421.458737)
			(xy 457.995821 -421.43111) (xy 458.123433 -421.411301) (xy 458.252022 -421.399385) (xy 458.3811 -421.395409)
			(xy 458.510178 -421.399385) (xy 458.638767 -421.411301) (xy 458.766379 -421.43111) (xy 458.892528 -421.458737)
			(xy 459.016738 -421.494078) (xy 459.138537 -421.536998) (xy 459.257462 -421.587335) (xy 459.373063 -421.644897)
			(xy 459.484902 -421.709467) (xy 459.592553 -421.780799) (xy 459.695608 -421.858623) (xy 459.793678 -421.942644)
			(xy 459.886389 -422.032543) (xy 459.973389 -422.127978) (xy 460.05435 -422.228588) (xy 460.128964 -422.333991)
			(xy 460.196947 -422.443788) (xy 460.258042 -422.557562) (xy 460.312017 -422.674881) (xy 460.358668 -422.7953)
			(xy 460.397817 -422.918363) (xy 460.429316 -423.043602) (xy 460.453045 -423.170543) (xy 460.468915 -423.298703)
			(xy 460.476865 -423.427598) (xy 460.477362 -423.492168) (xy 460.476865 -423.556738) (xy 460.468915 -423.685633)
			(xy 460.453045 -423.813793) (xy 460.429316 -423.940734) (xy 460.397817 -424.065973) (xy 460.358668 -424.189036)
			(xy 460.312017 -424.309455) (xy 460.258042 -424.426774) (xy 460.196947 -424.540548) (xy 460.128964 -424.650345)
			(xy 460.05435 -424.755748) (xy 459.973389 -424.856358) (xy 459.886389 -424.951793) (xy 459.793678 -425.041692)
			(xy 459.695608 -425.125713) (xy 459.592553 -425.203537) (xy 459.484902 -425.274869) (xy 459.373063 -425.339439)
			(xy 459.257462 -425.397001) (xy 459.138537 -425.447338) (xy 459.016738 -425.490258) (xy 458.892528 -425.525599)
			(xy 458.766379 -425.553226) (xy 458.638767 -425.573035) (xy 458.510178 -425.584951) (xy 458.3811 -425.588928)
			(xy 458.252022 -425.584951) (xy 458.123433 -425.573035) (xy 457.995821 -425.553226) (xy 457.869672 -425.525599)
			(xy 457.745462 -425.490258) (xy 457.623663 -425.447338) (xy 457.504738 -425.397001) (xy 457.389137 -425.339439)
			(xy 457.277298 -425.274869) (xy 457.169647 -425.203537) (xy 457.066592 -425.125713) (xy 456.968522 -425.041692)
			(xy 456.875811 -424.951793) (xy 456.788811 -424.856358) (xy 456.70785 -424.755748) (xy 456.633236 -424.650345)
			(xy 456.565253 -424.540548) (xy 456.504158 -424.426774) (xy 456.450183 -424.309455) (xy 456.403532 -424.189036)
			(xy 456.364383 -424.065973) (xy 456.332884 -423.940734) (xy 456.309155 -423.813793) (xy 456.293285 -423.685633)
			(xy 456.285335 -423.556738) (xy 440.755743 -423.556738) (xy 440.7191 -423.573473) (xy 440.666805 -423.588828)
			(xy 440.612857 -423.596584) (xy 440.558355 -423.596584) (xy 440.504407 -423.588828) (xy 440.452112 -423.573473)
			(xy 440.402535 -423.550831) (xy 440.356685 -423.521365) (xy 440.315494 -423.485674) (xy 440.279803 -423.444483)
			(xy 440.250337 -423.398633) (xy 440.227695 -423.349056) (xy 440.21234 -423.296761) (xy 440.204584 -423.242813)
			(xy 440.204098 -423.215562) (xy 437.345328 -423.215562) (xy 437.345328 -423.478452) (xy 437.345446 -423.483548)
			(xy 437.347502 -423.49353) (xy 437.349392 -423.498264) (xy 437.360822 -423.524934) (xy 437.367426 -423.531792)
			(xy 437.385875 -423.551319) (xy 437.417667 -423.59462) (xy 437.443072 -423.641953) (xy 437.461585 -423.692381)
			(xy 437.472842 -423.744908) (xy 437.47662 -423.798494) (xy 437.472844 -423.852081) (xy 437.461589 -423.904608)
			(xy 437.443076 -423.955037) (xy 437.417673 -424.00237) (xy 437.385882 -424.045672) (xy 437.367426 -424.065192)
			(xy 437.360822 -424.07205) (xy 437.349392 -424.09872) (xy 437.347524 -424.10346) (xy 437.345483 -424.11344)
			(xy 437.345328 -424.118532) (xy 437.345328 -424.80611) (xy 437.580784 -424.80611) (xy 437.584855 -424.750488)
			(xy 437.596981 -424.696051) (xy 437.616904 -424.64396) (xy 437.6442 -424.595325) (xy 437.678286 -424.551182)
			(xy 437.718435 -424.512473) (xy 437.763793 -424.480022) (xy 437.813393 -424.454521) (xy 437.866177 -424.436514)
			(xy 437.92102 -424.426384) (xy 437.976754 -424.424347) (xy 438.032191 -424.430447) (xy 438.086148 -424.444553)
			(xy 438.137477 -424.466365) (xy 438.185083 -424.495419) (xy 438.227951 -424.531094) (xy 438.265168 -424.572631)
			(xy 438.295941 -424.619144) (xy 438.313008 -424.655552) (xy 447.233765 -424.655552) (xy 447.233765 -424.601048)
			(xy 447.241522 -424.547098) (xy 447.256878 -424.494801) (xy 447.27952 -424.445222) (xy 447.308987 -424.39937)
			(xy 447.34468 -424.358179) (xy 447.385872 -424.322486) (xy 447.431724 -424.293019) (xy 447.481303 -424.270377)
			(xy 447.5336 -424.255022) (xy 447.58755 -424.247265) (xy 447.614802 -424.246802) (xy 447.642246 -424.247291)
			(xy 447.696568 -424.255158) (xy 447.749197 -424.270743) (xy 447.799044 -424.293723) (xy 447.82232 -424.30827)
			(xy 447.834456 -424.315613) (xy 447.861559 -424.323945) (xy 447.889908 -424.324497) (xy 447.917314 -424.317226)
			(xy 447.941661 -424.302693) (xy 447.961068 -424.282021) (xy 447.974037 -424.256806) (xy 447.97726 -424.242992)
			(xy 447.983544 -424.214555) (xy 448.003543 -424.159862) (xy 448.031619 -424.108841) (xy 448.067119 -424.062677)
			(xy 448.10922 -424.022442) (xy 448.156944 -423.989069) (xy 448.209184 -423.963333) (xy 448.264727 -423.945832)
			(xy 448.322285 -423.936971) (xy 448.351402 -423.936414) (xy 448.378655 -423.936856) (xy 448.432605 -423.944613)
			(xy 448.484903 -423.959969) (xy 448.534483 -423.982612) (xy 448.580336 -424.01208) (xy 448.621528 -424.047774)
			(xy 448.657221 -424.088966) (xy 448.686689 -424.134819) (xy 448.709331 -424.184399) (xy 448.724687 -424.236697)
			(xy 448.732444 -424.290647) (xy 448.732444 -424.345153) (xy 448.724687 -424.399103) (xy 448.709331 -424.451401)
			(xy 448.686689 -424.500981) (xy 448.657221 -424.546834) (xy 448.621528 -424.588026) (xy 448.580336 -424.62372)
			(xy 448.534483 -424.653188) (xy 448.484903 -424.675831) (xy 448.432605 -424.691187) (xy 448.378655 -424.698944)
			(xy 448.351402 -424.69943) (xy 448.323958 -424.698934) (xy 448.269637 -424.691069) (xy 448.217008 -424.675486)
			(xy 448.167161 -424.652508) (xy 448.143884 -424.637962) (xy 448.131723 -424.630667) (xy 448.104631 -424.622343)
			(xy 448.076293 -424.621793) (xy 448.048898 -424.629059) (xy 448.024558 -424.64358) (xy 448.005151 -424.664236)
			(xy 447.992174 -424.689434) (xy 447.988944 -424.70324) (xy 447.982701 -424.731688) (xy 447.962704 -424.786389)
			(xy 447.934628 -424.837415) (xy 447.899125 -424.883583) (xy 447.857018 -424.923821) (xy 447.809287 -424.957193)
			(xy 447.757038 -424.982924) (xy 447.701487 -425.000418) (xy 447.643922 -425.009268) (xy 447.614802 -425.009818)
			(xy 447.58755 -425.009335) (xy 447.5336 -425.001578) (xy 447.481303 -424.986223) (xy 447.431724 -424.963581)
			(xy 447.385872 -424.934114) (xy 447.34468 -424.898421) (xy 447.308987 -424.85723) (xy 447.27952 -424.811378)
			(xy 447.256878 -424.761799) (xy 447.241522 -424.709502) (xy 447.233765 -424.655552) (xy 438.313008 -424.655552)
			(xy 438.319613 -424.669641) (xy 438.335681 -424.723048) (xy 438.343801 -424.778224) (xy 438.34431 -424.80611)
			(xy 438.343801 -424.833996) (xy 438.335681 -424.889172) (xy 438.319613 -424.942579) (xy 438.295941 -424.993076)
			(xy 438.265168 -425.039589) (xy 438.246781 -425.06011) (xy 440.298584 -425.06011) (xy 440.302655 -425.004488)
			(xy 440.314781 -424.950051) (xy 440.334704 -424.89796) (xy 440.362 -424.849325) (xy 440.396086 -424.805182)
			(xy 440.436235 -424.766473) (xy 440.481593 -424.734022) (xy 440.531193 -424.708521) (xy 440.583977 -424.690514)
			(xy 440.63882 -424.680384) (xy 440.694554 -424.678347) (xy 440.749991 -424.684447) (xy 440.803948 -424.698553)
			(xy 440.855277 -424.720365) (xy 440.902883 -424.749419) (xy 440.945751 -424.785094) (xy 440.982968 -424.826631)
			(xy 441.013741 -424.873144) (xy 441.037413 -424.923641) (xy 441.053481 -424.977048) (xy 441.061601 -425.032224)
			(xy 441.06211 -425.06011) (xy 441.061601 -425.087996) (xy 441.053481 -425.143172) (xy 441.037413 -425.196579)
			(xy 441.013741 -425.247076) (xy 440.982968 -425.293589) (xy 440.945751 -425.335126) (xy 440.902883 -425.370801)
			(xy 440.855277 -425.399855) (xy 440.803948 -425.421667) (xy 440.749991 -425.435773) (xy 440.694554 -425.441873)
			(xy 440.63882 -425.439836) (xy 440.583977 -425.429706) (xy 440.531193 -425.411699) (xy 440.481593 -425.386198)
			(xy 440.436235 -425.353747) (xy 440.396086 -425.315038) (xy 440.362 -425.270895) (xy 440.334704 -425.22226)
			(xy 440.314781 -425.170169) (xy 440.302655 -425.115732) (xy 440.298584 -425.06011) (xy 438.246781 -425.06011)
			(xy 438.227951 -425.081126) (xy 438.185083 -425.116801) (xy 438.137477 -425.145855) (xy 438.086148 -425.167667)
			(xy 438.032191 -425.181773) (xy 437.976754 -425.187873) (xy 437.92102 -425.185836) (xy 437.866177 -425.175706)
			(xy 437.813393 -425.157699) (xy 437.763793 -425.132198) (xy 437.718435 -425.099747) (xy 437.678286 -425.061038)
			(xy 437.6442 -425.016895) (xy 437.616904 -424.96826) (xy 437.596981 -424.916169) (xy 437.584855 -424.861732)
			(xy 437.580784 -424.80611) (xy 437.345328 -424.80611) (xy 437.345328 -426.07611) (xy 448.045584 -426.07611)
			(xy 448.049655 -426.020488) (xy 448.061781 -425.966051) (xy 448.081704 -425.91396) (xy 448.109 -425.865325)
			(xy 448.143086 -425.821182) (xy 448.183235 -425.782473) (xy 448.228593 -425.750022) (xy 448.278193 -425.724521)
			(xy 448.330977 -425.706514) (xy 448.38582 -425.696384) (xy 448.441554 -425.694347) (xy 448.496991 -425.700447)
			(xy 448.550948 -425.714553) (xy 448.602277 -425.736365) (xy 448.649883 -425.765419) (xy 448.692751 -425.801094)
			(xy 448.729968 -425.842631) (xy 448.760741 -425.889144) (xy 448.776945 -425.92371) (xy 450.299834 -425.92371)
			(xy 450.303905 -425.868088) (xy 450.316031 -425.813651) (xy 450.335954 -425.76156) (xy 450.36325 -425.712925)
			(xy 450.397336 -425.668782) (xy 450.437485 -425.630073) (xy 450.482843 -425.597622) (xy 450.532443 -425.572121)
			(xy 450.585227 -425.554114) (xy 450.64007 -425.543984) (xy 450.695804 -425.541947) (xy 450.751241 -425.548047)
			(xy 450.805198 -425.562153) (xy 450.856527 -425.583965) (xy 450.904133 -425.613019) (xy 450.947001 -425.648694)
			(xy 450.984218 -425.690231) (xy 451.014991 -425.736744) (xy 451.038663 -425.787241) (xy 451.054731 -425.840648)
			(xy 451.062851 -425.895824) (xy 451.06336 -425.92371) (xy 451.062851 -425.951596) (xy 451.054731 -426.006772)
			(xy 451.038663 -426.060179) (xy 451.014991 -426.110676) (xy 450.984218 -426.157189) (xy 450.947001 -426.198726)
			(xy 450.904133 -426.234401) (xy 450.856527 -426.263455) (xy 450.805198 -426.285267) (xy 450.751241 -426.299373)
			(xy 450.695804 -426.305473) (xy 450.64007 -426.303436) (xy 450.585227 -426.293306) (xy 450.532443 -426.275299)
			(xy 450.482843 -426.249798) (xy 450.437485 -426.217347) (xy 450.397336 -426.178638) (xy 450.36325 -426.134495)
			(xy 450.335954 -426.08586) (xy 450.316031 -426.033769) (xy 450.303905 -425.979332) (xy 450.299834 -425.92371)
			(xy 448.776945 -425.92371) (xy 448.784413 -425.939641) (xy 448.800481 -425.993048) (xy 448.808601 -426.048224)
			(xy 448.80911 -426.07611) (xy 448.808601 -426.103996) (xy 448.800481 -426.159172) (xy 448.784413 -426.212579)
			(xy 448.760741 -426.263076) (xy 448.729968 -426.309589) (xy 448.692751 -426.351126) (xy 448.649883 -426.386801)
			(xy 448.602277 -426.415855) (xy 448.550948 -426.437667) (xy 448.496991 -426.451773) (xy 448.441554 -426.457873)
			(xy 448.38582 -426.455836) (xy 448.330977 -426.445706) (xy 448.278193 -426.427699) (xy 448.228593 -426.402198)
			(xy 448.183235 -426.369747) (xy 448.143086 -426.331038) (xy 448.109 -426.286895) (xy 448.081704 -426.23826)
			(xy 448.061781 -426.186169) (xy 448.049655 -426.131732) (xy 448.045584 -426.07611) (xy 437.345328 -426.07611)
			(xy 437.345328 -426.83811) (xy 440.247784 -426.83811) (xy 440.251855 -426.782488) (xy 440.263981 -426.728051)
			(xy 440.283904 -426.67596) (xy 440.3112 -426.627325) (xy 440.345286 -426.583182) (xy 440.385435 -426.544473)
			(xy 440.430793 -426.512022) (xy 440.480393 -426.486521) (xy 440.533177 -426.468514) (xy 440.58802 -426.458384)
			(xy 440.643754 -426.456347) (xy 440.699191 -426.462447) (xy 440.753148 -426.476553) (xy 440.804477 -426.498365)
			(xy 440.852083 -426.527419) (xy 440.894951 -426.563094) (xy 440.932168 -426.604631) (xy 440.962941 -426.651144)
			(xy 440.986613 -426.701641) (xy 441.002681 -426.755048) (xy 441.010801 -426.810224) (xy 441.01131 -426.83811)
			(xy 441.010801 -426.865996) (xy 441.002681 -426.921172) (xy 440.986613 -426.974579) (xy 440.962941 -427.025076)
			(xy 440.932168 -427.071589) (xy 440.894951 -427.113126) (xy 440.852083 -427.148801) (xy 440.804477 -427.177855)
			(xy 440.753148 -427.199667) (xy 440.699191 -427.213773) (xy 440.643754 -427.219873) (xy 440.58802 -427.217836)
			(xy 440.533177 -427.207706) (xy 440.480393 -427.189699) (xy 440.430793 -427.164198) (xy 440.385435 -427.131747)
			(xy 440.345286 -427.093038) (xy 440.3112 -427.048895) (xy 440.283904 -427.00026) (xy 440.263981 -426.948169)
			(xy 440.251855 -426.893732) (xy 440.247784 -426.83811) (xy 437.345328 -426.83811) (xy 437.345328 -427.60011)
			(xy 447.029584 -427.60011) (xy 447.033655 -427.544488) (xy 447.045781 -427.490051) (xy 447.065704 -427.43796)
			(xy 447.093 -427.389325) (xy 447.127086 -427.345182) (xy 447.167235 -427.306473) (xy 447.212593 -427.274022)
			(xy 447.262193 -427.248521) (xy 447.314977 -427.230514) (xy 447.36982 -427.220384) (xy 447.425554 -427.218347)
			(xy 447.480991 -427.224447) (xy 447.534948 -427.238553) (xy 447.586277 -427.260365) (xy 447.633883 -427.289419)
			(xy 447.676751 -427.325094) (xy 447.713968 -427.366631) (xy 447.744741 -427.413144) (xy 447.768413 -427.463641)
			(xy 447.784481 -427.517048) (xy 447.792601 -427.572224) (xy 447.79311 -427.60011) (xy 447.792601 -427.627996)
			(xy 447.784481 -427.683172) (xy 447.768413 -427.736579) (xy 447.744741 -427.787076) (xy 447.713968 -427.833589)
			(xy 447.676751 -427.875126) (xy 447.633883 -427.910801) (xy 447.586277 -427.939855) (xy 447.534948 -427.961667)
			(xy 447.480991 -427.975773) (xy 447.425554 -427.981873) (xy 447.36982 -427.979836) (xy 447.314977 -427.969706)
			(xy 447.262193 -427.951699) (xy 447.212593 -427.926198) (xy 447.167235 -427.893747) (xy 447.127086 -427.855038)
			(xy 447.093 -427.810895) (xy 447.065704 -427.76226) (xy 447.045781 -427.710169) (xy 447.033655 -427.655732)
			(xy 447.029584 -427.60011) (xy 437.345328 -427.60011) (xy 437.345328 -427.952662) (xy 437.345763 -427.962727)
			(xy 437.353496 -427.981312) (xy 437.360314 -427.98873) (xy 437.697438 -428.325854) (xy 443.607365 -428.325854)
			(xy 443.607365 -428.271346) (xy 443.615123 -428.217392) (xy 443.630481 -428.165093) (xy 443.653126 -428.115511)
			(xy 443.682598 -428.069657) (xy 443.718295 -428.028464) (xy 443.759492 -427.992771) (xy 443.805349 -427.963305)
			(xy 443.854934 -427.940666) (xy 443.907236 -427.925314) (xy 443.96119 -427.917562) (xy 443.988444 -427.917102)
			(xy 444.017293 -427.917646) (xy 444.074335 -427.926313) (xy 444.129421 -427.943475) (xy 444.181293 -427.968738)
			(xy 444.228767 -428.001527) (xy 444.270761 -428.041093) (xy 444.306316 -428.086533) (xy 444.32093 -428.111412)
			(xy 444.3281 -428.123128) (xy 444.347478 -428.142576) (xy 444.371341 -428.156153) (xy 444.39796 -428.162874)
			(xy 444.425407 -428.162254) (xy 444.451695 -428.154337) (xy 444.47492 -428.139697) (xy 444.4934 -428.119393)
			(xy 444.5 -428.107348) (xy 444.512235 -428.084067) (xy 444.54219 -428.040838) (xy 444.577801 -428.002135)
			(xy 444.618393 -427.968693) (xy 444.663195 -427.941146) (xy 444.711358 -427.920018) (xy 444.761968 -427.905708)
			(xy 444.814063 -427.898489) (xy 444.84036 -427.898052) (xy 444.867612 -427.898593) (xy 444.921561 -427.906344)
			(xy 444.973859 -427.921695) (xy 445.023439 -427.944333) (xy 445.069292 -427.973797) (xy 445.110485 -428.009487)
			(xy 445.146179 -428.050676) (xy 445.175648 -428.096526) (xy 445.198291 -428.146104) (xy 445.213647 -428.198399)
			(xy 445.221405 -428.252348) (xy 445.221405 -428.306852) (xy 445.213647 -428.360801) (xy 445.198291 -428.413096)
			(xy 445.175648 -428.462674) (xy 445.146179 -428.508524) (xy 445.110485 -428.549713) (xy 445.069292 -428.585403)
			(xy 445.023439 -428.614867) (xy 444.973859 -428.637505) (xy 444.921561 -428.652856) (xy 444.867612 -428.660607)
			(xy 444.84036 -428.661068) (xy 444.811511 -428.660536) (xy 444.754467 -428.651868) (xy 444.69938 -428.634706)
			(xy 444.647508 -428.609441) (xy 444.600033 -428.57665) (xy 444.55804 -428.537081) (xy 444.522487 -428.491638)
			(xy 444.507874 -428.466758) (xy 444.500695 -428.45505) (xy 444.481316 -428.435607) (xy 444.457456 -428.422035)
			(xy 444.43084 -428.415316) (xy 444.403397 -428.415935) (xy 444.377112 -428.423849) (xy 444.353888 -428.438484)
			(xy 444.335406 -428.458781) (xy 444.328804 -428.470822) (xy 444.316553 -428.494094) (xy 444.286602 -428.537325)
			(xy 444.250993 -428.576029) (xy 444.210404 -428.609472) (xy 444.165604 -428.63702) (xy 444.117443 -428.65815)
			(xy 444.066835 -428.672461) (xy 444.01474 -428.679681) (xy 443.988444 -428.680118) (xy 443.96119 -428.679638)
			(xy 443.907236 -428.671886) (xy 443.854934 -428.656534) (xy 443.805349 -428.633895) (xy 443.759492 -428.604429)
			(xy 443.718295 -428.568736) (xy 443.682598 -428.527543) (xy 443.653126 -428.481689) (xy 443.630481 -428.432107)
			(xy 443.615123 -428.379808) (xy 443.607365 -428.325854) (xy 437.697438 -428.325854) (xy 438.673494 -429.30191)
			(xy 439.529726 -429.30191) (xy 439.533797 -429.246288) (xy 439.545923 -429.191851) (xy 439.565846 -429.13976)
			(xy 439.593142 -429.091125) (xy 439.627228 -429.046982) (xy 439.667377 -429.008273) (xy 439.712735 -428.975822)
			(xy 439.762335 -428.950321) (xy 439.815119 -428.932314) (xy 439.869962 -428.922184) (xy 439.925696 -428.920147)
			(xy 439.981133 -428.926247) (xy 440.03509 -428.940353) (xy 440.086419 -428.962165) (xy 440.134025 -428.991219)
			(xy 440.176893 -429.026894) (xy 440.21411 -429.068431) (xy 440.244883 -429.114944) (xy 440.268555 -429.165441)
			(xy 440.284623 -429.218848) (xy 440.292743 -429.274024) (xy 440.293252 -429.30191) (xy 440.292743 -429.329796)
			(xy 440.284623 -429.384972) (xy 440.268555 -429.438379) (xy 440.244883 -429.488876) (xy 440.21411 -429.535389)
			(xy 440.176893 -429.576926) (xy 440.134025 -429.612601) (xy 440.086419 -429.641655) (xy 440.03509 -429.663467)
			(xy 439.981133 -429.677573) (xy 439.925696 -429.683673) (xy 439.869962 -429.681636) (xy 439.815119 -429.671506)
			(xy 439.762335 -429.653499) (xy 439.712735 -429.627998) (xy 439.667377 -429.595547) (xy 439.627228 -429.556838)
			(xy 439.593142 -429.512695) (xy 439.565846 -429.46406) (xy 439.545923 -429.411969) (xy 439.533797 -429.357532)
			(xy 439.529726 -429.30191) (xy 438.673494 -429.30191) (xy 438.760616 -429.389032) (xy 438.767467 -429.396428)
			(xy 438.775203 -429.415027) (xy 438.775602 -429.4251) (xy 438.775602 -430.010824) (xy 449.461634 -430.010824)
			(xy 449.465705 -429.955202) (xy 449.477831 -429.900765) (xy 449.497754 -429.848674) (xy 449.52505 -429.800039)
			(xy 449.559136 -429.755896) (xy 449.599285 -429.717187) (xy 449.644643 -429.684736) (xy 449.694243 -429.659235)
			(xy 449.747027 -429.641228) (xy 449.80187 -429.631098) (xy 449.857604 -429.629061) (xy 449.913041 -429.635161)
			(xy 449.966998 -429.649267) (xy 450.018327 -429.671079) (xy 450.065933 -429.700133) (xy 450.108801 -429.735808)
			(xy 450.146018 -429.777345) (xy 450.176791 -429.823858) (xy 450.200463 -429.874355) (xy 450.216531 -429.927762)
			(xy 450.224651 -429.982938) (xy 450.22516 -430.010824) (xy 450.224651 -430.03871) (xy 450.216531 -430.093886)
			(xy 450.200463 -430.147293) (xy 450.176791 -430.19779) (xy 450.146018 -430.244303) (xy 450.108801 -430.28584)
			(xy 450.065933 -430.321515) (xy 450.018327 -430.350569) (xy 449.966998 -430.372381) (xy 449.913041 -430.386487)
			(xy 449.857604 -430.392587) (xy 449.80187 -430.39055) (xy 449.747027 -430.38042) (xy 449.694243 -430.362413)
			(xy 449.644643 -430.336912) (xy 449.599285 -430.304461) (xy 449.559136 -430.265752) (xy 449.52505 -430.221609)
			(xy 449.497754 -430.172974) (xy 449.477831 -430.120883) (xy 449.465705 -430.066446) (xy 449.461634 -430.010824)
			(xy 438.775602 -430.010824) (xy 438.775602 -430.39411) (xy 440.425584 -430.39411) (xy 440.429655 -430.338488)
			(xy 440.441781 -430.284051) (xy 440.461704 -430.23196) (xy 440.489 -430.183325) (xy 440.523086 -430.139182)
			(xy 440.563235 -430.100473) (xy 440.608593 -430.068022) (xy 440.658193 -430.042521) (xy 440.710977 -430.024514)
			(xy 440.76582 -430.014384) (xy 440.821554 -430.012347) (xy 440.876991 -430.018447) (xy 440.930948 -430.032553)
			(xy 440.982277 -430.054365) (xy 441.029883 -430.083419) (xy 441.072751 -430.119094) (xy 441.109968 -430.160631)
			(xy 441.140741 -430.207144) (xy 441.164413 -430.257641) (xy 441.180481 -430.311048) (xy 441.188601 -430.366224)
			(xy 441.18911 -430.39411) (xy 441.188601 -430.421996) (xy 441.180481 -430.477172) (xy 441.164413 -430.530579)
			(xy 441.140741 -430.581076) (xy 441.109968 -430.627589) (xy 441.072751 -430.669126) (xy 441.029883 -430.704801)
			(xy 440.982277 -430.733855) (xy 440.930948 -430.755667) (xy 440.876991 -430.769773) (xy 440.821554 -430.775873)
			(xy 440.76582 -430.773836) (xy 440.710977 -430.763706) (xy 440.658193 -430.745699) (xy 440.608593 -430.720198)
			(xy 440.563235 -430.687747) (xy 440.523086 -430.649038) (xy 440.489 -430.604895) (xy 440.461704 -430.55626)
			(xy 440.441781 -430.504169) (xy 440.429655 -430.449732) (xy 440.425584 -430.39411) (xy 438.775602 -430.39411)
			(xy 438.775602 -433.89931) (xy 439.609736 -433.89931) (xy 439.613807 -433.843688) (xy 439.625933 -433.789251)
			(xy 439.645856 -433.73716) (xy 439.673152 -433.688525) (xy 439.707238 -433.644382) (xy 439.747387 -433.605673)
			(xy 439.792745 -433.573222) (xy 439.842345 -433.547721) (xy 439.895129 -433.529714) (xy 439.949972 -433.519584)
			(xy 440.005706 -433.517547) (xy 440.061143 -433.523647) (xy 440.1151 -433.537753) (xy 440.166429 -433.559565)
			(xy 440.214035 -433.588619) (xy 440.256903 -433.624294) (xy 440.29412 -433.665831) (xy 440.314657 -433.696872)
			(xy 444.214502 -433.696872) (xy 444.218573 -433.64125) (xy 444.230699 -433.586813) (xy 444.250622 -433.534722)
			(xy 444.277918 -433.486087) (xy 444.312004 -433.441944) (xy 444.352153 -433.403235) (xy 444.397511 -433.370784)
			(xy 444.447111 -433.345283) (xy 444.499895 -433.327276) (xy 444.554738 -433.317146) (xy 444.610472 -433.315109)
			(xy 444.665909 -433.321209) (xy 444.719866 -433.335315) (xy 444.771195 -433.357127) (xy 444.818801 -433.386181)
			(xy 444.861669 -433.421856) (xy 444.898886 -433.463393) (xy 444.929659 -433.509906) (xy 444.953331 -433.560403)
			(xy 444.969399 -433.61381) (xy 444.977519 -433.668986) (xy 444.978028 -433.696872) (xy 444.977519 -433.724758)
			(xy 444.969399 -433.779934) (xy 444.953331 -433.833341) (xy 444.929659 -433.883838) (xy 444.898886 -433.930351)
			(xy 444.861669 -433.971888) (xy 444.818801 -434.007563) (xy 444.771195 -434.036617) (xy 444.719866 -434.058429)
			(xy 444.665909 -434.072535) (xy 444.610472 -434.078635) (xy 444.554738 -434.076598) (xy 444.499895 -434.066468)
			(xy 444.447111 -434.048461) (xy 444.397511 -434.02296) (xy 444.352153 -433.990509) (xy 444.312004 -433.9518)
			(xy 444.277918 -433.907657) (xy 444.250622 -433.859022) (xy 444.230699 -433.806931) (xy 444.218573 -433.752494)
			(xy 444.214502 -433.696872) (xy 440.314657 -433.696872) (xy 440.324893 -433.712344) (xy 440.348565 -433.762841)
			(xy 440.364633 -433.816248) (xy 440.372753 -433.871424) (xy 440.373262 -433.89931) (xy 440.372753 -433.927196)
			(xy 440.364633 -433.982372) (xy 440.348565 -434.035779) (xy 440.324893 -434.086276) (xy 440.29412 -434.132789)
			(xy 440.256903 -434.174326) (xy 440.214035 -434.210001) (xy 440.166429 -434.239055) (xy 440.1151 -434.260867)
			(xy 440.061143 -434.274973) (xy 440.005706 -434.281073) (xy 439.949972 -434.279036) (xy 439.895129 -434.268906)
			(xy 439.842345 -434.250899) (xy 439.792745 -434.225398) (xy 439.747387 -434.192947) (xy 439.707238 -434.154238)
			(xy 439.673152 -434.110095) (xy 439.645856 -434.06146) (xy 439.625933 -434.009369) (xy 439.613807 -433.954932)
			(xy 439.609736 -433.89931) (xy 438.775602 -433.89931) (xy 438.775602 -434.549296) (xy 443.386462 -434.549296)
			(xy 443.390533 -434.493674) (xy 443.402659 -434.439237) (xy 443.422582 -434.387146) (xy 443.449878 -434.338511)
			(xy 443.483964 -434.294368) (xy 443.524113 -434.255659) (xy 443.569471 -434.223208) (xy 443.619071 -434.197707)
			(xy 443.671855 -434.1797) (xy 443.726698 -434.16957) (xy 443.782432 -434.167533) (xy 443.837869 -434.173633)
			(xy 443.891826 -434.187739) (xy 443.943155 -434.209551) (xy 443.990761 -434.238605) (xy 444.033629 -434.27428)
			(xy 444.070846 -434.315817) (xy 444.101619 -434.36233) (xy 444.125291 -434.412827) (xy 444.141359 -434.466234)
			(xy 444.149479 -434.52141) (xy 444.149988 -434.549296) (xy 444.149479 -434.577182) (xy 444.141359 -434.632358)
			(xy 444.125291 -434.685765) (xy 444.101619 -434.736262) (xy 444.070846 -434.782775) (xy 444.033629 -434.824312)
			(xy 443.990761 -434.859987) (xy 443.943155 -434.889041) (xy 443.891826 -434.910853) (xy 443.837869 -434.924959)
			(xy 443.782432 -434.931059) (xy 443.726698 -434.929022) (xy 443.671855 -434.918892) (xy 443.619071 -434.900885)
			(xy 443.569471 -434.875384) (xy 443.524113 -434.842933) (xy 443.483964 -434.804224) (xy 443.449878 -434.760081)
			(xy 443.422582 -434.711446) (xy 443.402659 -434.659355) (xy 443.390533 -434.604918) (xy 443.386462 -434.549296)
			(xy 438.775602 -434.549296) (xy 438.775602 -435.67731) (xy 439.3217 -435.67731) (xy 439.325771 -435.621688)
			(xy 439.337897 -435.567251) (xy 439.35782 -435.51516) (xy 439.385116 -435.466525) (xy 439.419202 -435.422382)
			(xy 439.459351 -435.383673) (xy 439.504709 -435.351222) (xy 439.554309 -435.325721) (xy 439.607093 -435.307714)
			(xy 439.661936 -435.297584) (xy 439.71767 -435.295547) (xy 439.773107 -435.301647) (xy 439.827064 -435.315753)
			(xy 439.878393 -435.337565) (xy 439.925999 -435.366619) (xy 439.968867 -435.402294) (xy 440.006084 -435.443831)
			(xy 440.036857 -435.490344) (xy 440.060529 -435.540841) (xy 440.076597 -435.594248) (xy 440.084717 -435.649424)
			(xy 440.085226 -435.67731) (xy 440.084717 -435.705196) (xy 440.076597 -435.760372) (xy 440.060529 -435.813779)
			(xy 440.036857 -435.864276) (xy 440.034015 -435.868572) (xy 442.751462 -435.868572) (xy 442.755533 -435.81295)
			(xy 442.767659 -435.758513) (xy 442.787582 -435.706422) (xy 442.814878 -435.657787) (xy 442.848964 -435.613644)
			(xy 442.889113 -435.574935) (xy 442.934471 -435.542484) (xy 442.984071 -435.516983) (xy 443.036855 -435.498976)
			(xy 443.091698 -435.488846) (xy 443.147432 -435.486809) (xy 443.202869 -435.492909) (xy 443.256826 -435.507015)
			(xy 443.308155 -435.528827) (xy 443.355761 -435.557881) (xy 443.398629 -435.593556) (xy 443.435846 -435.635093)
			(xy 443.463648 -435.677116) (xy 445.799708 -435.677116) (xy 445.799708 -435.522564) (xy 445.807664 -435.368217)
			(xy 445.823555 -435.214484) (xy 445.847339 -435.061773) (xy 445.878953 -434.910489) (xy 445.918313 -434.761033)
			(xy 445.965314 -434.613801) (xy 446.019833 -434.469184) (xy 446.081724 -434.327565) (xy 446.150823 -434.189321)
			(xy 446.226947 -434.054816) (xy 446.309895 -433.924409) (xy 446.399446 -433.798445) (xy 446.495362 -433.677257)
			(xy 446.59739 -433.561169) (xy 446.705259 -433.450486) (xy 446.818682 -433.345503) (xy 446.93736 -433.246498)
			(xy 447.060976 -433.153733) (xy 447.189205 -433.067456) (xy 447.321704 -432.987893) (xy 447.458124 -432.915258)
			(xy 447.598102 -432.849741) (xy 447.741268 -432.791517) (xy 447.88724 -432.74074) (xy 448.035633 -432.697545)
			(xy 448.186053 -432.662046) (xy 448.338101 -432.634338) (xy 448.491374 -432.614494) (xy 448.645465 -432.602566)
			(xy 448.799966 -432.598587) (xy 448.954467 -432.602566) (xy 449.108558 -432.614494) (xy 449.261831 -432.634338)
			(xy 449.413879 -432.662046) (xy 449.564299 -432.697545) (xy 449.712692 -432.74074) (xy 449.858664 -432.791517)
			(xy 450.00183 -432.849741) (xy 450.141808 -432.915258) (xy 450.278228 -432.987893) (xy 450.410727 -433.067456)
			(xy 450.538956 -433.153733) (xy 450.662572 -433.246498) (xy 450.78125 -433.345503) (xy 450.894673 -433.450486)
			(xy 451.002542 -433.561169) (xy 451.10457 -433.677257) (xy 451.200486 -433.798445) (xy 451.290037 -433.924409)
			(xy 451.372985 -434.054816) (xy 451.449109 -434.189321) (xy 451.518208 -434.327565) (xy 451.580099 -434.469184)
			(xy 451.634618 -434.613801) (xy 451.681619 -434.761033) (xy 451.720979 -434.910489) (xy 451.752593 -435.061773)
			(xy 451.776377 -435.214484) (xy 451.792268 -435.368217) (xy 451.800224 -435.522564) (xy 451.800722 -435.59984)
			(xy 451.800224 -435.677116) (xy 451.792268 -435.831463) (xy 451.776377 -435.985196) (xy 451.752593 -436.137907)
			(xy 451.720979 -436.289191) (xy 451.681619 -436.438647) (xy 451.634618 -436.585879) (xy 451.580099 -436.730496)
			(xy 451.518208 -436.872115) (xy 451.449109 -437.010359) (xy 451.372985 -437.144864) (xy 451.290037 -437.275271)
			(xy 451.200486 -437.401235) (xy 451.10457 -437.522423) (xy 451.002542 -437.638511) (xy 450.894673 -437.749194)
			(xy 450.78125 -437.854177) (xy 450.662572 -437.953182) (xy 450.538956 -438.045947) (xy 450.410727 -438.132224)
			(xy 450.278228 -438.211787) (xy 450.141808 -438.284422) (xy 450.00183 -438.349939) (xy 449.858664 -438.408163)
			(xy 449.712692 -438.45894) (xy 449.564299 -438.502135) (xy 449.413879 -438.537634) (xy 449.261831 -438.565342)
			(xy 449.108558 -438.585186) (xy 448.954467 -438.597114) (xy 448.799966 -438.601094) (xy 448.645465 -438.597114)
			(xy 448.491374 -438.585186) (xy 448.338101 -438.565342) (xy 448.186053 -438.537634) (xy 448.035633 -438.502135)
			(xy 447.88724 -438.45894) (xy 447.741268 -438.408163) (xy 447.598102 -438.349939) (xy 447.458124 -438.284422)
			(xy 447.321704 -438.211787) (xy 447.189205 -438.132224) (xy 447.060976 -438.045947) (xy 446.93736 -437.953182)
			(xy 446.818682 -437.854177) (xy 446.705259 -437.749194) (xy 446.59739 -437.638511) (xy 446.495362 -437.522423)
			(xy 446.399446 -437.401235) (xy 446.309895 -437.275271) (xy 446.226947 -437.144864) (xy 446.150823 -437.010359)
			(xy 446.081724 -436.872115) (xy 446.019833 -436.730496) (xy 445.965314 -436.585879) (xy 445.918313 -436.438647)
			(xy 445.878953 -436.289191) (xy 445.847339 -436.137907) (xy 445.823555 -435.985196) (xy 445.807664 -435.831463)
			(xy 445.799708 -435.677116) (xy 443.463648 -435.677116) (xy 443.466619 -435.681606) (xy 443.490291 -435.732103)
			(xy 443.506359 -435.78551) (xy 443.514479 -435.840686) (xy 443.514988 -435.868572) (xy 443.514479 -435.896458)
			(xy 443.506359 -435.951634) (xy 443.490291 -436.005041) (xy 443.466619 -436.055538) (xy 443.435846 -436.102051)
			(xy 443.398629 -436.143588) (xy 443.355761 -436.179263) (xy 443.308155 -436.208317) (xy 443.256826 -436.230129)
			(xy 443.202869 -436.244235) (xy 443.147432 -436.250335) (xy 443.091698 -436.248298) (xy 443.036855 -436.238168)
			(xy 442.984071 -436.220161) (xy 442.934471 -436.19466) (xy 442.889113 -436.162209) (xy 442.848964 -436.1235)
			(xy 442.814878 -436.079357) (xy 442.787582 -436.030722) (xy 442.767659 -435.978631) (xy 442.755533 -435.924194)
			(xy 442.751462 -435.868572) (xy 440.034015 -435.868572) (xy 440.006084 -435.910789) (xy 439.968867 -435.952326)
			(xy 439.925999 -435.988001) (xy 439.878393 -436.017055) (xy 439.827064 -436.038867) (xy 439.773107 -436.052973)
			(xy 439.71767 -436.059073) (xy 439.661936 -436.057036) (xy 439.607093 -436.046906) (xy 439.554309 -436.028899)
			(xy 439.504709 -436.003398) (xy 439.459351 -435.970947) (xy 439.419202 -435.932238) (xy 439.385116 -435.888095)
			(xy 439.35782 -435.83946) (xy 439.337897 -435.787369) (xy 439.325771 -435.732932) (xy 439.3217 -435.67731)
			(xy 438.775602 -435.67731) (xy 438.775602 -436.412132) (xy 443.985902 -436.412132) (xy 443.989973 -436.35651)
			(xy 444.002099 -436.302073) (xy 444.022022 -436.249982) (xy 444.049318 -436.201347) (xy 444.083404 -436.157204)
			(xy 444.123553 -436.118495) (xy 444.168911 -436.086044) (xy 444.218511 -436.060543) (xy 444.271295 -436.042536)
			(xy 444.326138 -436.032406) (xy 444.381872 -436.030369) (xy 444.437309 -436.036469) (xy 444.491266 -436.050575)
			(xy 444.542595 -436.072387) (xy 444.590201 -436.101441) (xy 444.633069 -436.137116) (xy 444.670286 -436.178653)
			(xy 444.701059 -436.225166) (xy 444.724731 -436.275663) (xy 444.740799 -436.32907) (xy 444.748919 -436.384246)
			(xy 444.749428 -436.412132) (xy 444.748919 -436.440018) (xy 444.740799 -436.495194) (xy 444.724731 -436.548601)
			(xy 444.701059 -436.599098) (xy 444.670286 -436.645611) (xy 444.633069 -436.687148) (xy 444.590201 -436.722823)
			(xy 444.542595 -436.751877) (xy 444.491266 -436.773689) (xy 444.437309 -436.787795) (xy 444.381872 -436.793895)
			(xy 444.326138 -436.791858) (xy 444.271295 -436.781728) (xy 444.218511 -436.763721) (xy 444.168911 -436.73822)
			(xy 444.123553 -436.705769) (xy 444.083404 -436.66706) (xy 444.049318 -436.622917) (xy 444.022022 -436.574282)
			(xy 444.002099 -436.522191) (xy 443.989973 -436.467754) (xy 443.985902 -436.412132) (xy 438.775602 -436.412132)
			(xy 438.775602 -439.469276) (xy 438.776039 -439.47934) (xy 438.783773 -439.497924) (xy 438.790588 -439.505344)
			(xy 438.810654 -439.52541) (xy 439.3217 -439.52541) (xy 439.325771 -439.469788) (xy 439.337897 -439.415351)
			(xy 439.35782 -439.36326) (xy 439.385116 -439.314625) (xy 439.419202 -439.270482) (xy 439.459351 -439.231773)
			(xy 439.504709 -439.199322) (xy 439.554309 -439.173821) (xy 439.607093 -439.155814) (xy 439.661936 -439.145684)
			(xy 439.71767 -439.143647) (xy 439.773107 -439.149747) (xy 439.827064 -439.163853) (xy 439.878393 -439.185665)
			(xy 439.925999 -439.214719) (xy 439.968867 -439.250394) (xy 440.006084 -439.291931) (xy 440.036857 -439.338444)
			(xy 440.060529 -439.388941) (xy 440.076597 -439.442348) (xy 440.084717 -439.497524) (xy 440.085226 -439.52541)
			(xy 440.084717 -439.553296) (xy 440.076597 -439.608472) (xy 440.060529 -439.661879) (xy 440.036857 -439.712376)
			(xy 440.006084 -439.758889) (xy 439.968867 -439.800426) (xy 439.925999 -439.836101) (xy 439.878393 -439.865155)
			(xy 439.827064 -439.886967) (xy 439.773107 -439.901073) (xy 439.71767 -439.907173) (xy 439.661936 -439.905136)
			(xy 439.607093 -439.895006) (xy 439.554309 -439.876999) (xy 439.504709 -439.851498) (xy 439.459351 -439.819047)
			(xy 439.419202 -439.780338) (xy 439.385116 -439.736195) (xy 439.35782 -439.68756) (xy 439.337897 -439.635469)
			(xy 439.325771 -439.581032) (xy 439.3217 -439.52541) (xy 438.810654 -439.52541) (xy 439.895234 -440.60999)
			(xy 439.902634 -440.616832) (xy 439.921232 -440.624556) (xy 439.931302 -440.624976)
		)
		(stroke
			(width 0)
			(type solid)
		)
		(fill yes)
		(layer "In6.Cu")
		(net "GND")
	)
	(gr_poly
		(pts
			(xy 101.992684 -391.26922) (xy 102.002673 -391.268686) (xy 102.021111 -391.260979) (xy 102.028498 -391.254234)
			(xy 102.575106 -390.70788) (xy 102.581948 -390.70048) (xy 102.589675 -390.681882) (xy 102.590092 -390.671812)
			(xy 102.590092 -389.344662) (xy 102.589604 -389.334942) (xy 102.582287 -389.316926) (xy 102.575868 -389.30961)
			(xy 102.555294 -389.287766) (xy 102.548738 -389.281424) (xy 102.53233 -389.273489) (xy 102.52329 -389.272272)
			(xy 102.49395 -389.268809) (xy 102.43676 -389.254002) (xy 102.38253 -389.23057) (xy 102.332552 -389.199071)
			(xy 102.30993 -389.18007) (xy 102.302818 -389.173974) (xy 102.2858 -389.167624) (xy 102.200456 -389.167624)
			(xy 102.183438 -389.173974) (xy 102.176326 -389.18007) (xy 102.155393 -389.197711) (xy 102.109425 -389.227435)
			(xy 102.059679 -389.250281) (xy 102.007177 -389.265777) (xy 101.952999 -389.273606) (xy 101.898257 -389.273606)
			(xy 101.844079 -389.265777) (xy 101.791577 -389.250281) (xy 101.741831 -389.227435) (xy 101.695863 -389.197711)
			(xy 101.67493 -389.18007) (xy 101.667818 -389.173974) (xy 101.6508 -389.167624) (xy 101.565456 -389.167624)
			(xy 101.548438 -389.173974) (xy 101.541326 -389.18007) (xy 101.520396 -389.197715) (xy 101.474431 -389.227446)
			(xy 101.424684 -389.250295) (xy 101.37218 -389.26579) (xy 101.317999 -389.273613) (xy 101.290628 -389.27405)
			(xy 101.262026 -389.273542) (xy 101.205462 -389.265011) (xy 101.150803 -389.248136) (xy 101.099275 -389.223294)
			(xy 101.05203 -389.191041) (xy 101.010126 -389.152101) (xy 100.991924 -389.130032) (xy 100.983288 -389.118856)
			(xy 100.956618 -389.10895) (xy 100.840286 -389.131302) (xy 100.819458 -389.150098) (xy 100.815394 -389.163814)
			(xy 100.805267 -389.195148) (xy 100.777287 -389.254759) (xy 100.741065 -389.309752) (xy 100.719636 -389.334756)
			(xy 100.713286 -389.341868) (xy 100.706682 -389.35914) (xy 100.706682 -389.445246) (xy 100.713286 -389.462518)
			(xy 100.719636 -389.46963) (xy 100.741193 -389.494881) (xy 100.777553 -389.55043) (xy 100.805513 -389.610647)
			(xy 100.824487 -389.674269) (xy 100.834077 -389.739964) (xy 100.834698 -389.77316) (xy 100.834144 -389.804758)
			(xy 100.825416 -389.86735) (xy 100.808173 -389.92815) (xy 100.782744 -389.986006) (xy 100.766626 -390.01319)
			(xy 100.762071 -390.021409) (xy 100.758634 -390.039866) (xy 100.762046 -390.058327) (xy 100.766626 -390.06653)
			(xy 100.782765 -390.093705) (xy 100.808224 -390.151553) (xy 100.825468 -390.212358) (xy 100.83417 -390.274959)
			(xy 100.834698 -390.30656) (xy 100.834168 -390.338176) (xy 100.825469 -390.400806) (xy 100.808232 -390.461642)
			(xy 100.782785 -390.519527) (xy 100.749612 -390.573358) (xy 100.709345 -390.62211) (xy 100.66275 -390.664855)
			(xy 100.610715 -390.700779) (xy 100.58273 -390.7155) (xy 100.573326 -390.720681) (xy 100.55968 -390.737231)
			(xy 100.554039 -390.757926) (xy 100.555298 -390.768586) (xy 100.557097 -390.781145) (xy 100.559005 -390.806446)
			(xy 100.559108 -390.819132) (xy 100.558598 -390.845119) (xy 100.550468 -390.896454) (xy 100.534407 -390.945884)
			(xy 100.510811 -390.992194) (xy 100.480261 -391.034242) (xy 100.44351 -391.070993) (xy 100.401462 -391.101543)
			(xy 100.355152 -391.125139) (xy 100.305722 -391.1412) (xy 100.254387 -391.14933) (xy 100.202413 -391.14933)
			(xy 100.151078 -391.1412) (xy 100.101648 -391.125139) (xy 100.055338 -391.101543) (xy 100.01329 -391.070993)
			(xy 99.976539 -391.034242) (xy 99.945989 -390.992194) (xy 99.922393 -390.945884) (xy 99.906332 -390.896454)
			(xy 99.898202 -390.845119) (xy 99.897692 -390.819132) (xy 99.8981 -390.795394) (xy 99.904887 -390.748404)
			(xy 99.918325 -390.702869) (xy 99.938139 -390.659724) (xy 99.96392 -390.619858) (xy 99.979226 -390.601708)
			(xy 99.985967 -390.593323) (xy 99.992329 -390.572791) (xy 99.989726 -390.551454) (xy 99.98456 -390.542018)
			(xy 99.969089 -390.515232) (xy 99.944697 -390.458387) (xy 99.928168 -390.398778) (xy 99.919804 -390.337488)
			(xy 99.919282 -390.30656) (xy 99.919834 -390.274961) (xy 99.92856 -390.212368) (xy 99.9458 -390.151566)
			(xy 99.971226 -390.093709) (xy 99.987354 -390.06653) (xy 99.991896 -390.058312) (xy 99.995306 -390.039866)
			(xy 99.991871 -390.021423) (xy 99.987354 -390.01319) (xy 99.971211 -389.986016) (xy 99.945745 -389.928169)
			(xy 99.928495 -389.867364) (xy 99.91979 -389.804762) (xy 99.919282 -389.77316) (xy 99.919878 -389.739928)
			(xy 99.929493 -389.674162) (xy 99.948514 -389.610477) (xy 99.976543 -389.550211) (xy 100.012989 -389.494631)
			(xy 100.034598 -389.469376) (xy 100.040948 -389.462264) (xy 100.047552 -389.444992) (xy 100.047552 -389.358886)
			(xy 100.040948 -389.341614) (xy 100.034598 -389.334502) (xy 100.013038 -389.309253) (xy 99.976671 -389.253705)
			(xy 99.948705 -389.193488) (xy 99.929725 -389.129865) (xy 99.92013 -389.064169) (xy 99.919536 -389.030972)
			(xy 99.920085 -388.999148) (xy 99.928909 -388.936114) (xy 99.946381 -388.874912) (xy 99.972166 -388.81672)
			(xy 100.005765 -388.762663) (xy 100.025708 -388.737856) (xy 100.03155 -388.730744) (xy 100.037646 -388.713218)
			(xy 100.035106 -388.627112) (xy 100.027994 -388.610094) (xy 100.021644 -388.603236) (xy 100.002165 -388.581957)
			(xy 99.96816 -388.535355) (xy 99.940285 -388.484847) (xy 99.918982 -388.431234) (xy 99.90459 -388.375369)
			(xy 99.897337 -388.318137) (xy 99.89693 -388.289292) (xy 99.89742 -388.259324) (xy 99.905243 -388.199902)
			(xy 99.920756 -388.142009) (xy 99.943692 -388.086636) (xy 99.973659 -388.03473) (xy 100.010146 -387.98718)
			(xy 100.052526 -387.9448) (xy 100.100076 -387.908313) (xy 100.151982 -387.878346) (xy 100.207355 -387.85541)
			(xy 100.265248 -387.839897) (xy 100.32467 -387.832074) (xy 100.384606 -387.832074) (xy 100.444028 -387.839897)
			(xy 100.501921 -387.85541) (xy 100.557294 -387.878346) (xy 100.6092 -387.908313) (xy 100.65675 -387.9448)
			(xy 100.69913 -387.98718) (xy 100.735617 -388.03473) (xy 100.765584 -388.086636) (xy 100.78852 -388.142009)
			(xy 100.804033 -388.199902) (xy 100.811856 -388.259324) (xy 100.812346 -388.289292) (xy 100.811799 -388.321117)
			(xy 100.80298 -388.384152) (xy 100.785511 -388.445358) (xy 100.759728 -388.503552) (xy 100.726131 -388.557612)
			(xy 100.706174 -388.582408) (xy 100.700332 -388.58952) (xy 100.694236 -388.607046) (xy 100.696776 -388.693152)
			(xy 100.703888 -388.71017) (xy 100.710238 -388.717028) (xy 100.722735 -388.730546) (xy 100.745747 -388.759286)
			(xy 100.756212 -388.774432) (xy 100.76434 -388.786116) (xy 100.789994 -388.798054) (xy 100.907596 -388.784846)
			(xy 100.929948 -388.767574) (xy 100.935028 -388.754366) (xy 100.94588 -388.727868) (xy 100.97437 -388.6782)
			(xy 101.009963 -388.633347) (xy 101.05186 -388.594318) (xy 101.099119 -388.561989) (xy 101.150679 -388.537085)
			(xy 101.205382 -388.520167) (xy 101.261998 -388.511613) (xy 101.290628 -388.511034) (xy 101.317997 -388.511508)
			(xy 101.372173 -388.519336) (xy 101.424674 -388.534827) (xy 101.474421 -388.557663) (xy 101.520393 -388.587376)
			(xy 101.541326 -388.605014) (xy 101.548438 -388.61111) (xy 101.565456 -388.61746) (xy 101.6508 -388.61746)
			(xy 101.667818 -388.61111) (xy 101.67493 -388.605014) (xy 101.695863 -388.587373) (xy 101.741831 -388.557649)
			(xy 101.791577 -388.534803) (xy 101.844079 -388.519307) (xy 101.898257 -388.511478) (xy 101.952999 -388.511478)
			(xy 102.007177 -388.519307) (xy 102.059679 -388.534803) (xy 102.109425 -388.557649) (xy 102.155393 -388.587373)
			(xy 102.176326 -388.605014) (xy 102.183438 -388.61111) (xy 102.200456 -388.61746) (xy 102.2858 -388.61746)
			(xy 102.302818 -388.61111) (xy 102.30993 -388.605014) (xy 102.332547 -388.586003) (xy 102.382513 -388.554478)
			(xy 102.436746 -388.531041) (xy 102.493946 -388.516253) (xy 102.52329 -388.512812) (xy 102.53232 -388.511567)
			(xy 102.548717 -388.503629) (xy 102.555294 -388.497318) (xy 102.575868 -388.475474) (xy 102.582315 -388.468176)
			(xy 102.589632 -388.450149) (xy 102.590092 -388.440422) (xy 102.590092 -387.96214) (xy 102.590551 -387.929629)
			(xy 102.597835 -387.865015) (xy 102.612304 -387.801623) (xy 102.633778 -387.740248) (xy 102.661986 -387.681662)
			(xy 102.696574 -387.626602) (xy 102.737106 -387.575758) (xy 102.759764 -387.552438) (xy 102.76459 -387.547358)
			(xy 102.771312 -387.539925) (xy 102.778959 -387.521422) (xy 102.778964 -387.501402) (xy 102.771326 -387.482895)
			(xy 102.76459 -387.475476) (xy 102.758748 -387.469634) (xy 102.744524 -387.462522) (xy 102.736396 -387.461252)
			(xy 102.709668 -387.456718) (xy 102.657759 -387.441087) (xy 102.608585 -387.418265) (xy 102.563137 -387.388714)
			(xy 102.522328 -387.353027) (xy 102.486982 -387.311923) (xy 102.457809 -387.266231) (xy 102.435397 -387.216869)
			(xy 102.420197 -387.164832) (xy 102.412515 -387.111168) (xy 102.412038 -387.084062) (xy 102.412504 -387.056812)
			(xy 102.420266 -387.002868) (xy 102.435625 -386.950577) (xy 102.458271 -386.901005) (xy 102.48774 -386.85516)
			(xy 102.523435 -386.813975) (xy 102.564627 -386.77829) (xy 102.610478 -386.74883) (xy 102.660056 -386.726196)
			(xy 102.71235 -386.710848) (xy 102.766296 -386.703098) (xy 102.793546 -386.702554) (xy 102.822772 -386.703108)
			(xy 102.88054 -386.712017) (xy 102.936273 -386.729636) (xy 102.988666 -386.755551) (xy 103.036491 -386.789155)
			(xy 103.07863 -386.829663) (xy 103.114096 -386.876125) (xy 103.142058 -386.927454) (xy 103.152448 -386.954776)
			(xy 103.15702 -386.967222) (xy 103.176324 -386.98424) (xy 103.272844 -387.00583) (xy 103.281246 -387.007331)
			(xy 103.298186 -387.005314) (xy 103.313541 -386.997883) (xy 103.319834 -386.992114) (xy 104.96042 -385.351782)
			(xy 104.967193 -385.344356) (xy 104.974777 -385.325759) (xy 104.975152 -385.315714) (xy 104.975152 -385.085844)
			(xy 104.975601 -385.053322) (xy 104.982903 -384.98869) (xy 104.997398 -384.925283) (xy 105.018904 -384.863897)
			(xy 105.04715 -384.805307) (xy 105.08178 -384.750249) (xy 105.122359 -384.699416) (xy 105.145078 -384.676142)
			(xy 105.488994 -384.331972) (xy 105.495801 -384.324625) (xy 105.503524 -384.306163) (xy 105.50398 -384.296158)
			(xy 105.50398 -383.388362) (xy 105.503549 -383.378295) (xy 105.495823 -383.359703) (xy 105.488994 -383.352294)
			(xy 104.810306 -382.673606) (xy 104.802908 -382.666758) (xy 104.78431 -382.65902) (xy 104.774238 -382.65862)
			(xy 103.015542 -382.65862) (xy 103.005476 -382.658187) (xy 102.986885 -382.65046) (xy 102.979474 -382.643634)
			(xy 102.554024 -382.218184) (xy 102.547001 -382.211765) (xy 102.529557 -382.204203) (xy 102.510557 -382.203504)
			(xy 102.501446 -382.206246) (xy 102.401116 -382.241552) (xy 102.382828 -382.264412) (xy 102.381304 -382.279144)
			(xy 102.377778 -382.306815) (xy 102.363679 -382.360785) (xy 102.341871 -382.412126) (xy 102.312819 -382.459744)
			(xy 102.277142 -382.502624) (xy 102.2356 -382.539851) (xy 102.189081 -382.570631) (xy 102.138575 -382.594309)
			(xy 102.085159 -382.61038) (xy 102.029972 -382.618501) (xy 102.002082 -382.618996) (xy 101.974832 -382.618508)
			(xy 101.920887 -382.61075) (xy 101.868595 -382.595393) (xy 101.819021 -382.572751) (xy 101.773174 -382.543284)
			(xy 101.731987 -382.507592) (xy 101.696298 -382.466402) (xy 101.666835 -382.420553) (xy 101.644196 -382.370977)
			(xy 101.628844 -382.318684) (xy 101.621089 -382.264738) (xy 101.620574 -382.237488) (xy 101.621059 -382.209597)
			(xy 101.629183 -382.154411) (xy 101.645257 -382.100995) (xy 101.668937 -382.050489) (xy 101.699719 -382.00397)
			(xy 101.736946 -381.962429) (xy 101.779826 -381.926751) (xy 101.827444 -381.897697) (xy 101.878785 -381.875887)
			(xy 101.932754 -381.861785) (xy 101.960426 -381.858266) (xy 101.975158 -381.856742) (xy 101.998018 -381.838454)
			(xy 102.033324 -381.738124) (xy 102.036086 -381.729019) (xy 102.035376 -381.710019) (xy 102.027789 -381.692586)
			(xy 102.021386 -381.685546) (xy 101.223826 -380.887986) (xy 101.216428 -380.881142) (xy 101.197828 -380.873421)
			(xy 101.187758 -380.873) (xy 76.597002 -380.873) (xy 76.568554 -380.8984) (xy 76.566268 -380.917704)
			(xy 76.562528 -380.945197) (xy 76.548124 -380.998777) (xy 76.526108 -381.049704) (xy 76.496945 -381.096904)
			(xy 76.46125 -381.13938) (xy 76.419778 -381.176235) (xy 76.373403 -381.206693) (xy 76.323104 -381.230109)
			(xy 76.269943 -381.24599) (xy 76.215042 -381.254001) (xy 76.1873 -381.254508) (xy 76.157235 -381.253973)
			(xy 76.097844 -381.244588) (xy 76.040664 -381.22599) (xy 75.987116 -381.198638) (xy 75.96251 -381.181356)
			(xy 75.94727 -381.17018) (xy 75.909932 -381.173228) (xy 74.884534 -382.198626) (xy 74.877683 -382.20599)
			(xy 74.869921 -382.224528) (xy 74.869912 -382.244626) (xy 74.877656 -382.263171) (xy 74.884534 -382.270508)
			(xy 74.884788 -382.270762) (xy 74.885042 -382.271016) (xy 74.902946 -382.289036) (xy 74.934312 -382.328994)
			(xy 74.960098 -382.372761) (xy 74.979846 -382.419563) (xy 74.993209 -382.468572) (xy 74.999948 -382.518921)
			(xy 75.000358 -382.54432) (xy 74.999893 -382.571571) (xy 74.992134 -382.625517) (xy 74.976775 -382.677809)
			(xy 74.954131 -382.727384) (xy 74.924662 -382.773231) (xy 74.888967 -382.814417) (xy 74.847775 -382.850104)
			(xy 74.8092 -382.874889) (xy 77.570068 -382.874889) (xy 77.570068 -382.822911) (xy 77.578198 -382.771574)
			(xy 77.594259 -382.72214) (xy 77.617856 -382.675828) (xy 77.648406 -382.633776) (xy 77.685158 -382.597021)
			(xy 77.727207 -382.566468) (xy 77.773518 -382.542869) (xy 77.822951 -382.526804) (xy 77.874287 -382.518669)
			(xy 77.900276 -382.518158) (xy 77.926317 -382.518672) (xy 77.977757 -382.526826) (xy 78.02728 -382.542952)
			(xy 78.073658 -382.566649) (xy 78.115743 -382.597332) (xy 78.134464 -382.61544) (xy 78.141068 -382.622044)
			(xy 78.15707 -382.62941) (xy 78.241398 -382.636522) (xy 78.258416 -382.631696) (xy 78.265782 -382.626362)
			(xy 78.286989 -382.611691) (xy 78.333018 -382.588445) (xy 78.382098 -382.572628) (xy 78.433039 -382.564625)
			(xy 78.458822 -382.564132) (xy 78.483658 -382.564604) (xy 78.532774 -382.572017) (xy 78.580225 -382.586703)
			(xy 78.624942 -382.608329) (xy 78.665916 -382.636409) (xy 78.684374 -382.653032) (xy 78.691433 -382.659081)
			(xy 78.708627 -382.66611) (xy 78.717902 -382.666748) (xy 78.749144 -382.66751) (xy 78.758398 -382.667333)
			(xy 78.77585 -382.661222) (xy 78.78318 -382.655572) (xy 78.805727 -382.637384) (xy 78.855864 -382.608373)
			(xy 78.910282 -382.588526) (xy 78.967324 -382.578447) (xy 78.996286 -382.577848) (xy 79.022273 -382.578418)
			(xy 79.073606 -382.586546) (xy 79.123036 -382.602605) (xy 79.169345 -382.626199) (xy 79.211393 -382.656747)
			(xy 79.248144 -382.693497) (xy 79.278694 -382.735543) (xy 79.302289 -382.781851) (xy 79.31835 -382.83128)
			(xy 79.325896 -382.878917) (xy 80.014066 -382.878917) (xy 80.014066 -382.826943) (xy 80.022196 -382.775608)
			(xy 80.038257 -382.726178) (xy 80.061853 -382.679868) (xy 80.092403 -382.63782) (xy 80.129154 -382.601069)
			(xy 80.171202 -382.570519) (xy 80.217512 -382.546923) (xy 80.266942 -382.530862) (xy 80.318277 -382.522732)
			(xy 80.370251 -382.522732) (xy 80.421586 -382.530862) (xy 80.471016 -382.546923) (xy 80.517326 -382.570519)
			(xy 80.559374 -382.601069) (xy 80.596125 -382.63782) (xy 80.626675 -382.679868) (xy 80.650271 -382.726178)
			(xy 80.666332 -382.775608) (xy 80.674462 -382.826943) (xy 80.674972 -382.85293) (xy 80.674462 -382.878917)
			(xy 81.214216 -382.878917) (xy 81.214216 -382.826943) (xy 81.222346 -382.775608) (xy 81.238407 -382.726178)
			(xy 81.262003 -382.679868) (xy 81.292553 -382.63782) (xy 81.329304 -382.601069) (xy 81.371352 -382.570519)
			(xy 81.417662 -382.546923) (xy 81.467092 -382.530862) (xy 81.518427 -382.522732) (xy 81.570401 -382.522732)
			(xy 81.621736 -382.530862) (xy 81.671166 -382.546923) (xy 81.717476 -382.570519) (xy 81.759524 -382.601069)
			(xy 81.796275 -382.63782) (xy 81.826825 -382.679868) (xy 81.850421 -382.726178) (xy 81.866482 -382.775608)
			(xy 81.874612 -382.826943) (xy 81.875122 -382.85293) (xy 81.874612 -382.878917) (xy 82.414112 -382.878917)
			(xy 82.414112 -382.826943) (xy 82.422242 -382.775608) (xy 82.438303 -382.726178) (xy 82.461899 -382.679868)
			(xy 82.492449 -382.63782) (xy 82.5292 -382.601069) (xy 82.571248 -382.570519) (xy 82.617558 -382.546923)
			(xy 82.666988 -382.530862) (xy 82.718323 -382.522732) (xy 82.770297 -382.522732) (xy 82.821632 -382.530862)
			(xy 82.871062 -382.546923) (xy 82.917372 -382.570519) (xy 82.95942 -382.601069) (xy 82.996171 -382.63782)
			(xy 83.026721 -382.679868) (xy 83.050317 -382.726178) (xy 83.066378 -382.775608) (xy 83.074508 -382.826943)
			(xy 83.075018 -382.85293) (xy 83.074508 -382.878917) (xy 83.614008 -382.878917) (xy 83.614008 -382.826943)
			(xy 83.622138 -382.775608) (xy 83.638199 -382.726178) (xy 83.661795 -382.679868) (xy 83.692345 -382.63782)
			(xy 83.729096 -382.601069) (xy 83.771144 -382.570519) (xy 83.817454 -382.546923) (xy 83.866884 -382.530862)
			(xy 83.918219 -382.522732) (xy 83.970193 -382.522732) (xy 84.021528 -382.530862) (xy 84.070958 -382.546923)
			(xy 84.117268 -382.570519) (xy 84.159316 -382.601069) (xy 84.196067 -382.63782) (xy 84.226617 -382.679868)
			(xy 84.250213 -382.726178) (xy 84.266274 -382.775608) (xy 84.274404 -382.826943) (xy 84.274914 -382.85293)
			(xy 84.274404 -382.878917) (xy 84.814158 -382.878917) (xy 84.814158 -382.826943) (xy 84.822288 -382.775608)
			(xy 84.838349 -382.726178) (xy 84.861945 -382.679868) (xy 84.892495 -382.63782) (xy 84.929246 -382.601069)
			(xy 84.971294 -382.570519) (xy 85.017604 -382.546923) (xy 85.067034 -382.530862) (xy 85.118369 -382.522732)
			(xy 85.170343 -382.522732) (xy 85.221678 -382.530862) (xy 85.271108 -382.546923) (xy 85.317418 -382.570519)
			(xy 85.359466 -382.601069) (xy 85.396217 -382.63782) (xy 85.426767 -382.679868) (xy 85.450363 -382.726178)
			(xy 85.466424 -382.775608) (xy 85.474554 -382.826943) (xy 85.475064 -382.85293) (xy 85.474554 -382.878917)
			(xy 86.014054 -382.878917) (xy 86.014054 -382.826943) (xy 86.022184 -382.775608) (xy 86.038245 -382.726178)
			(xy 86.061841 -382.679868) (xy 86.092391 -382.63782) (xy 86.129142 -382.601069) (xy 86.17119 -382.570519)
			(xy 86.2175 -382.546923) (xy 86.26693 -382.530862) (xy 86.318265 -382.522732) (xy 86.370239 -382.522732)
			(xy 86.421574 -382.530862) (xy 86.471004 -382.546923) (xy 86.517314 -382.570519) (xy 86.559362 -382.601069)
			(xy 86.596113 -382.63782) (xy 86.626663 -382.679868) (xy 86.650259 -382.726178) (xy 86.66632 -382.775608)
			(xy 86.67445 -382.826943) (xy 86.67496 -382.85293) (xy 86.67445 -382.878917) (xy 87.214204 -382.878917)
			(xy 87.214204 -382.826943) (xy 87.222334 -382.775608) (xy 87.238395 -382.726178) (xy 87.261991 -382.679868)
			(xy 87.292541 -382.63782) (xy 87.329292 -382.601069) (xy 87.37134 -382.570519) (xy 87.41765 -382.546923)
			(xy 87.46708 -382.530862) (xy 87.518415 -382.522732) (xy 87.570389 -382.522732) (xy 87.621724 -382.530862)
			(xy 87.671154 -382.546923) (xy 87.717464 -382.570519) (xy 87.759512 -382.601069) (xy 87.796263 -382.63782)
			(xy 87.826813 -382.679868) (xy 87.850409 -382.726178) (xy 87.86647 -382.775608) (xy 87.8746 -382.826943)
			(xy 87.87511 -382.85293) (xy 87.8746 -382.878917) (xy 88.4141 -382.878917) (xy 88.4141 -382.826943)
			(xy 88.42223 -382.775608) (xy 88.438291 -382.726178) (xy 88.461887 -382.679868) (xy 88.492437 -382.63782)
			(xy 88.529188 -382.601069) (xy 88.571236 -382.570519) (xy 88.617546 -382.546923) (xy 88.666976 -382.530862)
			(xy 88.718311 -382.522732) (xy 88.770285 -382.522732) (xy 88.82162 -382.530862) (xy 88.87105 -382.546923)
			(xy 88.91736 -382.570519) (xy 88.959408 -382.601069) (xy 88.996159 -382.63782) (xy 89.026709 -382.679868)
			(xy 89.050305 -382.726178) (xy 89.066366 -382.775608) (xy 89.074496 -382.826943) (xy 89.075006 -382.85293)
			(xy 89.074496 -382.878917) (xy 89.613996 -382.878917) (xy 89.613996 -382.826943) (xy 89.622126 -382.775608)
			(xy 89.638187 -382.726178) (xy 89.661783 -382.679868) (xy 89.692333 -382.63782) (xy 89.729084 -382.601069)
			(xy 89.771132 -382.570519) (xy 89.817442 -382.546923) (xy 89.866872 -382.530862) (xy 89.918207 -382.522732)
			(xy 89.970181 -382.522732) (xy 90.021516 -382.530862) (xy 90.070946 -382.546923) (xy 90.117256 -382.570519)
			(xy 90.159304 -382.601069) (xy 90.196055 -382.63782) (xy 90.226605 -382.679868) (xy 90.250201 -382.726178)
			(xy 90.266262 -382.775608) (xy 90.274392 -382.826943) (xy 90.274902 -382.85293) (xy 90.274392 -382.878917)
			(xy 90.814146 -382.878917) (xy 90.814146 -382.826943) (xy 90.822276 -382.775608) (xy 90.838337 -382.726178)
			(xy 90.861933 -382.679868) (xy 90.892483 -382.63782) (xy 90.929234 -382.601069) (xy 90.971282 -382.570519)
			(xy 91.017592 -382.546923) (xy 91.067022 -382.530862) (xy 91.118357 -382.522732) (xy 91.170331 -382.522732)
			(xy 91.221666 -382.530862) (xy 91.271096 -382.546923) (xy 91.317406 -382.570519) (xy 91.359454 -382.601069)
			(xy 91.396205 -382.63782) (xy 91.426755 -382.679868) (xy 91.450351 -382.726178) (xy 91.466412 -382.775608)
			(xy 91.474542 -382.826943) (xy 91.475052 -382.85293) (xy 91.474542 -382.878917) (xy 92.014042 -382.878917)
			(xy 92.014042 -382.826943) (xy 92.022172 -382.775608) (xy 92.038233 -382.726178) (xy 92.061829 -382.679868)
			(xy 92.092379 -382.63782) (xy 92.12913 -382.601069) (xy 92.171178 -382.570519) (xy 92.217488 -382.546923)
			(xy 92.266918 -382.530862) (xy 92.318253 -382.522732) (xy 92.370227 -382.522732) (xy 92.421562 -382.530862)
			(xy 92.470992 -382.546923) (xy 92.517302 -382.570519) (xy 92.55935 -382.601069) (xy 92.596101 -382.63782)
			(xy 92.626651 -382.679868) (xy 92.650247 -382.726178) (xy 92.666308 -382.775608) (xy 92.674438 -382.826943)
			(xy 92.674948 -382.85293) (xy 92.674438 -382.878917) (xy 93.214192 -382.878917) (xy 93.214192 -382.826943)
			(xy 93.222322 -382.775608) (xy 93.238383 -382.726178) (xy 93.261979 -382.679868) (xy 93.292529 -382.63782)
			(xy 93.32928 -382.601069) (xy 93.371328 -382.570519) (xy 93.417638 -382.546923) (xy 93.467068 -382.530862)
			(xy 93.518403 -382.522732) (xy 93.570377 -382.522732) (xy 93.621712 -382.530862) (xy 93.671142 -382.546923)
			(xy 93.717452 -382.570519) (xy 93.7595 -382.601069) (xy 93.796251 -382.63782) (xy 93.826801 -382.679868)
			(xy 93.850397 -382.726178) (xy 93.866458 -382.775608) (xy 93.874588 -382.826943) (xy 93.875098 -382.85293)
			(xy 93.874588 -382.878917) (xy 94.414088 -382.878917) (xy 94.414088 -382.826943) (xy 94.422218 -382.775608)
			(xy 94.438279 -382.726178) (xy 94.461875 -382.679868) (xy 94.492425 -382.63782) (xy 94.529176 -382.601069)
			(xy 94.571224 -382.570519) (xy 94.617534 -382.546923) (xy 94.666964 -382.530862) (xy 94.718299 -382.522732)
			(xy 94.770273 -382.522732) (xy 94.821608 -382.530862) (xy 94.871038 -382.546923) (xy 94.917348 -382.570519)
			(xy 94.959396 -382.601069) (xy 94.996147 -382.63782) (xy 95.026697 -382.679868) (xy 95.050293 -382.726178)
			(xy 95.066354 -382.775608) (xy 95.074484 -382.826943) (xy 95.074994 -382.85293) (xy 95.074484 -382.878917)
			(xy 95.613984 -382.878917) (xy 95.613984 -382.826943) (xy 95.622114 -382.775608) (xy 95.638175 -382.726178)
			(xy 95.661771 -382.679868) (xy 95.692321 -382.63782) (xy 95.729072 -382.601069) (xy 95.77112 -382.570519)
			(xy 95.81743 -382.546923) (xy 95.86686 -382.530862) (xy 95.918195 -382.522732) (xy 95.970169 -382.522732)
			(xy 96.021504 -382.530862) (xy 96.070934 -382.546923) (xy 96.117244 -382.570519) (xy 96.159292 -382.601069)
			(xy 96.196043 -382.63782) (xy 96.226593 -382.679868) (xy 96.250189 -382.726178) (xy 96.26625 -382.775608)
			(xy 96.27438 -382.826943) (xy 96.27489 -382.85293) (xy 96.27438 -382.878917) (xy 96.814134 -382.878917)
			(xy 96.814134 -382.826943) (xy 96.822264 -382.775608) (xy 96.838325 -382.726178) (xy 96.861921 -382.679868)
			(xy 96.892471 -382.63782) (xy 96.929222 -382.601069) (xy 96.97127 -382.570519) (xy 97.01758 -382.546923)
			(xy 97.06701 -382.530862) (xy 97.118345 -382.522732) (xy 97.170319 -382.522732) (xy 97.221654 -382.530862)
			(xy 97.271084 -382.546923) (xy 97.317394 -382.570519) (xy 97.359442 -382.601069) (xy 97.396193 -382.63782)
			(xy 97.426743 -382.679868) (xy 97.450339 -382.726178) (xy 97.4664 -382.775608) (xy 97.47453 -382.826943)
			(xy 97.47504 -382.85293) (xy 97.47453 -382.878917) (xy 98.01403 -382.878917) (xy 98.01403 -382.826943)
			(xy 98.02216 -382.775608) (xy 98.038221 -382.726178) (xy 98.061817 -382.679868) (xy 98.092367 -382.63782)
			(xy 98.129118 -382.601069) (xy 98.171166 -382.570519) (xy 98.217476 -382.546923) (xy 98.266906 -382.530862)
			(xy 98.318241 -382.522732) (xy 98.370215 -382.522732) (xy 98.42155 -382.530862) (xy 98.47098 -382.546923)
			(xy 98.51729 -382.570519) (xy 98.559338 -382.601069) (xy 98.596089 -382.63782) (xy 98.626639 -382.679868)
			(xy 98.650235 -382.726178) (xy 98.666296 -382.775608) (xy 98.674426 -382.826943) (xy 98.674936 -382.85293)
			(xy 98.674426 -382.878917) (xy 98.672007 -382.894189) (xy 99.081072 -382.894189) (xy 99.081072 -382.842211)
			(xy 99.089202 -382.790874) (xy 99.105264 -382.74144) (xy 99.12886 -382.695128) (xy 99.159411 -382.653077)
			(xy 99.196163 -382.616322) (xy 99.238213 -382.585769) (xy 99.284524 -382.562171) (xy 99.333956 -382.546107)
			(xy 99.385293 -382.537973) (xy 99.411282 -382.537462) (xy 99.435056 -382.537864) (xy 99.482116 -382.544666)
			(xy 99.527714 -382.558148) (xy 99.570906 -382.578029) (xy 99.610801 -382.603899) (xy 99.62896 -382.61925)
			(xy 99.636076 -382.624941) (xy 99.65313 -382.631322) (xy 99.662234 -382.631696) (xy 99.69373 -382.631696)
			(xy 99.702832 -382.631316) (xy 99.719882 -382.624932) (xy 99.727004 -382.61925) (xy 99.745165 -382.603904)
			(xy 99.785066 -382.578047) (xy 99.828259 -382.558172) (xy 99.873853 -382.544689) (xy 99.920909 -382.537876)
			(xy 99.944682 -382.537462) (xy 99.97067 -382.538004) (xy 100.022006 -382.546132) (xy 100.071438 -382.562191)
			(xy 100.11775 -382.585786) (xy 100.1598 -382.616335) (xy 100.196553 -382.653086) (xy 100.227105 -382.695135)
			(xy 100.250702 -382.741445) (xy 100.266764 -382.790877) (xy 100.274895 -382.842212) (xy 100.274895 -382.894188)
			(xy 100.266764 -382.945523) (xy 100.250702 -382.994955) (xy 100.227105 -383.041265) (xy 100.196553 -383.083314)
			(xy 100.1598 -383.120065) (xy 100.11775 -383.150614) (xy 100.071438 -383.174209) (xy 100.022006 -383.190268)
			(xy 99.97067 -383.198396) (xy 99.944682 -383.198878) (xy 99.920907 -383.198488) (xy 99.873848 -383.191681)
			(xy 99.82825 -383.178196) (xy 99.785058 -383.158313) (xy 99.745163 -383.132441) (xy 99.727004 -383.11709)
			(xy 99.719903 -383.111377) (xy 99.702838 -383.105011) (xy 99.69373 -383.104644) (xy 99.662234 -383.104644)
			(xy 99.653134 -383.105046) (xy 99.636083 -383.111414) (xy 99.62896 -383.11709) (xy 99.61078 -383.132413)
			(xy 99.570884 -383.158272) (xy 99.527696 -383.178151) (xy 99.482106 -383.19164) (xy 99.435054 -383.19846)
			(xy 99.411282 -383.198878) (xy 99.385293 -383.198427) (xy 99.333956 -383.190293) (xy 99.284524 -383.174229)
			(xy 99.238213 -383.150631) (xy 99.196163 -383.120078) (xy 99.159411 -383.083323) (xy 99.12886 -383.041272)
			(xy 99.105264 -382.99496) (xy 99.089202 -382.945526) (xy 99.081072 -382.894189) (xy 98.672007 -382.894189)
			(xy 98.666296 -382.930252) (xy 98.650235 -382.979682) (xy 98.626639 -383.025992) (xy 98.596089 -383.06804)
			(xy 98.559338 -383.104791) (xy 98.51729 -383.135341) (xy 98.47098 -383.158937) (xy 98.42155 -383.174998)
			(xy 98.370215 -383.183128) (xy 98.318241 -383.183128) (xy 98.266906 -383.174998) (xy 98.217476 -383.158937)
			(xy 98.171166 -383.135341) (xy 98.129118 -383.104791) (xy 98.092367 -383.06804) (xy 98.061817 -383.025992)
			(xy 98.038221 -382.979682) (xy 98.02216 -382.930252) (xy 98.01403 -382.878917) (xy 97.47453 -382.878917)
			(xy 97.4664 -382.930252) (xy 97.450339 -382.979682) (xy 97.426743 -383.025992) (xy 97.396193 -383.06804)
			(xy 97.359442 -383.104791) (xy 97.317394 -383.135341) (xy 97.271084 -383.158937) (xy 97.221654 -383.174998)
			(xy 97.170319 -383.183128) (xy 97.118345 -383.183128) (xy 97.06701 -383.174998) (xy 97.01758 -383.158937)
			(xy 96.97127 -383.135341) (xy 96.929222 -383.104791) (xy 96.892471 -383.06804) (xy 96.861921 -383.025992)
			(xy 96.838325 -382.979682) (xy 96.822264 -382.930252) (xy 96.814134 -382.878917) (xy 96.27438 -382.878917)
			(xy 96.26625 -382.930252) (xy 96.250189 -382.979682) (xy 96.226593 -383.025992) (xy 96.196043 -383.06804)
			(xy 96.159292 -383.104791) (xy 96.117244 -383.135341) (xy 96.070934 -383.158937) (xy 96.021504 -383.174998)
			(xy 95.970169 -383.183128) (xy 95.918195 -383.183128) (xy 95.86686 -383.174998) (xy 95.81743 -383.158937)
			(xy 95.77112 -383.135341) (xy 95.729072 -383.104791) (xy 95.692321 -383.06804) (xy 95.661771 -383.025992)
			(xy 95.638175 -382.979682) (xy 95.622114 -382.930252) (xy 95.613984 -382.878917) (xy 95.074484 -382.878917)
			(xy 95.066354 -382.930252) (xy 95.050293 -382.979682) (xy 95.026697 -383.025992) (xy 94.996147 -383.06804)
			(xy 94.959396 -383.104791) (xy 94.917348 -383.135341) (xy 94.871038 -383.158937) (xy 94.821608 -383.174998)
			(xy 94.770273 -383.183128) (xy 94.718299 -383.183128) (xy 94.666964 -383.174998) (xy 94.617534 -383.158937)
			(xy 94.571224 -383.135341) (xy 94.529176 -383.104791) (xy 94.492425 -383.06804) (xy 94.461875 -383.025992)
			(xy 94.438279 -382.979682) (xy 94.422218 -382.930252) (xy 94.414088 -382.878917) (xy 93.874588 -382.878917)
			(xy 93.866458 -382.930252) (xy 93.850397 -382.979682) (xy 93.826801 -383.025992) (xy 93.796251 -383.06804)
			(xy 93.7595 -383.104791) (xy 93.717452 -383.135341) (xy 93.671142 -383.158937) (xy 93.621712 -383.174998)
			(xy 93.570377 -383.183128) (xy 93.518403 -383.183128) (xy 93.467068 -383.174998) (xy 93.417638 -383.158937)
			(xy 93.371328 -383.135341) (xy 93.32928 -383.104791) (xy 93.292529 -383.06804) (xy 93.261979 -383.025992)
			(xy 93.238383 -382.979682) (xy 93.222322 -382.930252) (xy 93.214192 -382.878917) (xy 92.674438 -382.878917)
			(xy 92.666308 -382.930252) (xy 92.650247 -382.979682) (xy 92.626651 -383.025992) (xy 92.596101 -383.06804)
			(xy 92.55935 -383.104791) (xy 92.517302 -383.135341) (xy 92.470992 -383.158937) (xy 92.421562 -383.174998)
			(xy 92.370227 -383.183128) (xy 92.318253 -383.183128) (xy 92.266918 -383.174998) (xy 92.217488 -383.158937)
			(xy 92.171178 -383.135341) (xy 92.12913 -383.104791) (xy 92.092379 -383.06804) (xy 92.061829 -383.025992)
			(xy 92.038233 -382.979682) (xy 92.022172 -382.930252) (xy 92.014042 -382.878917) (xy 91.474542 -382.878917)
			(xy 91.466412 -382.930252) (xy 91.450351 -382.979682) (xy 91.426755 -383.025992) (xy 91.396205 -383.06804)
			(xy 91.359454 -383.104791) (xy 91.317406 -383.135341) (xy 91.271096 -383.158937) (xy 91.221666 -383.174998)
			(xy 91.170331 -383.183128) (xy 91.118357 -383.183128) (xy 91.067022 -383.174998) (xy 91.017592 -383.158937)
			(xy 90.971282 -383.135341) (xy 90.929234 -383.104791) (xy 90.892483 -383.06804) (xy 90.861933 -383.025992)
			(xy 90.838337 -382.979682) (xy 90.822276 -382.930252) (xy 90.814146 -382.878917) (xy 90.274392 -382.878917)
			(xy 90.266262 -382.930252) (xy 90.250201 -382.979682) (xy 90.226605 -383.025992) (xy 90.196055 -383.06804)
			(xy 90.159304 -383.104791) (xy 90.117256 -383.135341) (xy 90.070946 -383.158937) (xy 90.021516 -383.174998)
			(xy 89.970181 -383.183128) (xy 89.918207 -383.183128) (xy 89.866872 -383.174998) (xy 89.817442 -383.158937)
			(xy 89.771132 -383.135341) (xy 89.729084 -383.104791) (xy 89.692333 -383.06804) (xy 89.661783 -383.025992)
			(xy 89.638187 -382.979682) (xy 89.622126 -382.930252) (xy 89.613996 -382.878917) (xy 89.074496 -382.878917)
			(xy 89.066366 -382.930252) (xy 89.050305 -382.979682) (xy 89.026709 -383.025992) (xy 88.996159 -383.06804)
			(xy 88.959408 -383.104791) (xy 88.91736 -383.135341) (xy 88.87105 -383.158937) (xy 88.82162 -383.174998)
			(xy 88.770285 -383.183128) (xy 88.718311 -383.183128) (xy 88.666976 -383.174998) (xy 88.617546 -383.158937)
			(xy 88.571236 -383.135341) (xy 88.529188 -383.104791) (xy 88.492437 -383.06804) (xy 88.461887 -383.025992)
			(xy 88.438291 -382.979682) (xy 88.42223 -382.930252) (xy 88.4141 -382.878917) (xy 87.8746 -382.878917)
			(xy 87.86647 -382.930252) (xy 87.850409 -382.979682) (xy 87.826813 -383.025992) (xy 87.796263 -383.06804)
			(xy 87.759512 -383.104791) (xy 87.717464 -383.135341) (xy 87.671154 -383.158937) (xy 87.621724 -383.174998)
			(xy 87.570389 -383.183128) (xy 87.518415 -383.183128) (xy 87.46708 -383.174998) (xy 87.41765 -383.158937)
			(xy 87.37134 -383.135341) (xy 87.329292 -383.104791) (xy 87.292541 -383.06804) (xy 87.261991 -383.025992)
			(xy 87.238395 -382.979682) (xy 87.222334 -382.930252) (xy 87.214204 -382.878917) (xy 86.67445 -382.878917)
			(xy 86.66632 -382.930252) (xy 86.650259 -382.979682) (xy 86.626663 -383.025992) (xy 86.596113 -383.06804)
			(xy 86.559362 -383.104791) (xy 86.517314 -383.135341) (xy 86.471004 -383.158937) (xy 86.421574 -383.174998)
			(xy 86.370239 -383.183128) (xy 86.318265 -383.183128) (xy 86.26693 -383.174998) (xy 86.2175 -383.158937)
			(xy 86.17119 -383.135341) (xy 86.129142 -383.104791) (xy 86.092391 -383.06804) (xy 86.061841 -383.025992)
			(xy 86.038245 -382.979682) (xy 86.022184 -382.930252) (xy 86.014054 -382.878917) (xy 85.474554 -382.878917)
			(xy 85.466424 -382.930252) (xy 85.450363 -382.979682) (xy 85.426767 -383.025992) (xy 85.396217 -383.06804)
			(xy 85.359466 -383.104791) (xy 85.317418 -383.135341) (xy 85.271108 -383.158937) (xy 85.221678 -383.174998)
			(xy 85.170343 -383.183128) (xy 85.118369 -383.183128) (xy 85.067034 -383.174998) (xy 85.017604 -383.158937)
			(xy 84.971294 -383.135341) (xy 84.929246 -383.104791) (xy 84.892495 -383.06804) (xy 84.861945 -383.025992)
			(xy 84.838349 -382.979682) (xy 84.822288 -382.930252) (xy 84.814158 -382.878917) (xy 84.274404 -382.878917)
			(xy 84.266274 -382.930252) (xy 84.250213 -382.979682) (xy 84.226617 -383.025992) (xy 84.196067 -383.06804)
			(xy 84.159316 -383.104791) (xy 84.117268 -383.135341) (xy 84.070958 -383.158937) (xy 84.021528 -383.174998)
			(xy 83.970193 -383.183128) (xy 83.918219 -383.183128) (xy 83.866884 -383.174998) (xy 83.817454 -383.158937)
			(xy 83.771144 -383.135341) (xy 83.729096 -383.104791) (xy 83.692345 -383.06804) (xy 83.661795 -383.025992)
			(xy 83.638199 -382.979682) (xy 83.622138 -382.930252) (xy 83.614008 -382.878917) (xy 83.074508 -382.878917)
			(xy 83.066378 -382.930252) (xy 83.050317 -382.979682) (xy 83.026721 -383.025992) (xy 82.996171 -383.06804)
			(xy 82.95942 -383.104791) (xy 82.917372 -383.135341) (xy 82.871062 -383.158937) (xy 82.821632 -383.174998)
			(xy 82.770297 -383.183128) (xy 82.718323 -383.183128) (xy 82.666988 -383.174998) (xy 82.617558 -383.158937)
			(xy 82.571248 -383.135341) (xy 82.5292 -383.104791) (xy 82.492449 -383.06804) (xy 82.461899 -383.025992)
			(xy 82.438303 -382.979682) (xy 82.422242 -382.930252) (xy 82.414112 -382.878917) (xy 81.874612 -382.878917)
			(xy 81.866482 -382.930252) (xy 81.850421 -382.979682) (xy 81.826825 -383.025992) (xy 81.796275 -383.06804)
			(xy 81.759524 -383.104791) (xy 81.717476 -383.135341) (xy 81.671166 -383.158937) (xy 81.621736 -383.174998)
			(xy 81.570401 -383.183128) (xy 81.518427 -383.183128) (xy 81.467092 -383.174998) (xy 81.417662 -383.158937)
			(xy 81.371352 -383.135341) (xy 81.329304 -383.104791) (xy 81.292553 -383.06804) (xy 81.262003 -383.025992)
			(xy 81.238407 -382.979682) (xy 81.222346 -382.930252) (xy 81.214216 -382.878917) (xy 80.674462 -382.878917)
			(xy 80.666332 -382.930252) (xy 80.650271 -382.979682) (xy 80.626675 -383.025992) (xy 80.596125 -383.06804)
			(xy 80.559374 -383.104791) (xy 80.517326 -383.135341) (xy 80.471016 -383.158937) (xy 80.421586 -383.174998)
			(xy 80.370251 -383.183128) (xy 80.318277 -383.183128) (xy 80.266942 -383.174998) (xy 80.217512 -383.158937)
			(xy 80.171202 -383.135341) (xy 80.129154 -383.104791) (xy 80.092403 -383.06804) (xy 80.061853 -383.025992)
			(xy 80.038257 -382.979682) (xy 80.022196 -382.930252) (xy 80.014066 -382.878917) (xy 79.325896 -382.878917)
			(xy 79.326481 -382.882613) (xy 79.326481 -382.934587) (xy 79.31835 -382.98592) (xy 79.302289 -383.035349)
			(xy 79.278694 -383.081657) (xy 79.248144 -383.123703) (xy 79.211393 -383.160453) (xy 79.169345 -383.191001)
			(xy 79.123036 -383.214595) (xy 79.073606 -383.230654) (xy 79.022273 -383.238782) (xy 78.996286 -383.239264)
			(xy 78.971448 -383.238849) (xy 78.922329 -383.231422) (xy 78.874877 -383.216723) (xy 78.830161 -383.195084)
			(xy 78.789191 -383.166992) (xy 78.770734 -383.150364) (xy 78.763673 -383.144317) (xy 78.74648 -383.137287)
			(xy 78.737206 -383.136648) (xy 78.705964 -383.135886) (xy 78.696711 -383.136068) (xy 78.679258 -383.142175)
			(xy 78.671928 -383.147824) (xy 78.649377 -383.166008) (xy 78.599242 -383.19502) (xy 78.544825 -383.214868)
			(xy 78.487784 -383.224948) (xy 78.458822 -383.225548) (xy 78.432781 -383.225034) (xy 78.381341 -383.216879)
			(xy 78.331818 -383.200754) (xy 78.28544 -383.177056) (xy 78.243355 -383.146374) (xy 78.224634 -383.128266)
			(xy 78.21803 -383.121662) (xy 78.202028 -383.114296) (xy 78.1177 -383.107184) (xy 78.100682 -383.11201)
			(xy 78.093316 -383.117344) (xy 78.07211 -383.132017) (xy 78.026081 -383.155262) (xy 77.977 -383.171078)
			(xy 77.926059 -383.179081) (xy 77.900276 -383.179574) (xy 77.874287 -383.179131) (xy 77.822951 -383.170996)
			(xy 77.773518 -383.154931) (xy 77.727207 -383.131332) (xy 77.685158 -383.100779) (xy 77.648406 -383.064024)
			(xy 77.617856 -383.021972) (xy 77.594259 -382.97566) (xy 77.578198 -382.926226) (xy 77.570068 -382.874889)
			(xy 74.8092 -382.874889) (xy 74.801922 -382.879565) (xy 74.752344 -382.9022) (xy 74.700048 -382.917549)
			(xy 74.646101 -382.925298) (xy 74.61885 -382.925828) (xy 74.594777 -382.925481) (xy 74.54701 -382.919457)
			(xy 74.500384 -382.90746) (xy 74.47788 -382.898904) (xy 74.465434 -382.893824) (xy 74.439526 -382.897126)
			(xy 74.348848 -382.963928) (xy 74.337926 -382.98755) (xy 74.338942 -383.000758) (xy 74.339958 -383.02946)
			(xy 74.339472 -383.056711) (xy 74.331716 -383.110659) (xy 74.316361 -383.162954) (xy 74.293719 -383.212531)
			(xy 74.264253 -383.258381) (xy 74.228562 -383.299572) (xy 74.187371 -383.335263) (xy 74.141521 -383.364729)
			(xy 74.091944 -383.387371) (xy 74.039649 -383.402726) (xy 73.985701 -383.410482) (xy 73.931199 -383.410482)
			(xy 73.877251 -383.402726) (xy 73.824956 -383.387371) (xy 73.775379 -383.364729) (xy 73.729529 -383.335263)
			(xy 73.688338 -383.299572) (xy 73.652647 -383.258381) (xy 73.623181 -383.212531) (xy 73.600539 -383.162954)
			(xy 73.585184 -383.110659) (xy 73.577428 -383.056711) (xy 73.576942 -383.02946) (xy 73.577242 -383.007349)
			(xy 73.582333 -382.963422) (xy 73.587102 -382.94183) (xy 73.588626 -382.935988) (xy 73.588626 -382.930146)
			(xy 73.588215 -382.920117) (xy 73.580554 -382.90158) (xy 73.566381 -382.887387) (xy 73.547855 -382.8797)
			(xy 73.537826 -382.879346) (xy 73.487026 -382.879346) (xy 73.475596 -382.88214) (xy 73.470262 -382.884934)
			(xy 73.443414 -382.897853) (xy 73.386703 -382.916109) (xy 73.32784 -382.925306) (xy 73.29805 -382.925828)
			(xy 73.268264 -382.925271) (xy 73.209409 -382.916057) (xy 73.152694 -382.897828) (xy 73.125838 -382.884934)
			(xy 73.120504 -382.88214) (xy 73.109074 -382.879346) (xy 72.718168 -382.879346) (xy 72.708102 -382.878916)
			(xy 72.689511 -382.871187) (xy 72.6821 -382.86436) (xy 70.226682 -382.86436) (xy 70.216615 -382.864788)
			(xy 70.198021 -382.872514) (xy 70.190614 -382.879346) (xy 70.160896 -382.909064) (xy 70.154719 -382.915715)
			(xy 70.147131 -382.932189) (xy 70.145803 -382.950279) (xy 70.147942 -382.959102) (xy 70.17639 -383.058162)
			(xy 70.196456 -383.076958) (xy 70.210172 -383.080006) (xy 70.237925 -383.086832) (xy 70.291144 -383.107666)
			(xy 70.340658 -383.136207) (xy 70.385359 -383.171818) (xy 70.424246 -383.2137) (xy 70.456447 -383.260916)
			(xy 70.481243 -383.312408) (xy 70.498077 -383.367024) (xy 70.506573 -383.42354) (xy 70.507098 -383.452116)
			(xy 70.506474 -383.483767) (xy 70.495998 -383.546196) (xy 70.48627 -383.576322) (xy 70.483823 -383.584614)
			(xy 70.484083 -383.601889) (xy 70.486778 -383.610104) (xy 70.496938 -383.638298) (xy 70.500309 -383.646496)
			(xy 70.511601 -383.660144) (xy 70.519036 -383.664968) (xy 70.547373 -383.682128) (xy 70.59976 -383.722677)
			(xy 70.620136 -383.7432) (xy 76.211682 -383.7432) (xy 76.215753 -383.687578) (xy 76.227879 -383.633141)
			(xy 76.247802 -383.58105) (xy 76.275098 -383.532415) (xy 76.309184 -383.488272) (xy 76.349333 -383.449563)
			(xy 76.394691 -383.417112) (xy 76.444291 -383.391611) (xy 76.497075 -383.373604) (xy 76.551918 -383.363474)
			(xy 76.607652 -383.361437) (xy 76.663089 -383.367537) (xy 76.717046 -383.381643) (xy 76.768375 -383.403455)
			(xy 76.815981 -383.432509) (xy 76.858849 -383.468184) (xy 76.896066 -383.509721) (xy 76.926839 -383.556234)
			(xy 76.950511 -383.606731) (xy 76.966579 -383.660138) (xy 76.974699 -383.715314) (xy 76.975208 -383.7432)
			(xy 76.974699 -383.771086) (xy 76.966579 -383.826262) (xy 76.950511 -383.879669) (xy 76.926839 -383.930166)
			(xy 76.896066 -383.976679) (xy 76.858849 -384.018216) (xy 76.815981 -384.053891) (xy 76.768375 -384.082945)
			(xy 76.717046 -384.104757) (xy 76.663089 -384.118863) (xy 76.607652 -384.124963) (xy 76.551918 -384.122926)
			(xy 76.497075 -384.112796) (xy 76.444291 -384.094789) (xy 76.394691 -384.069288) (xy 76.349333 -384.036837)
			(xy 76.309184 -383.998128) (xy 76.275098 -383.953985) (xy 76.247802 -383.90535) (xy 76.227879 -383.853259)
			(xy 76.215753 -383.798822) (xy 76.211682 -383.7432) (xy 70.620136 -383.7432) (xy 70.646434 -383.769688)
			(xy 70.686605 -383.822365) (xy 70.719592 -383.879815) (xy 70.744834 -383.941063) (xy 70.761905 -384.005072)
			(xy 70.770515 -384.070757) (xy 70.771004 -384.10388) (xy 70.77056 -384.133991) (xy 70.763447 -384.19379)
			(xy 70.749317 -384.252331) (xy 70.728369 -384.308791) (xy 70.700896 -384.36238) (xy 70.667283 -384.412348)
			(xy 70.628001 -384.457994) (xy 70.583601 -384.498679) (xy 70.559422 -384.51663) (xy 70.549998 -384.524291)
			(xy 70.538998 -384.545904) (xy 70.53834 -384.558032) (xy 70.53834 -384.640328) (xy 70.538972 -384.652459)
			(xy 70.544187 -384.66268) (xy 76.211682 -384.66268) (xy 76.215753 -384.607058) (xy 76.227879 -384.552621)
			(xy 76.247802 -384.50053) (xy 76.275098 -384.451895) (xy 76.309184 -384.407752) (xy 76.349333 -384.369043)
			(xy 76.394691 -384.336592) (xy 76.444291 -384.311091) (xy 76.497075 -384.293084) (xy 76.551918 -384.282954)
			(xy 76.607652 -384.280917) (xy 76.663089 -384.287017) (xy 76.717046 -384.301123) (xy 76.768375 -384.322935)
			(xy 76.815981 -384.351989) (xy 76.85846 -384.38734) (xy 77.47176 -384.38734) (xy 77.47176 -384.327404)
			(xy 77.479583 -384.267982) (xy 77.495096 -384.210089) (xy 77.518032 -384.154716) (xy 77.547999 -384.10281)
			(xy 77.584486 -384.05526) (xy 77.626866 -384.01288) (xy 77.674416 -383.976393) (xy 77.726322 -383.946426)
			(xy 77.781695 -383.92349) (xy 77.839588 -383.907977) (xy 77.89901 -383.900154) (xy 77.958946 -383.900154)
			(xy 78.018368 -383.907977) (xy 78.076261 -383.92349) (xy 78.131634 -383.946426) (xy 78.18354 -383.976393)
			(xy 78.23109 -384.01288) (xy 78.27347 -384.05526) (xy 78.309957 -384.10281) (xy 78.339924 -384.154716)
			(xy 78.36286 -384.210089) (xy 78.378373 -384.267982) (xy 78.386196 -384.327404) (xy 78.386686 -384.357372)
			(xy 78.386196 -384.38734) (xy 78.378373 -384.446762) (xy 78.36286 -384.504655) (xy 78.339924 -384.560028)
			(xy 78.309957 -384.611934) (xy 78.27347 -384.659484) (xy 78.23109 -384.701864) (xy 78.18354 -384.738351)
			(xy 78.131634 -384.768318) (xy 78.076261 -384.791254) (xy 78.018368 -384.806767) (xy 77.958946 -384.81459)
			(xy 77.89901 -384.81459) (xy 77.839588 -384.806767) (xy 77.781695 -384.791254) (xy 77.726322 -384.768318)
			(xy 77.674416 -384.738351) (xy 77.626866 -384.701864) (xy 77.584486 -384.659484) (xy 77.547999 -384.611934)
			(xy 77.518032 -384.560028) (xy 77.495096 -384.504655) (xy 77.479583 -384.446762) (xy 77.47176 -384.38734)
			(xy 76.85846 -384.38734) (xy 76.858849 -384.387664) (xy 76.896066 -384.429201) (xy 76.926839 -384.475714)
			(xy 76.950511 -384.526211) (xy 76.966579 -384.579618) (xy 76.974699 -384.634794) (xy 76.975208 -384.66268)
			(xy 76.974699 -384.690566) (xy 76.966579 -384.745742) (xy 76.950511 -384.799149) (xy 76.926839 -384.849646)
			(xy 76.896066 -384.896159) (xy 76.858849 -384.937696) (xy 76.815981 -384.973371) (xy 76.768375 -385.002425)
			(xy 76.717046 -385.024237) (xy 76.663089 -385.038343) (xy 76.607652 -385.044443) (xy 76.551918 -385.042406)
			(xy 76.497075 -385.032276) (xy 76.444291 -385.014269) (xy 76.394691 -384.988768) (xy 76.349333 -384.956317)
			(xy 76.309184 -384.917608) (xy 76.275098 -384.873465) (xy 76.247802 -384.82483) (xy 76.227879 -384.772739)
			(xy 76.215753 -384.718302) (xy 76.211682 -384.66268) (xy 70.544187 -384.66268) (xy 70.549995 -384.674065)
			(xy 70.559422 -384.68173) (xy 70.583601 -384.699677) (xy 70.627982 -384.740375) (xy 70.667247 -384.786029)
			(xy 70.700848 -384.835999) (xy 70.728313 -384.889588) (xy 70.74926 -384.946044) (xy 70.763393 -385.004578)
			(xy 70.770517 -385.064372) (xy 70.771004 -385.09448) (xy 70.77056 -385.125213) (xy 70.763153 -385.186231)
			(xy 70.748445 -385.24591) (xy 70.726651 -385.303382) (xy 70.698088 -385.357808) (xy 70.663172 -385.408394)
			(xy 70.622414 -385.454402) (xy 70.576407 -385.495162) (xy 70.525822 -385.530079) (xy 70.471397 -385.558644)
			(xy 70.413926 -385.58044) (xy 70.354246 -385.59515) (xy 70.293229 -385.602559) (xy 70.262496 -385.602988)
			(xy 70.232179 -385.602566) (xy 70.171973 -385.595388) (xy 70.113048 -385.581098) (xy 70.056242 -385.5599)
			(xy 70.002361 -385.532094) (xy 69.952171 -385.498075) (xy 69.928994 -385.478528) (xy 69.922136 -385.472178)
			(xy 69.905118 -385.466082) (xy 69.819774 -385.466082) (xy 69.802756 -385.472178) (xy 69.795898 -385.478528)
			(xy 69.768466 -385.500626) (xy 69.759116 -385.508529) (xy 69.748511 -385.530552) (xy 69.748146 -385.54279)
			(xy 69.749162 -385.574286) (xy 69.750306 -385.586525) (xy 69.762374 -385.607897) (xy 69.772276 -385.61518)
			(xy 69.798364 -385.63285) (xy 69.84639 -385.673642) (xy 69.889013 -385.72005) (xy 69.925581 -385.771365)
			(xy 69.955534 -385.826802) (xy 69.978415 -385.885512) (xy 69.993874 -385.946598) (xy 70.001673 -386.009124)
			(xy 70.002146 -386.04063) (xy 70.001681 -386.071361) (xy 69.994269 -386.132374) (xy 69.979558 -386.192048)
			(xy 69.957762 -386.249515) (xy 69.929199 -386.303936) (xy 69.894284 -386.354518) (xy 69.853528 -386.400522)
			(xy 69.807524 -386.441279) (xy 69.756943 -386.476195) (xy 69.702523 -386.504759) (xy 69.645056 -386.526556)
			(xy 69.585381 -386.541268) (xy 69.524369 -386.54868) (xy 69.493638 -386.549138) (xy 69.460089 -386.548602)
			(xy 69.393575 -386.539778) (xy 69.3288 -386.522278) (xy 69.266891 -386.496408) (xy 69.208925 -386.462616)
			(xy 69.155909 -386.42149) (xy 69.131942 -386.398008) (xy 69.124499 -386.391136) (xy 69.105795 -386.3834)
			(xy 69.085554 -386.383491) (xy 69.06692 -386.391395) (xy 69.052786 -386.405885) (xy 69.045349 -386.42471)
			(xy 69.045074 -386.434838) (xy 69.045074 -386.444744) (xy 69.044566 -386.467858) (xy 69.044058 -386.478526)
			(xy 69.051678 -386.498338) (xy 69.597778 -387.044438) (xy 69.605125 -387.051243) (xy 69.623588 -387.058957)
			(xy 69.633592 -387.059424) (xy 69.85889 -387.059424) (xy 69.88683 -387.035802) (xy 69.890132 -387.01726)
			(xy 69.895246 -386.991131) (xy 69.911761 -386.940516) (xy 69.935154 -386.892689) (xy 69.96497 -386.84858)
			(xy 70.000632 -386.809046) (xy 70.041444 -386.774856) (xy 70.086615 -386.746673) (xy 70.135266 -386.725046)
			(xy 70.186451 -386.710395) (xy 70.239177 -386.703005) (xy 70.265798 -386.702554) (xy 70.29305 -386.70304)
			(xy 70.347 -386.710796) (xy 70.399297 -386.72615) (xy 70.448877 -386.748791) (xy 70.494731 -386.778256)
			(xy 70.535924 -386.813947) (xy 70.57162 -386.855137) (xy 70.60109 -386.900988) (xy 70.623736 -386.950565)
			(xy 70.639096 -387.002861) (xy 70.646858 -387.05681) (xy 70.647306 -387.084062) (xy 70.64685 -387.110978)
			(xy 70.639284 -387.164276) (xy 70.624284 -387.215976) (xy 70.602149 -387.265046) (xy 70.588124 -387.288024)
			(xy 70.578472 -387.303264) (xy 70.582536 -387.338316) (xy 70.805294 -387.561074) (xy 70.812638 -387.567888)
			(xy 70.8311 -387.575627) (xy 70.841108 -387.57606) (xy 71.721218 -387.57606) (xy 71.731286 -387.575632)
			(xy 71.749882 -387.567909) (xy 71.757286 -387.561074) (xy 73.180194 -386.138166) (xy 73.187589 -386.131311)
			(xy 73.206188 -386.123564) (xy 73.216262 -386.12318) (xy 74.224896 -386.12318) (xy 74.233532 -386.119878)
			(xy 74.25526 -386.111974) (xy 74.300148 -386.100885) (xy 74.346049 -386.095316) (xy 74.369168 -386.094986)
			(xy 74.392286 -386.095325) (xy 74.438183 -386.100908) (xy 74.483073 -386.111984) (xy 74.504804 -386.119878)
			(xy 74.51344 -386.12318) (xy 77.001878 -386.12318) (xy 77.011942 -386.123617) (xy 77.030528 -386.131349)
			(xy 77.037946 -386.138166) (xy 77.105764 -386.205984) (xy 77.113678 -386.213074) (xy 77.133492 -386.220682)
			(xy 77.144118 -386.220716) (xy 77.22997 -386.216652) (xy 77.24902 -386.207) (xy 77.255878 -386.198618)
			(xy 77.264795 -386.188024) (xy 77.283731 -386.167818) (xy 77.293724 -386.158232) (xy 77.30236 -386.14985)
			(xy 77.310488 -386.127498) (xy 77.29855 -386.023104) (xy 77.285596 -386.003292) (xy 77.275182 -385.996942)
			(xy 77.251814 -385.982697) (xy 77.208319 -385.949477) (xy 77.169091 -385.911313) (xy 77.134688 -385.868748)
			(xy 77.105599 -385.822389) (xy 77.093572 -385.797806) (xy 77.087476 -385.785106) (xy 77.064616 -385.769612)
			(xy 76.947776 -385.762246) (xy 76.923392 -385.774692) (xy 76.915772 -385.78663) (xy 76.900683 -385.809508)
			(xy 76.864987 -385.851091) (xy 76.823709 -385.887139) (xy 76.777697 -385.91691) (xy 76.7279 -385.939791)
			(xy 76.675341 -385.955312) (xy 76.621101 -385.963154) (xy 76.5937 -385.963668) (xy 76.566452 -385.963182)
			(xy 76.51251 -385.955426) (xy 76.46022 -385.940073) (xy 76.410648 -385.917434) (xy 76.364803 -385.887971)
			(xy 76.323617 -385.852283) (xy 76.287929 -385.811097) (xy 76.258466 -385.765252) (xy 76.235827 -385.71568)
			(xy 76.220474 -385.66339) (xy 76.212718 -385.609448) (xy 76.212718 -385.554952) (xy 76.220474 -385.50101)
			(xy 76.235827 -385.44872) (xy 76.258466 -385.399148) (xy 76.287929 -385.353303) (xy 76.323617 -385.312117)
			(xy 76.364803 -385.276429) (xy 76.410648 -385.246966) (xy 76.46022 -385.224327) (xy 76.51251 -385.208974)
			(xy 76.566452 -385.201218) (xy 76.5937 -385.200652) (xy 76.622334 -385.201165) (xy 76.678959 -385.209726)
			(xy 76.733668 -385.226656) (xy 76.785231 -385.251575) (xy 76.83249 -385.283921) (xy 76.874382 -385.322969)
			(xy 76.909966 -385.367841) (xy 76.924662 -385.392422) (xy 76.931774 -385.404614) (xy 76.95565 -385.41833)
			(xy 77.072744 -385.416044) (xy 77.096112 -385.40182) (xy 77.102716 -385.389374) (xy 77.117666 -385.362133)
			(xy 77.153814 -385.311592) (xy 77.196466 -385.266405) (xy 77.244839 -385.227401) (xy 77.298041 -385.195299)
			(xy 77.355098 -385.170687) (xy 77.414958 -385.154019) (xy 77.476523 -385.1456) (xy 77.507592 -385.145026)
			(xy 77.537561 -385.145495) (xy 77.596985 -385.153317) (xy 77.65488 -385.16883) (xy 77.710254 -385.191767)
			(xy 77.762161 -385.221737) (xy 77.809711 -385.258225) (xy 77.852092 -385.300608) (xy 77.888578 -385.348161)
			(xy 77.918544 -385.400069) (xy 77.941478 -385.455445) (xy 77.956988 -385.513341) (xy 77.964807 -385.572765)
			(xy 77.9653 -385.602734) (xy 77.964772 -385.633611) (xy 77.956431 -385.694799) (xy 77.939946 -385.754312)
			(xy 77.915615 -385.811071) (xy 77.883879 -385.864047) (xy 77.874698 -385.87553) (xy 79.361792 -385.87553)
			(xy 79.362303 -385.849542) (xy 79.37043 -385.798204) (xy 79.386488 -385.74877) (xy 79.410082 -385.702457)
			(xy 79.440631 -385.660405) (xy 79.477382 -385.62365) (xy 79.519431 -385.593097) (xy 79.565742 -385.569499)
			(xy 79.615175 -385.553437) (xy 79.666512 -385.545305) (xy 79.6925 -385.544822) (xy 79.708933 -385.545053)
			(xy 79.741633 -385.548357) (xy 79.757778 -385.551426) (xy 79.770732 -385.553966) (xy 79.795878 -385.546092)
			(xy 79.873094 -385.464304) (xy 79.879698 -385.438904) (xy 79.876396 -385.426204) (xy 79.86939 -385.397762)
			(xy 79.861872 -385.339669) (xy 79.86141 -385.31038) (xy 79.861934 -385.279492) (xy 79.87024 -385.218276)
			(xy 79.886697 -385.158733) (xy 79.911007 -385.101941) (xy 79.926434 -385.075176) (xy 79.932276 -385.06527)
			(xy 79.934562 -385.042918) (xy 79.901288 -384.947668) (xy 79.88554 -384.931666) (xy 79.874872 -384.927602)
			(xy 79.851485 -384.918431) (xy 79.807589 -384.894009) (xy 79.767893 -384.863226) (xy 79.733313 -384.826791)
			(xy 79.704644 -384.785542) (xy 79.682547 -384.740431) (xy 79.667531 -384.692495) (xy 79.659942 -384.642839)
			(xy 79.65948 -384.617722) (xy 79.65999 -384.591735) (xy 79.66812 -384.5404) (xy 79.684181 -384.49097)
			(xy 79.707777 -384.44466) (xy 79.738327 -384.402612) (xy 79.775078 -384.365861) (xy 79.817126 -384.335311)
			(xy 79.863436 -384.311715) (xy 79.912866 -384.295654) (xy 79.964201 -384.287524) (xy 80.016175 -384.287524)
			(xy 80.06751 -384.295654) (xy 80.11694 -384.311715) (xy 80.16325 -384.335311) (xy 80.205298 -384.365861)
			(xy 80.242049 -384.402612) (xy 80.272599 -384.44466) (xy 80.296195 -384.49097) (xy 80.312256 -384.5404)
			(xy 80.320386 -384.591735) (xy 80.320896 -384.617722) (xy 80.859376 -384.617722) (xy 80.859886 -384.591735)
			(xy 80.868016 -384.5404) (xy 80.884077 -384.49097) (xy 80.907673 -384.44466) (xy 80.938223 -384.402612)
			(xy 80.974974 -384.365861) (xy 81.017022 -384.335311) (xy 81.063332 -384.311715) (xy 81.112762 -384.295654)
			(xy 81.164097 -384.287524) (xy 81.216071 -384.287524) (xy 81.267406 -384.295654) (xy 81.316836 -384.311715)
			(xy 81.363146 -384.335311) (xy 81.405194 -384.365861) (xy 81.441945 -384.402612) (xy 81.472495 -384.44466)
			(xy 81.496091 -384.49097) (xy 81.512152 -384.5404) (xy 81.520282 -384.591735) (xy 81.520792 -384.617722)
			(xy 82.059526 -384.617722) (xy 82.060036 -384.591735) (xy 82.068166 -384.5404) (xy 82.084227 -384.49097)
			(xy 82.107823 -384.44466) (xy 82.138373 -384.402612) (xy 82.175124 -384.365861) (xy 82.217172 -384.335311)
			(xy 82.263482 -384.311715) (xy 82.312912 -384.295654) (xy 82.364247 -384.287524) (xy 82.416221 -384.287524)
			(xy 82.467556 -384.295654) (xy 82.516986 -384.311715) (xy 82.563296 -384.335311) (xy 82.605344 -384.365861)
			(xy 82.642095 -384.402612) (xy 82.672645 -384.44466) (xy 82.696241 -384.49097) (xy 82.712302 -384.5404)
			(xy 82.720432 -384.591735) (xy 82.720942 -384.617722) (xy 83.259422 -384.617722) (xy 83.259932 -384.591735)
			(xy 83.268062 -384.5404) (xy 83.284123 -384.49097) (xy 83.307719 -384.44466) (xy 83.338269 -384.402612)
			(xy 83.37502 -384.365861) (xy 83.417068 -384.335311) (xy 83.463378 -384.311715) (xy 83.512808 -384.295654)
			(xy 83.564143 -384.287524) (xy 83.616117 -384.287524) (xy 83.667452 -384.295654) (xy 83.716882 -384.311715)
			(xy 83.763192 -384.335311) (xy 83.80524 -384.365861) (xy 83.841991 -384.402612) (xy 83.872541 -384.44466)
			(xy 83.896137 -384.49097) (xy 83.912198 -384.5404) (xy 83.920328 -384.591735) (xy 83.920838 -384.617722)
			(xy 84.459572 -384.617722) (xy 84.460082 -384.591735) (xy 84.468212 -384.5404) (xy 84.484273 -384.49097)
			(xy 84.507869 -384.44466) (xy 84.538419 -384.402612) (xy 84.57517 -384.365861) (xy 84.617218 -384.335311)
			(xy 84.663528 -384.311715) (xy 84.712958 -384.295654) (xy 84.764293 -384.287524) (xy 84.816267 -384.287524)
			(xy 84.867602 -384.295654) (xy 84.917032 -384.311715) (xy 84.963342 -384.335311) (xy 85.00539 -384.365861)
			(xy 85.042141 -384.402612) (xy 85.072691 -384.44466) (xy 85.096287 -384.49097) (xy 85.112348 -384.5404)
			(xy 85.120478 -384.591735) (xy 85.120988 -384.617722) (xy 85.659468 -384.617722) (xy 85.659978 -384.591735)
			(xy 85.668108 -384.5404) (xy 85.684169 -384.49097) (xy 85.707765 -384.44466) (xy 85.738315 -384.402612)
			(xy 85.775066 -384.365861) (xy 85.817114 -384.335311) (xy 85.863424 -384.311715) (xy 85.912854 -384.295654)
			(xy 85.964189 -384.287524) (xy 86.016163 -384.287524) (xy 86.067498 -384.295654) (xy 86.116928 -384.311715)
			(xy 86.163238 -384.335311) (xy 86.205286 -384.365861) (xy 86.242037 -384.402612) (xy 86.272587 -384.44466)
			(xy 86.296183 -384.49097) (xy 86.312244 -384.5404) (xy 86.320374 -384.591735) (xy 86.320884 -384.617722)
			(xy 86.859364 -384.617722) (xy 86.859874 -384.591735) (xy 86.868004 -384.5404) (xy 86.884065 -384.49097)
			(xy 86.907661 -384.44466) (xy 86.938211 -384.402612) (xy 86.974962 -384.365861) (xy 87.01701 -384.335311)
			(xy 87.06332 -384.311715) (xy 87.11275 -384.295654) (xy 87.164085 -384.287524) (xy 87.216059 -384.287524)
			(xy 87.267394 -384.295654) (xy 87.316824 -384.311715) (xy 87.363134 -384.335311) (xy 87.405182 -384.365861)
			(xy 87.441933 -384.402612) (xy 87.472483 -384.44466) (xy 87.496079 -384.49097) (xy 87.51214 -384.5404)
			(xy 87.52027 -384.591735) (xy 87.52078 -384.617722) (xy 88.059514 -384.617722) (xy 88.060024 -384.591735)
			(xy 88.068154 -384.5404) (xy 88.084215 -384.49097) (xy 88.107811 -384.44466) (xy 88.138361 -384.402612)
			(xy 88.175112 -384.365861) (xy 88.21716 -384.335311) (xy 88.26347 -384.311715) (xy 88.3129 -384.295654)
			(xy 88.364235 -384.287524) (xy 88.416209 -384.287524) (xy 88.467544 -384.295654) (xy 88.516974 -384.311715)
			(xy 88.563284 -384.335311) (xy 88.605332 -384.365861) (xy 88.642083 -384.402612) (xy 88.672633 -384.44466)
			(xy 88.696229 -384.49097) (xy 88.71229 -384.5404) (xy 88.72042 -384.591735) (xy 88.72093 -384.617722)
			(xy 89.25941 -384.617722) (xy 89.25992 -384.591735) (xy 89.26805 -384.5404) (xy 89.284111 -384.49097)
			(xy 89.307707 -384.44466) (xy 89.338257 -384.402612) (xy 89.375008 -384.365861) (xy 89.417056 -384.335311)
			(xy 89.463366 -384.311715) (xy 89.512796 -384.295654) (xy 89.564131 -384.287524) (xy 89.616105 -384.287524)
			(xy 89.66744 -384.295654) (xy 89.71687 -384.311715) (xy 89.76318 -384.335311) (xy 89.805228 -384.365861)
			(xy 89.841979 -384.402612) (xy 89.872529 -384.44466) (xy 89.896125 -384.49097) (xy 89.912186 -384.5404)
			(xy 89.920316 -384.591735) (xy 89.920826 -384.617722) (xy 90.45956 -384.617722) (xy 90.46007 -384.591735)
			(xy 90.4682 -384.5404) (xy 90.484261 -384.49097) (xy 90.507857 -384.44466) (xy 90.538407 -384.402612)
			(xy 90.575158 -384.365861) (xy 90.617206 -384.335311) (xy 90.663516 -384.311715) (xy 90.712946 -384.295654)
			(xy 90.764281 -384.287524) (xy 90.816255 -384.287524) (xy 90.86759 -384.295654) (xy 90.91702 -384.311715)
			(xy 90.96333 -384.335311) (xy 91.005378 -384.365861) (xy 91.042129 -384.402612) (xy 91.072679 -384.44466)
			(xy 91.096275 -384.49097) (xy 91.112336 -384.5404) (xy 91.120466 -384.591735) (xy 91.120976 -384.617722)
			(xy 91.659456 -384.617722) (xy 91.659966 -384.591735) (xy 91.668096 -384.5404) (xy 91.684157 -384.49097)
			(xy 91.707753 -384.44466) (xy 91.738303 -384.402612) (xy 91.775054 -384.365861) (xy 91.817102 -384.335311)
			(xy 91.863412 -384.311715) (xy 91.912842 -384.295654) (xy 91.964177 -384.287524) (xy 92.016151 -384.287524)
			(xy 92.067486 -384.295654) (xy 92.116916 -384.311715) (xy 92.163226 -384.335311) (xy 92.205274 -384.365861)
			(xy 92.242025 -384.402612) (xy 92.272575 -384.44466) (xy 92.296171 -384.49097) (xy 92.312232 -384.5404)
			(xy 92.320362 -384.591735) (xy 92.320872 -384.617722) (xy 92.859352 -384.617722) (xy 92.859862 -384.591735)
			(xy 92.867992 -384.5404) (xy 92.884053 -384.49097) (xy 92.907649 -384.44466) (xy 92.938199 -384.402612)
			(xy 92.97495 -384.365861) (xy 93.016998 -384.335311) (xy 93.063308 -384.311715) (xy 93.112738 -384.295654)
			(xy 93.164073 -384.287524) (xy 93.216047 -384.287524) (xy 93.267382 -384.295654) (xy 93.316812 -384.311715)
			(xy 93.363122 -384.335311) (xy 93.40517 -384.365861) (xy 93.441921 -384.402612) (xy 93.472471 -384.44466)
			(xy 93.496067 -384.49097) (xy 93.512128 -384.5404) (xy 93.520258 -384.591735) (xy 93.520768 -384.617722)
			(xy 94.059502 -384.617722) (xy 94.060012 -384.591735) (xy 94.068142 -384.5404) (xy 94.084203 -384.49097)
			(xy 94.107799 -384.44466) (xy 94.138349 -384.402612) (xy 94.1751 -384.365861) (xy 94.217148 -384.335311)
			(xy 94.263458 -384.311715) (xy 94.312888 -384.295654) (xy 94.364223 -384.287524) (xy 94.416197 -384.287524)
			(xy 94.467532 -384.295654) (xy 94.516962 -384.311715) (xy 94.563272 -384.335311) (xy 94.60532 -384.365861)
			(xy 94.642071 -384.402612) (xy 94.672621 -384.44466) (xy 94.696217 -384.49097) (xy 94.712278 -384.5404)
			(xy 94.720408 -384.591735) (xy 94.720918 -384.617722) (xy 95.259398 -384.617722) (xy 95.259908 -384.591735)
			(xy 95.268038 -384.5404) (xy 95.284099 -384.49097) (xy 95.307695 -384.44466) (xy 95.338245 -384.402612)
			(xy 95.374996 -384.365861) (xy 95.417044 -384.335311) (xy 95.463354 -384.311715) (xy 95.512784 -384.295654)
			(xy 95.564119 -384.287524) (xy 95.616093 -384.287524) (xy 95.667428 -384.295654) (xy 95.716858 -384.311715)
			(xy 95.763168 -384.335311) (xy 95.805216 -384.365861) (xy 95.841967 -384.402612) (xy 95.872517 -384.44466)
			(xy 95.896113 -384.49097) (xy 95.912174 -384.5404) (xy 95.920304 -384.591735) (xy 95.920814 -384.617722)
			(xy 96.459548 -384.617722) (xy 96.460058 -384.591735) (xy 96.468188 -384.5404) (xy 96.484249 -384.49097)
			(xy 96.507845 -384.44466) (xy 96.538395 -384.402612) (xy 96.575146 -384.365861) (xy 96.617194 -384.335311)
			(xy 96.663504 -384.311715) (xy 96.712934 -384.295654) (xy 96.764269 -384.287524) (xy 96.816243 -384.287524)
			(xy 96.867578 -384.295654) (xy 96.917008 -384.311715) (xy 96.963318 -384.335311) (xy 97.005366 -384.365861)
			(xy 97.042117 -384.402612) (xy 97.072667 -384.44466) (xy 97.096263 -384.49097) (xy 97.112324 -384.5404)
			(xy 97.120454 -384.591735) (xy 97.120964 -384.617722) (xy 97.659444 -384.617722) (xy 97.659954 -384.591735)
			(xy 97.668084 -384.5404) (xy 97.684145 -384.49097) (xy 97.707741 -384.44466) (xy 97.738291 -384.402612)
			(xy 97.775042 -384.365861) (xy 97.81709 -384.335311) (xy 97.8634 -384.311715) (xy 97.91283 -384.295654)
			(xy 97.964165 -384.287524) (xy 98.016139 -384.287524) (xy 98.067474 -384.295654) (xy 98.116904 -384.311715)
			(xy 98.163214 -384.335311) (xy 98.205262 -384.365861) (xy 98.242013 -384.402612) (xy 98.272563 -384.44466)
			(xy 98.296159 -384.49097) (xy 98.31222 -384.5404) (xy 98.32035 -384.591735) (xy 98.32086 -384.617722)
			(xy 98.320329 -384.644824) (xy 98.31152 -384.698307) (xy 98.303334 -384.724148) (xy 98.299524 -384.73507)
			(xy 98.302064 -384.757422) (xy 98.354642 -384.843274) (xy 98.373692 -384.85572) (xy 98.384868 -384.857498)
			(xy 98.414191 -384.862176) (xy 98.471362 -384.878229) (xy 98.525976 -384.901543) (xy 98.577115 -384.931726)
			(xy 98.62392 -384.968271) (xy 98.665604 -385.010563) (xy 98.701467 -385.057892) (xy 98.730907 -385.109462)
			(xy 98.747254 -385.149344) (xy 99.830128 -385.149344) (xy 99.830552 -385.120708) (xy 99.837709 -385.063886)
			(xy 99.851891 -385.008398) (xy 99.872879 -384.95511) (xy 99.900343 -384.904854) (xy 99.916742 -384.881374)
			(xy 99.922418 -384.872857) (xy 99.927027 -384.85293) (xy 99.92346 -384.832791) (xy 99.918266 -384.82397)
			(xy 99.900779 -384.795992) (xy 99.87315 -384.73608) (xy 99.854404 -384.672823) (xy 99.844931 -384.60753)
			(xy 99.844352 -384.574542) (xy 99.844809 -384.545301) (xy 99.852241 -384.487293) (xy 99.867003 -384.430705)
			(xy 99.888854 -384.376458) (xy 99.917438 -384.325437) (xy 99.952288 -384.278474) (xy 99.992838 -384.236333)
			(xy 100.038426 -384.199701) (xy 100.088309 -384.169176) (xy 100.141675 -384.145254) (xy 100.197653 -384.128326)
			(xy 100.255332 -384.118667) (xy 100.284534 -384.117088) (xy 100.294186 -384.116834) (xy 100.311712 -384.109214)
			(xy 100.374196 -384.046222) (xy 100.381816 -384.02895) (xy 100.38207 -384.019044) (xy 100.383653 -383.986493)
			(xy 100.394143 -383.922172) (xy 100.412764 -383.859717) (xy 100.439211 -383.800153) (xy 100.473052 -383.744457)
			(xy 100.513731 -383.69354) (xy 100.560581 -383.648237) (xy 100.612836 -383.609292) (xy 100.669638 -383.577341)
			(xy 100.730056 -383.552909) (xy 100.793101 -383.536396) (xy 100.857738 -383.528073) (xy 100.890324 -383.527554)
			(xy 100.923907 -383.528118) (xy 100.990491 -383.536944) (xy 101.055331 -383.554466) (xy 101.117297 -383.580378)
			(xy 101.175309 -383.614227) (xy 101.228356 -383.655426) (xy 101.275513 -383.703253) (xy 101.315957 -383.756877)
			(xy 101.348983 -383.815362) (xy 101.362002 -383.846324) (xy 101.36759 -383.86004) (xy 101.391212 -383.877058)
			(xy 101.51237 -383.884678) (xy 101.538024 -383.870454) (xy 101.545136 -383.8575) (xy 101.562074 -383.828167)
			(xy 101.602482 -383.773805) (xy 101.649745 -383.725285) (xy 101.703028 -383.683465) (xy 101.761388 -383.649084)
			(xy 101.823794 -383.622749) (xy 101.889142 -383.604927) (xy 101.956277 -383.595933) (xy 101.990144 -383.595372)
			(xy 102.029396 -383.596137) (xy 102.106961 -383.608257) (xy 102.144576 -383.619502) (xy 102.157022 -383.623312)
			(xy 102.18293 -383.618232) (xy 102.268528 -383.545334) (xy 102.277926 -383.520696) (xy 102.275894 -383.507742)
			(xy 102.273995 -383.493914) (xy 102.27196 -383.466073) (xy 102.27183 -383.452116) (xy 102.272316 -383.424865)
			(xy 102.280072 -383.370917) (xy 102.295427 -383.318622) (xy 102.318069 -383.269045) (xy 102.347535 -383.223195)
			(xy 102.383226 -383.182004) (xy 102.424417 -383.146313) (xy 102.470267 -383.116847) (xy 102.519844 -383.094205)
			(xy 102.572139 -383.07885) (xy 102.626087 -383.071094) (xy 102.680589 -383.071094) (xy 102.734537 -383.07885)
			(xy 102.786832 -383.094205) (xy 102.836409 -383.116847) (xy 102.882259 -383.146313) (xy 102.92345 -383.182004)
			(xy 102.959141 -383.223195) (xy 102.988607 -383.269045) (xy 103.011249 -383.318622) (xy 103.026604 -383.370917)
			(xy 103.03436 -383.424865) (xy 103.034846 -383.452116) (xy 103.034176 -383.483763) (xy 103.0237 -383.546185)
			(xy 103.014018 -383.576322) (xy 103.011611 -383.58462) (xy 103.011866 -383.601884) (xy 103.014526 -383.610104)
			(xy 103.024686 -383.638298) (xy 103.027976 -383.646544) (xy 103.039289 -383.66021) (xy 103.046784 -383.664968)
			(xy 103.075106 -383.682148) (xy 103.127486 -383.722698) (xy 103.174154 -383.769708) (xy 103.21432 -383.822383)
			(xy 103.247301 -383.87983) (xy 103.27254 -383.941075) (xy 103.289609 -384.00508) (xy 103.298217 -384.070759)
			(xy 103.298752 -384.10388) (xy 103.298332 -384.13399) (xy 103.2912 -384.193787) (xy 103.277058 -384.252324)
			(xy 103.256103 -384.308782) (xy 103.228628 -384.36237) (xy 103.195018 -384.412339) (xy 103.155744 -384.457991)
			(xy 103.111353 -384.498686) (xy 103.08717 -384.51663) (xy 103.077707 -384.524257) (xy 103.066705 -384.545892)
			(xy 103.066088 -384.558032) (xy 103.066088 -384.640328) (xy 103.066693 -384.652463) (xy 103.077729 -384.674077)
			(xy 103.08717 -384.68173) (xy 103.111366 -384.69966) (xy 103.155767 -384.740346) (xy 103.19505 -384.785994)
			(xy 103.228662 -384.835965) (xy 103.256133 -384.889558) (xy 103.277079 -384.946022) (xy 103.291204 -385.004566)
			(xy 103.298312 -385.064368) (xy 103.298752 -385.09448) (xy 103.298225 -385.125209) (xy 103.29082 -385.186219)
			(xy 103.276115 -385.245891) (xy 103.254325 -385.303356) (xy 103.225767 -385.357776) (xy 103.190858 -385.408357)
			(xy 103.150106 -385.454361) (xy 103.104107 -385.495118) (xy 103.053531 -385.530034) (xy 102.999115 -385.558598)
			(xy 102.941653 -385.580396) (xy 102.881982 -385.595108) (xy 102.820973 -385.602521) (xy 102.790244 -385.602988)
			(xy 102.758119 -385.602513) (xy 102.694383 -385.594403) (xy 102.632176 -385.578332) (xy 102.572487 -385.554557)
			(xy 102.516267 -385.523454) (xy 102.464411 -385.48552) (xy 102.44074 -385.463796) (xy 102.433392 -385.457454)
			(xy 102.415383 -385.450262) (xy 102.405688 -385.449826) (xy 102.3747 -385.449826) (xy 102.364999 -385.450255)
			(xy 102.346973 -385.457423) (xy 102.339648 -385.463796) (xy 102.3239 -385.478274) (xy 102.31501 -385.485894)
			(xy 102.30612 -385.506468) (xy 102.309422 -385.608576) (xy 102.319582 -385.628642) (xy 102.32898 -385.635754)
			(xy 102.355302 -385.656433) (xy 102.40284 -385.703557) (xy 102.44378 -385.756513) (xy 102.477416 -385.814385)
			(xy 102.503165 -385.876172) (xy 102.520581 -385.940803) (xy 102.529363 -386.007162) (xy 102.529894 -386.04063)
			(xy 102.529472 -386.071362) (xy 102.52206 -386.132378) (xy 102.507347 -386.192056) (xy 102.485549 -386.249525)
			(xy 102.456982 -386.303947) (xy 102.422064 -386.35453) (xy 102.381304 -386.400535) (xy 102.335295 -386.441291)
			(xy 102.28471 -386.476205) (xy 102.230284 -386.504767) (xy 102.172813 -386.52656) (xy 102.113135 -386.541268)
			(xy 102.052118 -386.548675) (xy 102.021386 -386.549138) (xy 101.989884 -386.548649) (xy 101.927363 -386.540861)
			(xy 101.866284 -386.525406) (xy 101.807583 -386.502521) (xy 101.75216 -386.472556) (xy 101.726238 -386.45465)
			(xy 101.715316 -386.44703) (xy 101.689408 -386.444236) (xy 101.585014 -386.488178) (xy 101.569012 -386.508752)
			(xy 101.56698 -386.52196) (xy 101.561539 -386.554308) (xy 101.543309 -386.617322) (xy 101.517129 -386.677469)
			(xy 101.483434 -386.733752) (xy 101.442783 -386.785236) (xy 101.39585 -386.831067) (xy 101.343415 -386.870483)
			(xy 101.286348 -386.902832) (xy 101.225596 -386.927576) (xy 101.162166 -386.944304) (xy 101.097113 -386.952739)
			(xy 101.064314 -386.953252) (xy 101.032911 -386.952714) (xy 100.970582 -386.94498) (xy 100.90968 -386.929629)
			(xy 100.851132 -386.906893) (xy 100.795831 -386.87712) (xy 100.744617 -386.840763) (xy 100.698271 -386.798375)
			(xy 100.657499 -386.750602) (xy 100.62292 -386.69817) (xy 100.595063 -386.641879) (xy 100.57435 -386.582586)
			(xy 100.561098 -386.521193) (xy 100.557838 -386.489956) (xy 100.556822 -386.479796) (xy 100.548186 -386.462778)
			(xy 100.480114 -386.403342) (xy 100.461826 -386.396992) (xy 100.451666 -386.3975) (xy 100.427536 -386.398008)
			(xy 100.396805 -386.397529) (xy 100.33579 -386.390124) (xy 100.276112 -386.375419) (xy 100.218642 -386.353627)
			(xy 100.164218 -386.325066) (xy 100.113634 -386.290154) (xy 100.067627 -386.249398) (xy 100.026868 -386.203394)
			(xy 99.991952 -386.152812) (xy 99.963388 -386.09839) (xy 99.941592 -386.040922) (xy 99.926882 -385.981246)
			(xy 99.919474 -385.920231) (xy 99.919028 -385.8895) (xy 99.919451 -385.858719) (xy 99.926867 -385.797605)
			(xy 99.941603 -385.737833) (xy 99.963444 -385.680275) (xy 99.99207 -385.625773) (xy 100.009198 -385.600194)
			(xy 100.014276 -385.5922) (xy 100.018725 -385.573807) (xy 100.017834 -385.56438) (xy 100.013516 -385.533646)
			(xy 100.011852 -385.524383) (xy 100.002729 -385.507939) (xy 99.995736 -385.501642) (xy 99.973912 -385.482952)
			(xy 99.934606 -385.441038) (xy 99.900858 -385.394534) (xy 99.873197 -385.344169) (xy 99.852061 -385.290738)
			(xy 99.83778 -385.235081) (xy 99.83058 -385.178074) (xy 99.830128 -385.149344) (xy 98.747254 -385.149344)
			(xy 98.753428 -385.164408) (xy 98.768652 -385.221805) (xy 98.776323 -385.280689) (xy 98.77679 -385.31038)
			(xy 98.776262 -385.341443) (xy 98.767851 -385.402996) (xy 98.760026 -385.433062) (xy 98.757232 -385.443222)
			(xy 98.759772 -385.463034) (xy 98.80727 -385.54533) (xy 98.823272 -385.557522) (xy 98.833432 -385.560062)
			(xy 98.862538 -385.568075) (xy 98.918504 -385.590707) (xy 98.97101 -385.620499) (xy 99.019144 -385.656935)
			(xy 99.062071 -385.699382) (xy 99.099045 -385.747103) (xy 99.129426 -385.799271) (xy 99.152685 -385.85498)
			(xy 99.16842 -385.913262) (xy 99.176356 -385.973107) (xy 99.17684 -386.003292) (xy 99.176738 -386.017042)
			(xy 99.175086 -386.044493) (xy 99.173538 -386.058156) (xy 99.172818 -386.066844) (xy 99.176592 -386.083853)
			(xy 99.180904 -386.09143) (xy 99.196906 -386.11683) (xy 99.201673 -386.123868) (xy 99.214917 -386.134509)
			(xy 99.222814 -386.137658) (xy 99.24659 -386.146579) (xy 99.291239 -386.170772) (xy 99.331664 -386.201507)
			(xy 99.366915 -386.238061) (xy 99.396163 -386.279575) (xy 99.41872 -386.325073) (xy 99.434056 -386.373484)
			(xy 99.441811 -386.423671) (xy 99.44227 -386.449062) (xy 99.44179 -386.475052) (xy 99.433663 -386.526393)
			(xy 99.417604 -386.57583) (xy 99.394007 -386.622146) (xy 99.363455 -386.664199) (xy 99.326699 -386.700955)
			(xy 99.284646 -386.731507) (xy 99.23833 -386.755104) (xy 99.188893 -386.771163) (xy 99.137552 -386.77929)
			(xy 99.111562 -386.77977) (xy 99.086655 -386.779263) (xy 99.037401 -386.771813) (xy 98.989822 -386.757059)
			(xy 98.944996 -386.735333) (xy 98.903936 -386.707128) (xy 98.867573 -386.673082) (xy 98.836729 -386.633966)
			(xy 98.812102 -386.590665) (xy 98.794251 -386.54416) (xy 98.788474 -386.519928) (xy 98.786308 -386.511709)
			(xy 98.777499 -386.497188) (xy 98.771202 -386.49148) (xy 98.747834 -386.47243) (xy 98.740942 -386.467229)
			(xy 98.724709 -386.461383) (xy 98.716084 -386.461) (xy 98.686248 -386.460288) (xy 98.627126 -386.45214)
			(xy 98.569564 -386.436377) (xy 98.51454 -386.413266) (xy 98.462987 -386.383199) (xy 98.415779 -386.346685)
			(xy 98.373718 -386.304346) (xy 98.337517 -386.256898) (xy 98.307791 -386.205147) (xy 98.285044 -386.149971)
			(xy 98.269662 -386.092307) (xy 98.261905 -386.033132) (xy 98.261424 -386.003292) (xy 98.261946 -385.972229)
			(xy 98.270361 -385.910675) (xy 98.278188 -385.88061) (xy 98.280982 -385.87045) (xy 98.278442 -385.850638)
			(xy 98.230944 -385.768342) (xy 98.214942 -385.75615) (xy 98.204782 -385.75361) (xy 98.175671 -385.745613)
			(xy 98.119703 -385.722981) (xy 98.067196 -385.693188) (xy 98.019061 -385.656751) (xy 97.976134 -385.614302)
			(xy 97.93916 -385.566578) (xy 97.90878 -385.514408) (xy 97.885522 -385.458698) (xy 97.86979 -385.400413)
			(xy 97.861856 -385.340565) (xy 97.861374 -385.31038) (xy 97.861903 -385.279492) (xy 97.870208 -385.218277)
			(xy 97.886664 -385.158733) (xy 97.910972 -385.101941) (xy 97.926398 -385.075176) (xy 97.93224 -385.06527)
			(xy 97.934526 -385.042918) (xy 97.901252 -384.947668) (xy 97.885504 -384.931666) (xy 97.874836 -384.927602)
			(xy 97.851442 -384.91845) (xy 97.807546 -384.894024) (xy 97.767852 -384.863237) (xy 97.733273 -384.826799)
			(xy 97.704606 -384.785548) (xy 97.68251 -384.740434) (xy 97.667495 -384.692497) (xy 97.659906 -384.642839)
			(xy 97.659444 -384.617722) (xy 97.120964 -384.617722) (xy 97.120433 -384.644824) (xy 97.111624 -384.698307)
			(xy 97.103438 -384.724148) (xy 97.099628 -384.73507) (xy 97.102168 -384.757422) (xy 97.154746 -384.843274)
			(xy 97.173796 -384.85572) (xy 97.184972 -384.857498) (xy 97.214296 -384.862173) (xy 97.271466 -384.878227)
			(xy 97.32608 -384.901541) (xy 97.377219 -384.931724) (xy 97.424024 -384.968269) (xy 97.465708 -385.010561)
			(xy 97.501571 -385.057891) (xy 97.531011 -385.109462) (xy 97.553532 -385.164407) (xy 97.568756 -385.221805)
			(xy 97.576427 -385.280689) (xy 97.576894 -385.31038) (xy 97.57637 -385.341506) (xy 97.567965 -385.403188)
			(xy 97.56013 -385.433316) (xy 97.557336 -385.443476) (xy 97.559876 -385.463542) (xy 97.60712 -385.54533)
			(xy 97.623122 -385.557522) (xy 97.633282 -385.560062) (xy 97.662397 -385.568042) (xy 97.718363 -385.59068)
			(xy 97.770868 -385.620477) (xy 97.819001 -385.656918) (xy 97.861926 -385.699369) (xy 97.898899 -385.747093)
			(xy 97.929278 -385.799264) (xy 97.952537 -385.854975) (xy 97.968271 -385.913259) (xy 97.976207 -385.973106)
			(xy 97.97669 -386.003292) (xy 97.976565 -386.017427) (xy 97.974783 -386.045641) (xy 97.973134 -386.05968)
			(xy 97.972377 -386.068287) (xy 97.976015 -386.085167) (xy 97.980246 -386.0927) (xy 97.995994 -386.1181)
			(xy 98.000703 -386.125161) (xy 98.013809 -386.135929) (xy 98.021648 -386.139182) (xy 98.045033 -386.148356)
			(xy 98.088929 -386.172778) (xy 98.128623 -386.203562) (xy 98.163203 -386.239997) (xy 98.191871 -386.281245)
			(xy 98.213969 -386.326356) (xy 98.228986 -386.374291) (xy 98.236577 -386.423946) (xy 98.23704 -386.449062)
			(xy 98.236625 -386.473265) (xy 98.22955 -386.52115) (xy 98.215561 -386.56749) (xy 98.194957 -386.611291)
			(xy 98.181922 -386.631688) (xy 98.177131 -386.639643) (xy 98.1731 -386.657755) (xy 98.174048 -386.666994)
			(xy 98.178366 -386.697982) (xy 98.180058 -386.707275) (xy 98.189333 -386.723717) (xy 98.1964 -386.729986)
			(xy 98.218475 -386.748684) (xy 98.25825 -386.790691) (xy 98.292414 -386.837376) (xy 98.320425 -386.887993)
			(xy 98.341834 -386.941736) (xy 98.356301 -386.997748) (xy 98.363595 -387.055137) (xy 98.36404 -387.084062)
			(xy 98.36345 -387.117383) (xy 98.353788 -387.183322) (xy 98.334662 -387.247161) (xy 98.321114 -387.27761)
			(xy 98.316854 -387.288072) (xy 98.316968 -387.310635) (xy 98.326709 -387.330988) (xy 98.335084 -387.33857)
			(xy 98.357311 -387.357267) (xy 98.397376 -387.399318) (xy 98.431799 -387.4461) (xy 98.460026 -387.496861)
			(xy 98.481605 -387.550785) (xy 98.496188 -387.607007) (xy 98.503541 -387.664621) (xy 98.503994 -387.693662)
			(xy 98.503502 -387.722666) (xy 98.496192 -387.780212) (xy 98.481671 -387.836374) (xy 98.460173 -387.890252)
			(xy 98.432041 -387.940982) (xy 98.397727 -387.987753) (xy 98.35778 -388.029814) (xy 98.335592 -388.0485)
			(xy 98.32848 -388.054088) (xy 98.319336 -388.069328) (xy 98.304096 -388.152132) (xy 98.30689 -388.169404)
			(xy 98.311462 -388.177532) (xy 98.324039 -388.200718) (xy 98.341912 -388.25034) (xy 98.351012 -388.302291)
			(xy 98.351594 -388.328662) (xy 98.35149 -388.339943) (xy 98.349839 -388.362445) (xy 98.348292 -388.37362)
			(xy 98.347022 -388.38251) (xy 98.350578 -388.400036) (xy 98.394012 -388.470902) (xy 98.407728 -388.482078)
			(xy 98.416364 -388.484872) (xy 98.438611 -388.492803) (xy 98.480532 -388.514555) (xy 98.518605 -388.542501)
			(xy 98.551923 -388.575974) (xy 98.579691 -388.614176) (xy 98.590862 -388.634986) (xy 98.59137 -388.636002)
			(xy 98.9838 -389.314944) (xy 98.996532 -389.33831) (xy 99.014648 -389.388338) (xy 99.023858 -389.440741)
			(xy 99.02444 -389.467344) (xy 99.023978 -389.491335) (xy 99.016466 -389.538725) (xy 99.001635 -389.584357)
			(xy 98.979849 -389.627107) (xy 98.951644 -389.665924) (xy 98.917715 -389.699852) (xy 98.878897 -389.728055)
			(xy 98.836146 -389.74984) (xy 98.790513 -389.764669) (xy 98.743123 -389.772179) (xy 98.719132 -389.772652)
			(xy 98.6956 -389.772223) (xy 98.649091 -389.765013) (xy 98.604242 -389.750742) (xy 98.562119 -389.72975)
			(xy 98.52372 -389.702536) (xy 98.489959 -389.669745) (xy 98.461636 -389.632157) (xy 98.450146 -389.611616)
			(xy 98.449892 -389.611108) (xy 98.449384 -389.610346) (xy 98.05162 -388.922006) (xy 98.039706 -388.899337)
			(xy 98.022768 -388.851012) (xy 98.014108 -388.800542) (xy 98.01352 -388.77494) (xy 98.01352 -388.774432)
			(xy 98.013677 -388.763083) (xy 98.015454 -388.740453) (xy 98.017076 -388.72922) (xy 98.018346 -388.72033)
			(xy 98.01479 -388.703058) (xy 97.971356 -388.631938) (xy 97.957386 -388.621016) (xy 97.949004 -388.617968)
			(xy 97.926594 -388.609957) (xy 97.884376 -388.587993) (xy 97.846081 -388.559741) (xy 97.812636 -388.525886)
			(xy 97.784853 -388.487248) (xy 97.763406 -388.444766) (xy 97.748814 -388.39947) (xy 97.741431 -388.352457)
			(xy 97.740978 -388.328662) (xy 97.741547 -388.302289) (xy 97.750629 -388.250331) (xy 97.768516 -388.20071)
			(xy 97.78111 -388.177532) (xy 97.785682 -388.169404) (xy 97.788476 -388.152132) (xy 97.773236 -388.069328)
			(xy 97.764092 -388.054088) (xy 97.75698 -388.0485) (xy 97.734805 -388.029799) (xy 97.694859 -387.987736)
			(xy 97.660543 -387.940967) (xy 97.632405 -387.89024) (xy 97.610895 -387.836367) (xy 97.596359 -387.780209)
			(xy 97.589029 -387.722666) (xy 97.588578 -387.693662) (xy 97.589175 -387.660341) (xy 97.598834 -387.594402)
			(xy 97.617957 -387.530563) (xy 97.631504 -387.500114) (xy 97.635735 -387.489643) (xy 97.63563 -387.467088)
			(xy 97.625902 -387.446738) (xy 97.617534 -387.439154) (xy 97.595274 -387.420495) (xy 97.55521 -387.378438)
			(xy 97.52079 -387.331649) (xy 97.492566 -387.280882) (xy 97.470993 -387.226951) (xy 97.456417 -387.170724)
			(xy 97.449072 -387.113105) (xy 97.448624 -387.084062) (xy 97.449086 -387.055136) (xy 97.456369 -386.997745)
			(xy 97.470827 -386.941728) (xy 97.492229 -386.887981) (xy 97.520234 -386.83736) (xy 97.554396 -386.790671)
			(xy 97.594169 -386.74866) (xy 97.616264 -386.729986) (xy 97.623236 -386.723639) (xy 97.632494 -386.707235)
			(xy 97.634298 -386.697982) (xy 97.638616 -386.666994) (xy 97.639525 -386.657758) (xy 97.635498 -386.639657)
			(xy 97.630742 -386.631688) (xy 97.614438 -386.60584) (xy 97.590532 -386.549606) (xy 97.583244 -386.519928)
			(xy 97.581173 -386.51177) (xy 97.57248 -386.497367) (xy 97.566226 -386.491734) (xy 97.543112 -386.472684)
			(xy 97.536224 -386.467451) (xy 97.52 -386.461477) (xy 97.511362 -386.461) (xy 97.481725 -386.459991)
			(xy 97.423061 -386.451342) (xy 97.366003 -386.435191) (xy 97.311509 -386.411808) (xy 97.26049 -386.381585)
			(xy 97.2138 -386.345028) (xy 97.172221 -386.302749) (xy 97.136449 -386.255455) (xy 97.107082 -386.203938)
			(xy 97.084613 -386.149061) (xy 97.069417 -386.091742) (xy 97.061749 -386.032941) (xy 97.061274 -386.003292)
			(xy 97.061794 -385.972229) (xy 97.070211 -385.910675) (xy 97.078038 -385.88061) (xy 97.080832 -385.87045)
			(xy 97.078292 -385.850638) (xy 97.030794 -385.768342) (xy 97.014792 -385.75615) (xy 97.004632 -385.75361)
			(xy 96.975544 -385.745579) (xy 96.919617 -385.722912) (xy 96.867151 -385.693096) (xy 96.819057 -385.656647)
			(xy 96.776167 -385.614197) (xy 96.739224 -385.566481) (xy 96.708869 -385.514325) (xy 96.685627 -385.458635)
			(xy 96.669902 -385.400374) (xy 96.661965 -385.340553) (xy 96.661478 -385.31038) (xy 96.662007 -385.279492)
			(xy 96.670311 -385.218277) (xy 96.686767 -385.158733) (xy 96.711076 -385.101941) (xy 96.726502 -385.075176)
			(xy 96.732344 -385.06527) (xy 96.73463 -385.042918) (xy 96.701356 -384.947668) (xy 96.685608 -384.931666)
			(xy 96.67494 -384.927602) (xy 96.651546 -384.918448) (xy 96.607651 -384.894022) (xy 96.567957 -384.863236)
			(xy 96.533378 -384.826798) (xy 96.50471 -384.785547) (xy 96.482614 -384.740434) (xy 96.467599 -384.692496)
			(xy 96.46001 -384.642839) (xy 96.459548 -384.617722) (xy 95.920814 -384.617722) (xy 95.920281 -384.644824)
			(xy 95.911473 -384.698306) (xy 95.903288 -384.724148) (xy 95.899478 -384.73507) (xy 95.902018 -384.757422)
			(xy 95.954596 -384.843274) (xy 95.973646 -384.85572) (xy 95.984822 -384.857498) (xy 96.014139 -384.862212)
			(xy 96.071309 -384.87826) (xy 96.125923 -384.901568) (xy 96.177063 -384.931747) (xy 96.223869 -384.968287)
			(xy 96.265554 -385.010575) (xy 96.301419 -385.057901) (xy 96.330859 -385.109469) (xy 96.353381 -385.164412)
			(xy 96.368605 -385.221808) (xy 96.376277 -385.28069) (xy 96.376744 -385.31038) (xy 96.376217 -385.341443)
			(xy 96.367805 -385.402996) (xy 96.35998 -385.433062) (xy 96.357186 -385.443222) (xy 96.359726 -385.463034)
			(xy 96.407224 -385.54533) (xy 96.423226 -385.557522) (xy 96.433386 -385.560062) (xy 96.462502 -385.568039)
			(xy 96.518468 -385.590677) (xy 96.570973 -385.620475) (xy 96.619105 -385.656916) (xy 96.66203 -385.699367)
			(xy 96.699003 -385.747092) (xy 96.729383 -385.799263) (xy 96.752641 -385.854974) (xy 96.768375 -385.913259)
			(xy 96.776311 -385.973106) (xy 96.776794 -386.003292) (xy 96.776669 -386.017427) (xy 96.774887 -386.045641)
			(xy 96.773238 -386.05968) (xy 96.77248 -386.068287) (xy 96.776118 -386.085167) (xy 96.78035 -386.0927)
			(xy 96.796098 -386.1181) (xy 96.800805 -386.125162) (xy 96.813913 -386.13593) (xy 96.821752 -386.139182)
			(xy 96.845138 -386.148353) (xy 96.889033 -386.172777) (xy 96.928728 -386.203561) (xy 96.963307 -386.239996)
			(xy 96.991976 -386.281244) (xy 97.014073 -386.326355) (xy 97.02909 -386.37429) (xy 97.036681 -386.423946)
			(xy 97.037144 -386.449062) (xy 97.036728 -386.473265) (xy 97.029653 -386.52115) (xy 97.015664 -386.56749)
			(xy 96.995061 -386.611291) (xy 96.982026 -386.631688) (xy 96.977235 -386.639643) (xy 96.973204 -386.657756)
			(xy 96.974152 -386.666994) (xy 96.97847 -386.697982) (xy 96.980161 -386.707276) (xy 96.989436 -386.723718)
			(xy 96.996504 -386.729986) (xy 97.01858 -386.748683) (xy 97.058354 -386.79069) (xy 97.092519 -386.837375)
			(xy 97.120529 -386.887992) (xy 97.141938 -386.941736) (xy 97.156405 -386.997748) (xy 97.163699 -387.055137)
			(xy 97.164144 -387.084062) (xy 97.163554 -387.117383) (xy 97.153891 -387.183322) (xy 97.134766 -387.247161)
			(xy 97.121218 -387.27761) (xy 97.116957 -387.288071) (xy 97.11707 -387.310635) (xy 97.126812 -387.330988)
			(xy 97.135188 -387.33857) (xy 97.157416 -387.357266) (xy 97.197481 -387.399317) (xy 97.231903 -387.446099)
			(xy 97.260131 -387.496861) (xy 97.281709 -387.550785) (xy 97.296292 -387.607007) (xy 97.303645 -387.664621)
			(xy 97.304098 -387.693662) (xy 97.30364 -387.722668) (xy 97.296329 -387.780216) (xy 97.281805 -387.83638)
			(xy 97.260302 -387.890259) (xy 97.232164 -387.940989) (xy 97.197842 -387.987758) (xy 97.157887 -388.029816)
			(xy 97.135696 -388.0485) (xy 97.128584 -388.054088) (xy 97.11944 -388.069328) (xy 97.1042 -388.152132)
			(xy 97.106994 -388.169404) (xy 97.111566 -388.177532) (xy 97.124143 -388.200718) (xy 97.142016 -388.25034)
			(xy 97.151116 -388.302291) (xy 97.151698 -388.328662) (xy 97.151594 -388.339943) (xy 97.149943 -388.362445)
			(xy 97.148396 -388.37362) (xy 97.147126 -388.382764) (xy 97.150428 -388.400036) (xy 97.194116 -388.471156)
			(xy 97.207832 -388.482078) (xy 97.216468 -388.484872) (xy 97.244632 -388.495072) (xy 97.296578 -388.524881)
			(xy 97.319592 -388.544054) (xy 97.341076 -388.563636) (xy 97.376889 -388.609414) (xy 97.390712 -388.634986)
			(xy 97.391474 -388.636256) (xy 97.78365 -389.314944) (xy 97.796457 -389.338285) (xy 97.814684 -389.388304)
			(xy 97.823951 -389.440726) (xy 97.824544 -389.467344) (xy 97.824102 -389.491349) (xy 97.816582 -389.538767)
			(xy 97.801734 -389.584424) (xy 97.779924 -389.627195) (xy 97.75169 -389.666026) (xy 97.717726 -389.69996)
			(xy 97.678871 -389.728161) (xy 97.636082 -389.749934) (xy 97.590412 -389.764743) (xy 97.542988 -389.772222)
			(xy 97.518982 -389.772652) (xy 97.495451 -389.772183) (xy 97.448944 -389.76498) (xy 97.404096 -389.750716)
			(xy 97.361973 -389.729731) (xy 97.323574 -389.702523) (xy 97.289811 -389.669738) (xy 97.261487 -389.632155)
			(xy 97.249996 -389.611616) (xy 97.249742 -389.611108) (xy 97.249234 -389.610346) (xy 96.851724 -388.921752)
			(xy 96.841152 -388.901825) (xy 96.825349 -388.859575) (xy 96.815941 -388.815459) (xy 96.814132 -388.792974)
			(xy 96.813624 -388.781798) (xy 96.813624 -388.774432) (xy 96.813715 -388.763087) (xy 96.81537 -388.740458)
			(xy 96.816926 -388.72922) (xy 96.818196 -388.72033) (xy 96.81464 -388.703058) (xy 96.771206 -388.631938)
			(xy 96.75749 -388.620762) (xy 96.748854 -388.617968) (xy 96.726448 -388.609981) (xy 96.684278 -388.587976)
			(xy 96.64603 -388.559697) (xy 96.612631 -388.525829) (xy 96.584888 -388.487191) (xy 96.563473 -388.444717)
			(xy 96.548904 -388.399437) (xy 96.541533 -388.352445) (xy 96.541082 -388.328662) (xy 96.54165 -388.302289)
			(xy 96.550732 -388.250331) (xy 96.56862 -388.20071) (xy 96.581214 -388.177532) (xy 96.585786 -388.169404)
			(xy 96.58858 -388.152132) (xy 96.57334 -388.069328) (xy 96.564196 -388.054088) (xy 96.557084 -388.0485)
			(xy 96.53491 -388.029798) (xy 96.494964 -387.987735) (xy 96.460647 -387.940967) (xy 96.432509 -387.89024)
			(xy 96.411 -387.836367) (xy 96.396463 -387.780209) (xy 96.389133 -387.722666) (xy 96.388682 -387.693662)
			(xy 96.389278 -387.660341) (xy 96.398938 -387.594402) (xy 96.418061 -387.530563) (xy 96.431608 -387.500114)
			(xy 96.435838 -387.489643) (xy 96.435732 -387.467088) (xy 96.426005 -387.446739) (xy 96.417638 -387.439154)
			(xy 96.395379 -387.420494) (xy 96.355315 -387.378437) (xy 96.320894 -387.331649) (xy 96.29267 -387.280881)
			(xy 96.271097 -387.226951) (xy 96.256521 -387.170724) (xy 96.249176 -387.113105) (xy 96.248728 -387.084062)
			(xy 96.249188 -387.055136) (xy 96.256471 -386.997744) (xy 96.27093 -386.941728) (xy 96.292332 -386.887981)
			(xy 96.320338 -386.837359) (xy 96.3545 -386.790671) (xy 96.394273 -386.74866) (xy 96.416368 -386.729986)
			(xy 96.423341 -386.72364) (xy 96.432598 -386.707235) (xy 96.434402 -386.697982) (xy 96.43872 -386.666994)
			(xy 96.439628 -386.657757) (xy 96.435602 -386.639657) (xy 96.430846 -386.631688) (xy 96.414542 -386.60584)
			(xy 96.390636 -386.549606) (xy 96.383348 -386.519928) (xy 96.381276 -386.51177) (xy 96.372583 -386.497368)
			(xy 96.36633 -386.491734) (xy 96.343216 -386.472684) (xy 96.336327 -386.467452) (xy 96.320103 -386.461478)
			(xy 96.311466 -386.461) (xy 96.28183 -386.459987) (xy 96.223165 -386.451338) (xy 96.166108 -386.435188)
			(xy 96.111614 -386.411806) (xy 96.060594 -386.381583) (xy 96.013905 -386.345027) (xy 95.972325 -386.302748)
			(xy 95.936553 -386.255454) (xy 95.907186 -386.203938) (xy 95.884717 -386.149061) (xy 95.869521 -386.091742)
			(xy 95.861853 -386.032941) (xy 95.861378 -386.003292) (xy 95.861898 -385.972229) (xy 95.870315 -385.910675)
			(xy 95.878142 -385.88061) (xy 95.880936 -385.87045) (xy 95.878396 -385.850638) (xy 95.830898 -385.768342)
			(xy 95.814896 -385.75615) (xy 95.804736 -385.75361) (xy 95.775617 -385.745644) (xy 95.719649 -385.723006)
			(xy 95.667143 -385.693208) (xy 95.619009 -385.656767) (xy 95.576083 -385.614314) (xy 95.53911 -385.566588)
			(xy 95.508731 -385.514415) (xy 95.485474 -385.458702) (xy 95.469743 -385.400415) (xy 95.461809 -385.340566)
			(xy 95.461328 -385.31038) (xy 95.46185 -385.279492) (xy 95.470155 -385.218276) (xy 95.486613 -385.158732)
			(xy 95.510925 -385.10194) (xy 95.526352 -385.075176) (xy 95.532194 -385.06527) (xy 95.53448 -385.042918)
			(xy 95.501206 -384.947668) (xy 95.485458 -384.931666) (xy 95.47479 -384.927602) (xy 95.451407 -384.918421)
			(xy 95.40751 -384.894002) (xy 95.367814 -384.863221) (xy 95.333233 -384.826787) (xy 95.304564 -384.785539)
			(xy 95.282466 -384.740429) (xy 95.26745 -384.692494) (xy 95.25986 -384.642838) (xy 95.259398 -384.617722)
			(xy 94.720918 -384.617722) (xy 94.720385 -384.644824) (xy 94.711577 -384.698306) (xy 94.703392 -384.724148)
			(xy 94.699582 -384.73507) (xy 94.702122 -384.757422) (xy 94.7547 -384.843274) (xy 94.77375 -384.85572)
			(xy 94.784926 -384.857498) (xy 94.814243 -384.862209) (xy 94.871414 -384.878257) (xy 94.926028 -384.901566)
			(xy 94.977168 -384.931745) (xy 95.023973 -384.968286) (xy 95.065659 -385.010574) (xy 95.101523 -385.057901)
			(xy 95.130963 -385.109469) (xy 95.153485 -385.164412) (xy 95.168709 -385.221807) (xy 95.176381 -385.28069)
			(xy 95.176848 -385.31038) (xy 95.176325 -385.341506) (xy 95.167919 -385.403188) (xy 95.160084 -385.433316)
			(xy 95.15729 -385.443476) (xy 95.15983 -385.463542) (xy 95.207074 -385.54533) (xy 95.223076 -385.557522)
			(xy 95.233236 -385.560062) (xy 95.262342 -385.568073) (xy 95.318309 -385.590705) (xy 95.370815 -385.620498)
			(xy 95.418948 -385.656934) (xy 95.461875 -385.699381) (xy 95.498849 -385.747103) (xy 95.52923 -385.79927)
			(xy 95.552489 -385.854979) (xy 95.568224 -385.913262) (xy 95.57616 -385.973107) (xy 95.576644 -386.003292)
			(xy 95.576519 -386.017427) (xy 95.574737 -386.045641) (xy 95.573088 -386.05968) (xy 95.572323 -386.068287)
			(xy 95.575965 -386.085168) (xy 95.5802 -386.0927) (xy 95.595948 -386.1181) (xy 95.600639 -386.125174)
			(xy 95.613758 -386.135936) (xy 95.621602 -386.139182) (xy 95.644977 -386.14838) (xy 95.688874 -386.172797)
			(xy 95.72857 -386.203576) (xy 95.763152 -386.240007) (xy 95.791822 -386.281252) (xy 95.813921 -386.32636)
			(xy 95.828939 -386.374293) (xy 95.836531 -386.423947) (xy 95.836994 -386.449062) (xy 95.83657 -386.473264)
			(xy 95.829496 -386.521149) (xy 95.815509 -386.567488) (xy 95.794909 -386.61129) (xy 95.781876 -386.631688)
			(xy 95.777089 -386.639645) (xy 95.773054 -386.657756) (xy 95.774002 -386.666994) (xy 95.77832 -386.697982)
			(xy 95.779996 -386.70728) (xy 95.789281 -386.723721) (xy 95.796354 -386.729986) (xy 95.81844 -386.74867)
			(xy 95.858212 -386.790681) (xy 95.892375 -386.837369) (xy 95.920383 -386.887988) (xy 95.94179 -386.941733)
			(xy 95.956256 -386.997747) (xy 95.963549 -387.055136) (xy 95.963994 -387.084062) (xy 95.963399 -387.117383)
			(xy 95.953738 -387.183321) (xy 95.934614 -387.247161) (xy 95.921068 -387.27761) (xy 95.916823 -387.288076)
			(xy 95.916937 -387.310634) (xy 95.926669 -387.330985) (xy 95.935038 -387.33857) (xy 95.957276 -387.357254)
			(xy 95.997338 -387.399308) (xy 96.031759 -387.446093) (xy 96.059984 -387.496857) (xy 96.081561 -387.550783)
			(xy 96.096143 -387.607005) (xy 96.103495 -387.664621) (xy 96.103948 -387.693662) (xy 96.103473 -387.722667)
			(xy 96.096162 -387.780214) (xy 96.08164 -387.836377) (xy 96.060139 -387.890255) (xy 96.032004 -387.940986)
			(xy 95.997687 -387.987756) (xy 95.957735 -388.029815) (xy 95.935546 -388.0485) (xy 95.928434 -388.054088)
			(xy 95.91929 -388.069328) (xy 95.90405 -388.152132) (xy 95.906844 -388.169404) (xy 95.911416 -388.177532)
			(xy 95.923989 -388.20072) (xy 95.941864 -388.25034) (xy 95.950966 -388.302291) (xy 95.951548 -388.328662)
			(xy 95.951445 -388.339943) (xy 95.949793 -388.362445) (xy 95.948246 -388.37362) (xy 95.946976 -388.38251)
			(xy 95.950532 -388.400036) (xy 95.993966 -388.470902) (xy 96.007682 -388.482078) (xy 96.016318 -388.484872)
			(xy 96.038574 -388.492778) (xy 96.080494 -388.514537) (xy 96.118565 -388.542489) (xy 96.151881 -388.575967)
			(xy 96.179647 -388.614174) (xy 96.190816 -388.634986) (xy 96.191324 -388.636002) (xy 96.583754 -389.314944)
			(xy 96.596562 -389.338285) (xy 96.614788 -389.388304) (xy 96.624055 -389.440726) (xy 96.624648 -389.467344)
			(xy 96.624202 -389.491349) (xy 96.616682 -389.538767) (xy 96.601834 -389.584423) (xy 96.580025 -389.627194)
			(xy 96.551791 -389.666025) (xy 96.517828 -389.699959) (xy 96.478973 -389.72816) (xy 96.436184 -389.749933)
			(xy 96.390515 -389.764742) (xy 96.343091 -389.772222) (xy 96.319086 -389.772652) (xy 96.295555 -389.77218)
			(xy 96.249049 -389.764977) (xy 96.204201 -389.750714) (xy 96.162077 -389.72973) (xy 96.123678 -389.702522)
			(xy 96.089916 -389.669737) (xy 96.061591 -389.632154) (xy 96.0501 -389.611616) (xy 96.049846 -389.611108)
			(xy 96.049338 -389.610346) (xy 95.651574 -388.922006) (xy 95.639699 -388.899329) (xy 95.622848 -388.850996)
			(xy 95.614274 -388.800533) (xy 95.613728 -388.77494) (xy 95.613728 -388.774432) (xy 95.613819 -388.763087)
			(xy 95.615474 -388.740458) (xy 95.61703 -388.72922) (xy 95.6183 -388.72033) (xy 95.614744 -388.703058)
			(xy 95.57131 -388.631938) (xy 95.55734 -388.621016) (xy 95.548958 -388.617968) (xy 95.526559 -388.609926)
			(xy 95.48434 -388.587969) (xy 95.446043 -388.559723) (xy 95.412596 -388.525873) (xy 95.384811 -388.48724)
			(xy 95.363362 -388.444761) (xy 95.348769 -388.399466) (xy 95.341385 -388.352456) (xy 95.340932 -388.328662)
			(xy 95.341494 -388.302289) (xy 95.350578 -388.25033) (xy 95.368468 -388.20071) (xy 95.381064 -388.177532)
			(xy 95.385636 -388.169404) (xy 95.38843 -388.152132) (xy 95.37319 -388.069328) (xy 95.364046 -388.054088)
			(xy 95.356934 -388.0485) (xy 95.33477 -388.029786) (xy 95.294822 -387.987727) (xy 95.260503 -387.940961)
			(xy 95.232362 -387.890236) (xy 95.210851 -387.836364) (xy 95.196314 -387.780208) (xy 95.188983 -387.722666)
			(xy 95.188532 -387.693662) (xy 95.189133 -387.660341) (xy 95.198791 -387.594403) (xy 95.217913 -387.530563)
			(xy 95.231458 -387.500114) (xy 95.235704 -387.489647) (xy 95.2356 -387.467087) (xy 95.225862 -387.446735)
			(xy 95.217488 -387.439154) (xy 95.195218 -387.420506) (xy 95.155157 -387.378446) (xy 95.120739 -387.331655)
			(xy 95.092517 -387.280885) (xy 95.070945 -387.226953) (xy 95.05637 -387.170725) (xy 95.049026 -387.113105)
			(xy 95.048578 -387.084062) (xy 95.04902 -387.055135) (xy 95.056304 -386.997742) (xy 95.070764 -386.941725)
			(xy 95.092169 -386.887977) (xy 95.120178 -386.837355) (xy 95.154343 -386.790668) (xy 95.194121 -386.748659)
			(xy 95.216218 -386.729986) (xy 95.223183 -386.723632) (xy 95.232446 -386.707233) (xy 95.234252 -386.697982)
			(xy 95.23857 -386.666994) (xy 95.239471 -386.657757) (xy 95.235448 -386.639658) (xy 95.230696 -386.631688)
			(xy 95.214387 -386.605843) (xy 95.190484 -386.549607) (xy 95.183198 -386.519928) (xy 95.181139 -386.511766)
			(xy 95.172438 -386.497365) (xy 95.16618 -386.491734) (xy 95.143066 -386.472684) (xy 95.13619 -386.467432)
			(xy 95.119956 -386.46147) (xy 95.111316 -386.461) (xy 95.081681 -386.459941) (xy 95.023018 -386.451299)
			(xy 94.965962 -386.435154) (xy 94.911468 -386.411777) (xy 94.860449 -386.38156) (xy 94.813758 -386.345007)
			(xy 94.772178 -386.302732) (xy 94.736405 -386.255442) (xy 94.707038 -386.203929) (xy 94.684568 -386.149055)
			(xy 94.669371 -386.091739) (xy 94.661703 -386.03294) (xy 94.661228 -386.003292) (xy 94.661749 -385.972229)
			(xy 94.670165 -385.910675) (xy 94.677992 -385.88061) (xy 94.680786 -385.87045) (xy 94.678246 -385.850638)
			(xy 94.630748 -385.768342) (xy 94.614746 -385.75615) (xy 94.604586 -385.75361) (xy 94.575508 -385.745543)
			(xy 94.51958 -385.722883) (xy 94.467114 -385.693073) (xy 94.419018 -385.656629) (xy 94.376126 -385.614182)
			(xy 94.339182 -385.56647) (xy 94.308825 -385.514318) (xy 94.285582 -385.45863) (xy 94.269856 -385.400371)
			(xy 94.261919 -385.340552) (xy 94.261432 -385.31038) (xy 94.261953 -385.279492) (xy 94.270259 -385.218276)
			(xy 94.286717 -385.158732) (xy 94.311029 -385.10194) (xy 94.326456 -385.075176) (xy 94.332298 -385.06527)
			(xy 94.334584 -385.042918) (xy 94.30131 -384.947668) (xy 94.285562 -384.931666) (xy 94.274894 -384.927602)
			(xy 94.251512 -384.918419) (xy 94.207615 -384.894) (xy 94.167919 -384.863219) (xy 94.133337 -384.826786)
			(xy 94.104668 -384.785539) (xy 94.08257 -384.740428) (xy 94.067554 -384.692493) (xy 94.059964 -384.642838)
			(xy 94.059502 -384.617722) (xy 93.520768 -384.617722) (xy 93.520237 -384.644824) (xy 93.511428 -384.698307)
			(xy 93.503242 -384.724148) (xy 93.499432 -384.73507) (xy 93.501972 -384.757422) (xy 93.55455 -384.843274)
			(xy 93.5736 -384.85572) (xy 93.584776 -384.857498) (xy 93.6141 -384.86217) (xy 93.671271 -384.878224)
			(xy 93.725885 -384.901539) (xy 93.777024 -384.931722) (xy 93.823828 -384.968268) (xy 93.865513 -385.01056)
			(xy 93.901376 -385.05789) (xy 93.930815 -385.109461) (xy 93.953336 -385.164407) (xy 93.96856 -385.221804)
			(xy 93.976231 -385.280689) (xy 93.976698 -385.31038) (xy 93.976173 -385.341443) (xy 93.96776 -385.402997)
			(xy 93.959934 -385.433062) (xy 93.95714 -385.443222) (xy 93.95968 -385.463034) (xy 94.007178 -385.54533)
			(xy 94.02318 -385.557522) (xy 94.03334 -385.560062) (xy 94.062447 -385.56807) (xy 94.118413 -385.590703)
			(xy 94.170919 -385.620496) (xy 94.219053 -385.656932) (xy 94.261979 -385.69938) (xy 94.298954 -385.747102)
			(xy 94.329334 -385.79927) (xy 94.352593 -385.854979) (xy 94.368328 -385.913262) (xy 94.376264 -385.973107)
			(xy 94.376748 -386.003292) (xy 94.376623 -386.017427) (xy 94.374841 -386.045641) (xy 94.373192 -386.05968)
			(xy 94.372426 -386.068287) (xy 94.376068 -386.085168) (xy 94.380304 -386.0927) (xy 94.396052 -386.1181)
			(xy 94.400774 -386.125151) (xy 94.413871 -386.135925) (xy 94.421706 -386.139182) (xy 94.445082 -386.148378)
			(xy 94.488979 -386.172796) (xy 94.528675 -386.203575) (xy 94.563256 -386.240006) (xy 94.591926 -386.281251)
			(xy 94.614025 -386.32636) (xy 94.629043 -386.374293) (xy 94.636635 -386.423947) (xy 94.637098 -386.449062)
			(xy 94.636673 -386.473264) (xy 94.6296 -386.521149) (xy 94.615613 -386.567488) (xy 94.595013 -386.61129)
			(xy 94.58198 -386.631688) (xy 94.577193 -386.639645) (xy 94.573158 -386.657756) (xy 94.574106 -386.666994)
			(xy 94.578424 -386.697982) (xy 94.580099 -386.70728) (xy 94.589384 -386.723721) (xy 94.596458 -386.729986)
			(xy 94.618545 -386.748669) (xy 94.658317 -386.790681) (xy 94.692479 -386.837368) (xy 94.720487 -386.887988)
			(xy 94.741894 -386.941733) (xy 94.75636 -386.997747) (xy 94.763653 -387.055136) (xy 94.764098 -387.084062)
			(xy 94.763512 -387.117384) (xy 94.753849 -387.183322) (xy 94.734721 -387.247161) (xy 94.721172 -387.27761)
			(xy 94.716926 -387.288075) (xy 94.71704 -387.310634) (xy 94.726773 -387.330985) (xy 94.735142 -387.33857)
			(xy 94.75736 -387.357277) (xy 94.797427 -387.399325) (xy 94.831852 -387.446105) (xy 94.860082 -387.496864)
			(xy 94.881662 -387.550787) (xy 94.896246 -387.607008) (xy 94.903599 -387.664621) (xy 94.904052 -387.693662)
			(xy 94.903575 -387.722667) (xy 94.896264 -387.780214) (xy 94.881742 -387.836377) (xy 94.860242 -387.890255)
			(xy 94.832108 -387.940985) (xy 94.79779 -387.987755) (xy 94.757839 -388.029815) (xy 94.73565 -388.0485)
			(xy 94.728538 -388.054088) (xy 94.719394 -388.069328) (xy 94.704154 -388.152132) (xy 94.706948 -388.169404)
			(xy 94.71152 -388.177532) (xy 94.724093 -388.200719) (xy 94.741969 -388.25034) (xy 94.75107 -388.302291)
			(xy 94.751652 -388.328662) (xy 94.751549 -388.339943) (xy 94.749897 -388.362445) (xy 94.74835 -388.37362)
			(xy 94.74708 -388.382764) (xy 94.750382 -388.400036) (xy 94.79407 -388.471156) (xy 94.807786 -388.482078)
			(xy 94.816422 -388.484872) (xy 94.844591 -388.49506) (xy 94.896534 -388.524878) (xy 94.919546 -388.544054)
			(xy 94.941036 -388.563629) (xy 94.976845 -388.609412) (xy 94.990666 -388.634986) (xy 94.991428 -388.636256)
			(xy 95.383604 -389.314944) (xy 95.396337 -389.33831) (xy 95.414452 -389.388337) (xy 95.423662 -389.440741)
			(xy 95.424244 -389.467344) (xy 95.423778 -389.491335) (xy 95.416267 -389.538724) (xy 95.401435 -389.584356)
			(xy 95.379649 -389.627106) (xy 95.351445 -389.665923) (xy 95.317517 -389.69985) (xy 95.278699 -389.728054)
			(xy 95.235949 -389.749838) (xy 95.190317 -389.764668) (xy 95.142927 -389.772179) (xy 95.118936 -389.772652)
			(xy 95.095404 -389.77222) (xy 95.048895 -389.76501) (xy 95.004047 -389.75074) (xy 94.961923 -389.729749)
			(xy 94.923525 -389.702535) (xy 94.889763 -389.669745) (xy 94.86144 -389.632157) (xy 94.84995 -389.611616)
			(xy 94.849696 -389.611108) (xy 94.849188 -389.610346) (xy 94.451678 -388.921752) (xy 94.441103 -388.901827)
			(xy 94.425301 -388.859576) (xy 94.415895 -388.815459) (xy 94.414086 -388.792974) (xy 94.413578 -388.781798)
			(xy 94.413324 -388.774432) (xy 94.413481 -388.763083) (xy 94.415258 -388.740453) (xy 94.41688 -388.72922)
			(xy 94.41815 -388.72033) (xy 94.414594 -388.703058) (xy 94.37116 -388.631938) (xy 94.357444 -388.620762)
			(xy 94.348808 -388.617968) (xy 94.326414 -388.60995) (xy 94.284242 -388.587952) (xy 94.245992 -388.559679)
			(xy 94.212591 -388.525816) (xy 94.184846 -388.487182) (xy 94.163429 -388.444712) (xy 94.148859 -388.399434)
			(xy 94.141487 -388.352444) (xy 94.141036 -388.328662) (xy 94.141597 -388.302289) (xy 94.150681 -388.25033)
			(xy 94.168572 -388.20071) (xy 94.181168 -388.177532) (xy 94.18574 -388.169404) (xy 94.188534 -388.152132)
			(xy 94.173294 -388.069328) (xy 94.16415 -388.054088) (xy 94.157038 -388.0485) (xy 94.134875 -388.029785)
			(xy 94.094926 -387.987726) (xy 94.060607 -387.94096) (xy 94.032467 -387.890236) (xy 94.010956 -387.836364)
			(xy 93.996418 -387.780208) (xy 93.989087 -387.722666) (xy 93.988636 -387.693662) (xy 93.989236 -387.660341)
			(xy 93.998895 -387.594403) (xy 94.018017 -387.530563) (xy 94.031562 -387.500114) (xy 94.035807 -387.489647)
			(xy 94.035702 -387.467087) (xy 94.025966 -387.446735) (xy 94.017592 -387.439154) (xy 93.995323 -387.420505)
			(xy 93.955262 -387.378445) (xy 93.920843 -387.331654) (xy 93.892621 -387.280885) (xy 93.871049 -387.226953)
			(xy 93.856474 -387.170725) (xy 93.84913 -387.113105) (xy 93.848682 -387.084062) (xy 93.849122 -387.055135)
			(xy 93.856407 -386.997742) (xy 93.870867 -386.941725) (xy 93.892272 -386.887977) (xy 93.920281 -386.837355)
			(xy 93.954447 -386.790668) (xy 93.994225 -386.748659) (xy 94.016322 -386.729986) (xy 94.023288 -386.723632)
			(xy 94.03255 -386.707234) (xy 94.034356 -386.697982) (xy 94.038674 -386.666994) (xy 94.039574 -386.657757)
			(xy 94.035552 -386.639658) (xy 94.0308 -386.631688) (xy 94.014492 -386.605843) (xy 93.990588 -386.549607)
			(xy 93.983302 -386.519928) (xy 93.981242 -386.511766) (xy 93.972542 -386.497365) (xy 93.966284 -386.491734)
			(xy 93.94317 -386.472684) (xy 93.936293 -386.467434) (xy 93.92006 -386.461471) (xy 93.91142 -386.461)
			(xy 93.881782 -386.460029) (xy 93.823116 -386.451375) (xy 93.766058 -386.435219) (xy 93.711564 -386.411832)
			(xy 93.660545 -386.381605) (xy 93.613855 -386.345044) (xy 93.572277 -386.302762) (xy 93.536505 -386.255465)
			(xy 93.507139 -386.203946) (xy 93.48467 -386.149066) (xy 93.469475 -386.091745) (xy 93.461807 -386.032942)
			(xy 93.461332 -386.003292) (xy 93.461853 -385.972229) (xy 93.470269 -385.910675) (xy 93.478096 -385.88061)
			(xy 93.48089 -385.87045) (xy 93.47835 -385.850638) (xy 93.430852 -385.768342) (xy 93.41485 -385.75615)
			(xy 93.40469 -385.75361) (xy 93.375581 -385.745608) (xy 93.319613 -385.722977) (xy 93.267105 -385.693184)
			(xy 93.21897 -385.656748) (xy 93.176043 -385.6143) (xy 93.139068 -385.566577) (xy 93.108688 -385.514407)
			(xy 93.08543 -385.458697) (xy 93.069698 -385.400412) (xy 93.061764 -385.340565) (xy 93.061282 -385.31038)
			(xy 93.06181 -385.279492) (xy 93.070115 -385.218277) (xy 93.086571 -385.158733) (xy 93.11088 -385.101941)
			(xy 93.126306 -385.075176) (xy 93.132148 -385.06527) (xy 93.134434 -385.042918) (xy 93.10116 -384.947668)
			(xy 93.085412 -384.931666) (xy 93.074744 -384.927602) (xy 93.051351 -384.918446) (xy 93.007456 -384.894021)
			(xy 92.967761 -384.863235) (xy 92.933182 -384.826797) (xy 92.904514 -384.785547) (xy 92.882418 -384.740433)
			(xy 92.867403 -384.692496) (xy 92.859814 -384.642839) (xy 92.859352 -384.617722) (xy 92.320872 -384.617722)
			(xy 92.320341 -384.644824) (xy 92.311532 -384.698307) (xy 92.303346 -384.724148) (xy 92.299536 -384.73507)
			(xy 92.302076 -384.757422) (xy 92.354654 -384.843274) (xy 92.373704 -384.85572) (xy 92.38488 -384.857498)
			(xy 92.414205 -384.862167) (xy 92.471376 -384.878222) (xy 92.525989 -384.901537) (xy 92.577128 -384.931721)
			(xy 92.623933 -384.968266) (xy 92.665617 -385.010559) (xy 92.70148 -385.057889) (xy 92.730919 -385.10946)
			(xy 92.75344 -385.164406) (xy 92.768664 -385.221804) (xy 92.776335 -385.280689) (xy 92.776802 -385.31038)
			(xy 92.776277 -385.341443) (xy 92.767864 -385.402997) (xy 92.760038 -385.433062) (xy 92.757244 -385.443222)
			(xy 92.759784 -385.463034) (xy 92.807282 -385.54533) (xy 92.823284 -385.557522) (xy 92.833444 -385.560062)
			(xy 92.862552 -385.568067) (xy 92.918518 -385.5907) (xy 92.971024 -385.620494) (xy 93.019158 -385.656931)
			(xy 93.062084 -385.699379) (xy 93.099058 -385.747101) (xy 93.129439 -385.799269) (xy 93.152698 -385.854978)
			(xy 93.168432 -385.913261) (xy 93.176369 -385.973107) (xy 93.176852 -386.003292) (xy 93.176727 -386.017427)
			(xy 93.174945 -386.045641) (xy 93.173296 -386.05968) (xy 93.172529 -386.068287) (xy 93.176172 -386.085168)
			(xy 93.180408 -386.0927) (xy 93.196156 -386.1181) (xy 93.200864 -386.125164) (xy 93.213964 -386.135942)
			(xy 93.22181 -386.139182) (xy 93.245154 -386.148421) (xy 93.288998 -386.172873) (xy 93.328643 -386.203671)
			(xy 93.363178 -386.240106) (xy 93.39181 -386.281341) (xy 93.413882 -386.32643) (xy 93.428887 -386.374337)
			(xy 93.436479 -386.423961) (xy 93.436948 -386.449062) (xy 93.436531 -386.473264) (xy 93.429457 -386.52115)
			(xy 93.415468 -386.56749) (xy 93.394865 -386.611291) (xy 93.38183 -386.631688) (xy 93.377039 -386.639643)
			(xy 93.373008 -386.657756) (xy 93.373956 -386.666994) (xy 93.378274 -386.697982) (xy 93.379964 -386.707276)
			(xy 93.38924 -386.723718) (xy 93.396308 -386.729986) (xy 93.418384 -386.748682) (xy 93.458159 -386.79069)
			(xy 93.492323 -386.837375) (xy 93.520333 -386.887992) (xy 93.541742 -386.941735) (xy 93.556209 -386.997748)
			(xy 93.563503 -387.055137) (xy 93.563948 -387.084062) (xy 93.563358 -387.117383) (xy 93.553695 -387.183322)
			(xy 93.534569 -387.247161) (xy 93.521022 -387.27761) (xy 93.51676 -387.288071) (xy 93.516873 -387.310635)
			(xy 93.526616 -387.330988) (xy 93.534992 -387.33857) (xy 93.557221 -387.357265) (xy 93.597285 -387.399316)
			(xy 93.631708 -387.446099) (xy 93.659935 -387.49686) (xy 93.681513 -387.550785) (xy 93.696096 -387.607006)
			(xy 93.703449 -387.664621) (xy 93.703902 -387.693662) (xy 93.703443 -387.722668) (xy 93.696131 -387.780216)
			(xy 93.681608 -387.83638) (xy 93.660105 -387.890259) (xy 93.631967 -387.940989) (xy 93.597646 -387.987758)
			(xy 93.557691 -388.029816) (xy 93.5355 -388.0485) (xy 93.528388 -388.054088) (xy 93.519244 -388.069328)
			(xy 93.504004 -388.152132) (xy 93.506798 -388.169404) (xy 93.51137 -388.177532) (xy 93.523939 -388.200722)
			(xy 93.541817 -388.250341) (xy 93.55092 -388.302292) (xy 93.551502 -388.328662) (xy 93.551398 -388.339943)
			(xy 93.549747 -388.362445) (xy 93.5482 -388.37362) (xy 93.54693 -388.38251) (xy 93.550486 -388.400036)
			(xy 93.59392 -388.470902) (xy 93.607636 -388.482078) (xy 93.616272 -388.484872) (xy 93.63852 -388.4928)
			(xy 93.680441 -388.514553) (xy 93.718514 -388.542499) (xy 93.751831 -388.575973) (xy 93.779599 -388.614176)
			(xy 93.79077 -388.634986) (xy 93.791278 -388.636002) (xy 94.183708 -389.314944) (xy 94.196441 -389.33831)
			(xy 94.214556 -389.388337) (xy 94.223766 -389.440741) (xy 94.224348 -389.467344) (xy 94.223878 -389.491334)
			(xy 94.216367 -389.538724) (xy 94.201536 -389.584355) (xy 94.17975 -389.627105) (xy 94.151546 -389.665922)
			(xy 94.117618 -389.699849) (xy 94.078802 -389.728052) (xy 94.036051 -389.749837) (xy 93.99042 -389.764668)
			(xy 93.94303 -389.772178) (xy 93.91904 -389.772652) (xy 93.895508 -389.772217) (xy 93.848999 -389.765007)
			(xy 93.804151 -389.750738) (xy 93.762027 -389.729747) (xy 93.723629 -389.702534) (xy 93.689867 -389.669744)
			(xy 93.661545 -389.632156) (xy 93.650054 -389.611616) (xy 93.6498 -389.611108) (xy 93.649292 -389.610346)
			(xy 93.251528 -388.922006) (xy 93.239615 -388.899337) (xy 93.222676 -388.851012) (xy 93.214016 -388.800542)
			(xy 93.213428 -388.77494) (xy 93.213428 -388.774432) (xy 93.213585 -388.763083) (xy 93.215362 -388.740453)
			(xy 93.216984 -388.72922) (xy 93.218254 -388.72033) (xy 93.214698 -388.703058) (xy 93.171264 -388.631938)
			(xy 93.157294 -388.621016) (xy 93.148912 -388.617968) (xy 93.126503 -388.609953) (xy 93.084286 -388.58799)
			(xy 93.04599 -388.559738) (xy 93.012545 -388.525884) (xy 92.984762 -388.487247) (xy 92.963314 -388.444766)
			(xy 92.948722 -388.399469) (xy 92.941339 -388.352456) (xy 92.940886 -388.328662) (xy 92.941454 -388.302289)
			(xy 92.950536 -388.250331) (xy 92.968424 -388.20071) (xy 92.981018 -388.177532) (xy 92.98559 -388.169404)
			(xy 92.988384 -388.152132) (xy 92.973144 -388.069328) (xy 92.964 -388.054088) (xy 92.956888 -388.0485)
			(xy 92.934715 -388.029797) (xy 92.894768 -387.987735) (xy 92.860451 -387.940966) (xy 92.832313 -387.890239)
			(xy 92.810804 -387.836366) (xy 92.796267 -387.780209) (xy 92.788937 -387.722666) (xy 92.788486 -387.693662)
			(xy 92.789082 -387.660341) (xy 92.798741 -387.594402) (xy 92.817865 -387.530563) (xy 92.831412 -387.500114)
			(xy 92.835641 -387.489643) (xy 92.835536 -387.467088) (xy 92.825809 -387.446739) (xy 92.817442 -387.439154)
			(xy 92.795184 -387.420493) (xy 92.755119 -387.378436) (xy 92.720699 -387.331648) (xy 92.692475 -387.280881)
			(xy 92.670901 -387.226951) (xy 92.656325 -387.170724) (xy 92.64898 -387.113105) (xy 92.648532 -387.084062)
			(xy 92.648991 -387.055136) (xy 92.656274 -386.997744) (xy 92.670732 -386.941728) (xy 92.692135 -386.887981)
			(xy 92.720141 -386.837359) (xy 92.754303 -386.790671) (xy 92.794077 -386.74866) (xy 92.816172 -386.729986)
			(xy 92.823146 -386.723641) (xy 92.832402 -386.707235) (xy 92.834206 -386.697982) (xy 92.838524 -386.666994)
			(xy 92.839432 -386.657757) (xy 92.835405 -386.639657) (xy 92.83065 -386.631688) (xy 92.814338 -386.605845)
			(xy 92.790437 -386.549608) (xy 92.783152 -386.519928) (xy 92.781079 -386.51177) (xy 92.772387 -386.497368)
			(xy 92.766134 -386.491734) (xy 92.74302 -386.472684) (xy 92.736188 -386.467481) (xy 92.720097 -386.461509)
			(xy 92.711524 -386.461) (xy 92.681886 -386.460025) (xy 92.62322 -386.451372) (xy 92.566162 -386.435216)
			(xy 92.511668 -386.41183) (xy 92.460649 -386.381603) (xy 92.41396 -386.345043) (xy 92.372381 -386.302761)
			(xy 92.336609 -386.255464) (xy 92.307243 -386.203945) (xy 92.284774 -386.149066) (xy 92.269579 -386.091745)
			(xy 92.261911 -386.032942) (xy 92.261436 -386.003292) (xy 92.261957 -385.972229) (xy 92.270373 -385.910675)
			(xy 92.2782 -385.88061) (xy 92.280994 -385.87045) (xy 92.278454 -385.850638) (xy 92.230956 -385.768342)
			(xy 92.214954 -385.75615) (xy 92.204794 -385.75361) (xy 92.175686 -385.745605) (xy 92.119717 -385.722974)
			(xy 92.06721 -385.693183) (xy 92.019075 -385.656747) (xy 91.976147 -385.614299) (xy 91.939173 -385.566576)
			(xy 91.908792 -385.514407) (xy 91.885534 -385.458696) (xy 91.869802 -385.400412) (xy 91.861868 -385.340565)
			(xy 91.861386 -385.31038) (xy 91.861914 -385.279492) (xy 91.870219 -385.218277) (xy 91.886675 -385.158733)
			(xy 91.910984 -385.101941) (xy 91.92641 -385.075176) (xy 91.932252 -385.06527) (xy 91.934538 -385.042918)
			(xy 91.901264 -384.947668) (xy 91.885516 -384.931666) (xy 91.874848 -384.927602) (xy 91.851456 -384.918444)
			(xy 91.80756 -384.894019) (xy 91.767866 -384.863233) (xy 91.733286 -384.826796) (xy 91.704619 -384.785546)
			(xy 91.682523 -384.740433) (xy 91.667507 -384.692496) (xy 91.659918 -384.642839) (xy 91.659456 -384.617722)
			(xy 91.120976 -384.617722) (xy 91.120445 -384.644824) (xy 91.111636 -384.698307) (xy 91.10345 -384.724148)
			(xy 91.09964 -384.73507) (xy 91.10218 -384.757422) (xy 91.154758 -384.843528) (xy 91.173554 -384.85572)
			(xy 91.184984 -384.857498) (xy 91.214278 -384.862274) (xy 91.271413 -384.878352) (xy 91.325989 -384.901682)
			(xy 91.377092 -384.931872) (xy 91.423862 -384.968414) (xy 91.465516 -385.010697) (xy 91.501354 -385.05801)
			(xy 91.530774 -385.109559) (xy 91.553283 -385.164479) (xy 91.568504 -385.221848) (xy 91.57618 -385.280703)
			(xy 91.576652 -385.31038) (xy 91.576125 -385.341443) (xy 91.567713 -385.402996) (xy 91.559888 -385.433062)
			(xy 91.557094 -385.443222) (xy 91.559634 -385.463034) (xy 91.607132 -385.54533) (xy 91.623134 -385.557522)
			(xy 91.633294 -385.560062) (xy 91.662411 -385.568034) (xy 91.718377 -385.590673) (xy 91.770882 -385.620472)
			(xy 91.819014 -385.656913) (xy 91.861939 -385.699365) (xy 91.898912 -385.747091) (xy 91.929291 -385.799262)
			(xy 91.952549 -385.854974) (xy 91.968283 -385.913259) (xy 91.976219 -385.973106) (xy 91.976702 -386.003292)
			(xy 91.976577 -386.017427) (xy 91.974795 -386.045641) (xy 91.973146 -386.05968) (xy 91.972387 -386.068287)
			(xy 91.976026 -386.085167) (xy 91.980258 -386.0927) (xy 91.996006 -386.1181) (xy 92.000711 -386.125164)
			(xy 92.01382 -386.135931) (xy 92.02166 -386.139182) (xy 92.045048 -386.148349) (xy 92.088943 -386.172773)
			(xy 92.128637 -386.203558) (xy 92.163216 -386.239994) (xy 92.191884 -386.281243) (xy 92.213981 -386.326354)
			(xy 92.228998 -386.37429) (xy 92.236589 -386.423946) (xy 92.237052 -386.449062) (xy 92.236635 -386.473264)
			(xy 92.22956 -386.52115) (xy 92.215572 -386.567489) (xy 92.194969 -386.611291) (xy 92.181934 -386.631688)
			(xy 92.177144 -386.639643) (xy 92.173112 -386.657756) (xy 92.17406 -386.666994) (xy 92.178378 -386.697982)
			(xy 92.180067 -386.707276) (xy 92.189343 -386.723718) (xy 92.196412 -386.729986) (xy 92.218489 -386.748681)
			(xy 92.258263 -386.790689) (xy 92.292428 -386.837374) (xy 92.320437 -386.887992) (xy 92.341846 -386.941735)
			(xy 92.356313 -386.997748) (xy 92.363607 -387.055137) (xy 92.364052 -387.084062) (xy 92.363461 -387.117383)
			(xy 92.353799 -387.183322) (xy 92.334673 -387.247161) (xy 92.321126 -387.27761) (xy 92.316862 -387.288071)
			(xy 92.316976 -387.310635) (xy 92.32672 -387.330988) (xy 92.335096 -387.33857) (xy 92.357325 -387.357264)
			(xy 92.39739 -387.399316) (xy 92.431812 -387.446098) (xy 92.460039 -387.49686) (xy 92.481618 -387.550785)
			(xy 92.4962 -387.607006) (xy 92.503553 -387.664621) (xy 92.504006 -387.693662) (xy 92.503546 -387.722668)
			(xy 92.496234 -387.780216) (xy 92.481711 -387.83638) (xy 92.460208 -387.890259) (xy 92.432071 -387.940989)
			(xy 92.39775 -387.987758) (xy 92.357795 -388.029817) (xy 92.335604 -388.0485) (xy 92.328492 -388.054088)
			(xy 92.319348 -388.069328) (xy 92.304108 -388.152132) (xy 92.306902 -388.169404) (xy 92.311474 -388.177532)
			(xy 92.324044 -388.200721) (xy 92.341921 -388.250341) (xy 92.351024 -388.302292) (xy 92.351606 -388.328662)
			(xy 92.351502 -388.339943) (xy 92.349851 -388.362445) (xy 92.348304 -388.37362) (xy 92.347034 -388.38251)
			(xy 92.35059 -388.400036) (xy 92.394024 -388.470902) (xy 92.40774 -388.482078) (xy 92.416376 -388.484872)
			(xy 92.438625 -388.492798) (xy 92.480545 -388.514551) (xy 92.518618 -388.542498) (xy 92.551936 -388.575972)
			(xy 92.579704 -388.614176) (xy 92.590874 -388.634986) (xy 92.591382 -388.636002) (xy 92.983812 -389.314944)
			(xy 92.996545 -389.338309) (xy 93.01466 -389.388337) (xy 93.02387 -389.440741) (xy 93.024452 -389.467344)
			(xy 93.023978 -389.491334) (xy 93.016467 -389.538723) (xy 93.001636 -389.584354) (xy 92.979851 -389.627104)
			(xy 92.951648 -389.66592) (xy 92.91772 -389.699848) (xy 92.878904 -389.728051) (xy 92.836154 -389.749836)
			(xy 92.790523 -389.764667) (xy 92.743134 -389.772178) (xy 92.719144 -389.772652) (xy 92.695612 -389.772214)
			(xy 92.649104 -389.765005) (xy 92.604255 -389.750736) (xy 92.562132 -389.729746) (xy 92.523733 -389.702533)
			(xy 92.489972 -389.669743) (xy 92.461649 -389.632156) (xy 92.450158 -389.611616) (xy 92.449904 -389.611108)
			(xy 92.449396 -389.610346) (xy 92.051632 -388.922006) (xy 92.039719 -388.899336) (xy 92.02278 -388.851012)
			(xy 92.01412 -388.800542) (xy 92.013532 -388.77494) (xy 92.013532 -388.774432) (xy 92.013689 -388.763083)
			(xy 92.015466 -388.740453) (xy 92.017088 -388.72922) (xy 92.018358 -388.72033) (xy 92.014802 -388.703058)
			(xy 91.971368 -388.631938) (xy 91.957398 -388.621016) (xy 91.949016 -388.617968) (xy 91.926608 -388.60995)
			(xy 91.884391 -388.587988) (xy 91.846095 -388.559737) (xy 91.81265 -388.525883) (xy 91.784866 -388.487246)
			(xy 91.763418 -388.444765) (xy 91.748826 -388.399469) (xy 91.741443 -388.352456) (xy 91.74099 -388.328662)
			(xy 91.741557 -388.302289) (xy 91.75064 -388.250331) (xy 91.768528 -388.20071) (xy 91.781122 -388.177532)
			(xy 91.785694 -388.169404) (xy 91.788488 -388.152132) (xy 91.773248 -388.069328) (xy 91.764104 -388.054088)
			(xy 91.756992 -388.0485) (xy 91.73482 -388.029796) (xy 91.694873 -387.987734) (xy 91.660556 -387.940966)
			(xy 91.632417 -387.890239) (xy 91.610908 -387.836366) (xy 91.596371 -387.780209) (xy 91.589041 -387.722666)
			(xy 91.58859 -387.693662) (xy 91.589185 -387.660341) (xy 91.598845 -387.594402) (xy 91.617969 -387.530563)
			(xy 91.631516 -387.500114) (xy 91.635743 -387.489642) (xy 91.635638 -387.467088) (xy 91.625912 -387.446739)
			(xy 91.617546 -387.439154) (xy 91.595289 -387.420492) (xy 91.555224 -387.378436) (xy 91.520803 -387.331648)
			(xy 91.492579 -387.280881) (xy 91.471005 -387.22695) (xy 91.456429 -387.170724) (xy 91.449084 -387.113105)
			(xy 91.448636 -387.084062) (xy 91.449093 -387.055136) (xy 91.456377 -386.997744) (xy 91.470835 -386.941728)
			(xy 91.492238 -386.88798) (xy 91.520244 -386.837359) (xy 91.554407 -386.790671) (xy 91.594181 -386.74866)
			(xy 91.616276 -386.729986) (xy 91.62325 -386.723641) (xy 91.632506 -386.707235) (xy 91.63431 -386.697982)
			(xy 91.638628 -386.666994) (xy 91.639535 -386.657757) (xy 91.635509 -386.639657) (xy 91.630754 -386.631688)
			(xy 91.614442 -386.605845) (xy 91.590541 -386.549608) (xy 91.583256 -386.519928) (xy 91.581182 -386.511771)
			(xy 91.572491 -386.497368) (xy 91.566238 -386.491734) (xy 91.543124 -386.472684) (xy 91.536232 -386.467455)
			(xy 91.520011 -386.461479) (xy 91.511374 -386.461) (xy 91.481738 -386.45998) (xy 91.423073 -386.451332)
			(xy 91.366016 -386.435183) (xy 91.311522 -386.411801) (xy 91.260503 -386.38158) (xy 91.213813 -386.345024)
			(xy 91.172234 -386.302745) (xy 91.136461 -386.255452) (xy 91.107095 -386.203936) (xy 91.084625 -386.14906)
			(xy 91.069429 -386.091742) (xy 91.061761 -386.032941) (xy 91.061286 -386.003292) (xy 91.061806 -385.972229)
			(xy 91.070222 -385.910675) (xy 91.07805 -385.88061) (xy 91.080844 -385.87045) (xy 91.078304 -385.850638)
			(xy 91.030806 -385.768342) (xy 91.014804 -385.75615) (xy 91.004644 -385.75361) (xy 90.975526 -385.745639)
			(xy 90.919558 -385.723002) (xy 90.867052 -385.693205) (xy 90.818918 -385.656764) (xy 90.775992 -385.614312)
			(xy 90.739018 -385.566586) (xy 90.70864 -385.514414) (xy 90.685383 -385.458701) (xy 90.669651 -385.400415)
			(xy 90.661717 -385.340566) (xy 90.661236 -385.31038) (xy 90.66171 -385.279458) (xy 90.669992 -385.218171)
			(xy 90.686457 -385.158559) (xy 90.710805 -385.10171) (xy 90.72626 -385.074922) (xy 90.732356 -385.06527)
			(xy 90.734642 -385.042918) (xy 90.701114 -384.947668) (xy 90.685366 -384.931666) (xy 90.674698 -384.927602)
			(xy 90.65135 -384.918372) (xy 90.607505 -384.893919) (xy 90.56786 -384.863121) (xy 90.533325 -384.826685)
			(xy 90.504692 -384.785448) (xy 90.482621 -384.740357) (xy 90.467618 -384.692449) (xy 90.460028 -384.642823)
			(xy 90.45956 -384.617722) (xy 89.920826 -384.617722) (xy 89.920297 -384.644824) (xy 89.911487 -384.698307)
			(xy 89.9033 -384.724148) (xy 89.89949 -384.73507) (xy 89.90203 -384.757422) (xy 89.954608 -384.843274)
			(xy 89.973658 -384.85572) (xy 89.984834 -384.857498) (xy 90.014153 -384.862203) (xy 90.071323 -384.878252)
			(xy 90.125937 -384.901562) (xy 90.177077 -384.931741) (xy 90.223882 -384.968283) (xy 90.265567 -385.010572)
			(xy 90.301431 -385.057899) (xy 90.330871 -385.109467) (xy 90.353393 -385.164411) (xy 90.368617 -385.221807)
			(xy 90.376289 -385.28069) (xy 90.376756 -385.31038) (xy 90.376229 -385.341443) (xy 90.367818 -385.402997)
			(xy 90.359992 -385.433062) (xy 90.357198 -385.443222) (xy 90.359738 -385.463034) (xy 90.407236 -385.54533)
			(xy 90.423238 -385.557522) (xy 90.433398 -385.560062) (xy 90.462516 -385.568031) (xy 90.518482 -385.590671)
			(xy 90.570987 -385.62047) (xy 90.619119 -385.656912) (xy 90.662044 -385.699364) (xy 90.699016 -385.74709)
			(xy 90.729395 -385.799261) (xy 90.752653 -385.854973) (xy 90.768387 -385.913259) (xy 90.776323 -385.973106)
			(xy 90.776806 -386.003292) (xy 90.776681 -386.017427) (xy 90.774899 -386.045641) (xy 90.77325 -386.05968)
			(xy 90.77249 -386.068287) (xy 90.77613 -386.085167) (xy 90.780362 -386.0927) (xy 90.79611 -386.1181)
			(xy 90.800833 -386.125152) (xy 90.813923 -386.135937) (xy 90.821764 -386.139182) (xy 90.84512 -386.148392)
			(xy 90.888962 -386.172851) (xy 90.928605 -386.203654) (xy 90.963138 -386.240094) (xy 90.991768 -386.281333)
			(xy 91.013838 -386.326425) (xy 91.028842 -386.374334) (xy 91.036433 -386.42396) (xy 91.036902 -386.449062)
			(xy 91.036476 -386.473264) (xy 91.029403 -386.521149) (xy 91.015417 -386.567488) (xy 90.994817 -386.61129)
			(xy 90.981784 -386.631688) (xy 90.976997 -386.639645) (xy 90.972962 -386.657756) (xy 90.97391 -386.666994)
			(xy 90.978228 -386.697982) (xy 90.979901 -386.70728) (xy 90.989188 -386.723722) (xy 90.996262 -386.729986)
			(xy 91.01835 -386.748668) (xy 91.058122 -386.79068) (xy 91.092284 -386.837368) (xy 91.120291 -386.887988)
			(xy 91.141699 -386.941733) (xy 91.156164 -386.997746) (xy 91.163457 -387.055136) (xy 91.163902 -387.084062)
			(xy 91.163316 -387.117384) (xy 91.153652 -387.183322) (xy 91.134525 -387.247161) (xy 91.120976 -387.27761)
			(xy 91.116729 -387.288075) (xy 91.116843 -387.310634) (xy 91.126576 -387.330985) (xy 91.134946 -387.33857)
			(xy 91.157165 -387.357276) (xy 91.197232 -387.399324) (xy 91.231657 -387.446104) (xy 91.259886 -387.496864)
			(xy 91.281466 -387.550787) (xy 91.29605 -387.607008) (xy 91.303403 -387.664621) (xy 91.303856 -387.693662)
			(xy 91.303378 -387.722667) (xy 91.296067 -387.780214) (xy 91.281545 -387.836376) (xy 91.260045 -387.890255)
			(xy 91.231911 -387.940985) (xy 91.197594 -387.987755) (xy 91.157643 -388.029815) (xy 91.135454 -388.0485)
			(xy 91.128342 -388.054088) (xy 91.119198 -388.069328) (xy 91.103958 -388.152132) (xy 91.106752 -388.169404)
			(xy 91.111324 -388.177532) (xy 91.123898 -388.200719) (xy 91.141773 -388.25034) (xy 91.150874 -388.302291)
			(xy 91.151456 -388.328662) (xy 91.151353 -388.339943) (xy 91.149701 -388.362445) (xy 91.148154 -388.37362)
			(xy 91.146884 -388.38251) (xy 91.15044 -388.400036) (xy 91.193874 -388.470902) (xy 91.20759 -388.482078)
			(xy 91.216226 -388.484872) (xy 91.238466 -388.492821) (xy 91.280388 -388.514568) (xy 91.318463 -388.542509)
			(xy 91.351782 -388.575978) (xy 91.379552 -388.614178) (xy 91.390724 -388.634986) (xy 91.391232 -388.636002)
			(xy 91.783662 -389.314944) (xy 91.79647 -389.338285) (xy 91.814696 -389.388304) (xy 91.823963 -389.440726)
			(xy 91.824556 -389.467344) (xy 91.824102 -389.491349) (xy 91.816582 -389.538765) (xy 91.801735 -389.584421)
			(xy 91.779926 -389.627191) (xy 91.751693 -389.666022) (xy 91.717731 -389.699956) (xy 91.678878 -389.728157)
			(xy 91.63609 -389.749931) (xy 91.590422 -389.76474) (xy 91.542999 -389.772221) (xy 91.518994 -389.772652)
			(xy 91.495463 -389.772173) (xy 91.448957 -389.764972) (xy 91.404109 -389.75071) (xy 91.361986 -389.729727)
			(xy 91.323587 -389.70252) (xy 91.289824 -389.669736) (xy 91.261499 -389.632154) (xy 91.250008 -389.611616)
			(xy 91.249754 -389.611108) (xy 91.249246 -389.610346) (xy 90.851482 -388.922006) (xy 90.839608 -388.899328)
			(xy 90.822756 -388.850996) (xy 90.814182 -388.800533) (xy 90.813636 -388.77494) (xy 90.813636 -388.774432)
			(xy 90.813727 -388.763087) (xy 90.815382 -388.740458) (xy 90.816938 -388.72922) (xy 90.818208 -388.72033)
			(xy 90.814652 -388.703058) (xy 90.771218 -388.631938) (xy 90.757248 -388.621016) (xy 90.748866 -388.617968)
			(xy 90.726469 -388.609922) (xy 90.68425 -388.587966) (xy 90.645952 -388.55972) (xy 90.612505 -388.525871)
			(xy 90.58472 -388.487238) (xy 90.56327 -388.44476) (xy 90.548677 -388.399466) (xy 90.541293 -388.352455)
			(xy 90.54084 -388.328662) (xy 90.541401 -388.302289) (xy 90.550485 -388.25033) (xy 90.568376 -388.20071)
			(xy 90.580972 -388.177532) (xy 90.585544 -388.169404) (xy 90.588338 -388.152132) (xy 90.573098 -388.069328)
			(xy 90.563954 -388.054088) (xy 90.556842 -388.0485) (xy 90.53468 -388.029784) (xy 90.494731 -387.987725)
			(xy 90.460411 -387.94096) (xy 90.432271 -387.890235) (xy 90.41076 -387.836364) (xy 90.396222 -387.780208)
			(xy 90.388891 -387.722666) (xy 90.38844 -387.693662) (xy 90.38904 -387.660341) (xy 90.398699 -387.594403)
			(xy 90.417821 -387.530563) (xy 90.431366 -387.500114) (xy 90.43561 -387.489646) (xy 90.435505 -387.467087)
			(xy 90.425769 -387.446736) (xy 90.417396 -387.439154) (xy 90.395128 -387.420504) (xy 90.355066 -387.378444)
			(xy 90.320648 -387.331654) (xy 90.292426 -387.280885) (xy 90.270853 -387.226953) (xy 90.256278 -387.170725)
			(xy 90.248934 -387.113105) (xy 90.248486 -387.084062) (xy 90.248925 -387.055135) (xy 90.256209 -386.997742)
			(xy 90.270669 -386.941724) (xy 90.292075 -386.887976) (xy 90.320084 -386.837355) (xy 90.35425 -386.790667)
			(xy 90.394029 -386.748659) (xy 90.416126 -386.729986) (xy 90.423092 -386.723633) (xy 90.432354 -386.707234)
			(xy 90.43416 -386.697982) (xy 90.438478 -386.666994) (xy 90.439377 -386.657757) (xy 90.435355 -386.639658)
			(xy 90.430604 -386.631688) (xy 90.414296 -386.605842) (xy 90.390392 -386.549607) (xy 90.383106 -386.519928)
			(xy 90.381045 -386.511766) (xy 90.372345 -386.497365) (xy 90.366088 -386.491734) (xy 90.342974 -386.472684)
			(xy 90.336154 -386.467463) (xy 90.320054 -386.461502) (xy 90.311478 -386.461) (xy 90.281842 -386.459976)
			(xy 90.223178 -386.451329) (xy 90.166121 -386.43518) (xy 90.111627 -386.411799) (xy 90.060607 -386.381578)
			(xy 90.013917 -386.345022) (xy 89.972338 -386.302744) (xy 89.936566 -386.255451) (xy 89.907199 -386.203936)
			(xy 89.884729 -386.149059) (xy 89.869533 -386.091741) (xy 89.861865 -386.032941) (xy 89.86139 -386.003292)
			(xy 89.86191 -385.972229) (xy 89.870326 -385.910675) (xy 89.878154 -385.88061) (xy 89.880948 -385.87045)
			(xy 89.878408 -385.850638) (xy 89.83091 -385.768342) (xy 89.814908 -385.75615) (xy 89.804748 -385.75361)
			(xy 89.775631 -385.745636) (xy 89.719663 -385.723) (xy 89.667156 -385.693203) (xy 89.619022 -385.656763)
			(xy 89.576096 -385.614311) (xy 89.539123 -385.566585) (xy 89.508744 -385.514414) (xy 89.485487 -385.458701)
			(xy 89.469755 -385.400415) (xy 89.461821 -385.340566) (xy 89.46134 -385.31038) (xy 89.46186 -385.279492)
			(xy 89.470166 -385.218276) (xy 89.486624 -385.158732) (xy 89.510936 -385.10194) (xy 89.526364 -385.075176)
			(xy 89.532206 -385.06527) (xy 89.534492 -385.042918) (xy 89.501218 -384.947668) (xy 89.48547 -384.931666)
			(xy 89.474802 -384.927602) (xy 89.451422 -384.918415) (xy 89.407525 -384.893997) (xy 89.367828 -384.863217)
			(xy 89.333246 -384.826784) (xy 89.304576 -384.785538) (xy 89.282479 -384.740428) (xy 89.267462 -384.692493)
			(xy 89.259872 -384.642838) (xy 89.25941 -384.617722) (xy 88.72093 -384.617722) (xy 88.720401 -384.644824)
			(xy 88.711591 -384.698307) (xy 88.703404 -384.724148) (xy 88.699594 -384.73507) (xy 88.702134 -384.757422)
			(xy 88.754712 -384.843274) (xy 88.773762 -384.85572) (xy 88.784938 -384.857498) (xy 88.814257 -384.8622)
			(xy 88.871428 -384.878249) (xy 88.926042 -384.90156) (xy 88.977181 -384.931739) (xy 89.023987 -384.968281)
			(xy 89.065672 -385.010571) (xy 89.101535 -385.057898) (xy 89.130976 -385.109467) (xy 89.153497 -385.164411)
			(xy 89.168721 -385.221807) (xy 89.176393 -385.28069) (xy 89.17686 -385.31038) (xy 89.176337 -385.341506)
			(xy 89.167931 -385.403188) (xy 89.160096 -385.433316) (xy 89.157302 -385.443476) (xy 89.159842 -385.463542)
			(xy 89.207086 -385.54533) (xy 89.223088 -385.557522) (xy 89.233248 -385.560062) (xy 89.262357 -385.568064)
			(xy 89.318323 -385.590698) (xy 89.370829 -385.620492) (xy 89.418962 -385.656929) (xy 89.461889 -385.699377)
			(xy 89.498863 -385.7471) (xy 89.529243 -385.799269) (xy 89.552502 -385.854978) (xy 89.568236 -385.913261)
			(xy 89.576173 -385.973107) (xy 89.576656 -386.003292) (xy 89.576531 -386.017427) (xy 89.574749 -386.045641)
			(xy 89.5731 -386.05968) (xy 89.572333 -386.068287) (xy 89.575976 -386.085168) (xy 89.580212 -386.0927)
			(xy 89.59596 -386.1181) (xy 89.600679 -386.125153) (xy 89.613778 -386.135926) (xy 89.621614 -386.139182)
			(xy 89.644992 -386.148374) (xy 89.688888 -386.172792) (xy 89.728584 -386.203572) (xy 89.763165 -386.240005)
			(xy 89.791835 -386.28125) (xy 89.813933 -386.326359) (xy 89.828951 -386.374292) (xy 89.836543 -386.423946)
			(xy 89.837006 -386.449062) (xy 89.83658 -386.473264) (xy 89.829506 -386.521149) (xy 89.81552 -386.567488)
			(xy 89.794921 -386.61129) (xy 89.781888 -386.631688) (xy 89.777101 -386.639645) (xy 89.773066 -386.657756)
			(xy 89.774014 -386.666994) (xy 89.778332 -386.697982) (xy 89.780004 -386.707281) (xy 89.789291 -386.723722)
			(xy 89.796366 -386.729986) (xy 89.818455 -386.748667) (xy 89.858226 -386.790679) (xy 89.892388 -386.837367)
			(xy 89.920396 -386.887987) (xy 89.941803 -386.941732) (xy 89.956268 -386.997746) (xy 89.963561 -387.055136)
			(xy 89.964006 -387.084062) (xy 89.963419 -387.117384) (xy 89.953756 -387.183322) (xy 89.934629 -387.247161)
			(xy 89.92108 -387.27761) (xy 89.916831 -387.288075) (xy 89.916945 -387.310634) (xy 89.92668 -387.330985)
			(xy 89.93505 -387.33857) (xy 89.95727 -387.357275) (xy 89.997337 -387.399324) (xy 90.031761 -387.446104)
			(xy 90.05999 -387.496864) (xy 90.08157 -387.550787) (xy 90.096154 -387.607008) (xy 90.103507 -387.664621)
			(xy 90.10396 -387.693662) (xy 90.10348 -387.722667) (xy 90.09617 -387.780214) (xy 90.081648 -387.836376)
			(xy 90.060148 -387.890254) (xy 90.032014 -387.940985) (xy 89.997697 -387.987755) (xy 89.957747 -388.029815)
			(xy 89.935558 -388.0485) (xy 89.928446 -388.054088) (xy 89.919302 -388.069328) (xy 89.904062 -388.152132)
			(xy 89.906856 -388.169404) (xy 89.911428 -388.177532) (xy 89.924002 -388.200719) (xy 89.941877 -388.25034)
			(xy 89.950978 -388.302291) (xy 89.95156 -388.328662) (xy 89.951457 -388.339943) (xy 89.949805 -388.362445)
			(xy 89.948258 -388.37362) (xy 89.946988 -388.38251) (xy 89.950544 -388.400036) (xy 89.993978 -388.470902)
			(xy 90.007694 -388.482078) (xy 90.01633 -388.484872) (xy 90.038571 -388.492819) (xy 90.080493 -388.514567)
			(xy 90.118567 -388.542508) (xy 90.151886 -388.575978) (xy 90.179656 -388.614178) (xy 90.190828 -388.634986)
			(xy 90.191336 -388.636002) (xy 90.583766 -389.314944) (xy 90.596575 -389.338285) (xy 90.6148 -389.388303)
			(xy 90.624067 -389.440726) (xy 90.62466 -389.467344) (xy 90.624301 -389.491353) (xy 90.616779 -389.53878)
			(xy 90.601926 -389.584444) (xy 90.580109 -389.62722) (xy 90.551865 -389.666055) (xy 90.517891 -389.69999)
			(xy 90.479025 -389.72819) (xy 90.436223 -389.749958) (xy 90.390542 -389.764759) (xy 90.343108 -389.772228)
			(xy 90.319098 -389.772652) (xy 90.295567 -389.77217) (xy 90.249061 -389.764969) (xy 90.204214 -389.750708)
			(xy 90.16209 -389.729725) (xy 90.123691 -389.702519) (xy 90.089928 -389.669736) (xy 90.061604 -389.632154)
			(xy 90.050112 -389.611616) (xy 90.049858 -389.611108) (xy 90.04935 -389.610346) (xy 89.651586 -388.922006)
			(xy 89.639712 -388.899328) (xy 89.62286 -388.850996) (xy 89.614286 -388.800533) (xy 89.61374 -388.77494)
			(xy 89.61374 -388.774432) (xy 89.613831 -388.763087) (xy 89.615486 -388.740458) (xy 89.617042 -388.72922)
			(xy 89.618312 -388.72033) (xy 89.614756 -388.703058) (xy 89.571322 -388.631938) (xy 89.557352 -388.621016)
			(xy 89.54897 -388.617968) (xy 89.526574 -388.609919) (xy 89.484355 -388.587964) (xy 89.446057 -388.559719)
			(xy 89.41261 -388.52587) (xy 89.384824 -388.487238) (xy 89.363374 -388.444759) (xy 89.348781 -388.399466)
			(xy 89.341397 -388.352455) (xy 89.340944 -388.328662) (xy 89.341504 -388.302289) (xy 89.350588 -388.25033)
			(xy 89.36848 -388.20071) (xy 89.381076 -388.177532) (xy 89.385648 -388.169404) (xy 89.388442 -388.152132)
			(xy 89.373202 -388.069328) (xy 89.364058 -388.054088) (xy 89.356946 -388.0485) (xy 89.334764 -388.029807)
			(xy 89.29482 -387.987742) (xy 89.260505 -387.940971) (xy 89.232368 -387.890243) (xy 89.21086 -387.836369)
			(xy 89.196325 -387.78021) (xy 89.188994 -387.722666) (xy 89.188544 -387.693662) (xy 89.189144 -387.660341)
			(xy 89.198802 -387.594403) (xy 89.217924 -387.530563) (xy 89.23147 -387.500114) (xy 89.235712 -387.489646)
			(xy 89.235608 -387.467087) (xy 89.225873 -387.446736) (xy 89.2175 -387.439154) (xy 89.195233 -387.420503)
			(xy 89.155171 -387.378444) (xy 89.120752 -387.331653) (xy 89.09253 -387.280884) (xy 89.070958 -387.226953)
			(xy 89.056382 -387.170725) (xy 89.049038 -387.113105) (xy 89.04859 -387.084062) (xy 89.049028 -387.055135)
			(xy 89.056312 -386.997742) (xy 89.070772 -386.941724) (xy 89.092178 -386.887976) (xy 89.120187 -386.837355)
			(xy 89.154354 -386.790667) (xy 89.194133 -386.748659) (xy 89.21623 -386.729986) (xy 89.223197 -386.723634)
			(xy 89.232458 -386.707234) (xy 89.234264 -386.697982) (xy 89.238582 -386.666994) (xy 89.239481 -386.657757)
			(xy 89.235459 -386.639658) (xy 89.230708 -386.631688) (xy 89.2144 -386.605842) (xy 89.190497 -386.549607)
			(xy 89.18321 -386.519928) (xy 89.181148 -386.511767) (xy 89.172449 -386.497365) (xy 89.166192 -386.491734)
			(xy 89.143078 -386.472684) (xy 89.136199 -386.467437) (xy 89.119968 -386.461472) (xy 89.111328 -386.461)
			(xy 89.08169 -386.460022) (xy 89.023024 -386.451369) (xy 88.965967 -386.435214) (xy 88.911472 -386.411827)
			(xy 88.860453 -386.381601) (xy 88.813764 -386.345041) (xy 88.772185 -386.302759) (xy 88.736413 -386.255463)
			(xy 88.707047 -386.203944) (xy 88.684578 -386.149065) (xy 88.669383 -386.091745) (xy 88.661715 -386.032942)
			(xy 88.66124 -386.003292) (xy 88.661761 -385.972229) (xy 88.670177 -385.910675) (xy 88.678004 -385.88061)
			(xy 88.680798 -385.87045) (xy 88.678258 -385.850638) (xy 88.63076 -385.768342) (xy 88.614758 -385.75615)
			(xy 88.604598 -385.75361) (xy 88.575503 -385.745601) (xy 88.519577 -385.722931) (xy 88.467112 -385.693111)
			(xy 88.419019 -385.656659) (xy 88.376129 -385.614206) (xy 88.339188 -385.566487) (xy 88.308833 -385.51433)
			(xy 88.285592 -385.458638) (xy 88.269867 -385.400376) (xy 88.261931 -385.340553) (xy 88.261444 -385.31038)
			(xy 88.261964 -385.279492) (xy 88.27027 -385.218276) (xy 88.286728 -385.158732) (xy 88.31104 -385.10194)
			(xy 88.326468 -385.075176) (xy 88.33231 -385.06527) (xy 88.334596 -385.042918) (xy 88.301322 -384.947668)
			(xy 88.285574 -384.931666) (xy 88.274906 -384.927602) (xy 88.251527 -384.918413) (xy 88.207629 -384.893995)
			(xy 88.167932 -384.863216) (xy 88.133351 -384.826783) (xy 88.104681 -384.785537) (xy 88.082583 -384.740427)
			(xy 88.067566 -384.692493) (xy 88.059976 -384.642838) (xy 88.059514 -384.617722) (xy 87.52078 -384.617722)
			(xy 87.520248 -384.644824) (xy 87.51144 -384.698307) (xy 87.503254 -384.724148) (xy 87.499444 -384.73507)
			(xy 87.501984 -384.757422) (xy 87.554562 -384.843274) (xy 87.573612 -384.85572) (xy 87.584788 -384.857498)
			(xy 87.6141 -384.862239) (xy 87.671271 -384.878282) (xy 87.725885 -384.901587) (xy 87.777025 -384.931762)
			(xy 87.823831 -384.968299) (xy 87.865518 -385.010585) (xy 87.901383 -385.057909) (xy 87.930824 -385.109475)
			(xy 87.953346 -385.164416) (xy 87.968571 -385.22181) (xy 87.976243 -385.280691) (xy 87.97671 -385.31038)
			(xy 87.976185 -385.341443) (xy 87.967772 -385.402997) (xy 87.959946 -385.433062) (xy 87.957152 -385.443222)
			(xy 87.959692 -385.463034) (xy 88.00719 -385.54533) (xy 88.023192 -385.557522) (xy 88.033352 -385.560062)
			(xy 88.062462 -385.568062) (xy 88.118428 -385.590696) (xy 88.170933 -385.62049) (xy 88.219067 -385.656928)
			(xy 88.261993 -385.699376) (xy 88.298967 -385.747099) (xy 88.329347 -385.799268) (xy 88.352606 -385.854978)
			(xy 88.36834 -385.913261) (xy 88.376277 -385.973107) (xy 88.37676 -386.003292) (xy 88.376635 -386.017427)
			(xy 88.374853 -386.045641) (xy 88.373204 -386.05968) (xy 88.372437 -386.068287) (xy 88.37608 -386.085168)
			(xy 88.380316 -386.0927) (xy 88.396064 -386.1181) (xy 88.400782 -386.125154) (xy 88.413882 -386.135926)
			(xy 88.421718 -386.139182) (xy 88.445097 -386.148372) (xy 88.488993 -386.172791) (xy 88.528689 -386.203571)
			(xy 88.563269 -386.240004) (xy 88.591939 -386.281249) (xy 88.614037 -386.326359) (xy 88.629055 -386.374292)
			(xy 88.636647 -386.423946) (xy 88.63711 -386.449062) (xy 88.636683 -386.473264) (xy 88.62961 -386.521149)
			(xy 88.615624 -386.567488) (xy 88.595025 -386.61129) (xy 88.581992 -386.631688) (xy 88.577205 -386.639646)
			(xy 88.57317 -386.657756) (xy 88.574118 -386.666994) (xy 88.578436 -386.697982) (xy 88.580107 -386.707281)
			(xy 88.589395 -386.723722) (xy 88.59647 -386.729986) (xy 88.61856 -386.748666) (xy 88.658331 -386.790679)
			(xy 88.692493 -386.837367) (xy 88.7205 -386.887987) (xy 88.741907 -386.941732) (xy 88.756372 -386.997746)
			(xy 88.763665 -387.055136) (xy 88.76411 -387.084062) (xy 88.763523 -387.117384) (xy 88.75386 -387.183322)
			(xy 88.734732 -387.247161) (xy 88.721184 -387.27761) (xy 88.716934 -387.288074) (xy 88.717048 -387.310634)
			(xy 88.726783 -387.330986) (xy 88.735154 -387.33857) (xy 88.757375 -387.357274) (xy 88.797441 -387.399323)
			(xy 88.831865 -387.446103) (xy 88.860094 -387.496863) (xy 88.881674 -387.550787) (xy 88.896258 -387.607007)
			(xy 88.903611 -387.664621) (xy 88.904064 -387.693662) (xy 88.903583 -387.722667) (xy 88.896272 -387.780214)
			(xy 88.881751 -387.836376) (xy 88.860251 -387.890254) (xy 88.832117 -387.940984) (xy 88.797801 -387.987755)
			(xy 88.757851 -388.029815) (xy 88.735662 -388.0485) (xy 88.72855 -388.054088) (xy 88.719406 -388.069328)
			(xy 88.704166 -388.152132) (xy 88.70696 -388.169404) (xy 88.711532 -388.177532) (xy 88.724106 -388.200719)
			(xy 88.741981 -388.25034) (xy 88.751082 -388.302291) (xy 88.751664 -388.328662) (xy 88.751561 -388.339943)
			(xy 88.749909 -388.362445) (xy 88.748362 -388.37362) (xy 88.747092 -388.382764) (xy 88.750394 -388.400036)
			(xy 88.794082 -388.471156) (xy 88.807798 -388.482078) (xy 88.816434 -388.484872) (xy 88.844604 -388.495057)
			(xy 88.896547 -388.524877) (xy 88.919558 -388.544054) (xy 88.941038 -388.56364) (xy 88.976854 -388.609415)
			(xy 88.990678 -388.634986) (xy 88.99144 -388.636256) (xy 89.383616 -389.314944) (xy 89.39635 -389.338309)
			(xy 89.414465 -389.388337) (xy 89.423674 -389.440741) (xy 89.424256 -389.467344) (xy 89.423778 -389.491334)
			(xy 89.416267 -389.538723) (xy 89.401436 -389.584353) (xy 89.379652 -389.627103) (xy 89.351449 -389.665919)
			(xy 89.317522 -389.699846) (xy 89.278706 -389.72805) (xy 89.235957 -389.749835) (xy 89.190327 -389.764666)
			(xy 89.142938 -389.772178) (xy 89.118948 -389.772652) (xy 89.095416 -389.772211) (xy 89.048908 -389.765002)
			(xy 89.00406 -389.750734) (xy 88.961936 -389.729744) (xy 88.923537 -389.702532) (xy 88.889776 -389.669743)
			(xy 88.861453 -389.632156) (xy 88.849962 -389.611616) (xy 88.849708 -389.611108) (xy 88.8492 -389.610346)
			(xy 88.45169 -388.921752) (xy 88.441116 -388.901826) (xy 88.425314 -388.859576) (xy 88.415907 -388.815459)
			(xy 88.414098 -388.792974) (xy 88.41359 -388.781798) (xy 88.413336 -388.774432) (xy 88.413493 -388.763083)
			(xy 88.41527 -388.740453) (xy 88.416892 -388.72922) (xy 88.418162 -388.72033) (xy 88.414606 -388.703058)
			(xy 88.371172 -388.631938) (xy 88.357456 -388.620762) (xy 88.34882 -388.617968) (xy 88.326428 -388.609943)
			(xy 88.284256 -388.587947) (xy 88.246006 -388.559675) (xy 88.212604 -388.525813) (xy 88.184859 -388.48718)
			(xy 88.163442 -388.444711) (xy 88.148871 -388.399433) (xy 88.141499 -388.352444) (xy 88.141048 -388.328662)
			(xy 88.141608 -388.302289) (xy 88.150692 -388.25033) (xy 88.168583 -388.20071) (xy 88.18118 -388.177532)
			(xy 88.185752 -388.169404) (xy 88.188546 -388.152132) (xy 88.173306 -388.069328) (xy 88.164162 -388.054088)
			(xy 88.15705 -388.0485) (xy 88.134869 -388.029806) (xy 88.094924 -387.987741) (xy 88.060609 -387.940971)
			(xy 88.032473 -387.890242) (xy 88.010964 -387.836368) (xy 87.996429 -387.78021) (xy 87.989098 -387.722666)
			(xy 87.988648 -387.693662) (xy 87.989247 -387.660341) (xy 87.998906 -387.594403) (xy 88.018028 -387.530563)
			(xy 88.031574 -387.500114) (xy 88.035815 -387.489646) (xy 88.03571 -387.467087) (xy 88.025976 -387.446736)
			(xy 88.017604 -387.439154) (xy 87.995338 -387.420502) (xy 87.955275 -387.378443) (xy 87.920857 -387.331653)
			(xy 87.892634 -387.280884) (xy 87.871062 -387.226952) (xy 87.856486 -387.170725) (xy 87.849142 -387.113105)
			(xy 87.848694 -387.084062) (xy 87.84913 -387.055135) (xy 87.856415 -386.997741) (xy 87.870875 -386.941724)
			(xy 87.892281 -386.887976) (xy 87.92029 -386.837354) (xy 87.954457 -386.790667) (xy 87.994236 -386.748659)
			(xy 88.016334 -386.729986) (xy 88.023301 -386.723634) (xy 88.032562 -386.707234) (xy 88.034368 -386.697982)
			(xy 88.038686 -386.666994) (xy 88.039584 -386.657757) (xy 88.035563 -386.639658) (xy 88.030812 -386.631688)
			(xy 88.014505 -386.605842) (xy 87.990601 -386.549607) (xy 87.983314 -386.519928) (xy 87.981251 -386.511767)
			(xy 87.972553 -386.497365) (xy 87.966296 -386.491734) (xy 87.943182 -386.472684) (xy 87.936302 -386.467439)
			(xy 87.920071 -386.461473) (xy 87.911432 -386.461) (xy 87.881794 -386.460018) (xy 87.823129 -386.451365)
			(xy 87.766071 -386.435211) (xy 87.711577 -386.411825) (xy 87.660558 -386.381599) (xy 87.613868 -386.34504)
			(xy 87.572289 -386.302758) (xy 87.536518 -386.255462) (xy 87.507151 -386.203944) (xy 87.484683 -386.149065)
			(xy 87.469487 -386.091745) (xy 87.461819 -386.032942) (xy 87.461344 -386.003292) (xy 87.461865 -385.972229)
			(xy 87.470281 -385.910675) (xy 87.478108 -385.88061) (xy 87.480902 -385.87045) (xy 87.478362 -385.850638)
			(xy 87.430864 -385.768342) (xy 87.414862 -385.75615) (xy 87.404702 -385.75361) (xy 87.375576 -385.745666)
			(xy 87.319609 -385.723025) (xy 87.267103 -385.693223) (xy 87.21897 -385.656778) (xy 87.176045 -385.614323)
			(xy 87.139073 -385.566594) (xy 87.108696 -385.51442) (xy 87.08544 -385.458705) (xy 87.069708 -385.400417)
			(xy 87.061775 -385.340567) (xy 87.061294 -385.31038) (xy 87.061821 -385.279492) (xy 87.070126 -385.218277)
			(xy 87.086582 -385.158733) (xy 87.110892 -385.101941) (xy 87.126318 -385.075176) (xy 87.13216 -385.06527)
			(xy 87.134446 -385.042918) (xy 87.101172 -384.947668) (xy 87.085424 -384.931666) (xy 87.074756 -384.927602)
			(xy 87.051366 -384.91844) (xy 87.00747 -384.894016) (xy 86.967775 -384.863231) (xy 86.933195 -384.826794)
			(xy 86.904527 -384.785545) (xy 86.882431 -384.740432) (xy 86.867415 -384.692496) (xy 86.859826 -384.642839)
			(xy 86.859364 -384.617722) (xy 86.320884 -384.617722) (xy 86.320352 -384.644824) (xy 86.311544 -384.698307)
			(xy 86.303358 -384.724148) (xy 86.299548 -384.73507) (xy 86.302088 -384.757422) (xy 86.354666 -384.843274)
			(xy 86.373716 -384.85572) (xy 86.384892 -384.857498) (xy 86.414205 -384.862236) (xy 86.471375 -384.87828)
			(xy 86.525989 -384.901585) (xy 86.577129 -384.93176) (xy 86.623936 -384.968298) (xy 86.665622 -385.010584)
			(xy 86.701487 -385.057908) (xy 86.730928 -385.109474) (xy 86.75345 -385.164416) (xy 86.768675 -385.221809)
			(xy 86.776347 -385.280691) (xy 86.776814 -385.31038) (xy 86.776288 -385.341443) (xy 86.767876 -385.402997)
			(xy 86.76005 -385.433062) (xy 86.757256 -385.443222) (xy 86.759796 -385.463034) (xy 86.807294 -385.54533)
			(xy 86.823296 -385.557522) (xy 86.833456 -385.560062) (xy 86.862566 -385.568059) (xy 86.918533 -385.590694)
			(xy 86.971038 -385.620489) (xy 87.019171 -385.656927) (xy 87.062097 -385.699375) (xy 87.099071 -385.747098)
			(xy 87.129451 -385.799267) (xy 87.15271 -385.854977) (xy 87.168444 -385.913261) (xy 87.176381 -385.973107)
			(xy 87.176864 -386.003292) (xy 87.176739 -386.017427) (xy 87.174957 -386.045641) (xy 87.173308 -386.05968)
			(xy 87.172554 -386.068287) (xy 87.17619 -386.085166) (xy 87.18042 -386.0927) (xy 87.196168 -386.1181)
			(xy 87.200872 -386.125167) (xy 87.213975 -386.135944) (xy 87.221822 -386.139182) (xy 87.245169 -386.148414)
			(xy 87.289012 -386.172868) (xy 87.328656 -386.203667) (xy 87.363191 -386.240103) (xy 87.391823 -386.281339)
			(xy 87.413895 -386.326429) (xy 87.428899 -386.374336) (xy 87.436491 -386.423961) (xy 87.43696 -386.449062)
			(xy 87.436541 -386.473264) (xy 87.429467 -386.52115) (xy 87.415479 -386.567489) (xy 87.394877 -386.611291)
			(xy 87.381842 -386.631688) (xy 87.377052 -386.639644) (xy 87.37302 -386.657756) (xy 87.373968 -386.666994)
			(xy 87.378286 -386.697982) (xy 87.379972 -386.707277) (xy 87.389251 -386.723719) (xy 87.39632 -386.729986)
			(xy 87.418399 -386.748679) (xy 87.458173 -386.790688) (xy 87.492337 -386.837373) (xy 87.520346 -386.887991)
			(xy 87.541755 -386.941735) (xy 87.556221 -386.997748) (xy 87.563515 -387.055137) (xy 87.56396 -387.084062)
			(xy 87.563368 -387.117383) (xy 87.553706 -387.183322) (xy 87.534581 -387.247161) (xy 87.521034 -387.27761)
			(xy 87.516768 -387.28807) (xy 87.516881 -387.310636) (xy 87.526626 -387.330989) (xy 87.535004 -387.33857)
			(xy 87.557235 -387.357262) (xy 87.597299 -387.399314) (xy 87.631721 -387.446097) (xy 87.659948 -387.496859)
			(xy 87.681526 -387.550784) (xy 87.696109 -387.607006) (xy 87.703461 -387.664621) (xy 87.703914 -387.693662)
			(xy 87.703451 -387.722668) (xy 87.69614 -387.780216) (xy 87.681616 -387.836379) (xy 87.660114 -387.890258)
			(xy 87.631977 -387.940988) (xy 87.597657 -387.987758) (xy 87.557703 -388.029816) (xy 87.535512 -388.0485)
			(xy 87.5284 -388.054088) (xy 87.519256 -388.069328) (xy 87.504016 -388.152132) (xy 87.50681 -388.169404)
			(xy 87.511382 -388.177532) (xy 87.523952 -388.200721) (xy 87.541829 -388.250341) (xy 87.550932 -388.302292)
			(xy 87.551514 -388.328662) (xy 87.55141 -388.339943) (xy 87.549759 -388.362445) (xy 87.548212 -388.37362)
			(xy 87.546942 -388.38251) (xy 87.550498 -388.400036) (xy 87.593932 -388.470902) (xy 87.607648 -388.482078)
			(xy 87.616284 -388.484872) (xy 87.638534 -388.492794) (xy 87.680455 -388.514548) (xy 87.718527 -388.542496)
			(xy 87.751845 -388.575971) (xy 87.779612 -388.614175) (xy 87.790782 -388.634986) (xy 87.79129 -388.636002)
			(xy 88.18372 -389.314944) (xy 88.196454 -389.338309) (xy 88.214569 -389.388337) (xy 88.223778 -389.440741)
			(xy 88.22436 -389.467344) (xy 88.224002 -389.491341) (xy 88.216487 -389.538742) (xy 88.20165 -389.584385)
			(xy 88.179855 -389.627144) (xy 88.151639 -389.665968) (xy 88.117698 -389.699899) (xy 88.078866 -389.728103)
			(xy 88.0361 -389.749885) (xy 87.990453 -389.764709) (xy 87.943049 -389.772209) (xy 87.919052 -389.772652)
			(xy 87.89552 -389.772207) (xy 87.849012 -389.765) (xy 87.804164 -389.750732) (xy 87.76204 -389.729743)
			(xy 87.723642 -389.702531) (xy 87.68988 -389.669742) (xy 87.661557 -389.632156) (xy 87.650066 -389.611616)
			(xy 87.649812 -389.611108) (xy 87.649304 -389.610346) (xy 87.25154 -388.922006) (xy 87.239628 -388.899336)
			(xy 87.222688 -388.851012) (xy 87.214028 -388.800542) (xy 87.21344 -388.77494) (xy 87.21344 -388.774432)
			(xy 87.213597 -388.763083) (xy 87.215374 -388.740453) (xy 87.216996 -388.72922) (xy 87.218266 -388.72033)
			(xy 87.21471 -388.703058) (xy 87.171276 -388.631938) (xy 87.157306 -388.621016) (xy 87.148924 -388.617968)
			(xy 87.126518 -388.609946) (xy 87.0843 -388.587984) (xy 87.046004 -388.559734) (xy 87.012559 -388.525881)
			(xy 86.984775 -388.487245) (xy 86.963327 -388.444764) (xy 86.948734 -388.399468) (xy 86.941351 -388.352456)
			(xy 86.940898 -388.328662) (xy 86.941464 -388.302289) (xy 86.950547 -388.250331) (xy 86.968435 -388.20071)
			(xy 86.98103 -388.177532) (xy 86.985602 -388.169404) (xy 86.988396 -388.152132) (xy 86.973156 -388.069328)
			(xy 86.964012 -388.054088) (xy 86.9569 -388.0485) (xy 86.934729 -388.029794) (xy 86.894782 -387.987733)
			(xy 86.860465 -387.940965) (xy 86.832326 -387.890239) (xy 86.810816 -387.836366) (xy 86.796279 -387.780209)
			(xy 86.788949 -387.722666) (xy 86.788498 -387.693662) (xy 86.789093 -387.660341) (xy 86.798753 -387.594402)
			(xy 86.817877 -387.530563) (xy 86.831424 -387.500114) (xy 86.835649 -387.489642) (xy 86.835543 -387.467089)
			(xy 86.825819 -387.446739) (xy 86.817454 -387.439154) (xy 86.795198 -387.42049) (xy 86.755133 -387.378434)
			(xy 86.720712 -387.331647) (xy 86.692488 -387.28088) (xy 86.670914 -387.22695) (xy 86.656337 -387.170724)
			(xy 86.648992 -387.113105) (xy 86.648544 -387.084062) (xy 86.648998 -387.055136) (xy 86.656282 -386.997744)
			(xy 86.670741 -386.941727) (xy 86.692144 -386.88798) (xy 86.72015 -386.837358) (xy 86.754314 -386.79067)
			(xy 86.794089 -386.74866) (xy 86.816184 -386.729986) (xy 86.82316 -386.723642) (xy 86.832415 -386.707236)
			(xy 86.834218 -386.697982) (xy 86.838536 -386.666994) (xy 86.839442 -386.657757) (xy 86.835416 -386.639657)
			(xy 86.830662 -386.631688) (xy 86.814351 -386.605845) (xy 86.79045 -386.549607) (xy 86.783164 -386.519928)
			(xy 86.781115 -386.511763) (xy 86.772408 -386.497363) (xy 86.766146 -386.491734) (xy 86.743032 -386.472684)
			(xy 86.736196 -386.467486) (xy 86.720108 -386.461511) (xy 86.711536 -386.461) (xy 86.681898 -386.460014)
			(xy 86.623233 -386.451362) (xy 86.566175 -386.435208) (xy 86.511681 -386.411823) (xy 86.460662 -386.381598)
			(xy 86.413972 -386.345038) (xy 86.372394 -386.302757) (xy 86.336622 -386.255461) (xy 86.307256 -386.203943)
			(xy 86.284787 -386.149064) (xy 86.269591 -386.091744) (xy 86.261923 -386.032942) (xy 86.261448 -386.003292)
			(xy 86.261969 -385.972229) (xy 86.270385 -385.910675) (xy 86.278212 -385.88061) (xy 86.281006 -385.87045)
			(xy 86.278466 -385.850638) (xy 86.230968 -385.768342) (xy 86.214966 -385.75615) (xy 86.204806 -385.75361)
			(xy 86.175681 -385.745664) (xy 86.119714 -385.723023) (xy 86.067208 -385.693221) (xy 86.019075 -385.656777)
			(xy 85.97615 -385.614322) (xy 85.939178 -385.566594) (xy 85.9088 -385.514419) (xy 85.885544 -385.458705)
			(xy 85.869812 -385.400417) (xy 85.861879 -385.340567) (xy 85.861398 -385.31038) (xy 85.861924 -385.279492)
			(xy 85.870229 -385.218277) (xy 85.886686 -385.158733) (xy 85.910996 -385.101941) (xy 85.926422 -385.075176)
			(xy 85.932264 -385.06527) (xy 85.93455 -385.042918) (xy 85.901276 -384.947668) (xy 85.885528 -384.931666)
			(xy 85.87486 -384.927602) (xy 85.851471 -384.918438) (xy 85.807575 -384.894014) (xy 85.76788 -384.86323)
			(xy 85.7333 -384.826793) (xy 85.704631 -384.785544) (xy 85.682535 -384.740432) (xy 85.667519 -384.692495)
			(xy 85.65993 -384.642839) (xy 85.659468 -384.617722) (xy 85.120988 -384.617722) (xy 85.120456 -384.644824)
			(xy 85.111648 -384.698306) (xy 85.103462 -384.724148) (xy 85.099652 -384.73507) (xy 85.102192 -384.757422)
			(xy 85.15477 -384.843528) (xy 85.173566 -384.85572) (xy 85.184996 -384.857498) (xy 85.214292 -384.862264)
			(xy 85.271427 -384.878344) (xy 85.326003 -384.901675) (xy 85.377105 -384.931866) (xy 85.423875 -384.96841)
			(xy 85.465529 -385.010694) (xy 85.501366 -385.058007) (xy 85.530787 -385.109557) (xy 85.553296 -385.164478)
			(xy 85.568516 -385.221847) (xy 85.576192 -385.280703) (xy 85.576664 -385.31038) (xy 85.576137 -385.341443)
			(xy 85.567725 -385.402996) (xy 85.5599 -385.433062) (xy 85.557106 -385.443222) (xy 85.559646 -385.463034)
			(xy 85.607144 -385.54533) (xy 85.623146 -385.557522) (xy 85.633306 -385.560062) (xy 85.662407 -385.568092)
			(xy 85.718373 -385.590721) (xy 85.77088 -385.620511) (xy 85.819014 -385.656944) (xy 85.861942 -385.699389)
			(xy 85.898917 -385.747109) (xy 85.929298 -385.799275) (xy 85.952558 -385.854982) (xy 85.968293 -385.913264)
			(xy 85.97623 -385.973108) (xy 85.976714 -386.003292) (xy 85.976589 -386.017427) (xy 85.974807 -386.045641)
			(xy 85.973158 -386.05968) (xy 85.972397 -386.068287) (xy 85.976037 -386.085167) (xy 85.98027 -386.0927)
			(xy 85.996018 -386.1181) (xy 86.000719 -386.125167) (xy 86.013831 -386.135932) (xy 86.021672 -386.139182)
			(xy 86.045062 -386.148343) (xy 86.088957 -386.172768) (xy 86.128651 -386.203554) (xy 86.163229 -386.239992)
			(xy 86.191897 -386.281241) (xy 86.213993 -386.326353) (xy 86.22901 -386.374289) (xy 86.236601 -386.423945)
			(xy 86.237064 -386.449062) (xy 86.236645 -386.473264) (xy 86.22957 -386.521149) (xy 86.215582 -386.567489)
			(xy 86.19498 -386.611291) (xy 86.181946 -386.631688) (xy 86.177156 -386.639644) (xy 86.173124 -386.657756)
			(xy 86.174072 -386.666994) (xy 86.17839 -386.697982) (xy 86.180075 -386.707277) (xy 86.189354 -386.723719)
			(xy 86.196424 -386.729986) (xy 86.218504 -386.748678) (xy 86.258277 -386.790687) (xy 86.292441 -386.837373)
			(xy 86.32045 -386.887991) (xy 86.341859 -386.941735) (xy 86.356325 -386.997747) (xy 86.363619 -387.055137)
			(xy 86.364064 -387.084062) (xy 86.363472 -387.117383) (xy 86.35381 -387.183322) (xy 86.334685 -387.247161)
			(xy 86.321138 -387.27761) (xy 86.31687 -387.28807) (xy 86.316984 -387.310636) (xy 86.32673 -387.330989)
			(xy 86.335108 -387.33857) (xy 86.35734 -387.357261) (xy 86.397404 -387.399314) (xy 86.431825 -387.446097)
			(xy 86.460052 -387.496859) (xy 86.48163 -387.550784) (xy 86.496213 -387.607006) (xy 86.503565 -387.664621)
			(xy 86.504018 -387.693662) (xy 86.503554 -387.722667) (xy 86.496242 -387.780216) (xy 86.481719 -387.836379)
			(xy 86.460217 -387.890258) (xy 86.43208 -387.940988) (xy 86.39776 -387.987757) (xy 86.357807 -388.029816)
			(xy 86.335616 -388.0485) (xy 86.328504 -388.054088) (xy 86.31936 -388.069328) (xy 86.30412 -388.152132)
			(xy 86.306914 -388.169404) (xy 86.311486 -388.177532) (xy 86.324057 -388.200721) (xy 86.341934 -388.250341)
			(xy 86.351036 -388.302292) (xy 86.351618 -388.328662) (xy 86.351514 -388.339943) (xy 86.349863 -388.362445)
			(xy 86.348316 -388.37362) (xy 86.347046 -388.38251) (xy 86.350602 -388.400036) (xy 86.394036 -388.470902)
			(xy 86.407752 -388.482078) (xy 86.416388 -388.484872) (xy 86.438639 -388.492792) (xy 86.48056 -388.514547)
			(xy 86.518632 -388.542495) (xy 86.551949 -388.575971) (xy 86.579716 -388.614175) (xy 86.590886 -388.634986)
			(xy 86.591394 -388.636002) (xy 86.983824 -389.314944) (xy 86.996558 -389.338309) (xy 87.014673 -389.388337)
			(xy 87.023882 -389.440741) (xy 87.024464 -389.467344) (xy 87.024078 -389.491339) (xy 87.016564 -389.538736)
			(xy 87.001728 -389.584375) (xy 86.979935 -389.62713) (xy 86.951722 -389.66595) (xy 86.917783 -389.699879)
			(xy 86.878955 -389.728081) (xy 86.836193 -389.749861) (xy 86.79055 -389.764684) (xy 86.743151 -389.772185)
			(xy 86.719156 -389.772652) (xy 86.695624 -389.772204) (xy 86.649117 -389.764997) (xy 86.604268 -389.75073)
			(xy 86.562145 -389.729741) (xy 86.523746 -389.70253) (xy 86.489984 -389.669742) (xy 86.461661 -389.632156)
			(xy 86.45017 -389.611616) (xy 86.449916 -389.611108) (xy 86.449408 -389.610346) (xy 86.051644 -388.922006)
			(xy 86.039732 -388.899336) (xy 86.022793 -388.851012) (xy 86.014132 -388.800542) (xy 86.013544 -388.77494)
			(xy 86.013544 -388.774432) (xy 86.013701 -388.763083) (xy 86.015478 -388.740453) (xy 86.0171 -388.72922)
			(xy 86.01837 -388.72033) (xy 86.014814 -388.703058) (xy 85.97138 -388.631938) (xy 85.95741 -388.621016)
			(xy 85.949028 -388.617968) (xy 85.926623 -388.609943) (xy 85.884405 -388.587982) (xy 85.846109 -388.559733)
			(xy 85.812663 -388.52588) (xy 85.784879 -388.487244) (xy 85.763431 -388.444764) (xy 85.748838 -388.399468)
			(xy 85.741455 -388.352456) (xy 85.741002 -388.328662) (xy 85.741567 -388.302289) (xy 85.750651 -388.25033)
			(xy 85.768539 -388.20071) (xy 85.781134 -388.177532) (xy 85.785706 -388.169404) (xy 85.7885 -388.152132)
			(xy 85.77326 -388.069328) (xy 85.764116 -388.054088) (xy 85.757004 -388.0485) (xy 85.734834 -388.029793)
			(xy 85.694887 -387.987732) (xy 85.660569 -387.940964) (xy 85.63243 -387.890238) (xy 85.61092 -387.836366)
			(xy 85.596384 -387.780209) (xy 85.589053 -387.722666) (xy 85.588602 -387.693662) (xy 85.589196 -387.660341)
			(xy 85.598856 -387.594402) (xy 85.617981 -387.530563) (xy 85.631528 -387.500114) (xy 85.635751 -387.489641)
			(xy 85.635646 -387.467089) (xy 85.625923 -387.44674) (xy 85.617558 -387.439154) (xy 85.595303 -387.420489)
			(xy 85.555238 -387.378433) (xy 85.520817 -387.331646) (xy 85.492592 -387.28088) (xy 85.471018 -387.22695)
			(xy 85.456441 -387.170723) (xy 85.449096 -387.113105) (xy 85.448648 -387.084062) (xy 85.449101 -387.055136)
			(xy 85.456384 -386.997743) (xy 85.470843 -386.941727) (xy 85.492247 -386.887979) (xy 85.520254 -386.837358)
			(xy 85.554417 -386.79067) (xy 85.594192 -386.74866) (xy 85.616288 -386.729986) (xy 85.623264 -386.723643)
			(xy 85.632519 -386.707236) (xy 85.634322 -386.697982) (xy 85.63864 -386.666994) (xy 85.639545 -386.657757)
			(xy 85.63552 -386.639657) (xy 85.630766 -386.631688) (xy 85.614455 -386.605844) (xy 85.590554 -386.549607)
			(xy 85.583268 -386.519928) (xy 85.581218 -386.511763) (xy 85.572511 -386.497363) (xy 85.56625 -386.491734)
			(xy 85.543136 -386.472684) (xy 85.536241 -386.46746) (xy 85.520022 -386.461481) (xy 85.511386 -386.461)
			(xy 85.48175 -386.459969) (xy 85.423086 -386.451323) (xy 85.366029 -386.435174) (xy 85.311535 -386.411794)
			(xy 85.260516 -386.381574) (xy 85.213826 -386.345019) (xy 85.172247 -386.302742) (xy 85.136474 -386.255449)
			(xy 85.107107 -386.203934) (xy 85.084637 -386.149058) (xy 85.069441 -386.091741) (xy 85.061773 -386.032941)
			(xy 85.061298 -386.003292) (xy 85.061818 -385.972229) (xy 85.070234 -385.910675) (xy 85.078062 -385.88061)
			(xy 85.080856 -385.87045) (xy 85.078316 -385.850638) (xy 85.030818 -385.768342) (xy 85.014816 -385.75615)
			(xy 85.004656 -385.75361) (xy 84.97554 -385.745631) (xy 84.919572 -385.722995) (xy 84.867066 -385.6932)
			(xy 84.818931 -385.65676) (xy 84.776005 -385.614309) (xy 84.739031 -385.566584) (xy 84.708652 -385.514412)
			(xy 84.685395 -385.4587) (xy 84.669663 -385.400414) (xy 84.661729 -385.340566) (xy 84.661248 -385.31038)
			(xy 84.66172 -385.279458) (xy 84.670003 -385.218171) (xy 84.686468 -385.158559) (xy 84.710817 -385.101709)
			(xy 84.726272 -385.074922) (xy 84.732368 -385.06527) (xy 84.734654 -385.042918) (xy 84.701126 -384.947668)
			(xy 84.685378 -384.931666) (xy 84.67471 -384.927602) (xy 84.651365 -384.918366) (xy 84.60752 -384.893914)
			(xy 84.567874 -384.863117) (xy 84.533338 -384.826682) (xy 84.504705 -384.785446) (xy 84.482634 -384.740356)
			(xy 84.46763 -384.692448) (xy 84.46004 -384.642823) (xy 84.459572 -384.617722) (xy 83.920838 -384.617722)
			(xy 83.920309 -384.644824) (xy 83.911499 -384.698307) (xy 83.903312 -384.724148) (xy 83.899502 -384.73507)
			(xy 83.902042 -384.757422) (xy 83.95462 -384.843274) (xy 83.97367 -384.85572) (xy 83.984846 -384.857498)
			(xy 84.014166 -384.862193) (xy 84.071337 -384.878244) (xy 84.125951 -384.901555) (xy 84.17709 -384.931736)
			(xy 84.223895 -384.968278) (xy 84.26558 -385.010569) (xy 84.301444 -385.057896) (xy 84.330884 -385.109466)
			(xy 84.353405 -385.16441) (xy 84.36863 -385.221806) (xy 84.376301 -385.280689) (xy 84.376768 -385.31038)
			(xy 84.376241 -385.341443) (xy 84.367829 -385.402996) (xy 84.360004 -385.433062) (xy 84.35721 -385.443222)
			(xy 84.35975 -385.463034) (xy 84.407248 -385.54533) (xy 84.42325 -385.557522) (xy 84.43341 -385.560062)
			(xy 84.462511 -385.56809) (xy 84.518478 -385.590719) (xy 84.570984 -385.620509) (xy 84.619119 -385.656943)
			(xy 84.662046 -385.699388) (xy 84.699021 -385.747108) (xy 84.729403 -385.799274) (xy 84.752662 -385.854982)
			(xy 84.768397 -385.913263) (xy 84.776334 -385.973108) (xy 84.776818 -386.003292) (xy 84.776693 -386.017427)
			(xy 84.774911 -386.045641) (xy 84.773262 -386.05968) (xy 84.772501 -386.068287) (xy 84.776141 -386.085167)
			(xy 84.780374 -386.0927) (xy 84.796122 -386.1181) (xy 84.800841 -386.125155) (xy 84.813934 -386.135938)
			(xy 84.821776 -386.139182) (xy 84.845135 -386.148385) (xy 84.888976 -386.172845) (xy 84.928619 -386.20365)
			(xy 84.963151 -386.240091) (xy 84.991781 -386.281331) (xy 85.013851 -386.326424) (xy 85.028854 -386.374333)
			(xy 85.036446 -386.42396) (xy 85.036914 -386.449062) (xy 85.036486 -386.473264) (xy 85.029413 -386.521148)
			(xy 85.015428 -386.567488) (xy 84.994829 -386.61129) (xy 84.981796 -386.631688) (xy 84.97701 -386.639646)
			(xy 84.972974 -386.657756) (xy 84.973922 -386.666994) (xy 84.97824 -386.697982) (xy 84.97991 -386.707281)
			(xy 84.989199 -386.723722) (xy 84.996274 -386.729986) (xy 85.018364 -386.748665) (xy 85.058136 -386.790678)
			(xy 85.092297 -386.837366) (xy 85.120304 -386.887987) (xy 85.141711 -386.941732) (xy 85.156176 -386.997746)
			(xy 85.163469 -387.055136) (xy 85.163914 -387.084062) (xy 85.163327 -387.117384) (xy 85.153664 -387.183322)
			(xy 85.134536 -387.247161) (xy 85.120988 -387.27761) (xy 85.116737 -387.288074) (xy 85.116851 -387.310634)
			(xy 85.126587 -387.330986) (xy 85.134958 -387.33857) (xy 85.15718 -387.357273) (xy 85.197246 -387.399322)
			(xy 85.23167 -387.446103) (xy 85.259899 -387.496863) (xy 85.281478 -387.550787) (xy 85.296062 -387.607007)
			(xy 85.303415 -387.664621) (xy 85.303868 -387.693662) (xy 85.303385 -387.722667) (xy 85.296075 -387.780213)
			(xy 85.281553 -387.836376) (xy 85.260054 -387.890254) (xy 85.231921 -387.940984) (xy 85.197604 -387.987754)
			(xy 85.157655 -388.029815) (xy 85.135466 -388.0485) (xy 85.128354 -388.054088) (xy 85.11921 -388.069328)
			(xy 85.10397 -388.152132) (xy 85.106764 -388.169404) (xy 85.111336 -388.177532) (xy 85.123911 -388.200719)
			(xy 85.141785 -388.25034) (xy 85.150886 -388.302291) (xy 85.151468 -388.328662) (xy 85.151364 -388.339943)
			(xy 85.149713 -388.362445) (xy 85.148166 -388.37362) (xy 85.146896 -388.38251) (xy 85.150452 -388.400036)
			(xy 85.193886 -388.470902) (xy 85.207602 -388.482078) (xy 85.216238 -388.484872) (xy 85.23848 -388.492816)
			(xy 85.280402 -388.514564) (xy 85.318476 -388.542506) (xy 85.351795 -388.575977) (xy 85.379565 -388.614177)
			(xy 85.390736 -388.634986) (xy 85.391244 -388.636002) (xy 85.783674 -389.314944) (xy 85.796483 -389.338284)
			(xy 85.814708 -389.388303) (xy 85.823975 -389.440726) (xy 85.824568 -389.467344) (xy 85.824201 -389.491353)
			(xy 85.816679 -389.538778) (xy 85.801826 -389.584442) (xy 85.78001 -389.627218) (xy 85.751767 -389.666052)
			(xy 85.717795 -389.699987) (xy 85.678929 -389.728187) (xy 85.636129 -389.749956) (xy 85.590449 -389.764758)
			(xy 85.543016 -389.772228) (xy 85.519006 -389.772652) (xy 85.495476 -389.772164) (xy 85.44897 -389.764964)
			(xy 85.404123 -389.750704) (xy 85.361999 -389.729722) (xy 85.3236 -389.702517) (xy 85.289837 -389.669735)
			(xy 85.261512 -389.632154) (xy 85.25002 -389.611616) (xy 85.249766 -389.611108) (xy 85.249258 -389.610346)
			(xy 84.851494 -388.922006) (xy 84.839621 -388.899328) (xy 84.822768 -388.850995) (xy 84.814194 -388.800532)
			(xy 84.813648 -388.77494) (xy 84.813648 -388.774432) (xy 84.81374 -388.763087) (xy 84.815394 -388.740458)
			(xy 84.81695 -388.72922) (xy 84.81822 -388.72033) (xy 84.814664 -388.703058) (xy 84.77123 -388.631938)
			(xy 84.75726 -388.621016) (xy 84.748878 -388.617968) (xy 84.726483 -388.609915) (xy 84.684264 -388.58796)
			(xy 84.645966 -388.559716) (xy 84.612518 -388.525868) (xy 84.584733 -388.487236) (xy 84.563283 -388.444759)
			(xy 84.548689 -388.399465) (xy 84.541305 -388.352455) (xy 84.540852 -388.328662) (xy 84.541424 -388.302289)
			(xy 84.550505 -388.250331) (xy 84.568391 -388.200711) (xy 84.580984 -388.177532) (xy 84.585556 -388.169404)
			(xy 84.58835 -388.152132) (xy 84.57311 -388.069328) (xy 84.563966 -388.054088) (xy 84.556854 -388.0485)
			(xy 84.534674 -388.029805) (xy 84.494729 -387.987741) (xy 84.460414 -387.94097) (xy 84.432277 -387.890242)
			(xy 84.410768 -387.836368) (xy 84.396233 -387.78021) (xy 84.388903 -387.722666) (xy 84.388452 -387.693662)
			(xy 84.389051 -387.660341) (xy 84.39871 -387.594403) (xy 84.417832 -387.530563) (xy 84.431378 -387.500114)
			(xy 84.435618 -387.489645) (xy 84.435513 -387.467087) (xy 84.425779 -387.446737) (xy 84.417408 -387.439154)
			(xy 84.395143 -387.420501) (xy 84.35508 -387.378442) (xy 84.320661 -387.331652) (xy 84.292438 -387.280884)
			(xy 84.270866 -387.226952) (xy 84.25629 -387.170725) (xy 84.248946 -387.113105) (xy 84.248498 -387.084062)
			(xy 84.248933 -387.055135) (xy 84.256217 -386.997741) (xy 84.270678 -386.941724) (xy 84.292084 -386.887975)
			(xy 84.320094 -386.837354) (xy 84.354261 -386.790667) (xy 84.39404 -386.748658) (xy 84.416138 -386.729986)
			(xy 84.423106 -386.723635) (xy 84.432367 -386.707234) (xy 84.434172 -386.697982) (xy 84.43849 -386.666994)
			(xy 84.439387 -386.657757) (xy 84.435366 -386.639658) (xy 84.430616 -386.631688) (xy 84.414309 -386.605842)
			(xy 84.390405 -386.549607) (xy 84.383118 -386.519928) (xy 84.381054 -386.511767) (xy 84.372357 -386.497366)
			(xy 84.3661 -386.491734) (xy 84.342986 -386.472684) (xy 84.336163 -386.467467) (xy 84.320065 -386.461504)
			(xy 84.31149 -386.461) (xy 84.281854 -386.459965) (xy 84.22319 -386.451319) (xy 84.166134 -386.435172)
			(xy 84.11164 -386.411792) (xy 84.06062 -386.381572) (xy 84.01393 -386.345017) (xy 83.972351 -386.30274)
			(xy 83.936578 -386.255448) (xy 83.907211 -386.203933) (xy 83.884741 -386.149058) (xy 83.869545 -386.09174)
			(xy 83.861877 -386.032941) (xy 83.861402 -386.003292) (xy 83.861921 -385.972229) (xy 83.870338 -385.910675)
			(xy 83.878166 -385.88061) (xy 83.88096 -385.87045) (xy 83.87842 -385.850638) (xy 83.830922 -385.768342)
			(xy 83.81492 -385.75615) (xy 83.80476 -385.75361) (xy 83.775645 -385.745627) (xy 83.719677 -385.722993)
			(xy 83.667171 -385.693197) (xy 83.619036 -385.656758) (xy 83.57611 -385.614308) (xy 83.539136 -385.566583)
			(xy 83.508757 -385.514412) (xy 83.485499 -385.4587) (xy 83.469767 -385.400414) (xy 83.461834 -385.340566)
			(xy 83.461352 -385.31038) (xy 83.46187 -385.279492) (xy 83.470177 -385.218276) (xy 83.486635 -385.158732)
			(xy 83.510948 -385.10194) (xy 83.526376 -385.075176) (xy 83.532218 -385.06527) (xy 83.534504 -385.042918)
			(xy 83.50123 -384.947668) (xy 83.485482 -384.931666) (xy 83.474814 -384.927602) (xy 83.451437 -384.918408)
			(xy 83.407539 -384.893992) (xy 83.367842 -384.863213) (xy 83.33326 -384.826781) (xy 83.304589 -384.785536)
			(xy 83.282491 -384.740426) (xy 83.267474 -384.692492) (xy 83.259884 -384.642838) (xy 83.259422 -384.617722)
			(xy 82.720942 -384.617722) (xy 82.720412 -384.644824) (xy 82.711603 -384.698307) (xy 82.703416 -384.724148)
			(xy 82.699606 -384.73507) (xy 82.702146 -384.757422) (xy 82.754724 -384.843274) (xy 82.773774 -384.85572)
			(xy 82.78495 -384.857498) (xy 82.814271 -384.86219) (xy 82.871441 -384.878241) (xy 82.926055 -384.901553)
			(xy 82.977194 -384.931734) (xy 83.024 -384.968277) (xy 83.065685 -385.010568) (xy 83.101548 -385.057895)
			(xy 83.130988 -385.109465) (xy 83.153509 -385.16441) (xy 83.168734 -385.221806) (xy 83.176405 -385.280689)
			(xy 83.176872 -385.31038) (xy 83.176349 -385.341506) (xy 83.167943 -385.403188) (xy 83.160108 -385.433316)
			(xy 83.157314 -385.443476) (xy 83.159854 -385.463542) (xy 83.207098 -385.54533) (xy 83.2231 -385.557522)
			(xy 83.23326 -385.560062) (xy 83.262371 -385.568056) (xy 83.318337 -385.590691) (xy 83.370843 -385.620487)
			(xy 83.418976 -385.656925) (xy 83.461902 -385.699374) (xy 83.498875 -385.747098) (xy 83.529255 -385.799267)
			(xy 83.552514 -385.854977) (xy 83.568248 -385.913261) (xy 83.576185 -385.973107) (xy 83.576668 -386.003292)
			(xy 83.576543 -386.017427) (xy 83.574761 -386.045641) (xy 83.573112 -386.05968) (xy 83.572357 -386.068287)
			(xy 83.575994 -386.085166) (xy 83.580224 -386.0927) (xy 83.595972 -386.1181) (xy 83.600688 -386.125156)
			(xy 83.613789 -386.135927) (xy 83.621626 -386.139182) (xy 83.645006 -386.148367) (xy 83.688902 -386.172787)
			(xy 83.728598 -386.203569) (xy 83.763178 -386.240002) (xy 83.791848 -386.281248) (xy 83.813946 -386.326358)
			(xy 83.828963 -386.374292) (xy 83.836555 -386.423946) (xy 83.837018 -386.449062) (xy 83.83659 -386.473264)
			(xy 83.829517 -386.521148) (xy 83.815531 -386.567488) (xy 83.794932 -386.61129) (xy 83.7819 -386.631688)
			(xy 83.777114 -386.639646) (xy 83.773078 -386.657756) (xy 83.774026 -386.666994) (xy 83.778344 -386.697982)
			(xy 83.780013 -386.707282) (xy 83.789302 -386.723722) (xy 83.796378 -386.729986) (xy 83.818469 -386.748664)
			(xy 83.85824 -386.790677) (xy 83.892401 -386.837366) (xy 83.920409 -386.887986) (xy 83.941815 -386.941732)
			(xy 83.95628 -386.997746) (xy 83.963573 -387.055136) (xy 83.964018 -387.084062) (xy 83.96343 -387.117384)
			(xy 83.953767 -387.183322) (xy 83.93464 -387.247161) (xy 83.921092 -387.27761) (xy 83.916839 -387.288074)
			(xy 83.916953 -387.310634) (xy 83.92669 -387.330986) (xy 83.935062 -387.33857) (xy 83.957284 -387.357272)
			(xy 83.99735 -387.399322) (xy 84.031774 -387.446102) (xy 84.060003 -387.496863) (xy 84.081582 -387.550787)
			(xy 84.096166 -387.607007) (xy 84.103519 -387.664621) (xy 84.103972 -387.693662) (xy 84.103488 -387.722667)
			(xy 84.096177 -387.780213) (xy 84.081656 -387.836375) (xy 84.060157 -387.890253) (xy 84.032024 -387.940984)
			(xy 83.997708 -387.987754) (xy 83.957758 -388.029815) (xy 83.93557 -388.0485) (xy 83.928458 -388.054088)
			(xy 83.919314 -388.069328) (xy 83.904074 -388.152132) (xy 83.906868 -388.169404) (xy 83.91144 -388.177532)
			(xy 83.924015 -388.200719) (xy 83.941889 -388.25034) (xy 83.95099 -388.302291) (xy 83.951572 -388.328662)
			(xy 83.951468 -388.339943) (xy 83.949817 -388.362445) (xy 83.94827 -388.37362) (xy 83.947 -388.38251)
			(xy 83.950556 -388.400036) (xy 83.99399 -388.470902) (xy 84.007706 -388.482078) (xy 84.016342 -388.484872)
			(xy 84.038585 -388.492814) (xy 84.080506 -388.514563) (xy 84.11858 -388.542506) (xy 84.151899 -388.575976)
			(xy 84.179669 -388.614177) (xy 84.19084 -388.634986) (xy 84.191348 -388.636002) (xy 84.583778 -389.314944)
			(xy 84.596588 -389.338284) (xy 84.614813 -389.388303) (xy 84.624079 -389.440726) (xy 84.624672 -389.467344)
			(xy 84.624301 -389.491353) (xy 84.616779 -389.538778) (xy 84.601927 -389.584441) (xy 84.580111 -389.627217)
			(xy 84.551868 -389.666051) (xy 84.517896 -389.699986) (xy 84.479031 -389.728185) (xy 84.436232 -389.749955)
			(xy 84.390552 -389.764757) (xy 84.343119 -389.772228) (xy 84.31911 -389.772652) (xy 84.295577 -389.772241)
			(xy 84.249067 -389.765027) (xy 84.204218 -389.750753) (xy 84.162095 -389.729759) (xy 84.123697 -389.702541)
			(xy 84.089936 -389.669748) (xy 84.061614 -389.632158) (xy 84.050124 -389.611616) (xy 84.04987 -389.611108)
			(xy 84.049362 -389.610346) (xy 83.651598 -388.922006) (xy 83.639725 -388.899328) (xy 83.622872 -388.850995)
			(xy 83.614298 -388.800532) (xy 83.613752 -388.77494) (xy 83.613752 -388.774432) (xy 83.613844 -388.763087)
			(xy 83.615498 -388.740458) (xy 83.617054 -388.72922) (xy 83.618324 -388.72033) (xy 83.614768 -388.703058)
			(xy 83.571334 -388.631938) (xy 83.557364 -388.621016) (xy 83.548982 -388.617968) (xy 83.526588 -388.609913)
			(xy 83.484369 -388.587959) (xy 83.446071 -388.559715) (xy 83.412623 -388.525867) (xy 83.384837 -388.487236)
			(xy 83.363387 -388.444758) (xy 83.348793 -388.399465) (xy 83.341409 -388.352455) (xy 83.340956 -388.328662)
			(xy 83.341527 -388.302289) (xy 83.350609 -388.250331) (xy 83.368495 -388.200711) (xy 83.381088 -388.177532)
			(xy 83.38566 -388.169404) (xy 83.388454 -388.152132) (xy 83.373214 -388.069328) (xy 83.36407 -388.054088)
			(xy 83.356958 -388.0485) (xy 83.334779 -388.029804) (xy 83.294834 -387.98774) (xy 83.260518 -387.94097)
			(xy 83.232381 -387.890242) (xy 83.210873 -387.836368) (xy 83.196337 -387.78021) (xy 83.189007 -387.722666)
			(xy 83.188556 -387.693662) (xy 83.189155 -387.660341) (xy 83.198813 -387.594403) (xy 83.217936 -387.530563)
			(xy 83.231482 -387.500114) (xy 83.23572 -387.489645) (xy 83.235615 -387.467087) (xy 83.225883 -387.446737)
			(xy 83.217512 -387.439154) (xy 83.195247 -387.4205) (xy 83.155185 -387.378441) (xy 83.120765 -387.331652)
			(xy 83.092543 -387.280883) (xy 83.07097 -387.226952) (xy 83.056394 -387.170725) (xy 83.04905 -387.113105)
			(xy 83.048602 -387.084062) (xy 83.049035 -387.055135) (xy 83.05632 -386.997741) (xy 83.07078 -386.941723)
			(xy 83.092187 -386.887975) (xy 83.120197 -386.837354) (xy 83.154364 -386.790666) (xy 83.194144 -386.748658)
			(xy 83.216242 -386.729986) (xy 83.223211 -386.723635) (xy 83.232471 -386.707234) (xy 83.234276 -386.697982)
			(xy 83.238594 -386.666994) (xy 83.239491 -386.657757) (xy 83.23547 -386.639658) (xy 83.23072 -386.631688)
			(xy 83.214414 -386.605841) (xy 83.190509 -386.549607) (xy 83.183222 -386.519928) (xy 83.181157 -386.511768)
			(xy 83.17246 -386.497366) (xy 83.166204 -386.491734) (xy 83.14309 -386.472684) (xy 83.136207 -386.467442)
			(xy 83.119979 -386.461474) (xy 83.11134 -386.461) (xy 83.081703 -386.460011) (xy 83.023037 -386.451359)
			(xy 82.96598 -386.435206) (xy 82.911485 -386.411821) (xy 82.860466 -386.381596) (xy 82.813777 -386.345037)
			(xy 82.772198 -386.302756) (xy 82.736426 -386.25546) (xy 82.70706 -386.203942) (xy 82.684591 -386.149064)
			(xy 82.669395 -386.091744) (xy 82.661727 -386.032942) (xy 82.661252 -386.003292) (xy 82.661773 -385.972229)
			(xy 82.670189 -385.910675) (xy 82.678016 -385.88061) (xy 82.68081 -385.87045) (xy 82.67827 -385.850638)
			(xy 82.630772 -385.768342) (xy 82.61477 -385.75615) (xy 82.60461 -385.75361) (xy 82.575517 -385.745593)
			(xy 82.519591 -385.722924) (xy 82.467126 -385.693106) (xy 82.419032 -385.656655) (xy 82.376143 -385.614202)
			(xy 82.3392 -385.566485) (xy 82.308846 -385.514328) (xy 82.285605 -385.458637) (xy 82.269879 -385.400375)
			(xy 82.261943 -385.340553) (xy 82.261456 -385.31038) (xy 82.261974 -385.279492) (xy 82.27028 -385.218276)
			(xy 82.286739 -385.158732) (xy 82.311052 -385.10194) (xy 82.32648 -385.075176) (xy 82.332322 -385.06527)
			(xy 82.334608 -385.042918) (xy 82.301334 -384.947668) (xy 82.285586 -384.931666) (xy 82.274918 -384.927602)
			(xy 82.251541 -384.918406) (xy 82.207644 -384.89399) (xy 82.167946 -384.863212) (xy 82.133364 -384.826781)
			(xy 82.104694 -384.785535) (xy 82.082595 -384.740426) (xy 82.067578 -384.692492) (xy 82.059988 -384.642838)
			(xy 82.059526 -384.617722) (xy 81.520792 -384.617722) (xy 81.52026 -384.644824) (xy 81.511452 -384.698306)
			(xy 81.503266 -384.724148) (xy 81.499456 -384.73507) (xy 81.501996 -384.757422) (xy 81.554574 -384.843274)
			(xy 81.573624 -384.85572) (xy 81.5848 -384.857498) (xy 81.614114 -384.862229) (xy 81.671284 -384.878274)
			(xy 81.725898 -384.90158) (xy 81.777038 -384.931756) (xy 81.823845 -384.968295) (xy 81.865531 -385.010582)
			(xy 81.901395 -385.057906) (xy 81.930836 -385.109473) (xy 81.953358 -385.164415) (xy 81.968583 -385.221809)
			(xy 81.976255 -385.28069) (xy 81.976722 -385.31038) (xy 81.976196 -385.341443) (xy 81.967784 -385.402996)
			(xy 81.959958 -385.433062) (xy 81.957164 -385.443222) (xy 81.959704 -385.463034) (xy 82.007202 -385.54533)
			(xy 82.023204 -385.557522) (xy 82.033364 -385.560062) (xy 82.062476 -385.568054) (xy 82.118442 -385.590689)
			(xy 82.170947 -385.620485) (xy 82.21908 -385.656924) (xy 82.262006 -385.699373) (xy 82.29898 -385.747097)
			(xy 82.32936 -385.799266) (xy 82.352618 -385.854976) (xy 82.368352 -385.91326) (xy 82.376289 -385.973107)
			(xy 82.376772 -386.003292) (xy 82.376646 -386.017427) (xy 82.374865 -386.045641) (xy 82.373216 -386.05968)
			(xy 82.372461 -386.068287) (xy 82.376098 -386.085166) (xy 82.380328 -386.0927) (xy 82.396076 -386.1181)
			(xy 82.40079 -386.125156) (xy 82.413893 -386.135927) (xy 82.42173 -386.139182) (xy 82.445111 -386.148365)
			(xy 82.489007 -386.172786) (xy 82.528702 -386.203567) (xy 82.563283 -386.240001) (xy 82.591952 -386.281248)
			(xy 82.61405 -386.326357) (xy 82.629067 -386.374292) (xy 82.636659 -386.423946) (xy 82.637122 -386.449062)
			(xy 82.636693 -386.473264) (xy 82.62962 -386.521148) (xy 82.615635 -386.567488) (xy 82.595036 -386.61129)
			(xy 82.582004 -386.631688) (xy 82.577218 -386.639646) (xy 82.573182 -386.657756) (xy 82.57413 -386.666994)
			(xy 82.578448 -386.697982) (xy 82.580145 -386.707274) (xy 82.589417 -386.723716) (xy 82.596482 -386.729986)
			(xy 82.618574 -386.748663) (xy 82.658345 -386.790677) (xy 82.692506 -386.837365) (xy 82.720513 -386.887986)
			(xy 82.741919 -386.941732) (xy 82.756384 -386.997746) (xy 82.763677 -387.055136) (xy 82.764122 -387.084062)
			(xy 82.763534 -387.117383) (xy 82.753871 -387.183322) (xy 82.734744 -387.247161) (xy 82.721196 -387.27761)
			(xy 82.716942 -387.288073) (xy 82.717056 -387.310634) (xy 82.726793 -387.330986) (xy 82.735166 -387.33857)
			(xy 82.757389 -387.357271) (xy 82.797455 -387.399321) (xy 82.831879 -387.446102) (xy 82.860107 -387.496862)
			(xy 82.881687 -387.550786) (xy 82.89627 -387.607007) (xy 82.903623 -387.664621) (xy 82.904076 -387.693662)
			(xy 82.90359 -387.722667) (xy 82.89628 -387.780213) (xy 82.881759 -387.836375) (xy 82.86026 -387.890253)
			(xy 82.832127 -387.940983) (xy 82.797811 -387.987754) (xy 82.757862 -388.029815) (xy 82.735674 -388.0485)
			(xy 82.728562 -388.054088) (xy 82.719418 -388.069328) (xy 82.704178 -388.152132) (xy 82.706972 -388.169404)
			(xy 82.711544 -388.177532) (xy 82.724119 -388.200718) (xy 82.741993 -388.25034) (xy 82.751094 -388.302291)
			(xy 82.751676 -388.328662) (xy 82.751572 -388.339943) (xy 82.749921 -388.362445) (xy 82.748374 -388.37362)
			(xy 82.747104 -388.382764) (xy 82.750406 -388.400036) (xy 82.794094 -388.471156) (xy 82.80781 -388.482078)
			(xy 82.816446 -388.484872) (xy 82.844608 -388.495077) (xy 82.896555 -388.524883) (xy 82.91957 -388.544054)
			(xy 82.941051 -388.563638) (xy 82.976867 -388.609415) (xy 82.99069 -388.634986) (xy 82.991452 -388.636256)
			(xy 83.383628 -389.314944) (xy 83.396363 -389.338309) (xy 83.414477 -389.388337) (xy 83.423686 -389.440741)
			(xy 83.424268 -389.467344) (xy 83.423878 -389.491338) (xy 83.416364 -389.538735) (xy 83.401528 -389.584374)
			(xy 83.379736 -389.627129) (xy 83.351523 -389.665949) (xy 83.317585 -389.699878) (xy 83.278757 -389.728079)
			(xy 83.235996 -389.74986) (xy 83.190354 -389.764684) (xy 83.142955 -389.772184) (xy 83.11896 -389.772652)
			(xy 83.095428 -389.772201) (xy 83.048921 -389.764994) (xy 83.004073 -389.750728) (xy 82.961949 -389.72974)
			(xy 82.92355 -389.702529) (xy 82.889788 -389.669741) (xy 82.861465 -389.632156) (xy 82.849974 -389.611616)
			(xy 82.84972 -389.611108) (xy 82.849212 -389.610346) (xy 82.451702 -388.921752) (xy 82.441129 -388.901826)
			(xy 82.425326 -388.859576) (xy 82.415919 -388.815459) (xy 82.41411 -388.792974) (xy 82.413602 -388.781798)
			(xy 82.413348 -388.774432) (xy 82.413506 -388.763083) (xy 82.415282 -388.740454) (xy 82.416904 -388.72922)
			(xy 82.418174 -388.72033) (xy 82.414618 -388.703058) (xy 82.371184 -388.631938) (xy 82.357468 -388.620762)
			(xy 82.348832 -388.617968) (xy 82.326422 -388.609994) (xy 82.284252 -388.587985) (xy 82.246005 -388.559704)
			(xy 82.212607 -388.525834) (xy 82.184865 -388.487194) (xy 82.163451 -388.44472) (xy 82.148882 -388.399438)
			(xy 82.141511 -388.352446) (xy 82.14106 -388.328662) (xy 82.141631 -388.302289) (xy 82.150713 -388.250331)
			(xy 82.168599 -388.200711) (xy 82.181192 -388.177532) (xy 82.185764 -388.169404) (xy 82.188558 -388.152132)
			(xy 82.173318 -388.069328) (xy 82.164174 -388.054088) (xy 82.157062 -388.0485) (xy 82.134883 -388.029803)
			(xy 82.094938 -387.987739) (xy 82.060623 -387.940969) (xy 82.032485 -387.890241) (xy 82.010977 -387.836368)
			(xy 81.996441 -387.78021) (xy 81.989111 -387.722666) (xy 81.98866 -387.693662) (xy 81.989258 -387.660341)
			(xy 81.998917 -387.594403) (xy 82.01804 -387.530563) (xy 82.031586 -387.500114) (xy 82.035823 -387.489645)
			(xy 82.035718 -387.467087) (xy 82.025986 -387.446737) (xy 82.017616 -387.439154) (xy 81.995352 -387.420499)
			(xy 81.955289 -387.378441) (xy 81.92087 -387.331651) (xy 81.892647 -387.280883) (xy 81.871074 -387.226952)
			(xy 81.856498 -387.170725) (xy 81.849154 -387.113105) (xy 81.848706 -387.084062) (xy 81.849174 -387.055136)
			(xy 81.856457 -386.997745) (xy 81.870914 -386.94173) (xy 81.892316 -386.887983) (xy 81.92032 -386.837361)
			(xy 81.95448 -386.790672) (xy 81.994252 -386.748661) (xy 82.016346 -386.729986) (xy 82.023315 -386.723636)
			(xy 82.032575 -386.707234) (xy 82.03438 -386.697982) (xy 82.038698 -386.666994) (xy 82.039594 -386.657757)
			(xy 82.035574 -386.639659) (xy 82.030824 -386.631688) (xy 82.014518 -386.605841) (xy 81.990613 -386.549607)
			(xy 81.983326 -386.519928) (xy 81.98126 -386.511768) (xy 81.972564 -386.497366) (xy 81.966308 -386.491734)
			(xy 81.943194 -386.472684) (xy 81.93631 -386.467443) (xy 81.920083 -386.461475) (xy 81.911444 -386.461)
			(xy 81.881807 -386.460007) (xy 81.823141 -386.451356) (xy 81.766084 -386.435203) (xy 81.71159 -386.411818)
			(xy 81.660571 -386.381594) (xy 81.613881 -386.345035) (xy 81.572302 -386.302754) (xy 81.53653 -386.255459)
			(xy 81.507164 -386.203942) (xy 81.484695 -386.149063) (xy 81.469499 -386.091744) (xy 81.461831 -386.032942)
			(xy 81.461356 -386.003292) (xy 81.461877 -385.972229) (xy 81.470293 -385.910675) (xy 81.47812 -385.88061)
			(xy 81.480914 -385.87045) (xy 81.478374 -385.850638) (xy 81.430876 -385.768342) (xy 81.414874 -385.75615)
			(xy 81.404714 -385.75361) (xy 81.37559 -385.745658) (xy 81.319623 -385.723018) (xy 81.267117 -385.693218)
			(xy 81.218984 -385.656774) (xy 81.176059 -385.61432) (xy 81.139086 -385.566592) (xy 81.108708 -385.514418)
			(xy 81.085452 -385.458704) (xy 81.069721 -385.400416) (xy 81.061787 -385.340567) (xy 81.061306 -385.31038)
			(xy 81.061831 -385.279492) (xy 81.070136 -385.218276) (xy 81.086593 -385.158733) (xy 81.110903 -385.101941)
			(xy 81.12633 -385.075176) (xy 81.132172 -385.06527) (xy 81.134458 -385.042918) (xy 81.101184 -384.947668)
			(xy 81.085436 -384.931666) (xy 81.074768 -384.927602) (xy 81.051381 -384.918433) (xy 81.007484 -384.894011)
			(xy 80.967789 -384.863227) (xy 80.933209 -384.826792) (xy 80.90454 -384.785543) (xy 80.882443 -384.740431)
			(xy 80.867427 -384.692495) (xy 80.859838 -384.642839) (xy 80.859376 -384.617722) (xy 80.320896 -384.617722)
			(xy 80.320364 -384.644824) (xy 80.311556 -384.698306) (xy 80.30337 -384.724148) (xy 80.29956 -384.73507)
			(xy 80.3021 -384.757422) (xy 80.354678 -384.843274) (xy 80.373728 -384.85572) (xy 80.384904 -384.857498)
			(xy 80.414219 -384.862226) (xy 80.471389 -384.878272) (xy 80.526003 -384.901578) (xy 80.577143 -384.931755)
			(xy 80.623949 -384.968293) (xy 80.665635 -385.010581) (xy 80.701499 -385.057905) (xy 80.73094 -385.109472)
			(xy 80.753462 -385.164414) (xy 80.768687 -385.221809) (xy 80.776359 -385.28069) (xy 80.776826 -385.31038)
			(xy 80.7763 -385.341443) (xy 80.767888 -385.402996) (xy 80.760062 -385.433062) (xy 80.757268 -385.443222)
			(xy 80.759808 -385.463034) (xy 80.807306 -385.54533) (xy 80.823308 -385.557522) (xy 80.833468 -385.560062)
			(xy 80.862581 -385.568051) (xy 80.918547 -385.590687) (xy 80.971052 -385.620483) (xy 81.019185 -385.656922)
			(xy 81.062111 -385.699372) (xy 81.099084 -385.747096) (xy 81.129464 -385.799266) (xy 81.152722 -385.854976)
			(xy 81.168456 -385.91326) (xy 81.176393 -385.973107) (xy 81.176876 -386.003292) (xy 81.17675 -386.017427)
			(xy 81.174969 -386.045641) (xy 81.17332 -386.05968) (xy 81.172564 -386.068287) (xy 81.176201 -386.085166)
			(xy 81.180432 -386.0927) (xy 81.19618 -386.1181) (xy 81.20088 -386.12517) (xy 81.213986 -386.135945)
			(xy 81.221834 -386.139182) (xy 81.245183 -386.148408) (xy 81.289026 -386.172863) (xy 81.32867 -386.203663)
			(xy 81.363205 -386.2401) (xy 81.391836 -386.281338) (xy 81.413907 -386.326428) (xy 81.428911 -386.374336)
			(xy 81.436503 -386.423961) (xy 81.436972 -386.449062) (xy 81.436551 -386.473264) (xy 81.429477 -386.521149)
			(xy 81.41549 -386.567489) (xy 81.394888 -386.611291) (xy 81.381854 -386.631688) (xy 81.377065 -386.639644)
			(xy 81.373032 -386.657756) (xy 81.37398 -386.666994) (xy 81.378298 -386.697982) (xy 81.379981 -386.707278)
			(xy 81.389261 -386.72372) (xy 81.396332 -386.729986) (xy 81.418413 -386.748676) (xy 81.458187 -386.790686)
			(xy 81.49235 -386.837372) (xy 81.520359 -386.88799) (xy 81.541767 -386.941734) (xy 81.556233 -386.997747)
			(xy 81.563527 -387.055137) (xy 81.563972 -387.084062) (xy 81.563379 -387.117383) (xy 81.553718 -387.183322)
			(xy 81.534593 -387.247161) (xy 81.521046 -387.27761) (xy 81.516776 -387.288069) (xy 81.516889 -387.310636)
			(xy 81.526637 -387.33099) (xy 81.535016 -387.33857) (xy 81.55725 -387.357259) (xy 81.597313 -387.399312)
			(xy 81.631734 -387.446096) (xy 81.659961 -387.496858) (xy 81.681538 -387.550784) (xy 81.696121 -387.607006)
			(xy 81.703473 -387.664621) (xy 81.703926 -387.693662) (xy 81.703459 -387.722667) (xy 81.696147 -387.780215)
			(xy 81.681625 -387.836378) (xy 81.660123 -387.890257) (xy 81.631987 -387.940987) (xy 81.597667 -387.987757)
			(xy 81.557714 -388.029816) (xy 81.535524 -388.0485) (xy 81.528412 -388.054088) (xy 81.519268 -388.069328)
			(xy 81.504028 -388.152132) (xy 81.506822 -388.169404) (xy 81.511394 -388.177532) (xy 81.523965 -388.200721)
			(xy 81.541842 -388.250341) (xy 81.550944 -388.302292) (xy 81.551526 -388.328662) (xy 81.551423 -388.339943)
			(xy 81.549771 -388.362445) (xy 81.548224 -388.37362) (xy 81.546954 -388.38251) (xy 81.55051 -388.400036)
			(xy 81.593944 -388.470902) (xy 81.60766 -388.482078) (xy 81.616296 -388.484872) (xy 81.638548 -388.492788)
			(xy 81.680469 -388.514544) (xy 81.718541 -388.542494) (xy 81.751857 -388.57597) (xy 81.779624 -388.614175)
			(xy 81.790794 -388.634986) (xy 81.791302 -388.636002) (xy 82.183732 -389.314944) (xy 82.196467 -389.338308)
			(xy 82.214581 -389.388337) (xy 82.22379 -389.440741) (xy 82.224372 -389.467344) (xy 82.223978 -389.491338)
			(xy 82.216464 -389.538735) (xy 82.201628 -389.584373) (xy 82.179836 -389.627128) (xy 82.151624 -389.665948)
			(xy 82.117687 -389.699876) (xy 82.078859 -389.728078) (xy 82.036099 -389.749859) (xy 81.990457 -389.764683)
			(xy 81.943058 -389.772184) (xy 81.919064 -389.772652) (xy 81.895533 -389.772198) (xy 81.849025 -389.764992)
			(xy 81.804177 -389.750726) (xy 81.762053 -389.729738) (xy 81.723655 -389.702528) (xy 81.689892 -389.669741)
			(xy 81.661569 -389.632155) (xy 81.650078 -389.611616) (xy 81.649824 -389.611108) (xy 81.649316 -389.610346)
			(xy 81.251552 -388.922006) (xy 81.239641 -388.899336) (xy 81.222701 -388.851012) (xy 81.21404 -388.800542)
			(xy 81.213452 -388.77494) (xy 81.213452 -388.774432) (xy 81.21361 -388.763083) (xy 81.215386 -388.740454)
			(xy 81.217008 -388.72922) (xy 81.218278 -388.72033) (xy 81.214722 -388.703058) (xy 81.171288 -388.631938)
			(xy 81.157318 -388.621016) (xy 81.148936 -388.617968) (xy 81.126532 -388.609939) (xy 81.084314 -388.587979)
			(xy 81.046018 -388.55973) (xy 81.012572 -388.525878) (xy 80.984788 -388.487243) (xy 80.963339 -388.444763)
			(xy 80.948746 -388.399468) (xy 80.941363 -388.352456) (xy 80.94091 -388.328662) (xy 80.941474 -388.302289)
			(xy 80.950558 -388.25033) (xy 80.968447 -388.20071) (xy 80.981042 -388.177532) (xy 80.985614 -388.169404)
			(xy 80.988408 -388.152132) (xy 80.973168 -388.069328) (xy 80.964024 -388.054088) (xy 80.956912 -388.0485)
			(xy 80.934744 -388.029791) (xy 80.894796 -387.98773) (xy 80.860478 -387.940963) (xy 80.832339 -387.890238)
			(xy 80.810829 -387.836365) (xy 80.796292 -387.780209) (xy 80.788961 -387.722666) (xy 80.78851 -387.693662)
			(xy 80.789113 -387.660341) (xy 80.798771 -387.594403) (xy 80.817891 -387.530564) (xy 80.831436 -387.500114)
			(xy 80.835657 -387.489641) (xy 80.835551 -387.467089) (xy 80.82583 -387.44674) (xy 80.817466 -387.439154)
			(xy 80.795192 -387.420512) (xy 80.755131 -387.37845) (xy 80.720714 -387.331657) (xy 80.692493 -387.280887)
			(xy 80.670922 -387.226954) (xy 80.656348 -387.170726) (xy 80.649004 -387.113105) (xy 80.648556 -387.084062)
			(xy 80.649006 -387.055136) (xy 80.65629 -386.997743) (xy 80.670749 -386.941726) (xy 80.692153 -386.887979)
			(xy 80.72016 -386.837357) (xy 80.754324 -386.790669) (xy 80.7941 -386.74866) (xy 80.816196 -386.729986)
			(xy 80.823173 -386.723644) (xy 80.832427 -386.707236) (xy 80.83423 -386.697982) (xy 80.838548 -386.666994)
			(xy 80.839452 -386.657757) (xy 80.835427 -386.639658) (xy 80.830674 -386.631688) (xy 80.814364 -386.605844)
			(xy 80.790462 -386.549607) (xy 80.783176 -386.519928) (xy 80.781123 -386.511764) (xy 80.772418 -386.497363)
			(xy 80.766158 -386.491734) (xy 80.743044 -386.472684) (xy 80.736205 -386.46749) (xy 80.720119 -386.461513)
			(xy 80.711548 -386.461) (xy 80.681911 -386.460003) (xy 80.623246 -386.451353) (xy 80.566188 -386.4352)
			(xy 80.511694 -386.411816) (xy 80.460675 -386.381592) (xy 80.413985 -386.345034) (xy 80.372406 -386.302753)
			(xy 80.336634 -386.255458) (xy 80.307268 -386.203941) (xy 80.284799 -386.149063) (xy 80.269603 -386.091743)
			(xy 80.261935 -386.032942) (xy 80.26146 -386.003292) (xy 80.261981 -385.972229) (xy 80.270397 -385.910675)
			(xy 80.278224 -385.88061) (xy 80.281018 -385.87045) (xy 80.278478 -385.850638) (xy 80.23098 -385.768342)
			(xy 80.214978 -385.75615) (xy 80.204818 -385.75361) (xy 80.193097 -385.750462) (xy 80.169971 -385.743093)
			(xy 80.15859 -385.738878) (xy 80.146144 -385.734306) (xy 80.120236 -385.738116) (xy 80.030828 -385.806696)
			(xy 80.020414 -385.830826) (xy 80.021684 -385.84378) (xy 80.023208 -385.87553) (xy 80.02282 -385.899206)
			(xy 80.016088 -385.946077) (xy 80.002725 -385.991503) (xy 79.993236 -386.013198) (xy 79.988918 -386.022596)
			(xy 79.988156 -386.042662) (xy 80.020414 -386.129022) (xy 80.03413 -386.143754) (xy 80.043528 -386.148072)
			(xy 80.067892 -386.159773) (xy 80.112763 -386.189897) (xy 80.152142 -386.226913) (xy 80.184981 -386.269836)
			(xy 80.210408 -386.317526) (xy 80.227747 -386.368714) (xy 80.236536 -386.42204) (xy 80.237076 -386.449062)
			(xy 80.236655 -386.473264) (xy 80.229581 -386.521149) (xy 80.215593 -386.567489) (xy 80.194992 -386.611291)
			(xy 80.181958 -386.631688) (xy 80.177169 -386.639644) (xy 80.173136 -386.657756) (xy 80.174084 -386.666994)
			(xy 80.178402 -386.697982) (xy 80.180083 -386.707278) (xy 80.189365 -386.72372) (xy 80.196436 -386.729986)
			(xy 80.218518 -386.748675) (xy 80.258291 -386.790685) (xy 80.292454 -386.837371) (xy 80.320463 -386.88799)
			(xy 80.341871 -386.941734) (xy 80.356337 -386.997747) (xy 80.363631 -387.055137) (xy 80.364076 -387.084062)
			(xy 80.363483 -387.117383) (xy 80.353821 -387.183322) (xy 80.334697 -387.247161) (xy 80.32115 -387.27761)
			(xy 80.316878 -387.288069) (xy 80.316992 -387.310636) (xy 80.32674 -387.33099) (xy 80.33512 -387.33857)
			(xy 80.357354 -387.357258) (xy 80.397418 -387.399312) (xy 80.431839 -387.446096) (xy 80.460065 -387.496858)
			(xy 80.481643 -387.550784) (xy 80.496225 -387.607006) (xy 80.503577 -387.664621) (xy 80.50403 -387.693662)
			(xy 80.503561 -387.722667) (xy 80.49625 -387.780215) (xy 80.481727 -387.836378) (xy 80.460226 -387.890257)
			(xy 80.43209 -387.940987) (xy 80.397771 -387.987757) (xy 80.357818 -388.029816) (xy 80.335628 -388.0485)
			(xy 80.328516 -388.054088) (xy 80.319372 -388.069328) (xy 80.304132 -388.152132) (xy 80.306926 -388.169404)
			(xy 80.311498 -388.177532) (xy 80.32407 -388.20072) (xy 80.341946 -388.250341) (xy 80.351048 -388.302292)
			(xy 80.35163 -388.328662) (xy 80.351527 -388.339943) (xy 80.349875 -388.362445) (xy 80.348328 -388.37362)
			(xy 80.347058 -388.38251) (xy 80.350614 -388.400036) (xy 80.394048 -388.470902) (xy 80.407764 -388.482078)
			(xy 80.4164 -388.484872) (xy 80.438653 -388.492786) (xy 80.480573 -388.514543) (xy 80.518645 -388.542493)
			(xy 80.551962 -388.575969) (xy 80.579729 -388.614175) (xy 80.590898 -388.634986) (xy 80.591406 -388.636002)
			(xy 80.983836 -389.314944) (xy 80.996571 -389.338308) (xy 81.014685 -389.388337) (xy 81.023894 -389.440741)
			(xy 81.024476 -389.467344) (xy 81.024078 -389.491338) (xy 81.016564 -389.538734) (xy 81.001729 -389.584372)
			(xy 80.979937 -389.627127) (xy 80.951725 -389.665946) (xy 80.917788 -389.699875) (xy 80.878962 -389.728077)
			(xy 80.836201 -389.749858) (xy 80.79056 -389.764682) (xy 80.743162 -389.772184) (xy 80.719168 -389.772652)
			(xy 80.695637 -389.772194) (xy 80.649129 -389.764989) (xy 80.604281 -389.750724) (xy 80.562158 -389.729737)
			(xy 80.523759 -389.702527) (xy 80.489997 -389.66974) (xy 80.461673 -389.632155) (xy 80.450182 -389.611616)
			(xy 80.449928 -389.611108) (xy 80.44942 -389.610346) (xy 80.051656 -388.922006) (xy 80.039745 -388.899335)
			(xy 80.022805 -388.851011) (xy 80.014144 -388.800542) (xy 80.013556 -388.77494) (xy 80.013556 -388.774432)
			(xy 80.013714 -388.763083) (xy 80.01549 -388.740454) (xy 80.017112 -388.72922) (xy 80.018382 -388.72033)
			(xy 80.014826 -388.703058) (xy 79.971392 -388.631938) (xy 79.957422 -388.621016) (xy 79.94904 -388.617968)
			(xy 79.926637 -388.609937) (xy 79.884419 -388.587977) (xy 79.846122 -388.559729) (xy 79.812676 -388.525877)
			(xy 79.784892 -388.487243) (xy 79.763443 -388.444763) (xy 79.74885 -388.399467) (xy 79.741467 -388.352456)
			(xy 79.741014 -388.328662) (xy 79.741578 -388.302289) (xy 79.750661 -388.25033) (xy 79.768551 -388.20071)
			(xy 79.781146 -388.177532) (xy 79.785718 -388.169404) (xy 79.788512 -388.152132) (xy 79.773272 -388.069328)
			(xy 79.764128 -388.054088) (xy 79.757016 -388.0485) (xy 79.734849 -388.02979) (xy 79.694901 -387.98773)
			(xy 79.660583 -387.940963) (xy 79.632443 -387.890237) (xy 79.610933 -387.836365) (xy 79.596396 -387.780208)
			(xy 79.589065 -387.722666) (xy 79.588614 -387.693662) (xy 79.589216 -387.660341) (xy 79.598874 -387.594403)
			(xy 79.617995 -387.530564) (xy 79.63154 -387.500114) (xy 79.635792 -387.489649) (xy 79.635687 -387.467086)
			(xy 79.625947 -387.446734) (xy 79.61757 -387.439154) (xy 79.595297 -387.420511) (xy 79.555236 -387.378449)
			(xy 79.520819 -387.331657) (xy 79.492598 -387.280887) (xy 79.471027 -387.226954) (xy 79.456452 -387.170726)
			(xy 79.449108 -387.113105) (xy 79.44866 -387.084062) (xy 79.449109 -387.055135) (xy 79.456392 -386.997743)
			(xy 79.470852 -386.941726) (xy 79.492256 -386.887978) (xy 79.520263 -386.837357) (xy 79.554428 -386.790669)
			(xy 79.594204 -386.748659) (xy 79.6163 -386.729986) (xy 79.623278 -386.723645) (xy 79.632531 -386.707236)
			(xy 79.634334 -386.697982) (xy 79.638652 -386.666994) (xy 79.639555 -386.657757) (xy 79.635531 -386.639658)
			(xy 79.630778 -386.631688) (xy 79.617788 -386.611267) (xy 79.597209 -386.567464) (xy 79.583222 -386.521133)
			(xy 79.576127 -386.47326) (xy 79.57566 -386.449062) (xy 79.57604 -386.425386) (xy 79.582774 -386.378515)
			(xy 79.596141 -386.333088) (xy 79.605632 -386.311394) (xy 79.60995 -386.301996) (xy 79.610712 -386.28193)
			(xy 79.578454 -386.19557) (xy 79.564738 -386.180838) (xy 79.55534 -386.17652) (xy 79.530966 -386.16484)
			(xy 79.486096 -386.134711) (xy 79.446719 -386.097691) (xy 79.413881 -386.054764) (xy 79.388456 -386.007071)
			(xy 79.371119 -385.955881) (xy 79.362331 -385.902553) (xy 79.361792 -385.87553) (xy 77.874698 -385.87553)
			(xy 77.845314 -385.912279) (xy 77.823314 -385.93395) (xy 77.814678 -385.942332) (xy 77.80655 -385.964684)
			(xy 77.818488 -386.069078) (xy 77.831442 -386.08889) (xy 77.841856 -386.09524) (xy 77.867216 -386.110721)
			(xy 77.914082 -386.14724) (xy 77.955826 -386.189521) (xy 77.991743 -386.236851) (xy 78.021229 -386.288434)
			(xy 78.043787 -386.3434) (xy 78.059039 -386.400824) (xy 78.066726 -386.45974) (xy 78.067154 -386.489448)
			(xy 78.066535 -386.523468) (xy 78.056469 -386.590759) (xy 78.036551 -386.655819) (xy 78.007221 -386.717212)
			(xy 77.988668 -386.745734) (xy 77.98054 -386.757672) (xy 77.979016 -386.785612) (xy 78.027784 -386.877306)
			(xy 78.032426 -386.8853) (xy 78.046243 -386.897556) (xy 78.063507 -386.904121) (xy 78.072742 -386.904484)
			(xy 78.239366 -386.904484) (xy 78.271877 -386.904943) (xy 78.336491 -386.912228) (xy 78.399883 -386.926698)
			(xy 78.461257 -386.948172) (xy 78.519843 -386.97638) (xy 78.574903 -387.010967) (xy 78.625747 -387.0515)
			(xy 78.649068 -387.074156) (xy 79.374238 -387.799326) (xy 79.396914 -387.822637) (xy 79.437474 -387.873474)
			(xy 79.472092 -387.928531) (xy 79.500331 -387.987115) (xy 79.521838 -388.048491) (xy 79.536342 -388.111889)
			(xy 79.54366 -388.176511) (xy 79.544164 -388.209028) (xy 79.544164 -389.934704) (xy 79.54461 -389.944733)
			(xy 79.552194 -389.963298) (xy 79.558896 -389.970772) (xy 79.586582 -389.998458) (xy 79.59396 -390.005271)
			(xy 79.61249 -390.012973) (xy 79.632556 -390.012973) (xy 79.651086 -390.005271) (xy 79.658464 -389.998458)
			(xy 79.66202 -389.994902) (xy 79.664814 -389.990584) (xy 79.679112 -389.970053) (xy 79.713286 -389.933517)
			(xy 79.75296 -389.903042) (xy 79.797072 -389.879442) (xy 79.844441 -389.86335) (xy 79.8938 -389.855196)
			(xy 79.918814 -389.854694) (xy 79.942804 -389.855166) (xy 79.990194 -389.862674) (xy 80.035826 -389.877502)
			(xy 80.078577 -389.899287) (xy 80.117393 -389.92749) (xy 80.15132 -389.961419) (xy 80.179522 -390.000237)
			(xy 80.201304 -390.042988) (xy 80.21613 -390.088621) (xy 80.223636 -390.136012) (xy 80.224122 -390.160002)
			(xy 80.81316 -390.160002) (xy 80.81712 -390.110948) (xy 80.828897 -390.063164) (xy 80.848188 -390.017888)
			(xy 80.874491 -389.976292) (xy 80.907126 -389.939455) (xy 80.945247 -389.90833) (xy 80.987868 -389.883723)
			(xy 81.033884 -389.866271) (xy 81.082103 -389.856427) (xy 81.131278 -389.854446) (xy 81.180133 -389.860378)
			(xy 81.227404 -389.87407) (xy 81.271866 -389.895168) (xy 81.312369 -389.923124) (xy 81.347862 -389.957216)
			(xy 81.377427 -389.99656) (xy 81.400298 -390.040137) (xy 81.415882 -390.086818) (xy 81.423777 -390.135395)
			(xy 81.424272 -390.160002) (xy 82.01331 -390.160002) (xy 82.01727 -390.110948) (xy 82.029047 -390.063164)
			(xy 82.048338 -390.017888) (xy 82.074641 -389.976292) (xy 82.107276 -389.939455) (xy 82.145397 -389.90833)
			(xy 82.188018 -389.883723) (xy 82.234034 -389.866271) (xy 82.282253 -389.856427) (xy 82.331428 -389.854446)
			(xy 82.380283 -389.860378) (xy 82.427554 -389.87407) (xy 82.472016 -389.895168) (xy 82.512519 -389.923124)
			(xy 82.548012 -389.957216) (xy 82.577577 -389.99656) (xy 82.600448 -390.040137) (xy 82.616032 -390.086818)
			(xy 82.623927 -390.135395) (xy 82.624422 -390.160002) (xy 83.213206 -390.160002) (xy 83.217166 -390.110948)
			(xy 83.228943 -390.063164) (xy 83.248234 -390.017888) (xy 83.274537 -389.976292) (xy 83.307172 -389.939455)
			(xy 83.345293 -389.90833) (xy 83.387914 -389.883723) (xy 83.43393 -389.866271) (xy 83.482149 -389.856427)
			(xy 83.531324 -389.854446) (xy 83.580179 -389.860378) (xy 83.62745 -389.87407) (xy 83.671912 -389.895168)
			(xy 83.712415 -389.923124) (xy 83.747908 -389.957216) (xy 83.777473 -389.99656) (xy 83.800344 -390.040137)
			(xy 83.815928 -390.086818) (xy 83.823823 -390.135395) (xy 83.824318 -390.160002) (xy 84.413356 -390.160002)
			(xy 84.417316 -390.110948) (xy 84.429093 -390.063164) (xy 84.448384 -390.017888) (xy 84.474687 -389.976292)
			(xy 84.507322 -389.939455) (xy 84.545443 -389.90833) (xy 84.588064 -389.883723) (xy 84.63408 -389.866271)
			(xy 84.682299 -389.856427) (xy 84.731474 -389.854446) (xy 84.780329 -389.860378) (xy 84.8276 -389.87407)
			(xy 84.872062 -389.895168) (xy 84.912565 -389.923124) (xy 84.948058 -389.957216) (xy 84.977623 -389.99656)
			(xy 85.000494 -390.040137) (xy 85.016078 -390.086818) (xy 85.023973 -390.135395) (xy 85.024468 -390.160002)
			(xy 85.613252 -390.160002) (xy 85.617212 -390.110948) (xy 85.628989 -390.063164) (xy 85.64828 -390.017888)
			(xy 85.674583 -389.976292) (xy 85.707218 -389.939455) (xy 85.745339 -389.90833) (xy 85.78796 -389.883723)
			(xy 85.833976 -389.866271) (xy 85.882195 -389.856427) (xy 85.93137 -389.854446) (xy 85.980225 -389.860378)
			(xy 86.027496 -389.87407) (xy 86.071958 -389.895168) (xy 86.112461 -389.923124) (xy 86.147954 -389.957216)
			(xy 86.177519 -389.99656) (xy 86.20039 -390.040137) (xy 86.215974 -390.086818) (xy 86.223869 -390.135395)
			(xy 86.224364 -390.160002) (xy 86.813148 -390.160002) (xy 86.817108 -390.110948) (xy 86.828885 -390.063164)
			(xy 86.848176 -390.017888) (xy 86.874479 -389.976292) (xy 86.907114 -389.939455) (xy 86.945235 -389.90833)
			(xy 86.987856 -389.883723) (xy 87.033872 -389.866271) (xy 87.082091 -389.856427) (xy 87.131266 -389.854446)
			(xy 87.180121 -389.860378) (xy 87.227392 -389.87407) (xy 87.271854 -389.895168) (xy 87.312357 -389.923124)
			(xy 87.34785 -389.957216) (xy 87.377415 -389.99656) (xy 87.400286 -390.040137) (xy 87.41587 -390.086818)
			(xy 87.423765 -390.135395) (xy 87.42426 -390.160002) (xy 88.013298 -390.160002) (xy 88.017258 -390.110948)
			(xy 88.029035 -390.063164) (xy 88.048326 -390.017888) (xy 88.074629 -389.976292) (xy 88.107264 -389.939455)
			(xy 88.145385 -389.90833) (xy 88.188006 -389.883723) (xy 88.234022 -389.866271) (xy 88.282241 -389.856427)
			(xy 88.331416 -389.854446) (xy 88.380271 -389.860378) (xy 88.427542 -389.87407) (xy 88.472004 -389.895168)
			(xy 88.512507 -389.923124) (xy 88.548 -389.957216) (xy 88.577565 -389.99656) (xy 88.600436 -390.040137)
			(xy 88.61602 -390.086818) (xy 88.623915 -390.135395) (xy 88.62441 -390.160002) (xy 89.213194 -390.160002)
			(xy 89.217154 -390.110948) (xy 89.228931 -390.063164) (xy 89.248222 -390.017888) (xy 89.274525 -389.976292)
			(xy 89.30716 -389.939455) (xy 89.345281 -389.90833) (xy 89.387902 -389.883723) (xy 89.433918 -389.866271)
			(xy 89.482137 -389.856427) (xy 89.531312 -389.854446) (xy 89.580167 -389.860378) (xy 89.627438 -389.87407)
			(xy 89.6719 -389.895168) (xy 89.712403 -389.923124) (xy 89.747896 -389.957216) (xy 89.777461 -389.99656)
			(xy 89.800332 -390.040137) (xy 89.815916 -390.086818) (xy 89.823811 -390.135395) (xy 89.824306 -390.160002)
			(xy 90.413344 -390.160002) (xy 90.417304 -390.110948) (xy 90.429081 -390.063164) (xy 90.448372 -390.017888)
			(xy 90.474675 -389.976292) (xy 90.50731 -389.939455) (xy 90.545431 -389.90833) (xy 90.588052 -389.883723)
			(xy 90.634068 -389.866271) (xy 90.682287 -389.856427) (xy 90.731462 -389.854446) (xy 90.780317 -389.860378)
			(xy 90.827588 -389.87407) (xy 90.87205 -389.895168) (xy 90.912553 -389.923124) (xy 90.948046 -389.957216)
			(xy 90.977611 -389.99656) (xy 91.000482 -390.040137) (xy 91.016066 -390.086818) (xy 91.023961 -390.135395)
			(xy 91.024456 -390.160002) (xy 91.61324 -390.160002) (xy 91.6172 -390.110948) (xy 91.628977 -390.063164)
			(xy 91.648268 -390.017888) (xy 91.674571 -389.976292) (xy 91.707206 -389.939455) (xy 91.745327 -389.90833)
			(xy 91.787948 -389.883723) (xy 91.833964 -389.866271) (xy 91.882183 -389.856427) (xy 91.931358 -389.854446)
			(xy 91.980213 -389.860378) (xy 92.027484 -389.87407) (xy 92.071946 -389.895168) (xy 92.112449 -389.923124)
			(xy 92.147942 -389.957216) (xy 92.177507 -389.99656) (xy 92.200378 -390.040137) (xy 92.215962 -390.086818)
			(xy 92.223857 -390.135395) (xy 92.224352 -390.160002) (xy 92.813136 -390.160002) (xy 92.817096 -390.110948)
			(xy 92.828873 -390.063164) (xy 92.848164 -390.017888) (xy 92.874467 -389.976292) (xy 92.907102 -389.939455)
			(xy 92.945223 -389.90833) (xy 92.987844 -389.883723) (xy 93.03386 -389.866271) (xy 93.082079 -389.856427)
			(xy 93.131254 -389.854446) (xy 93.180109 -389.860378) (xy 93.22738 -389.87407) (xy 93.271842 -389.895168)
			(xy 93.312345 -389.923124) (xy 93.347838 -389.957216) (xy 93.377403 -389.99656) (xy 93.400274 -390.040137)
			(xy 93.415858 -390.086818) (xy 93.423753 -390.135395) (xy 93.424248 -390.160002) (xy 94.013286 -390.160002)
			(xy 94.017246 -390.110948) (xy 94.029023 -390.063164) (xy 94.048314 -390.017888) (xy 94.074617 -389.976292)
			(xy 94.107252 -389.939455) (xy 94.145373 -389.90833) (xy 94.187994 -389.883723) (xy 94.23401 -389.866271)
			(xy 94.282229 -389.856427) (xy 94.331404 -389.854446) (xy 94.380259 -389.860378) (xy 94.42753 -389.87407)
			(xy 94.471992 -389.895168) (xy 94.512495 -389.923124) (xy 94.547988 -389.957216) (xy 94.577553 -389.99656)
			(xy 94.600424 -390.040137) (xy 94.616008 -390.086818) (xy 94.623903 -390.135395) (xy 94.624398 -390.160002)
			(xy 95.213182 -390.160002) (xy 95.217142 -390.110948) (xy 95.228919 -390.063164) (xy 95.24821 -390.017888)
			(xy 95.274513 -389.976292) (xy 95.307148 -389.939455) (xy 95.345269 -389.90833) (xy 95.38789 -389.883723)
			(xy 95.433906 -389.866271) (xy 95.482125 -389.856427) (xy 95.5313 -389.854446) (xy 95.580155 -389.860378)
			(xy 95.627426 -389.87407) (xy 95.671888 -389.895168) (xy 95.712391 -389.923124) (xy 95.747884 -389.957216)
			(xy 95.777449 -389.99656) (xy 95.80032 -390.040137) (xy 95.815904 -390.086818) (xy 95.823799 -390.135395)
			(xy 95.824294 -390.160002) (xy 96.413332 -390.160002) (xy 96.417292 -390.110948) (xy 96.429069 -390.063164)
			(xy 96.44836 -390.017888) (xy 96.474663 -389.976292) (xy 96.507298 -389.939455) (xy 96.545419 -389.90833)
			(xy 96.58804 -389.883723) (xy 96.634056 -389.866271) (xy 96.682275 -389.856427) (xy 96.73145 -389.854446)
			(xy 96.780305 -389.860378) (xy 96.827576 -389.87407) (xy 96.872038 -389.895168) (xy 96.912541 -389.923124)
			(xy 96.948034 -389.957216) (xy 96.977599 -389.99656) (xy 97.00047 -390.040137) (xy 97.016054 -390.086818)
			(xy 97.023949 -390.135395) (xy 97.024444 -390.160002) (xy 97.613228 -390.160002) (xy 97.617188 -390.110948)
			(xy 97.628965 -390.063164) (xy 97.648256 -390.017888) (xy 97.674559 -389.976292) (xy 97.707194 -389.939455)
			(xy 97.745315 -389.90833) (xy 97.787936 -389.883723) (xy 97.833952 -389.866271) (xy 97.882171 -389.856427)
			(xy 97.931346 -389.854446) (xy 97.980201 -389.860378) (xy 98.027472 -389.87407) (xy 98.071934 -389.895168)
			(xy 98.112437 -389.923124) (xy 98.14793 -389.957216) (xy 98.177495 -389.99656) (xy 98.200366 -390.040137)
			(xy 98.21595 -390.086818) (xy 98.223845 -390.135395) (xy 98.22434 -390.160002) (xy 98.223845 -390.184609)
			(xy 98.223621 -390.185989) (xy 98.942908 -390.185989) (xy 98.942908 -390.134015) (xy 98.951038 -390.08268)
			(xy 98.967099 -390.03325) (xy 98.990695 -389.98694) (xy 99.021245 -389.944892) (xy 99.057996 -389.908141)
			(xy 99.100044 -389.877591) (xy 99.146354 -389.853995) (xy 99.195784 -389.837934) (xy 99.247119 -389.829804)
			(xy 99.299093 -389.829804) (xy 99.350428 -389.837934) (xy 99.399858 -389.853995) (xy 99.446168 -389.877591)
			(xy 99.488216 -389.908141) (xy 99.524967 -389.944892) (xy 99.555517 -389.98694) (xy 99.579113 -390.03325)
			(xy 99.595174 -390.08268) (xy 99.603304 -390.134015) (xy 99.603814 -390.160002) (xy 99.603304 -390.185989)
			(xy 99.595174 -390.237324) (xy 99.579113 -390.286754) (xy 99.555517 -390.333064) (xy 99.524967 -390.375112)
			(xy 99.488216 -390.411863) (xy 99.446168 -390.442413) (xy 99.399858 -390.466009) (xy 99.350428 -390.48207)
			(xy 99.299093 -390.4902) (xy 99.247119 -390.4902) (xy 99.195784 -390.48207) (xy 99.146354 -390.466009)
			(xy 99.100044 -390.442413) (xy 99.057996 -390.411863) (xy 99.021245 -390.375112) (xy 98.990695 -390.333064)
			(xy 98.967099 -390.286754) (xy 98.951038 -390.237324) (xy 98.942908 -390.185989) (xy 98.223621 -390.185989)
			(xy 98.21595 -390.233186) (xy 98.200366 -390.279867) (xy 98.177495 -390.323444) (xy 98.14793 -390.362788)
			(xy 98.112437 -390.39688) (xy 98.071934 -390.424836) (xy 98.027472 -390.445934) (xy 97.980201 -390.459626)
			(xy 97.931346 -390.465558) (xy 97.882171 -390.463577) (xy 97.833952 -390.453733) (xy 97.787936 -390.436281)
			(xy 97.745315 -390.411674) (xy 97.707194 -390.380549) (xy 97.674559 -390.343712) (xy 97.648256 -390.302116)
			(xy 97.628965 -390.25684) (xy 97.617188 -390.209056) (xy 97.613228 -390.160002) (xy 97.024444 -390.160002)
			(xy 97.023949 -390.184609) (xy 97.016054 -390.233186) (xy 97.00047 -390.279867) (xy 96.977599 -390.323444)
			(xy 96.948034 -390.362788) (xy 96.912541 -390.39688) (xy 96.872038 -390.424836) (xy 96.827576 -390.445934)
			(xy 96.780305 -390.459626) (xy 96.73145 -390.465558) (xy 96.682275 -390.463577) (xy 96.634056 -390.453733)
			(xy 96.58804 -390.436281) (xy 96.545419 -390.411674) (xy 96.507298 -390.380549) (xy 96.474663 -390.343712)
			(xy 96.44836 -390.302116) (xy 96.429069 -390.25684) (xy 96.417292 -390.209056) (xy 96.413332 -390.160002)
			(xy 95.824294 -390.160002) (xy 95.823799 -390.184609) (xy 95.815904 -390.233186) (xy 95.80032 -390.279867)
			(xy 95.777449 -390.323444) (xy 95.747884 -390.362788) (xy 95.712391 -390.39688) (xy 95.671888 -390.424836)
			(xy 95.627426 -390.445934) (xy 95.580155 -390.459626) (xy 95.5313 -390.465558) (xy 95.482125 -390.463577)
			(xy 95.433906 -390.453733) (xy 95.38789 -390.436281) (xy 95.345269 -390.411674) (xy 95.307148 -390.380549)
			(xy 95.274513 -390.343712) (xy 95.24821 -390.302116) (xy 95.228919 -390.25684) (xy 95.217142 -390.209056)
			(xy 95.213182 -390.160002) (xy 94.624398 -390.160002) (xy 94.623903 -390.184609) (xy 94.616008 -390.233186)
			(xy 94.600424 -390.279867) (xy 94.577553 -390.323444) (xy 94.547988 -390.362788) (xy 94.512495 -390.39688)
			(xy 94.471992 -390.424836) (xy 94.42753 -390.445934) (xy 94.380259 -390.459626) (xy 94.331404 -390.465558)
			(xy 94.282229 -390.463577) (xy 94.23401 -390.453733) (xy 94.187994 -390.436281) (xy 94.145373 -390.411674)
			(xy 94.107252 -390.380549) (xy 94.074617 -390.343712) (xy 94.048314 -390.302116) (xy 94.029023 -390.25684)
			(xy 94.017246 -390.209056) (xy 94.013286 -390.160002) (xy 93.424248 -390.160002) (xy 93.423753 -390.184609)
			(xy 93.415858 -390.233186) (xy 93.400274 -390.279867) (xy 93.377403 -390.323444) (xy 93.347838 -390.362788)
			(xy 93.312345 -390.39688) (xy 93.271842 -390.424836) (xy 93.22738 -390.445934) (xy 93.180109 -390.459626)
			(xy 93.131254 -390.465558) (xy 93.082079 -390.463577) (xy 93.03386 -390.453733) (xy 92.987844 -390.436281)
			(xy 92.945223 -390.411674) (xy 92.907102 -390.380549) (xy 92.874467 -390.343712) (xy 92.848164 -390.302116)
			(xy 92.828873 -390.25684) (xy 92.817096 -390.209056) (xy 92.813136 -390.160002) (xy 92.224352 -390.160002)
			(xy 92.223857 -390.184609) (xy 92.215962 -390.233186) (xy 92.200378 -390.279867) (xy 92.177507 -390.323444)
			(xy 92.147942 -390.362788) (xy 92.112449 -390.39688) (xy 92.071946 -390.424836) (xy 92.027484 -390.445934)
			(xy 91.980213 -390.459626) (xy 91.931358 -390.465558) (xy 91.882183 -390.463577) (xy 91.833964 -390.453733)
			(xy 91.787948 -390.436281) (xy 91.745327 -390.411674) (xy 91.707206 -390.380549) (xy 91.674571 -390.343712)
			(xy 91.648268 -390.302116) (xy 91.628977 -390.25684) (xy 91.6172 -390.209056) (xy 91.61324 -390.160002)
			(xy 91.024456 -390.160002) (xy 91.023961 -390.184609) (xy 91.016066 -390.233186) (xy 91.000482 -390.279867)
			(xy 90.977611 -390.323444) (xy 90.948046 -390.362788) (xy 90.912553 -390.39688) (xy 90.87205 -390.424836)
			(xy 90.827588 -390.445934) (xy 90.780317 -390.459626) (xy 90.731462 -390.465558) (xy 90.682287 -390.463577)
			(xy 90.634068 -390.453733) (xy 90.588052 -390.436281) (xy 90.545431 -390.411674) (xy 90.50731 -390.380549)
			(xy 90.474675 -390.343712) (xy 90.448372 -390.302116) (xy 90.429081 -390.25684) (xy 90.417304 -390.209056)
			(xy 90.413344 -390.160002) (xy 89.824306 -390.160002) (xy 89.823811 -390.184609) (xy 89.815916 -390.233186)
			(xy 89.800332 -390.279867) (xy 89.777461 -390.323444) (xy 89.747896 -390.362788) (xy 89.712403 -390.39688)
			(xy 89.6719 -390.424836) (xy 89.627438 -390.445934) (xy 89.580167 -390.459626) (xy 89.531312 -390.465558)
			(xy 89.482137 -390.463577) (xy 89.433918 -390.453733) (xy 89.387902 -390.436281) (xy 89.345281 -390.411674)
			(xy 89.30716 -390.380549) (xy 89.274525 -390.343712) (xy 89.248222 -390.302116) (xy 89.228931 -390.25684)
			(xy 89.217154 -390.209056) (xy 89.213194 -390.160002) (xy 88.62441 -390.160002) (xy 88.623915 -390.184609)
			(xy 88.61602 -390.233186) (xy 88.600436 -390.279867) (xy 88.577565 -390.323444) (xy 88.548 -390.362788)
			(xy 88.512507 -390.39688) (xy 88.472004 -390.424836) (xy 88.427542 -390.445934) (xy 88.380271 -390.459626)
			(xy 88.331416 -390.465558) (xy 88.282241 -390.463577) (xy 88.234022 -390.453733) (xy 88.188006 -390.436281)
			(xy 88.145385 -390.411674) (xy 88.107264 -390.380549) (xy 88.074629 -390.343712) (xy 88.048326 -390.302116)
			(xy 88.029035 -390.25684) (xy 88.017258 -390.209056) (xy 88.013298 -390.160002) (xy 87.42426 -390.160002)
			(xy 87.423765 -390.184609) (xy 87.41587 -390.233186) (xy 87.400286 -390.279867) (xy 87.377415 -390.323444)
			(xy 87.34785 -390.362788) (xy 87.312357 -390.39688) (xy 87.271854 -390.424836) (xy 87.227392 -390.445934)
			(xy 87.180121 -390.459626) (xy 87.131266 -390.465558) (xy 87.082091 -390.463577) (xy 87.033872 -390.453733)
			(xy 86.987856 -390.436281) (xy 86.945235 -390.411674) (xy 86.907114 -390.380549) (xy 86.874479 -390.343712)
			(xy 86.848176 -390.302116) (xy 86.828885 -390.25684) (xy 86.817108 -390.209056) (xy 86.813148 -390.160002)
			(xy 86.224364 -390.160002) (xy 86.223869 -390.184609) (xy 86.215974 -390.233186) (xy 86.20039 -390.279867)
			(xy 86.177519 -390.323444) (xy 86.147954 -390.362788) (xy 86.112461 -390.39688) (xy 86.071958 -390.424836)
			(xy 86.027496 -390.445934) (xy 85.980225 -390.459626) (xy 85.93137 -390.465558) (xy 85.882195 -390.463577)
			(xy 85.833976 -390.453733) (xy 85.78796 -390.436281) (xy 85.745339 -390.411674) (xy 85.707218 -390.380549)
			(xy 85.674583 -390.343712) (xy 85.64828 -390.302116) (xy 85.628989 -390.25684) (xy 85.617212 -390.209056)
			(xy 85.613252 -390.160002) (xy 85.024468 -390.160002) (xy 85.023973 -390.184609) (xy 85.016078 -390.233186)
			(xy 85.000494 -390.279867) (xy 84.977623 -390.323444) (xy 84.948058 -390.362788) (xy 84.912565 -390.39688)
			(xy 84.872062 -390.424836) (xy 84.8276 -390.445934) (xy 84.780329 -390.459626) (xy 84.731474 -390.465558)
			(xy 84.682299 -390.463577) (xy 84.63408 -390.453733) (xy 84.588064 -390.436281) (xy 84.545443 -390.411674)
			(xy 84.507322 -390.380549) (xy 84.474687 -390.343712) (xy 84.448384 -390.302116) (xy 84.429093 -390.25684)
			(xy 84.417316 -390.209056) (xy 84.413356 -390.160002) (xy 83.824318 -390.160002) (xy 83.823823 -390.184609)
			(xy 83.815928 -390.233186) (xy 83.800344 -390.279867) (xy 83.777473 -390.323444) (xy 83.747908 -390.362788)
			(xy 83.712415 -390.39688) (xy 83.671912 -390.424836) (xy 83.62745 -390.445934) (xy 83.580179 -390.459626)
			(xy 83.531324 -390.465558) (xy 83.482149 -390.463577) (xy 83.43393 -390.453733) (xy 83.387914 -390.436281)
			(xy 83.345293 -390.411674) (xy 83.307172 -390.380549) (xy 83.274537 -390.343712) (xy 83.248234 -390.302116)
			(xy 83.228943 -390.25684) (xy 83.217166 -390.209056) (xy 83.213206 -390.160002) (xy 82.624422 -390.160002)
			(xy 82.623927 -390.184609) (xy 82.616032 -390.233186) (xy 82.600448 -390.279867) (xy 82.577577 -390.323444)
			(xy 82.548012 -390.362788) (xy 82.512519 -390.39688) (xy 82.472016 -390.424836) (xy 82.427554 -390.445934)
			(xy 82.380283 -390.459626) (xy 82.331428 -390.465558) (xy 82.282253 -390.463577) (xy 82.234034 -390.453733)
			(xy 82.188018 -390.436281) (xy 82.145397 -390.411674) (xy 82.107276 -390.380549) (xy 82.074641 -390.343712)
			(xy 82.048338 -390.302116) (xy 82.029047 -390.25684) (xy 82.01727 -390.209056) (xy 82.01331 -390.160002)
			(xy 81.424272 -390.160002) (xy 81.423777 -390.184609) (xy 81.415882 -390.233186) (xy 81.400298 -390.279867)
			(xy 81.377427 -390.323444) (xy 81.347862 -390.362788) (xy 81.312369 -390.39688) (xy 81.271866 -390.424836)
			(xy 81.227404 -390.445934) (xy 81.180133 -390.459626) (xy 81.131278 -390.465558) (xy 81.082103 -390.463577)
			(xy 81.033884 -390.453733) (xy 80.987868 -390.436281) (xy 80.945247 -390.411674) (xy 80.907126 -390.380549)
			(xy 80.874491 -390.343712) (xy 80.848188 -390.302116) (xy 80.828897 -390.25684) (xy 80.81712 -390.209056)
			(xy 80.81316 -390.160002) (xy 80.224122 -390.160002) (xy 80.223615 -390.185435) (xy 80.215185 -390.235597)
			(xy 80.198559 -390.283669) (xy 80.174196 -390.32832) (xy 80.142771 -390.368317) (xy 80.1243 -390.385808)
			(xy 80.11668 -390.39292) (xy 80.108044 -390.411462) (xy 80.106012 -390.495536) (xy 80.106293 -390.505861)
			(xy 80.114038 -390.524987) (xy 80.120998 -390.53262) (xy 80.199738 -390.611614) (xy 80.222414 -390.634925)
			(xy 80.262976 -390.685762) (xy 80.297595 -390.740818) (xy 80.325835 -390.799402) (xy 80.347343 -390.860779)
			(xy 80.361848 -390.924176) (xy 80.369168 -390.988798) (xy 80.369664 -391.021316) (xy 80.369664 -391.21842)
			(xy 80.370155 -391.228428) (xy 80.377817 -391.246919) (xy 80.391968 -391.261074) (xy 80.410457 -391.268742)
			(xy 80.420464 -391.26922)
		)
		(stroke
			(width 0)
			(type solid)
		)
		(fill yes)
		(layer "In6.Cu")
		(net "P1V8_CPU1_RT_1D")
	)
	(gr_poly
		(pts
			(xy 206.427578 -366.37722) (xy 206.437642 -366.376783) (xy 206.456228 -366.369051) (xy 206.463646 -366.362234)
			(xy 208.402174 -364.423706) (xy 208.402682 -364.423198) (xy 208.409254 -364.415813) (xy 208.416682 -364.397514)
			(xy 208.41716 -364.387638) (xy 208.41716 -363.638592) (xy 208.41462 -363.62767) (xy 208.411826 -363.622082)
			(xy 208.361399 -363.519895) (xy 208.266967 -363.312478) (xy 208.179979 -363.101831) (xy 208.100546 -362.888221)
			(xy 208.028768 -362.671917) (xy 207.964737 -362.453196) (xy 207.908533 -362.232334) (xy 207.860228 -362.00961)
			(xy 207.819883 -361.785308) (xy 207.787549 -361.559712) (xy 207.763268 -361.333108) (xy 207.747069 -361.105783)
			(xy 207.738974 -360.878025) (xy 207.738472 -360.764074) (xy 207.738973 -360.650124) (xy 207.747079 -360.422367)
			(xy 207.763286 -360.195043) (xy 207.787575 -359.968441) (xy 207.819914 -359.742846) (xy 207.860262 -359.518546)
			(xy 207.908568 -359.295823) (xy 207.964772 -359.074962) (xy 208.028801 -358.85624) (xy 208.100575 -358.639937)
			(xy 208.180003 -358.426325) (xy 208.266983 -358.215676) (xy 208.361406 -358.008256) (xy 208.411826 -357.906066)
			(xy 208.414286 -357.90074) (xy 208.41698 -357.889324) (xy 208.41716 -357.88346) (xy 208.41716 -332.624684)
			(xy 208.41666 -332.614692) (xy 208.409017 -332.596225) (xy 208.394926 -332.582051) (xy 208.385918 -332.577694)
			(xy 208.37144 -332.571852) (xy 208.341468 -332.577694) (xy 207.376268 -333.542894) (xy 206.906876 -334.01254)
			(xy 206.885261 -334.03332) (xy 206.836756 -334.068559) (xy 206.783337 -334.095781) (xy 206.72632 -334.114317)
			(xy 206.667105 -334.12371) (xy 206.637128 -334.1243) (xy 195.831968 -334.1243) (xy 195.822681 -334.124725)
			(xy 195.805328 -334.131355) (xy 195.791453 -334.143707) (xy 195.786756 -334.151732) (xy 195.745354 -334.231742)
			(xy 195.741485 -334.2401) (xy 195.739354 -334.258381) (xy 195.743794 -334.276241) (xy 195.748656 -334.284066)
			(xy 195.74891 -334.28432) (xy 195.74891 -334.284574) (xy 195.764462 -334.307437) (xy 195.789517 -334.356729)
			(xy 195.807197 -334.40912) (xy 195.817132 -334.463515) (xy 195.819113 -334.518773) (xy 195.813099 -334.57374)
			(xy 195.799216 -334.627262) (xy 195.777755 -334.678222) (xy 195.763896 -334.70215) (xy 195.746711 -334.729372)
			(xy 195.704704 -334.778147) (xy 195.68033 -334.799178) (xy 195.675758 -334.802734) (xy 195.669408 -334.810862)
			(xy 195.65747 -334.835246) (xy 195.655093 -334.840525) (xy 195.652524 -334.85181) (xy 195.65239 -334.857598)
			(xy 195.65239 -334.913986) (xy 195.652515 -334.919775) (xy 195.655077 -334.931065) (xy 195.65747 -334.936338)
			(xy 195.669408 -334.960722) (xy 195.676012 -334.96885) (xy 195.68033 -334.972406) (xy 195.701641 -334.990626)
			(xy 195.739208 -335.032247) (xy 195.77028 -335.078917) (xy 195.79419 -335.129631) (xy 195.810421 -335.183297)
			(xy 195.818626 -335.238761) (xy 195.818626 -335.294829) (xy 195.810423 -335.350293) (xy 195.794193 -335.40396)
			(xy 195.770285 -335.454674) (xy 195.739214 -335.501345) (xy 195.701649 -335.542967) (xy 195.68033 -335.561178)
			(xy 195.676012 -335.564734) (xy 195.669408 -335.572862) (xy 195.65747 -335.597246) (xy 195.655093 -335.602525)
			(xy 195.652524 -335.61381) (xy 195.65239 -335.619598) (xy 195.65239 -335.675986) (xy 195.652515 -335.681775)
			(xy 195.655077 -335.693065) (xy 195.65747 -335.698338) (xy 195.669408 -335.722722) (xy 195.676012 -335.73085)
			(xy 195.68033 -335.734406) (xy 195.701632 -335.752632) (xy 195.739179 -335.79426) (xy 195.770235 -335.840932)
			(xy 195.794131 -335.891643) (xy 195.810353 -335.945305) (xy 195.818553 -336.000762) (xy 195.819014 -336.028792)
			(xy 195.818528 -336.056043) (xy 195.810772 -336.109991) (xy 195.795417 -336.162286) (xy 195.772775 -336.211863)
			(xy 195.743309 -336.257713) (xy 195.707618 -336.298904) (xy 195.666427 -336.334595) (xy 195.620577 -336.364061)
			(xy 195.571 -336.386703) (xy 195.518705 -336.402058) (xy 195.464757 -336.409814) (xy 195.410255 -336.409814)
			(xy 195.356307 -336.402058) (xy 195.304012 -336.386703) (xy 195.254435 -336.364061) (xy 195.208585 -336.334595)
			(xy 195.167394 -336.298904) (xy 195.131703 -336.257713) (xy 195.102237 -336.211863) (xy 195.079595 -336.162286)
			(xy 195.06424 -336.109991) (xy 195.056484 -336.056043) (xy 195.055998 -336.028792) (xy 195.056492 -336.000764)
			(xy 195.06469 -335.94531) (xy 195.080908 -335.89165) (xy 195.104798 -335.840939) (xy 195.135846 -335.794266)
			(xy 195.173386 -335.752635) (xy 195.194682 -335.734406) (xy 195.199254 -335.73085) (xy 195.205604 -335.722722)
			(xy 195.217542 -335.698338) (xy 195.219917 -335.693059) (xy 195.222482 -335.681773) (xy 195.222622 -335.675986)
			(xy 195.222622 -335.619598) (xy 195.222496 -335.613809) (xy 195.219931 -335.602521) (xy 195.217542 -335.597246)
			(xy 195.205604 -335.572862) (xy 195.199 -335.564734) (xy 195.194682 -335.561178) (xy 195.173371 -335.542959)
			(xy 195.135806 -335.501338) (xy 195.104735 -335.454669) (xy 195.080827 -335.403956) (xy 195.064597 -335.350291)
			(xy 195.056394 -335.294828) (xy 195.056394 -335.238762) (xy 195.064599 -335.183299) (xy 195.08083 -335.129634)
			(xy 195.10474 -335.078922) (xy 195.135812 -335.032254) (xy 195.173379 -334.990634) (xy 195.194682 -334.972406)
			(xy 195.199 -334.96885) (xy 195.205604 -334.960722) (xy 195.217542 -334.936338) (xy 195.219917 -334.931059)
			(xy 195.222482 -334.919773) (xy 195.222622 -334.913986) (xy 195.222622 -334.857598) (xy 195.222496 -334.851809)
			(xy 195.219931 -334.840521) (xy 195.217542 -334.835246) (xy 195.205604 -334.810862) (xy 195.199254 -334.802734)
			(xy 195.194682 -334.799178) (xy 195.173381 -334.780953) (xy 195.135834 -334.739324) (xy 195.104779 -334.692652)
			(xy 195.080884 -334.64194) (xy 195.064664 -334.588279) (xy 195.056466 -334.532822) (xy 195.055998 -334.504792)
			(xy 195.056533 -334.475876) (xy 195.065261 -334.418705) (xy 195.082515 -334.363506) (xy 195.107902 -334.311543)
			(xy 195.140839 -334.264006) (xy 195.180572 -334.221983) (xy 195.203064 -334.203802) (xy 195.211882 -334.196206)
			(xy 195.222043 -334.175297) (xy 195.222622 -334.16367) (xy 195.222622 -334.071722) (xy 195.212462 -334.050894)
			(xy 195.20281 -334.043528) (xy 195.180367 -334.025337) (xy 195.140704 -333.983336) (xy 195.107826 -333.935836)
			(xy 195.082482 -333.883923) (xy 195.065253 -333.828783) (xy 195.056532 -333.771676) (xy 195.055998 -333.742792)
			(xy 195.056145 -333.730051) (xy 195.057922 -333.704629) (xy 195.059554 -333.691992) (xy 195.0593 -333.691992)
			(xy 195.063417 -333.664877) (xy 195.07842 -333.612126) (xy 195.100824 -333.562067) (xy 195.130167 -333.515734)
			(xy 195.165844 -333.474081) (xy 195.207119 -333.437968) (xy 195.253142 -333.40814) (xy 195.302963 -333.385212)
			(xy 195.355554 -333.369656) (xy 195.40983 -333.361793) (xy 195.437252 -333.361284) (xy 206.458058 -333.361284)
			(xy 206.467932 -333.360817) (xy 206.486218 -333.353361) (xy 206.493618 -333.346806) (xy 206.493872 -333.346552)
			(xy 207.55737 -332.283308) (xy 208.1784 -331.662278) (xy 208.185174 -331.654852) (xy 208.19276 -331.636255)
			(xy 208.193132 -331.62621) (xy 208.193132 -331.4065) (xy 208.192644 -331.39649) (xy 208.184986 -331.377993)
			(xy 208.170834 -331.363832) (xy 208.152342 -331.356162) (xy 208.142332 -331.3557) (xy 197.638162 -331.3557)
			(xy 197.628095 -331.35527) (xy 197.609501 -331.347546) (xy 197.602094 -331.340714) (xy 195.521326 -329.259946)
			(xy 195.514214 -329.25258) (xy 195.495418 -329.24496) (xy 174.752762 -329.24496) (xy 174.742696 -329.245392)
			(xy 174.724107 -329.253122) (xy 174.716694 -329.259946) (xy 168.61842 -335.35822) (xy 174.360114 -335.35822)
			(xy 174.363841 -335.304972) (xy 174.374954 -335.252763) (xy 174.393236 -335.202614) (xy 174.41833 -335.155502)
			(xy 174.449747 -335.112349) (xy 174.486872 -335.073996) (xy 174.507652 -335.057242) (xy 174.516399 -335.049667)
			(xy 174.526589 -335.028918) (xy 174.52721 -335.017364) (xy 174.52721 -334.9371) (xy 174.526636 -334.925533)
			(xy 174.516444 -334.904762) (xy 174.507652 -334.897222) (xy 174.486901 -334.88043) (xy 174.449772 -334.842081)
			(xy 174.418351 -334.798931) (xy 174.393252 -334.751822) (xy 174.374964 -334.701675) (xy 174.363846 -334.649467)
			(xy 174.360114 -334.59622) (xy 174.363841 -334.542972) (xy 174.374954 -334.490763) (xy 174.393236 -334.440614)
			(xy 174.41833 -334.393502) (xy 174.449747 -334.350349) (xy 174.486872 -334.311996) (xy 174.507652 -334.295242)
			(xy 174.516399 -334.287667) (xy 174.526589 -334.266918) (xy 174.52721 -334.255364) (xy 174.52721 -334.1751)
			(xy 174.526636 -334.163533) (xy 174.516444 -334.142762) (xy 174.507652 -334.135222) (xy 174.485169 -334.117031)
			(xy 174.445436 -334.07501) (xy 174.412498 -334.027474) (xy 174.38711 -333.975513) (xy 174.369853 -333.920316)
			(xy 174.361122 -333.863148) (xy 174.360586 -333.834232) (xy 174.361072 -333.806981) (xy 174.368828 -333.753033)
			(xy 174.384183 -333.700738) (xy 174.406825 -333.651161) (xy 174.436291 -333.605311) (xy 174.471982 -333.56412)
			(xy 174.513173 -333.528429) (xy 174.559023 -333.498963) (xy 174.6086 -333.476321) (xy 174.660895 -333.460966)
			(xy 174.714843 -333.45321) (xy 174.769345 -333.45321) (xy 174.823293 -333.460966) (xy 174.875588 -333.476321)
			(xy 174.925165 -333.498963) (xy 174.971015 -333.528429) (xy 175.012206 -333.56412) (xy 175.047897 -333.605311)
			(xy 175.077363 -333.651161) (xy 175.100005 -333.700738) (xy 175.11536 -333.753033) (xy 175.123116 -333.806981)
			(xy 175.123602 -333.834232) (xy 175.123034 -333.863147) (xy 175.114315 -333.920316) (xy 175.097067 -333.975514)
			(xy 175.071685 -334.027476) (xy 175.03875 -334.075011) (xy 174.999018 -334.11703) (xy 174.976536 -334.135222)
			(xy 174.967758 -334.142768) (xy 174.957586 -334.163539) (xy 174.956978 -334.1751) (xy 174.956978 -334.255364)
			(xy 174.957577 -334.266928) (xy 174.967752 -334.287699) (xy 174.976536 -334.295242) (xy 174.997351 -334.311958)
			(xy 175.034482 -334.350315) (xy 175.065904 -334.393474) (xy 175.091002 -334.440592) (xy 175.109288 -334.490748)
			(xy 175.120402 -334.542964) (xy 175.12413 -334.59622) (xy 175.120397 -334.649475) (xy 175.109277 -334.701689)
			(xy 175.090986 -334.751844) (xy 175.065883 -334.798959) (xy 175.034457 -334.842115) (xy 174.997321 -334.880469)
			(xy 174.976536 -334.897222) (xy 174.967758 -334.904768) (xy 174.957586 -334.925539) (xy 174.956978 -334.9371)
			(xy 174.956978 -335.017364) (xy 174.957577 -335.028928) (xy 174.967752 -335.049699) (xy 174.976536 -335.057242)
			(xy 174.997351 -335.073958) (xy 175.034482 -335.112315) (xy 175.065904 -335.155474) (xy 175.091002 -335.202592)
			(xy 175.109288 -335.252748) (xy 175.115518 -335.28202) (xy 176.773114 -335.28202) (xy 176.776841 -335.228772)
			(xy 176.787954 -335.176563) (xy 176.806236 -335.126414) (xy 176.83133 -335.079302) (xy 176.862747 -335.036149)
			(xy 176.899872 -334.997796) (xy 176.920652 -334.981042) (xy 176.929399 -334.973467) (xy 176.939589 -334.952718)
			(xy 176.94021 -334.941164) (xy 176.94021 -334.8609) (xy 176.939636 -334.849333) (xy 176.929444 -334.828562)
			(xy 176.920652 -334.821022) (xy 176.899901 -334.80423) (xy 176.862772 -334.765881) (xy 176.831351 -334.722731)
			(xy 176.806252 -334.675622) (xy 176.787964 -334.625475) (xy 176.776846 -334.573267) (xy 176.773114 -334.52002)
			(xy 176.776841 -334.466772) (xy 176.787954 -334.414563) (xy 176.806236 -334.364414) (xy 176.83133 -334.317302)
			(xy 176.862747 -334.274149) (xy 176.899872 -334.235796) (xy 176.920652 -334.219042) (xy 176.929399 -334.211467)
			(xy 176.939589 -334.190718) (xy 176.94021 -334.179164) (xy 176.94021 -334.0989) (xy 176.939636 -334.087333)
			(xy 176.929444 -334.066562) (xy 176.920652 -334.059022) (xy 176.898169 -334.040831) (xy 176.858436 -333.99881)
			(xy 176.825498 -333.951274) (xy 176.80011 -333.899313) (xy 176.782853 -333.844116) (xy 176.774122 -333.786948)
			(xy 176.773586 -333.758032) (xy 176.774072 -333.730781) (xy 176.781828 -333.676833) (xy 176.797183 -333.624538)
			(xy 176.819825 -333.574961) (xy 176.849291 -333.529111) (xy 176.884982 -333.48792) (xy 176.926173 -333.452229)
			(xy 176.972023 -333.422763) (xy 177.0216 -333.400121) (xy 177.073895 -333.384766) (xy 177.127843 -333.37701)
			(xy 177.182345 -333.37701) (xy 177.236293 -333.384766) (xy 177.288588 -333.400121) (xy 177.338165 -333.422763)
			(xy 177.384015 -333.452229) (xy 177.425206 -333.48792) (xy 177.460897 -333.529111) (xy 177.490363 -333.574961)
			(xy 177.513005 -333.624538) (xy 177.52836 -333.676833) (xy 177.536116 -333.730781) (xy 177.536602 -333.758032)
			(xy 177.536034 -333.786947) (xy 177.527315 -333.844116) (xy 177.510067 -333.899314) (xy 177.484685 -333.951276)
			(xy 177.45175 -333.998811) (xy 177.412018 -334.04083) (xy 177.389536 -334.059022) (xy 177.380758 -334.066568)
			(xy 177.370586 -334.087339) (xy 177.369978 -334.0989) (xy 177.369978 -334.179164) (xy 177.370577 -334.190728)
			(xy 177.380752 -334.211499) (xy 177.389536 -334.219042) (xy 177.410351 -334.235758) (xy 177.447482 -334.274115)
			(xy 177.478904 -334.317274) (xy 177.504002 -334.364392) (xy 177.522288 -334.414548) (xy 177.533402 -334.466764)
			(xy 177.53713 -334.52002) (xy 177.533397 -334.573275) (xy 177.522277 -334.625489) (xy 177.503986 -334.675644)
			(xy 177.478883 -334.722759) (xy 177.447457 -334.765915) (xy 177.410321 -334.804269) (xy 177.389536 -334.821022)
			(xy 177.380758 -334.828568) (xy 177.370586 -334.849339) (xy 177.369978 -334.8609) (xy 177.369978 -334.941164)
			(xy 177.370577 -334.952728) (xy 177.380752 -334.973499) (xy 177.389536 -334.981042) (xy 177.410351 -334.997758)
			(xy 177.447482 -335.036115) (xy 177.478904 -335.079274) (xy 177.504002 -335.126392) (xy 177.522288 -335.176548)
			(xy 177.533402 -335.228764) (xy 177.53713 -335.28202) (xy 177.533397 -335.335275) (xy 177.526343 -335.368395)
			(xy 180.425089 -335.368395) (xy 180.42882 -335.315143) (xy 180.439937 -335.26293) (xy 180.458225 -335.212777)
			(xy 180.483325 -335.165663) (xy 180.514748 -335.122508) (xy 180.55188 -335.084155) (xy 180.572664 -335.067402)
			(xy 180.581431 -335.059846) (xy 180.591609 -335.039082) (xy 180.592222 -335.027524) (xy 180.592222 -334.94726)
			(xy 180.59161 -334.935698) (xy 180.581444 -334.914927) (xy 180.572664 -334.907382) (xy 180.551873 -334.890638)
			(xy 180.514742 -334.852284) (xy 180.48332 -334.809128) (xy 180.458221 -334.762014) (xy 180.439935 -334.71186)
			(xy 180.428818 -334.659648) (xy 180.425089 -334.606395) (xy 180.42882 -334.553143) (xy 180.439937 -334.50093)
			(xy 180.458225 -334.450777) (xy 180.483325 -334.403663) (xy 180.514748 -334.360508) (xy 180.55188 -334.322155)
			(xy 180.572664 -334.305402) (xy 180.581431 -334.297846) (xy 180.591609 -334.277082) (xy 180.592222 -334.265524)
			(xy 180.592222 -334.18526) (xy 180.59161 -334.173698) (xy 180.581444 -334.152927) (xy 180.572664 -334.145382)
			(xy 180.550164 -334.12721) (xy 180.510432 -334.085185) (xy 180.477496 -334.037646) (xy 180.452111 -333.985681)
			(xy 180.434857 -333.930481) (xy 180.426131 -333.873309) (xy 180.425598 -333.844392) (xy 180.426084 -333.817141)
			(xy 180.43384 -333.763193) (xy 180.449195 -333.710898) (xy 180.471837 -333.661321) (xy 180.501303 -333.615471)
			(xy 180.536994 -333.57428) (xy 180.578185 -333.538589) (xy 180.624035 -333.509123) (xy 180.673612 -333.486481)
			(xy 180.725907 -333.471126) (xy 180.779855 -333.46337) (xy 180.834357 -333.46337) (xy 180.888305 -333.471126)
			(xy 180.9406 -333.486481) (xy 180.990177 -333.509123) (xy 181.036027 -333.538589) (xy 181.077218 -333.57428)
			(xy 181.112909 -333.615471) (xy 181.142375 -333.661321) (xy 181.165017 -333.710898) (xy 181.180372 -333.763193)
			(xy 181.188128 -333.817141) (xy 181.188614 -333.844392) (xy 181.188123 -333.87331) (xy 181.179393 -333.930484)
			(xy 181.162132 -333.985685) (xy 181.136735 -334.037647) (xy 181.103785 -334.08518) (xy 181.064037 -334.127194)
			(xy 181.041548 -334.145382) (xy 181.03279 -334.152947) (xy 181.022606 -334.173704) (xy 181.02199 -334.18526)
			(xy 181.02199 -334.265524) (xy 181.022608 -334.277086) (xy 181.032769 -334.297857) (xy 181.041548 -334.305402)
			(xy 181.062323 -334.322165) (xy 181.099452 -334.360517) (xy 181.130873 -334.403671) (xy 181.155972 -334.450783)
			(xy 181.174258 -334.500934) (xy 181.185375 -334.553145) (xy 181.189106 -334.606395) (xy 181.185377 -334.659646)
			(xy 181.174261 -334.711856) (xy 181.155976 -334.762008) (xy 181.130879 -334.809121) (xy 181.099459 -334.852275)
			(xy 181.06233 -334.890628) (xy 181.041548 -334.907382) (xy 181.03279 -334.914947) (xy 181.022606 -334.935704)
			(xy 181.02199 -334.94726) (xy 181.02199 -335.027524) (xy 181.022608 -335.039086) (xy 181.032769 -335.059857)
			(xy 181.041548 -335.067402) (xy 181.062323 -335.084165) (xy 181.099452 -335.122517) (xy 181.130873 -335.165671)
			(xy 181.155972 -335.212783) (xy 181.174258 -335.262934) (xy 181.180488 -335.292195) (xy 182.838089 -335.292195)
			(xy 182.84182 -335.238943) (xy 182.852937 -335.18673) (xy 182.871225 -335.136577) (xy 182.896325 -335.089463)
			(xy 182.927748 -335.046308) (xy 182.96488 -335.007955) (xy 182.985664 -334.991202) (xy 182.994431 -334.983646)
			(xy 183.004609 -334.962882) (xy 183.005222 -334.951324) (xy 183.005222 -334.87106) (xy 183.00461 -334.859498)
			(xy 182.994444 -334.838727) (xy 182.985664 -334.831182) (xy 182.964873 -334.814438) (xy 182.927742 -334.776084)
			(xy 182.89632 -334.732928) (xy 182.871221 -334.685814) (xy 182.852935 -334.63566) (xy 182.841818 -334.583448)
			(xy 182.838089 -334.530195) (xy 182.84182 -334.476943) (xy 182.852937 -334.42473) (xy 182.871225 -334.374577)
			(xy 182.896325 -334.327463) (xy 182.927748 -334.284308) (xy 182.96488 -334.245955) (xy 182.985664 -334.229202)
			(xy 182.994431 -334.221646) (xy 183.004609 -334.200882) (xy 183.005222 -334.189324) (xy 183.005222 -334.10906)
			(xy 183.00461 -334.097498) (xy 182.994444 -334.076727) (xy 182.985664 -334.069182) (xy 182.963164 -334.05101)
			(xy 182.923432 -334.008985) (xy 182.890496 -333.961446) (xy 182.865111 -333.909481) (xy 182.847857 -333.854281)
			(xy 182.839131 -333.797109) (xy 182.838598 -333.768192) (xy 182.839084 -333.740941) (xy 182.84684 -333.686993)
			(xy 182.862195 -333.634698) (xy 182.884837 -333.585121) (xy 182.914303 -333.539271) (xy 182.949994 -333.49808)
			(xy 182.991185 -333.462389) (xy 183.037035 -333.432923) (xy 183.086612 -333.410281) (xy 183.138907 -333.394926)
			(xy 183.192855 -333.38717) (xy 183.247357 -333.38717) (xy 183.301305 -333.394926) (xy 183.3536 -333.410281)
			(xy 183.403177 -333.432923) (xy 183.449027 -333.462389) (xy 183.490218 -333.49808) (xy 183.525909 -333.539271)
			(xy 183.555375 -333.585121) (xy 183.578017 -333.634698) (xy 183.593372 -333.686993) (xy 183.601128 -333.740941)
			(xy 183.601614 -333.768192) (xy 183.601123 -333.79711) (xy 183.592393 -333.854284) (xy 183.575132 -333.909485)
			(xy 183.549735 -333.961447) (xy 183.516785 -334.00898) (xy 183.477037 -334.050994) (xy 183.454548 -334.069182)
			(xy 183.44579 -334.076747) (xy 183.435606 -334.097504) (xy 183.43499 -334.10906) (xy 183.43499 -334.189324)
			(xy 183.435608 -334.200886) (xy 183.445769 -334.221657) (xy 183.454548 -334.229202) (xy 183.475323 -334.245965)
			(xy 183.512452 -334.284317) (xy 183.543873 -334.327471) (xy 183.568972 -334.374583) (xy 183.587258 -334.424734)
			(xy 183.598375 -334.476945) (xy 183.602106 -334.530195) (xy 183.598377 -334.583446) (xy 183.587261 -334.635656)
			(xy 183.568976 -334.685808) (xy 183.543879 -334.732921) (xy 183.512459 -334.776075) (xy 183.47533 -334.814428)
			(xy 183.454548 -334.831182) (xy 183.44579 -334.838747) (xy 183.435606 -334.859504) (xy 183.43499 -334.87106)
			(xy 183.43499 -334.951324) (xy 183.435608 -334.962886) (xy 183.445769 -334.983657) (xy 183.454548 -334.991202)
			(xy 183.475323 -335.007965) (xy 183.512452 -335.046317) (xy 183.543873 -335.089471) (xy 183.568972 -335.136583)
			(xy 183.587258 -335.186734) (xy 183.598375 -335.238945) (xy 183.602106 -335.292195) (xy 186.495689 -335.292195)
			(xy 186.49942 -335.238943) (xy 186.510537 -335.18673) (xy 186.528825 -335.136577) (xy 186.553925 -335.089463)
			(xy 186.585348 -335.046308) (xy 186.62248 -335.007955) (xy 186.643264 -334.991202) (xy 186.652031 -334.983646)
			(xy 186.662209 -334.962882) (xy 186.662822 -334.951324) (xy 186.662822 -334.87106) (xy 186.66221 -334.859498)
			(xy 186.652044 -334.838727) (xy 186.643264 -334.831182) (xy 186.622473 -334.814438) (xy 186.585342 -334.776084)
			(xy 186.55392 -334.732928) (xy 186.528821 -334.685814) (xy 186.510535 -334.63566) (xy 186.499418 -334.583448)
			(xy 186.495689 -334.530195) (xy 186.49942 -334.476943) (xy 186.510537 -334.42473) (xy 186.528825 -334.374577)
			(xy 186.553925 -334.327463) (xy 186.585348 -334.284308) (xy 186.62248 -334.245955) (xy 186.643264 -334.229202)
			(xy 186.652031 -334.221646) (xy 186.662209 -334.200882) (xy 186.662822 -334.189324) (xy 186.662822 -334.10906)
			(xy 186.66221 -334.097498) (xy 186.652044 -334.076727) (xy 186.643264 -334.069182) (xy 186.620764 -334.05101)
			(xy 186.581032 -334.008985) (xy 186.548096 -333.961446) (xy 186.522711 -333.909481) (xy 186.505457 -333.854281)
			(xy 186.496731 -333.797109) (xy 186.496198 -333.768192) (xy 186.496684 -333.740941) (xy 186.50444 -333.686993)
			(xy 186.519795 -333.634698) (xy 186.542437 -333.585121) (xy 186.571903 -333.539271) (xy 186.607594 -333.49808)
			(xy 186.648785 -333.462389) (xy 186.694635 -333.432923) (xy 186.744212 -333.410281) (xy 186.796507 -333.394926)
			(xy 186.850455 -333.38717) (xy 186.904957 -333.38717) (xy 186.958905 -333.394926) (xy 187.0112 -333.410281)
			(xy 187.060777 -333.432923) (xy 187.106627 -333.462389) (xy 187.147818 -333.49808) (xy 187.183509 -333.539271)
			(xy 187.212975 -333.585121) (xy 187.235617 -333.634698) (xy 187.250972 -333.686993) (xy 187.258728 -333.740941)
			(xy 187.259214 -333.768192) (xy 187.258723 -333.79711) (xy 187.249993 -333.854284) (xy 187.232732 -333.909485)
			(xy 187.207335 -333.961447) (xy 187.174385 -334.00898) (xy 187.134637 -334.050994) (xy 187.112148 -334.069182)
			(xy 187.10339 -334.076747) (xy 187.093206 -334.097504) (xy 187.09259 -334.10906) (xy 187.09259 -334.189324)
			(xy 187.093208 -334.200886) (xy 187.103369 -334.221657) (xy 187.112148 -334.229202) (xy 187.132923 -334.245965)
			(xy 187.170052 -334.284317) (xy 187.201473 -334.327471) (xy 187.226572 -334.374583) (xy 187.244858 -334.424734)
			(xy 187.255975 -334.476945) (xy 187.259706 -334.530195) (xy 187.255977 -334.583446) (xy 187.244861 -334.635656)
			(xy 187.226576 -334.685808) (xy 187.201479 -334.732921) (xy 187.170059 -334.776075) (xy 187.13293 -334.814428)
			(xy 187.112148 -334.831182) (xy 187.10339 -334.838747) (xy 187.093206 -334.859504) (xy 187.09259 -334.87106)
			(xy 187.09259 -334.951324) (xy 187.093208 -334.962886) (xy 187.103369 -334.983657) (xy 187.112148 -334.991202)
			(xy 187.132923 -335.007965) (xy 187.170052 -335.046317) (xy 187.201473 -335.089471) (xy 187.226572 -335.136583)
			(xy 187.244858 -335.186734) (xy 187.255975 -335.238945) (xy 187.259706 -335.292195) (xy 188.959489 -335.292195)
			(xy 188.96322 -335.238943) (xy 188.974337 -335.18673) (xy 188.992625 -335.136577) (xy 189.017725 -335.089463)
			(xy 189.049148 -335.046308) (xy 189.08628 -335.007955) (xy 189.107064 -334.991202) (xy 189.115831 -334.983646)
			(xy 189.126009 -334.962882) (xy 189.126622 -334.951324) (xy 189.126622 -334.87106) (xy 189.12601 -334.859498)
			(xy 189.115844 -334.838727) (xy 189.107064 -334.831182) (xy 189.086273 -334.814438) (xy 189.049142 -334.776084)
			(xy 189.01772 -334.732928) (xy 188.992621 -334.685814) (xy 188.974335 -334.63566) (xy 188.963218 -334.583448)
			(xy 188.959489 -334.530195) (xy 188.96322 -334.476943) (xy 188.974337 -334.42473) (xy 188.992625 -334.374577)
			(xy 189.017725 -334.327463) (xy 189.049148 -334.284308) (xy 189.08628 -334.245955) (xy 189.107064 -334.229202)
			(xy 189.115831 -334.221646) (xy 189.126009 -334.200882) (xy 189.126622 -334.189324) (xy 189.126622 -334.10906)
			(xy 189.12601 -334.097498) (xy 189.115844 -334.076727) (xy 189.107064 -334.069182) (xy 189.084564 -334.05101)
			(xy 189.044832 -334.008985) (xy 189.011896 -333.961446) (xy 188.986511 -333.909481) (xy 188.969257 -333.854281)
			(xy 188.960531 -333.797109) (xy 188.959998 -333.768192) (xy 188.960484 -333.740941) (xy 188.96824 -333.686993)
			(xy 188.983595 -333.634698) (xy 189.006237 -333.585121) (xy 189.035703 -333.539271) (xy 189.071394 -333.49808)
			(xy 189.112585 -333.462389) (xy 189.158435 -333.432923) (xy 189.208012 -333.410281) (xy 189.260307 -333.394926)
			(xy 189.314255 -333.38717) (xy 189.368757 -333.38717) (xy 189.422705 -333.394926) (xy 189.475 -333.410281)
			(xy 189.524577 -333.432923) (xy 189.570427 -333.462389) (xy 189.611618 -333.49808) (xy 189.647309 -333.539271)
			(xy 189.676775 -333.585121) (xy 189.699417 -333.634698) (xy 189.714772 -333.686993) (xy 189.722528 -333.740941)
			(xy 189.723014 -333.768192) (xy 189.722523 -333.79711) (xy 189.713793 -333.854284) (xy 189.696532 -333.909485)
			(xy 189.671135 -333.961447) (xy 189.638185 -334.00898) (xy 189.598437 -334.050994) (xy 189.575948 -334.069182)
			(xy 189.56719 -334.076747) (xy 189.557006 -334.097504) (xy 189.55639 -334.10906) (xy 189.55639 -334.189324)
			(xy 189.557008 -334.200886) (xy 189.567169 -334.221657) (xy 189.575948 -334.229202) (xy 189.596723 -334.245965)
			(xy 189.633852 -334.284317) (xy 189.665273 -334.327471) (xy 189.690372 -334.374583) (xy 189.708658 -334.424734)
			(xy 189.719775 -334.476945) (xy 189.723506 -334.530195) (xy 189.719777 -334.583446) (xy 189.708661 -334.635656)
			(xy 189.690376 -334.685808) (xy 189.665279 -334.732921) (xy 189.633859 -334.776075) (xy 189.59673 -334.814428)
			(xy 189.575948 -334.831182) (xy 189.56719 -334.838747) (xy 189.557006 -334.859504) (xy 189.55639 -334.87106)
			(xy 189.55639 -334.951324) (xy 189.557008 -334.962886) (xy 189.567169 -334.983657) (xy 189.575948 -334.991202)
			(xy 189.596723 -335.007965) (xy 189.633852 -335.046317) (xy 189.665273 -335.089471) (xy 189.690372 -335.136583)
			(xy 189.708658 -335.186734) (xy 189.719775 -335.238945) (xy 189.721726 -335.266795) (xy 192.617089 -335.266795)
			(xy 192.62082 -335.213543) (xy 192.631937 -335.16133) (xy 192.650225 -335.111177) (xy 192.675325 -335.064063)
			(xy 192.706748 -335.020908) (xy 192.74388 -334.982555) (xy 192.764664 -334.965802) (xy 192.773431 -334.958246)
			(xy 192.783609 -334.937482) (xy 192.784222 -334.925924) (xy 192.784222 -334.84566) (xy 192.78361 -334.834098)
			(xy 192.773444 -334.813327) (xy 192.764664 -334.805782) (xy 192.743873 -334.789038) (xy 192.706742 -334.750684)
			(xy 192.67532 -334.707528) (xy 192.650221 -334.660414) (xy 192.631935 -334.61026) (xy 192.620818 -334.558048)
			(xy 192.617089 -334.504795) (xy 192.62082 -334.451543) (xy 192.631937 -334.39933) (xy 192.650225 -334.349177)
			(xy 192.675325 -334.302063) (xy 192.706748 -334.258908) (xy 192.74388 -334.220555) (xy 192.764664 -334.203802)
			(xy 192.773431 -334.196246) (xy 192.783609 -334.175482) (xy 192.784222 -334.163924) (xy 192.784222 -334.08366)
			(xy 192.78361 -334.072098) (xy 192.773444 -334.051327) (xy 192.764664 -334.043782) (xy 192.742164 -334.02561)
			(xy 192.702432 -333.983585) (xy 192.669496 -333.936046) (xy 192.644111 -333.884081) (xy 192.626857 -333.828881)
			(xy 192.618131 -333.771709) (xy 192.617598 -333.742792) (xy 192.618084 -333.715541) (xy 192.62584 -333.661593)
			(xy 192.641195 -333.609298) (xy 192.663837 -333.559721) (xy 192.693303 -333.513871) (xy 192.728994 -333.47268)
			(xy 192.770185 -333.436989) (xy 192.816035 -333.407523) (xy 192.865612 -333.384881) (xy 192.917907 -333.369526)
			(xy 192.971855 -333.36177) (xy 193.026357 -333.36177) (xy 193.080305 -333.369526) (xy 193.1326 -333.384881)
			(xy 193.182177 -333.407523) (xy 193.228027 -333.436989) (xy 193.269218 -333.47268) (xy 193.304909 -333.513871)
			(xy 193.334375 -333.559721) (xy 193.357017 -333.609298) (xy 193.372372 -333.661593) (xy 193.380128 -333.715541)
			(xy 193.380614 -333.742792) (xy 193.380123 -333.77171) (xy 193.371393 -333.828884) (xy 193.354132 -333.884085)
			(xy 193.328735 -333.936047) (xy 193.295785 -333.98358) (xy 193.256037 -334.025594) (xy 193.233548 -334.043782)
			(xy 193.22479 -334.051347) (xy 193.214606 -334.072104) (xy 193.21399 -334.08366) (xy 193.21399 -334.163924)
			(xy 193.214608 -334.175486) (xy 193.224769 -334.196257) (xy 193.233548 -334.203802) (xy 193.254323 -334.220565)
			(xy 193.291452 -334.258917) (xy 193.322873 -334.302071) (xy 193.347972 -334.349183) (xy 193.366258 -334.399334)
			(xy 193.377375 -334.451545) (xy 193.381106 -334.504795) (xy 193.377377 -334.558046) (xy 193.366261 -334.610256)
			(xy 193.347976 -334.660408) (xy 193.322879 -334.707521) (xy 193.291459 -334.750675) (xy 193.25433 -334.789028)
			(xy 193.233548 -334.805782) (xy 193.22479 -334.813347) (xy 193.214606 -334.834104) (xy 193.21399 -334.84566)
			(xy 193.21399 -334.925924) (xy 193.214608 -334.937486) (xy 193.224769 -334.958257) (xy 193.233548 -334.965802)
			(xy 193.254323 -334.982565) (xy 193.291452 -335.020917) (xy 193.322873 -335.064071) (xy 193.347972 -335.111183)
			(xy 193.366258 -335.161334) (xy 193.377375 -335.213545) (xy 193.381106 -335.266795) (xy 193.377377 -335.320046)
			(xy 193.366261 -335.372256) (xy 193.347976 -335.422408) (xy 193.322879 -335.469521) (xy 193.291459 -335.512675)
			(xy 193.25433 -335.551028) (xy 193.233548 -335.567782) (xy 193.22479 -335.575347) (xy 193.214606 -335.596104)
			(xy 193.21399 -335.60766) (xy 193.21399 -335.687924) (xy 193.214608 -335.699486) (xy 193.224769 -335.720257)
			(xy 193.233548 -335.727802) (xy 193.256042 -335.74598) (xy 193.295775 -335.788004) (xy 193.328711 -335.835542)
			(xy 193.354097 -335.887505) (xy 193.371352 -335.942705) (xy 193.380079 -335.999875) (xy 193.380614 -336.028792)
			(xy 193.380128 -336.056043) (xy 193.372372 -336.109991) (xy 193.357017 -336.162286) (xy 193.334375 -336.211863)
			(xy 193.304909 -336.257713) (xy 193.269218 -336.298904) (xy 193.228027 -336.334595) (xy 193.182177 -336.364061)
			(xy 193.1326 -336.386703) (xy 193.080305 -336.402058) (xy 193.026357 -336.409814) (xy 192.971855 -336.409814)
			(xy 192.917907 -336.402058) (xy 192.865612 -336.386703) (xy 192.816035 -336.364061) (xy 192.770185 -336.334595)
			(xy 192.728994 -336.298904) (xy 192.693303 -336.257713) (xy 192.663837 -336.211863) (xy 192.641195 -336.162286)
			(xy 192.62584 -336.109991) (xy 192.618084 -336.056043) (xy 192.617598 -336.028792) (xy 192.618183 -335.999878)
			(xy 192.626898 -335.942709) (xy 192.644143 -335.887512) (xy 192.669522 -335.83555) (xy 192.702454 -335.788014)
			(xy 192.742184 -335.745994) (xy 192.764664 -335.727802) (xy 192.773431 -335.720246) (xy 192.783609 -335.699482)
			(xy 192.784222 -335.687924) (xy 192.784222 -335.60766) (xy 192.78361 -335.596098) (xy 192.773444 -335.575327)
			(xy 192.764664 -335.567782) (xy 192.743873 -335.551038) (xy 192.706742 -335.512684) (xy 192.67532 -335.469528)
			(xy 192.650221 -335.422414) (xy 192.631935 -335.37226) (xy 192.620818 -335.320048) (xy 192.617089 -335.266795)
			(xy 189.721726 -335.266795) (xy 189.723506 -335.292195) (xy 189.719777 -335.345446) (xy 189.708661 -335.397656)
			(xy 189.690376 -335.447808) (xy 189.665279 -335.494921) (xy 189.633859 -335.538075) (xy 189.59673 -335.576428)
			(xy 189.575948 -335.593182) (xy 189.56719 -335.600747) (xy 189.557006 -335.621504) (xy 189.55639 -335.63306)
			(xy 189.55639 -335.713324) (xy 189.557008 -335.724886) (xy 189.567169 -335.745657) (xy 189.575948 -335.753202)
			(xy 189.598442 -335.77138) (xy 189.638175 -335.813404) (xy 189.671111 -335.860942) (xy 189.696497 -335.912905)
			(xy 189.713752 -335.968105) (xy 189.722479 -336.025275) (xy 189.723014 -336.054192) (xy 189.722528 -336.081443)
			(xy 189.714772 -336.135391) (xy 189.699417 -336.187686) (xy 189.676775 -336.237263) (xy 189.647309 -336.283113)
			(xy 189.611618 -336.324304) (xy 189.570427 -336.359995) (xy 189.524577 -336.389461) (xy 189.475 -336.412103)
			(xy 189.422705 -336.427458) (xy 189.368757 -336.435214) (xy 189.314255 -336.435214) (xy 189.260307 -336.427458)
			(xy 189.208012 -336.412103) (xy 189.158435 -336.389461) (xy 189.112585 -336.359995) (xy 189.071394 -336.324304)
			(xy 189.035703 -336.283113) (xy 189.006237 -336.237263) (xy 188.983595 -336.187686) (xy 188.96824 -336.135391)
			(xy 188.960484 -336.081443) (xy 188.959998 -336.054192) (xy 188.960583 -336.025278) (xy 188.969298 -335.968109)
			(xy 188.986543 -335.912912) (xy 189.011922 -335.86095) (xy 189.044854 -335.813414) (xy 189.084584 -335.771394)
			(xy 189.107064 -335.753202) (xy 189.115831 -335.745646) (xy 189.126009 -335.724882) (xy 189.126622 -335.713324)
			(xy 189.126622 -335.63306) (xy 189.12601 -335.621498) (xy 189.115844 -335.600727) (xy 189.107064 -335.593182)
			(xy 189.086273 -335.576438) (xy 189.049142 -335.538084) (xy 189.01772 -335.494928) (xy 188.992621 -335.447814)
			(xy 188.974335 -335.39766) (xy 188.963218 -335.345448) (xy 188.959489 -335.292195) (xy 187.259706 -335.292195)
			(xy 187.255977 -335.345446) (xy 187.244861 -335.397656) (xy 187.226576 -335.447808) (xy 187.201479 -335.494921)
			(xy 187.170059 -335.538075) (xy 187.13293 -335.576428) (xy 187.112148 -335.593182) (xy 187.10339 -335.600747)
			(xy 187.093206 -335.621504) (xy 187.09259 -335.63306) (xy 187.09259 -335.713324) (xy 187.093208 -335.724886)
			(xy 187.103369 -335.745657) (xy 187.112148 -335.753202) (xy 187.134642 -335.77138) (xy 187.174375 -335.813404)
			(xy 187.207311 -335.860942) (xy 187.232697 -335.912905) (xy 187.249952 -335.968105) (xy 187.258679 -336.025275)
			(xy 187.259214 -336.054192) (xy 187.258728 -336.081443) (xy 187.250972 -336.135391) (xy 187.235617 -336.187686)
			(xy 187.212975 -336.237263) (xy 187.183509 -336.283113) (xy 187.147818 -336.324304) (xy 187.106627 -336.359995)
			(xy 187.060777 -336.389461) (xy 187.0112 -336.412103) (xy 186.958905 -336.427458) (xy 186.904957 -336.435214)
			(xy 186.850455 -336.435214) (xy 186.796507 -336.427458) (xy 186.744212 -336.412103) (xy 186.694635 -336.389461)
			(xy 186.648785 -336.359995) (xy 186.607594 -336.324304) (xy 186.571903 -336.283113) (xy 186.542437 -336.237263)
			(xy 186.519795 -336.187686) (xy 186.50444 -336.135391) (xy 186.496684 -336.081443) (xy 186.496198 -336.054192)
			(xy 186.496783 -336.025278) (xy 186.505498 -335.968109) (xy 186.522743 -335.912912) (xy 186.548122 -335.86095)
			(xy 186.581054 -335.813414) (xy 186.620784 -335.771394) (xy 186.643264 -335.753202) (xy 186.652031 -335.745646)
			(xy 186.662209 -335.724882) (xy 186.662822 -335.713324) (xy 186.662822 -335.63306) (xy 186.66221 -335.621498)
			(xy 186.652044 -335.600727) (xy 186.643264 -335.593182) (xy 186.622473 -335.576438) (xy 186.585342 -335.538084)
			(xy 186.55392 -335.494928) (xy 186.528821 -335.447814) (xy 186.510535 -335.39766) (xy 186.499418 -335.345448)
			(xy 186.495689 -335.292195) (xy 183.602106 -335.292195) (xy 183.598377 -335.345446) (xy 183.587261 -335.397656)
			(xy 183.568976 -335.447808) (xy 183.543879 -335.494921) (xy 183.512459 -335.538075) (xy 183.47533 -335.576428)
			(xy 183.454548 -335.593182) (xy 183.44579 -335.600747) (xy 183.435606 -335.621504) (xy 183.43499 -335.63306)
			(xy 183.43499 -335.713324) (xy 183.435608 -335.724886) (xy 183.445769 -335.745657) (xy 183.454548 -335.753202)
			(xy 183.477042 -335.77138) (xy 183.516775 -335.813404) (xy 183.549711 -335.860942) (xy 183.575097 -335.912905)
			(xy 183.592352 -335.968105) (xy 183.601079 -336.025275) (xy 183.601614 -336.054192) (xy 183.601128 -336.081443)
			(xy 183.593372 -336.135391) (xy 183.578017 -336.187686) (xy 183.555375 -336.237263) (xy 183.525909 -336.283113)
			(xy 183.490218 -336.324304) (xy 183.449027 -336.359995) (xy 183.403177 -336.389461) (xy 183.3536 -336.412103)
			(xy 183.301305 -336.427458) (xy 183.247357 -336.435214) (xy 183.192855 -336.435214) (xy 183.138907 -336.427458)
			(xy 183.086612 -336.412103) (xy 183.037035 -336.389461) (xy 182.991185 -336.359995) (xy 182.949994 -336.324304)
			(xy 182.914303 -336.283113) (xy 182.884837 -336.237263) (xy 182.862195 -336.187686) (xy 182.84684 -336.135391)
			(xy 182.839084 -336.081443) (xy 182.838598 -336.054192) (xy 182.839183 -336.025278) (xy 182.847898 -335.968109)
			(xy 182.865143 -335.912912) (xy 182.890522 -335.86095) (xy 182.923454 -335.813414) (xy 182.963184 -335.771394)
			(xy 182.985664 -335.753202) (xy 182.994431 -335.745646) (xy 183.004609 -335.724882) (xy 183.005222 -335.713324)
			(xy 183.005222 -335.63306) (xy 183.00461 -335.621498) (xy 182.994444 -335.600727) (xy 182.985664 -335.593182)
			(xy 182.964873 -335.576438) (xy 182.927742 -335.538084) (xy 182.89632 -335.494928) (xy 182.871221 -335.447814)
			(xy 182.852935 -335.39766) (xy 182.841818 -335.345448) (xy 182.838089 -335.292195) (xy 181.180488 -335.292195)
			(xy 181.185375 -335.315145) (xy 181.189106 -335.368395) (xy 181.185377 -335.421646) (xy 181.174261 -335.473856)
			(xy 181.155976 -335.524008) (xy 181.130879 -335.571121) (xy 181.099459 -335.614275) (xy 181.06233 -335.652628)
			(xy 181.041548 -335.669382) (xy 181.03279 -335.676947) (xy 181.022606 -335.697704) (xy 181.02199 -335.70926)
			(xy 181.02199 -335.789524) (xy 181.022608 -335.801086) (xy 181.032769 -335.821857) (xy 181.041548 -335.829402)
			(xy 181.064042 -335.84758) (xy 181.103775 -335.889604) (xy 181.136711 -335.937142) (xy 181.162097 -335.989105)
			(xy 181.179352 -336.044305) (xy 181.188079 -336.101475) (xy 181.188614 -336.130392) (xy 181.188128 -336.157643)
			(xy 181.180372 -336.211591) (xy 181.165017 -336.263886) (xy 181.142375 -336.313463) (xy 181.112909 -336.359313)
			(xy 181.077218 -336.400504) (xy 181.036027 -336.436195) (xy 180.990177 -336.465661) (xy 180.9406 -336.488303)
			(xy 180.888305 -336.503658) (xy 180.834357 -336.511414) (xy 180.779855 -336.511414) (xy 180.725907 -336.503658)
			(xy 180.673612 -336.488303) (xy 180.624035 -336.465661) (xy 180.578185 -336.436195) (xy 180.536994 -336.400504)
			(xy 180.501303 -336.359313) (xy 180.471837 -336.313463) (xy 180.449195 -336.263886) (xy 180.43384 -336.211591)
			(xy 180.426084 -336.157643) (xy 180.425598 -336.130392) (xy 180.426183 -336.101478) (xy 180.434898 -336.044309)
			(xy 180.452143 -335.989112) (xy 180.477522 -335.93715) (xy 180.510454 -335.889614) (xy 180.550184 -335.847594)
			(xy 180.572664 -335.829402) (xy 180.581431 -335.821846) (xy 180.591609 -335.801082) (xy 180.592222 -335.789524)
			(xy 180.592222 -335.70926) (xy 180.59161 -335.697698) (xy 180.581444 -335.676927) (xy 180.572664 -335.669382)
			(xy 180.551873 -335.652638) (xy 180.514742 -335.614284) (xy 180.48332 -335.571128) (xy 180.458221 -335.524014)
			(xy 180.439935 -335.47386) (xy 180.428818 -335.421648) (xy 180.425089 -335.368395) (xy 177.526343 -335.368395)
			(xy 177.522277 -335.387489) (xy 177.503986 -335.437644) (xy 177.478883 -335.484759) (xy 177.447457 -335.527915)
			(xy 177.410321 -335.566269) (xy 177.389536 -335.583022) (xy 177.380758 -335.590568) (xy 177.370586 -335.611339)
			(xy 177.369978 -335.6229) (xy 177.369978 -335.703164) (xy 177.370577 -335.714728) (xy 177.380752 -335.735499)
			(xy 177.389536 -335.743042) (xy 177.412047 -335.7612) (xy 177.451779 -335.803228) (xy 177.484714 -335.85077)
			(xy 177.510097 -335.902737) (xy 177.527348 -335.95794) (xy 177.53607 -336.015114) (xy 177.536602 -336.044032)
			(xy 177.536116 -336.071283) (xy 177.52836 -336.125231) (xy 177.513005 -336.177526) (xy 177.490363 -336.227103)
			(xy 177.460897 -336.272953) (xy 177.425206 -336.314144) (xy 177.384015 -336.349835) (xy 177.338165 -336.379301)
			(xy 177.288588 -336.401943) (xy 177.236293 -336.417298) (xy 177.182345 -336.425054) (xy 177.127843 -336.425054)
			(xy 177.073895 -336.417298) (xy 177.0216 -336.401943) (xy 176.972023 -336.379301) (xy 176.926173 -336.349835)
			(xy 176.884982 -336.314144) (xy 176.849291 -336.272953) (xy 176.819825 -336.227103) (xy 176.797183 -336.177526)
			(xy 176.781828 -336.125231) (xy 176.774072 -336.071283) (xy 176.773586 -336.044032) (xy 176.774095 -336.015114)
			(xy 176.782821 -335.957941) (xy 176.800079 -335.902741) (xy 176.825472 -335.850778) (xy 176.858419 -335.803245)
			(xy 176.898164 -335.76123) (xy 176.920652 -335.743042) (xy 176.929399 -335.735467) (xy 176.939589 -335.714718)
			(xy 176.94021 -335.703164) (xy 176.94021 -335.6229) (xy 176.939636 -335.611333) (xy 176.929444 -335.590562)
			(xy 176.920652 -335.583022) (xy 176.899901 -335.56623) (xy 176.862772 -335.527881) (xy 176.831351 -335.484731)
			(xy 176.806252 -335.437622) (xy 176.787964 -335.387475) (xy 176.776846 -335.335267) (xy 176.773114 -335.28202)
			(xy 175.115518 -335.28202) (xy 175.120402 -335.304964) (xy 175.12413 -335.35822) (xy 175.120397 -335.411475)
			(xy 175.109277 -335.463689) (xy 175.090986 -335.513844) (xy 175.065883 -335.560959) (xy 175.034457 -335.604115)
			(xy 174.997321 -335.642469) (xy 174.976536 -335.659222) (xy 174.967758 -335.666768) (xy 174.957586 -335.687539)
			(xy 174.956978 -335.6991) (xy 174.956978 -335.779364) (xy 174.957577 -335.790928) (xy 174.967752 -335.811699)
			(xy 174.976536 -335.819242) (xy 174.999047 -335.8374) (xy 175.038779 -335.879428) (xy 175.071714 -335.92697)
			(xy 175.097097 -335.978937) (xy 175.114348 -336.03414) (xy 175.12307 -336.091314) (xy 175.123602 -336.120232)
			(xy 175.123116 -336.147483) (xy 175.11536 -336.201431) (xy 175.100005 -336.253726) (xy 175.077363 -336.303303)
			(xy 175.047897 -336.349153) (xy 175.012206 -336.390344) (xy 174.971015 -336.426035) (xy 174.925165 -336.455501)
			(xy 174.875588 -336.478143) (xy 174.823293 -336.493498) (xy 174.769345 -336.501254) (xy 174.714843 -336.501254)
			(xy 174.660895 -336.493498) (xy 174.6086 -336.478143) (xy 174.559023 -336.455501) (xy 174.513173 -336.426035)
			(xy 174.471982 -336.390344) (xy 174.436291 -336.349153) (xy 174.406825 -336.303303) (xy 174.384183 -336.253726)
			(xy 174.368828 -336.201431) (xy 174.361072 -336.147483) (xy 174.360586 -336.120232) (xy 174.361095 -336.091314)
			(xy 174.369821 -336.034141) (xy 174.387079 -335.978941) (xy 174.412472 -335.926978) (xy 174.445419 -335.879445)
			(xy 174.485164 -335.83743) (xy 174.507652 -335.819242) (xy 174.516399 -335.811667) (xy 174.526589 -335.790918)
			(xy 174.52721 -335.779364) (xy 174.52721 -335.6991) (xy 174.526636 -335.687533) (xy 174.516444 -335.666762)
			(xy 174.507652 -335.659222) (xy 174.486901 -335.64243) (xy 174.449772 -335.604081) (xy 174.418351 -335.560931)
			(xy 174.393252 -335.513822) (xy 174.374964 -335.463675) (xy 174.363846 -335.411467) (xy 174.360114 -335.35822)
			(xy 168.61842 -335.35822) (xy 164.371782 -339.604858) (xy 164.364385 -339.611706) (xy 164.345786 -339.619441)
			(xy 164.335714 -339.619844) (xy 155.00604 -339.619844) (xy 154.995976 -339.620279) (xy 154.977391 -339.628014)
			(xy 154.969972 -339.63483) (xy 154.964384 -339.640418) (xy 154.945842 -339.648292) (xy 153.656538 -339.648292)
			(xy 153.646473 -339.648726) (xy 153.627884 -339.656455) (xy 153.62047 -339.663278) (xy 153.313892 -339.969856)
			(xy 153.307055 -339.977258) (xy 153.299342 -339.995856) (xy 153.298906 -340.005924) (xy 153.298906 -340.262718)
			(xy 172.934884 -340.262718) (xy 172.93534 -340.235347) (xy 172.943157 -340.181167) (xy 172.958647 -340.128663)
			(xy 172.981492 -340.078916) (xy 173.01122 -340.03295) (xy 173.028864 -340.01202) (xy 173.03496 -340.004908)
			(xy 173.04131 -339.98789) (xy 173.04131 -339.902546) (xy 173.03496 -339.885528) (xy 173.028864 -339.878416)
			(xy 173.011239 -339.85747) (xy 172.981511 -339.811505) (xy 172.958662 -339.761761) (xy 172.943163 -339.709261)
			(xy 172.935332 -339.655084) (xy 172.93533 -339.600343) (xy 172.943157 -339.546165) (xy 172.958653 -339.493664)
			(xy 172.981498 -339.443919) (xy 173.011223 -339.397952) (xy 173.028864 -339.37702) (xy 173.03496 -339.369908)
			(xy 173.04131 -339.35289) (xy 173.04131 -339.267546) (xy 173.03496 -339.250528) (xy 173.028864 -339.243416)
			(xy 173.011239 -339.22247) (xy 172.981511 -339.176505) (xy 172.958662 -339.126761) (xy 172.943163 -339.074261)
			(xy 172.935332 -339.020084) (xy 172.93533 -338.965343) (xy 172.943157 -338.911165) (xy 172.958653 -338.858664)
			(xy 172.981498 -338.808919) (xy 173.011223 -338.762952) (xy 173.028864 -338.74202) (xy 173.03496 -338.734908)
			(xy 173.04131 -338.71789) (xy 173.04131 -338.632546) (xy 173.03496 -338.615528) (xy 173.028864 -338.608416)
			(xy 173.011239 -338.58747) (xy 172.981511 -338.541505) (xy 172.958662 -338.491761) (xy 172.943163 -338.439261)
			(xy 172.935332 -338.385084) (xy 172.93533 -338.330343) (xy 172.943157 -338.276165) (xy 172.958653 -338.223664)
			(xy 172.981498 -338.173919) (xy 173.011223 -338.127952) (xy 173.028864 -338.10702) (xy 173.03496 -338.099908)
			(xy 173.04131 -338.08289) (xy 173.04131 -337.997546) (xy 173.03496 -337.980528) (xy 173.028864 -337.973416)
			(xy 173.011239 -337.95247) (xy 172.981511 -337.906505) (xy 172.958662 -337.856761) (xy 172.943163 -337.804261)
			(xy 172.935332 -337.750084) (xy 172.93533 -337.695343) (xy 172.943157 -337.641165) (xy 172.958653 -337.588664)
			(xy 172.981498 -337.538919) (xy 173.011223 -337.492952) (xy 173.028864 -337.47202) (xy 173.03496 -337.464908)
			(xy 173.04131 -337.44789) (xy 173.04131 -337.362546) (xy 173.03496 -337.345528) (xy 173.028864 -337.338416)
			(xy 173.011213 -337.317493) (xy 172.981504 -337.271517) (xy 172.958671 -337.221767) (xy 172.943183 -337.169265)
			(xy 172.935357 -337.115088) (xy 172.934884 -337.087718) (xy 172.935372 -337.060466) (xy 172.943126 -337.006516)
			(xy 172.95848 -336.954219) (xy 172.98112 -336.90464) (xy 173.010585 -336.858787) (xy 173.046276 -336.817594)
			(xy 173.087466 -336.781901) (xy 173.133317 -336.752432) (xy 173.182895 -336.729789) (xy 173.235191 -336.714432)
			(xy 173.28914 -336.706674) (xy 173.316392 -336.70621) (xy 173.344029 -336.706721) (xy 173.398725 -336.714708)
			(xy 173.451696 -336.730501) (xy 173.501835 -336.75377) (xy 173.548093 -336.784028) (xy 173.569122 -336.801968)
			(xy 173.576234 -336.808064) (xy 173.593506 -336.814668) (xy 173.679358 -336.814668) (xy 173.69663 -336.808064)
			(xy 173.703742 -336.801968) (xy 173.724753 -336.784003) (xy 173.771009 -336.753732) (xy 173.821151 -336.730458)
			(xy 173.874129 -336.714669) (xy 173.928832 -336.706697) (xy 173.956472 -336.70621) (xy 173.983725 -336.706681)
			(xy 174.037677 -336.714435) (xy 174.089975 -336.729788) (xy 174.139557 -336.752429) (xy 174.185411 -336.781896)
			(xy 174.226604 -336.817589) (xy 174.262298 -336.858781) (xy 174.291766 -336.904635) (xy 174.314408 -336.954215)
			(xy 174.329763 -337.006514) (xy 174.337518 -337.060465) (xy 174.33798 -337.087718) (xy 174.337529 -337.115089)
			(xy 174.329709 -337.169269) (xy 174.314216 -337.221772) (xy 174.291371 -337.271519) (xy 174.261643 -337.317485)
			(xy 174.244 -337.338416) (xy 174.237904 -337.345528) (xy 174.231554 -337.362546) (xy 174.231554 -337.44789)
			(xy 174.237904 -337.464908) (xy 174.244 -337.47202) (xy 174.261657 -337.492939) (xy 174.291379 -337.53891)
			(xy 174.314222 -337.588659) (xy 174.329716 -337.641162) (xy 174.337542 -337.695342) (xy 174.33754 -337.750085)
			(xy 174.32971 -337.804264) (xy 174.314212 -337.856767) (xy 174.291366 -337.906514) (xy 174.261641 -337.952483)
			(xy 174.244 -337.973416) (xy 174.237904 -337.980528) (xy 174.231554 -337.997546) (xy 174.231554 -338.08289)
			(xy 174.237904 -338.099908) (xy 174.244 -338.10702) (xy 174.261657 -338.127939) (xy 174.291379 -338.17391)
			(xy 174.314222 -338.223659) (xy 174.329716 -338.276162) (xy 174.337542 -338.330342) (xy 174.33754 -338.385085)
			(xy 174.32971 -338.439264) (xy 174.314212 -338.491767) (xy 174.291366 -338.541514) (xy 174.261641 -338.587483)
			(xy 174.244 -338.608416) (xy 174.237904 -338.615528) (xy 174.231554 -338.632546) (xy 174.231554 -338.71789)
			(xy 174.237904 -338.734908) (xy 174.244 -338.74202) (xy 174.261657 -338.762939) (xy 174.291379 -338.80891)
			(xy 174.314222 -338.858659) (xy 174.329716 -338.911162) (xy 174.337542 -338.965342) (xy 174.33754 -339.020085)
			(xy 174.32971 -339.074264) (xy 174.314212 -339.126767) (xy 174.291366 -339.176514) (xy 174.261641 -339.222483)
			(xy 174.244 -339.243416) (xy 174.237904 -339.250528) (xy 174.231554 -339.267546) (xy 174.231554 -339.35289)
			(xy 174.237904 -339.369908) (xy 174.244 -339.37702) (xy 174.261657 -339.397939) (xy 174.291379 -339.44391)
			(xy 174.314222 -339.493659) (xy 174.329716 -339.546162) (xy 174.337542 -339.600342) (xy 174.33754 -339.655085)
			(xy 174.32971 -339.709264) (xy 174.314212 -339.761767) (xy 174.291366 -339.811514) (xy 174.261641 -339.857483)
			(xy 174.244 -339.878416) (xy 174.237904 -339.885528) (xy 174.231554 -339.902546) (xy 174.231554 -339.98789)
			(xy 174.237904 -340.004908) (xy 174.244 -340.01202) (xy 174.261615 -340.032971) (xy 174.291331 -340.078939)
			(xy 174.314171 -340.128682) (xy 174.329668 -340.181178) (xy 174.337502 -340.23535) (xy 174.33798 -340.262718)
			(xy 174.337941 -340.265258) (xy 177.384964 -340.265258) (xy 177.385448 -340.237888) (xy 177.393259 -340.183709)
			(xy 177.408743 -340.131206) (xy 177.431581 -340.081459) (xy 177.461304 -340.035492) (xy 177.478944 -340.01456)
			(xy 177.48504 -340.007448) (xy 177.49139 -339.99043) (xy 177.49139 -339.905086) (xy 177.48504 -339.888068)
			(xy 177.478944 -339.880956) (xy 177.461261 -339.860057) (xy 177.431537 -339.814084) (xy 177.408693 -339.764332)
			(xy 177.393199 -339.711825) (xy 177.385374 -339.657641) (xy 177.385379 -339.602896) (xy 177.393213 -339.548713)
			(xy 177.408715 -339.496209) (xy 177.431568 -339.446461) (xy 177.4613 -339.400492) (xy 177.478944 -339.37956)
			(xy 177.48504 -339.372448) (xy 177.49139 -339.35543) (xy 177.49139 -339.270086) (xy 177.48504 -339.253068)
			(xy 177.478944 -339.245956) (xy 177.461261 -339.225057) (xy 177.431537 -339.179084) (xy 177.408693 -339.129332)
			(xy 177.393199 -339.076825) (xy 177.385374 -339.022641) (xy 177.385379 -338.967896) (xy 177.393213 -338.913713)
			(xy 177.408715 -338.861209) (xy 177.431568 -338.811461) (xy 177.4613 -338.765492) (xy 177.478944 -338.74456)
			(xy 177.48504 -338.737448) (xy 177.49139 -338.72043) (xy 177.49139 -338.635086) (xy 177.48504 -338.618068)
			(xy 177.478944 -338.610956) (xy 177.461261 -338.590057) (xy 177.431537 -338.544084) (xy 177.408693 -338.494332)
			(xy 177.393199 -338.441825) (xy 177.385374 -338.387641) (xy 177.385379 -338.332896) (xy 177.393213 -338.278713)
			(xy 177.408715 -338.226209) (xy 177.431568 -338.176461) (xy 177.4613 -338.130492) (xy 177.478944 -338.10956)
			(xy 177.48504 -338.102448) (xy 177.49139 -338.08543) (xy 177.49139 -338.000086) (xy 177.48504 -337.983068)
			(xy 177.478944 -337.975956) (xy 177.461261 -337.955057) (xy 177.431537 -337.909084) (xy 177.408693 -337.859332)
			(xy 177.393199 -337.806825) (xy 177.385374 -337.752641) (xy 177.385379 -337.697896) (xy 177.393213 -337.643713)
			(xy 177.408715 -337.591209) (xy 177.431568 -337.541461) (xy 177.4613 -337.495492) (xy 177.478944 -337.47456)
			(xy 177.48504 -337.467448) (xy 177.49139 -337.45043) (xy 177.49139 -337.365086) (xy 177.48504 -337.348068)
			(xy 177.478944 -337.340956) (xy 177.461325 -337.320008) (xy 177.431608 -337.27404) (xy 177.408768 -337.224297)
			(xy 177.393272 -337.171799) (xy 177.38544 -337.117626) (xy 177.384964 -337.090258) (xy 177.385439 -337.063007)
			(xy 177.3932 -337.00906) (xy 177.408559 -336.956767) (xy 177.431203 -336.907192) (xy 177.460671 -336.861343)
			(xy 177.496364 -336.820154) (xy 177.537554 -336.784463) (xy 177.583404 -336.754996) (xy 177.63298 -336.732354)
			(xy 177.685274 -336.716997) (xy 177.739221 -336.709238) (xy 177.766472 -336.70875) (xy 177.794111 -336.709229)
			(xy 177.848806 -336.717226) (xy 177.901777 -336.733027) (xy 177.951916 -336.756303) (xy 177.998173 -336.786566)
			(xy 178.019202 -336.804508) (xy 178.026314 -336.810604) (xy 178.043586 -336.817208) (xy 178.129438 -336.817208)
			(xy 178.14671 -336.810604) (xy 178.153822 -336.804508) (xy 178.174846 -336.786558) (xy 178.221097 -336.756284)
			(xy 178.271237 -336.733006) (xy 178.324212 -336.717214) (xy 178.378912 -336.709238) (xy 178.406552 -336.70875)
			(xy 178.433802 -336.7093) (xy 178.487747 -336.717049) (xy 178.540041 -336.732397) (xy 178.589618 -336.755031)
			(xy 178.63547 -336.78449) (xy 178.676662 -336.820175) (xy 178.712356 -336.861358) (xy 178.741826 -336.907203)
			(xy 178.764472 -336.956774) (xy 178.779832 -337.009065) (xy 178.787594 -337.063008) (xy 178.78806 -337.090258)
			(xy 178.787579 -337.117628) (xy 178.779766 -337.171807) (xy 178.764281 -337.22431) (xy 178.741443 -337.274057)
			(xy 178.71172 -337.320024) (xy 178.69408 -337.340956) (xy 178.687984 -337.348068) (xy 178.681634 -337.365086)
			(xy 178.681634 -337.45043) (xy 178.687984 -337.467448) (xy 178.69408 -337.47456) (xy 178.711679 -337.495526)
			(xy 178.741405 -337.541488) (xy 178.764253 -337.591229) (xy 178.779752 -337.643726) (xy 178.787584 -337.6979)
			(xy 178.787589 -337.752637) (xy 178.779765 -337.806812) (xy 178.764275 -337.859312) (xy 178.741436 -337.909056)
			(xy 178.711717 -337.955023) (xy 178.69408 -337.975956) (xy 178.687984 -337.983068) (xy 178.681634 -338.000086)
			(xy 178.681634 -338.08543) (xy 178.687984 -338.102448) (xy 178.69408 -338.10956) (xy 178.711679 -338.130526)
			(xy 178.741405 -338.176488) (xy 178.764253 -338.226229) (xy 178.779752 -338.278726) (xy 178.787584 -338.3329)
			(xy 178.787589 -338.387637) (xy 178.779765 -338.441812) (xy 178.764275 -338.494312) (xy 178.741436 -338.544056)
			(xy 178.711717 -338.590023) (xy 178.69408 -338.610956) (xy 178.687984 -338.618068) (xy 178.681634 -338.635086)
			(xy 178.681634 -338.72043) (xy 178.687984 -338.737448) (xy 178.69408 -338.74456) (xy 178.711679 -338.765526)
			(xy 178.741405 -338.811488) (xy 178.764253 -338.861229) (xy 178.779752 -338.913726) (xy 178.787584 -338.9679)
			(xy 178.787589 -339.022637) (xy 178.779765 -339.076812) (xy 178.764275 -339.129312) (xy 178.741436 -339.179056)
			(xy 178.711717 -339.225023) (xy 178.69408 -339.245956) (xy 178.687984 -339.253068) (xy 178.681634 -339.270086)
			(xy 178.681634 -339.35543) (xy 178.687984 -339.372448) (xy 178.69408 -339.37956) (xy 178.711679 -339.400526)
			(xy 178.741405 -339.446488) (xy 178.764253 -339.496229) (xy 178.779752 -339.548726) (xy 178.787584 -339.6029)
			(xy 178.787589 -339.657637) (xy 178.779765 -339.711812) (xy 178.764275 -339.764312) (xy 178.741436 -339.814056)
			(xy 178.711717 -339.860023) (xy 178.69408 -339.880956) (xy 178.687984 -339.888068) (xy 178.681634 -339.905086)
			(xy 178.681634 -339.99043) (xy 178.687984 -340.007448) (xy 178.69408 -340.01456) (xy 178.711711 -340.035499)
			(xy 178.741424 -340.08147) (xy 178.764262 -340.131215) (xy 178.779755 -340.183715) (xy 178.787585 -340.237889)
			(xy 178.78806 -340.265258) (xy 178.787627 -340.291269) (xy 178.780551 -340.342808) (xy 178.766539 -340.392908)
			(xy 178.74585 -340.44064) (xy 178.718867 -340.485118) (xy 178.686092 -340.525518) (xy 178.648133 -340.56109)
			(xy 178.605692 -340.591175) (xy 178.582828 -340.603586) (xy 178.572668 -340.60892) (xy 178.559206 -340.6267)
			(xy 178.53787 -340.725506) (xy 178.54295 -340.74735) (xy 178.549808 -340.756494) (xy 178.565166 -340.77672)
			(xy 178.590971 -340.820461) (xy 178.610745 -340.867239) (xy 178.624135 -340.916227) (xy 178.630907 -340.96656)
			(xy 178.631342 -340.991952) (xy 178.630862 -341.019322) (xy 178.62305 -341.073501) (xy 178.607565 -341.126004)
			(xy 178.584726 -341.175752) (xy 178.555003 -341.221718) (xy 178.537362 -341.24265) (xy 178.531266 -341.249762)
			(xy 178.524916 -341.26678) (xy 178.524916 -341.352124) (xy 178.531266 -341.369142) (xy 178.537362 -341.376254)
			(xy 178.554987 -341.397197) (xy 178.584702 -341.443167) (xy 178.607542 -341.492911) (xy 178.623036 -341.545409)
			(xy 178.630867 -341.599584) (xy 178.631342 -341.626952) (xy 180.014626 -341.626952) (xy 180.015116 -341.599583)
			(xy 180.022927 -341.545404) (xy 180.03841 -341.492901) (xy 180.061247 -341.443154) (xy 180.090967 -341.397186)
			(xy 180.108606 -341.376254) (xy 180.114702 -341.369142) (xy 180.121052 -341.352124) (xy 180.121052 -341.26678)
			(xy 180.114702 -341.249762) (xy 180.108606 -341.24265) (xy 180.090978 -341.221709) (xy 180.061264 -341.175739)
			(xy 180.038426 -341.125994) (xy 180.022932 -341.073495) (xy 180.015101 -341.019321) (xy 180.014626 -340.991952)
			(xy 180.015119 -340.964738) (xy 180.022847 -340.910863) (xy 180.038155 -340.858633) (xy 180.060731 -340.80911)
			(xy 180.090117 -340.763297) (xy 180.125716 -340.722127) (xy 180.145944 -340.703916) (xy 180.154072 -340.696804)
			(xy 180.163216 -340.6775) (xy 180.165502 -340.58098) (xy 180.157374 -340.561168) (xy 180.1495 -340.553802)
			(xy 180.131195 -340.535757) (xy 180.099159 -340.495557) (xy 180.072808 -340.451423) (xy 180.052617 -340.404151)
			(xy 180.038952 -340.354598) (xy 180.03206 -340.303659) (xy 180.031644 -340.277958) (xy 180.032133 -340.250588)
			(xy 180.039944 -340.19641) (xy 180.055427 -340.143907) (xy 180.078264 -340.094159) (xy 180.107984 -340.048192)
			(xy 180.125624 -340.02726) (xy 180.13172 -340.020148) (xy 180.13807 -340.00313) (xy 180.13807 -339.917786)
			(xy 180.13172 -339.900768) (xy 180.125624 -339.893656) (xy 180.107942 -339.872757) (xy 180.078219 -339.826783)
			(xy 180.055377 -339.777031) (xy 180.039884 -339.724524) (xy 180.032059 -339.670341) (xy 180.032064 -339.615596)
			(xy 180.039897 -339.561414) (xy 180.055399 -339.50891) (xy 180.07825 -339.459162) (xy 180.10798 -339.413193)
			(xy 180.125624 -339.39226) (xy 180.13172 -339.385148) (xy 180.13807 -339.36813) (xy 180.13807 -339.282786)
			(xy 180.13172 -339.265768) (xy 180.125624 -339.258656) (xy 180.107942 -339.237757) (xy 180.078219 -339.191783)
			(xy 180.055377 -339.142031) (xy 180.039884 -339.089524) (xy 180.032059 -339.035341) (xy 180.032064 -338.980596)
			(xy 180.039897 -338.926414) (xy 180.055399 -338.87391) (xy 180.07825 -338.824162) (xy 180.10798 -338.778193)
			(xy 180.125624 -338.75726) (xy 180.13172 -338.750148) (xy 180.13807 -338.73313) (xy 180.13807 -338.647786)
			(xy 180.13172 -338.630768) (xy 180.125624 -338.623656) (xy 180.107942 -338.602757) (xy 180.078219 -338.556783)
			(xy 180.055377 -338.507031) (xy 180.039884 -338.454524) (xy 180.032059 -338.400341) (xy 180.032064 -338.345596)
			(xy 180.039897 -338.291414) (xy 180.055399 -338.23891) (xy 180.07825 -338.189162) (xy 180.10798 -338.143193)
			(xy 180.125624 -338.12226) (xy 180.13172 -338.115148) (xy 180.13807 -338.09813) (xy 180.13807 -338.012786)
			(xy 180.13172 -337.995768) (xy 180.125624 -337.988656) (xy 180.108001 -337.967711) (xy 180.078286 -337.921742)
			(xy 180.055447 -337.871998) (xy 180.039952 -337.8195) (xy 180.03212 -337.765326) (xy 180.031644 -337.737958)
			(xy 180.032075 -337.71253) (xy 180.038826 -337.662123) (xy 180.052214 -337.61306) (xy 180.072004 -337.566211)
			(xy 180.097843 -337.522408) (xy 180.129275 -337.482427) (xy 180.147214 -337.4644) (xy 180.154072 -337.457796)
			(xy 180.161692 -337.441286) (xy 180.16855 -337.355688) (xy 180.163724 -337.338416) (xy 180.157882 -337.330796)
			(xy 180.140125 -337.305947) (xy 180.111948 -337.251765) (xy 180.092757 -337.193787) (xy 180.083041 -337.133494)
			(xy 180.082444 -337.102958) (xy 180.082939 -337.075708) (xy 180.0907 -337.021763) (xy 180.106058 -336.969471)
			(xy 180.1287 -336.919897) (xy 180.158166 -336.874049) (xy 180.193857 -336.832861) (xy 180.235044 -336.79717)
			(xy 180.280892 -336.767703) (xy 180.330466 -336.74506) (xy 180.382757 -336.729701) (xy 180.436702 -336.721939)
			(xy 180.463952 -336.72145) (xy 180.49159 -336.721941) (xy 180.546286 -336.729935) (xy 180.599256 -336.745733)
			(xy 180.649395 -336.769006) (xy 180.695653 -336.799267) (xy 180.716682 -336.817208) (xy 180.723794 -336.823304)
			(xy 180.741066 -336.829908) (xy 180.826918 -336.829908) (xy 180.84419 -336.823304) (xy 180.851302 -336.817208)
			(xy 180.872333 -336.799268) (xy 180.918583 -336.768992) (xy 180.96872 -336.745713) (xy 181.021694 -336.729918)
			(xy 181.076393 -336.72194) (xy 181.104032 -336.72145) (xy 181.131742 -336.721927) (xy 181.186579 -336.729943)
			(xy 181.239678 -336.745816) (xy 181.289918 -336.769212) (xy 181.33624 -336.799636) (xy 181.377667 -336.836448)
			(xy 181.395878 -336.85734) (xy 181.40299 -336.865722) (xy 181.42204 -336.874866) (xy 181.519068 -336.878422)
			(xy 181.53888 -336.870548) (xy 181.5465 -336.862674) (xy 181.564512 -336.844677) (xy 181.604524 -336.813185)
			(xy 181.648369 -336.787293) (xy 181.695267 -336.76746) (xy 181.744386 -336.754041) (xy 181.794853 -336.747271)
			(xy 181.820312 -336.74685) (xy 181.847562 -336.747366) (xy 181.901506 -336.755124) (xy 181.953798 -336.770478)
			(xy 182.003372 -336.793118) (xy 182.04922 -336.822581) (xy 182.090409 -336.858269) (xy 182.126101 -336.899455)
			(xy 182.155568 -336.945301) (xy 182.178211 -336.994874) (xy 182.19357 -337.047165) (xy 182.201331 -337.101108)
			(xy 182.20182 -337.128358) (xy 182.201434 -337.154335) (xy 182.194383 -337.205809) (xy 182.180405 -337.255849)
			(xy 182.15976 -337.303526) (xy 182.132831 -337.347957) (xy 182.100116 -337.388318) (xy 182.062223 -337.423862)
			(xy 182.041292 -337.439254) (xy 182.031809 -337.446895) (xy 182.020658 -337.4685) (xy 182.019956 -337.480656)
			(xy 182.019956 -337.56346) (xy 182.020637 -337.575624) (xy 182.031783 -337.597246) (xy 182.041292 -337.604862)
			(xy 182.062217 -337.620257) (xy 182.100092 -337.655812) (xy 182.13279 -337.696179) (xy 182.159708 -337.74061)
			(xy 182.180345 -337.788283) (xy 182.194322 -337.838316) (xy 182.201378 -337.889784) (xy 182.20182 -337.915758)
			(xy 182.201349 -337.943128) (xy 182.193535 -337.997308) (xy 182.178048 -338.049812) (xy 182.155207 -338.099559)
			(xy 182.125482 -338.145525) (xy 182.10784 -338.166456) (xy 182.101744 -338.173568) (xy 182.095394 -338.190586)
			(xy 182.095394 -338.27593) (xy 182.101744 -338.292948) (xy 182.10784 -338.30006) (xy 182.125441 -338.321025)
			(xy 182.15517 -338.366987) (xy 182.17802 -338.416727) (xy 182.193521 -338.469225) (xy 182.201354 -338.523399)
			(xy 182.201358 -338.578137) (xy 182.193534 -338.632313) (xy 182.178042 -338.684813) (xy 182.1552 -338.734558)
			(xy 182.125479 -338.780524) (xy 182.10784 -338.801456) (xy 182.101744 -338.808568) (xy 182.095394 -338.825586)
			(xy 182.095394 -338.91093) (xy 182.101744 -338.927948) (xy 182.10784 -338.93506) (xy 182.12548 -338.955991)
			(xy 182.155191 -339.001965) (xy 182.178026 -339.051713) (xy 182.193517 -339.104213) (xy 182.201346 -339.158389)
			(xy 182.20182 -339.185758) (xy 183.714644 -339.185758) (xy 183.715133 -339.158388) (xy 183.722944 -339.10421)
			(xy 183.738427 -339.051707) (xy 183.761264 -339.001959) (xy 183.790984 -338.955992) (xy 183.808624 -338.93506)
			(xy 183.81472 -338.927948) (xy 183.82107 -338.91093) (xy 183.82107 -338.825586) (xy 183.81472 -338.808568)
			(xy 183.808624 -338.801456) (xy 183.790942 -338.780557) (xy 183.761219 -338.734583) (xy 183.738377 -338.684831)
			(xy 183.722884 -338.632324) (xy 183.715059 -338.578141) (xy 183.715064 -338.523396) (xy 183.722897 -338.469214)
			(xy 183.738399 -338.41671) (xy 183.76125 -338.366962) (xy 183.79098 -338.320993) (xy 183.808624 -338.30006)
			(xy 183.81472 -338.292948) (xy 183.82107 -338.27593) (xy 183.82107 -338.190586) (xy 183.81472 -338.173568)
			(xy 183.808624 -338.166456) (xy 183.791001 -338.145511) (xy 183.761286 -338.099542) (xy 183.738447 -338.049798)
			(xy 183.722952 -337.9973) (xy 183.71512 -337.943126) (xy 183.714644 -337.915758) (xy 183.715057 -337.889782)
			(xy 183.722106 -337.838309) (xy 183.73608 -337.788271) (xy 183.75672 -337.740595) (xy 183.783645 -337.696164)
			(xy 183.816355 -337.655802) (xy 183.854244 -337.620256) (xy 183.875172 -337.604862) (xy 183.884659 -337.597226)
			(xy 183.895805 -337.575617) (xy 183.896508 -337.56346) (xy 183.896508 -337.480656) (xy 183.895832 -337.468491)
			(xy 183.884684 -337.446868) (xy 183.875172 -337.439254) (xy 183.854269 -337.423831) (xy 183.81639 -337.388282)
			(xy 183.783688 -337.347922) (xy 183.756767 -337.303495) (xy 183.736126 -337.255826) (xy 183.722146 -337.205796)
			(xy 183.715087 -337.154331) (xy 183.714644 -337.128358) (xy 183.715139 -337.101108) (xy 183.7229 -337.047163)
			(xy 183.738258 -336.994871) (xy 183.7609 -336.945297) (xy 183.790366 -336.899449) (xy 183.826057 -336.858261)
			(xy 183.867244 -336.82257) (xy 183.913092 -336.793103) (xy 183.962666 -336.77046) (xy 184.014957 -336.755101)
			(xy 184.068902 -336.747339) (xy 184.096152 -336.74685) (xy 184.125808 -336.747405) (xy 184.184404 -336.756591)
			(xy 184.240873 -336.774733) (xy 184.293855 -336.801394) (xy 184.342073 -336.835933) (xy 184.363614 -336.856324)
			(xy 184.37098 -336.86369) (xy 184.389776 -336.871056) (xy 184.482994 -336.869532) (xy 184.501282 -336.861404)
			(xy 184.508648 -336.853784) (xy 184.526731 -336.835375) (xy 184.566968 -336.803068) (xy 184.611194 -336.776483)
			(xy 184.658601 -336.756106) (xy 184.708324 -336.742308) (xy 184.759453 -336.735343) (xy 184.785254 -336.734912)
			(xy 184.812893 -336.735386) (xy 184.86759 -336.743382) (xy 184.920561 -336.759184) (xy 184.970699 -336.782461)
			(xy 185.016956 -336.812726) (xy 185.037984 -336.83067) (xy 185.045096 -336.836766) (xy 185.062368 -336.84337)
			(xy 185.14822 -336.84337) (xy 185.165492 -336.836766) (xy 185.172604 -336.83067) (xy 185.193629 -336.812723)
			(xy 185.239881 -336.782449) (xy 185.29002 -336.759172) (xy 185.342995 -336.743379) (xy 185.397695 -336.735401)
			(xy 185.425334 -336.734912) (xy 185.452587 -336.735346) (xy 185.506538 -336.743108) (xy 185.558835 -336.758468)
			(xy 185.608413 -336.781115) (xy 185.654264 -336.810587) (xy 185.695455 -336.846283) (xy 185.731146 -336.887479)
			(xy 185.760611 -336.933334) (xy 185.783251 -336.982916) (xy 185.798604 -337.035215) (xy 185.806358 -337.089167)
			(xy 185.806842 -337.11642) (xy 185.806402 -337.143791) (xy 185.79858 -337.197972) (xy 185.783086 -337.250476)
			(xy 185.760238 -337.300223) (xy 185.730507 -337.346188) (xy 185.712862 -337.367118) (xy 185.706766 -337.37423)
			(xy 185.700416 -337.391248) (xy 185.700416 -337.476592) (xy 185.706766 -337.49361) (xy 185.712862 -337.500722)
			(xy 185.730523 -337.521639) (xy 185.760248 -337.567609) (xy 185.783092 -337.617358) (xy 185.798588 -337.669862)
			(xy 185.806415 -337.724043) (xy 185.806412 -337.778787) (xy 185.798581 -337.832967) (xy 185.783082 -337.88547)
			(xy 185.760233 -337.935217) (xy 185.730505 -337.981185) (xy 185.712862 -338.002118) (xy 185.706766 -338.00923)
			(xy 185.700416 -338.026248) (xy 185.700416 -338.111592) (xy 185.706766 -338.12861) (xy 185.712862 -338.135722)
			(xy 185.730523 -338.156639) (xy 185.760248 -338.202609) (xy 185.783092 -338.252358) (xy 185.798588 -338.304862)
			(xy 185.806415 -338.359043) (xy 185.806412 -338.413787) (xy 185.798581 -338.467967) (xy 185.783082 -338.52047)
			(xy 185.760233 -338.570217) (xy 185.730505 -338.616185) (xy 185.712862 -338.637118) (xy 185.706766 -338.64423)
			(xy 185.700416 -338.661248) (xy 185.700416 -338.746592) (xy 185.706766 -338.76361) (xy 185.712862 -338.770722)
			(xy 185.730523 -338.791639) (xy 185.760248 -338.837609) (xy 185.783092 -338.887358) (xy 185.798588 -338.939862)
			(xy 185.806415 -338.994043) (xy 185.806412 -339.048787) (xy 185.798581 -339.102967) (xy 185.783082 -339.15547)
			(xy 185.760233 -339.205217) (xy 185.730505 -339.251185) (xy 185.712862 -339.272118) (xy 185.706766 -339.27923)
			(xy 185.700416 -339.296248) (xy 185.700416 -339.381592) (xy 185.706766 -339.39861) (xy 185.712862 -339.405722)
			(xy 185.730523 -339.426639) (xy 185.760248 -339.472609) (xy 185.783092 -339.522358) (xy 185.798588 -339.574862)
			(xy 185.806415 -339.629043) (xy 185.806412 -339.683787) (xy 185.798581 -339.737967) (xy 185.783082 -339.79047)
			(xy 185.760233 -339.840217) (xy 185.730505 -339.886185) (xy 185.712862 -339.907118) (xy 185.706766 -339.91423)
			(xy 185.700416 -339.931248) (xy 185.700416 -340.016592) (xy 185.706766 -340.03361) (xy 185.712862 -340.040722)
			(xy 185.730472 -340.061678) (xy 185.76019 -340.107643) (xy 185.783032 -340.157385) (xy 185.798529 -340.20988)
			(xy 185.806365 -340.264052) (xy 185.806373 -340.264496) (xy 188.333126 -340.264496) (xy 188.333583 -340.237125)
			(xy 188.341402 -340.182946) (xy 188.356893 -340.130442) (xy 188.379737 -340.080695) (xy 188.409464 -340.034729)
			(xy 188.427106 -340.013798) (xy 188.433202 -340.006686) (xy 188.439552 -339.989668) (xy 188.439552 -339.904324)
			(xy 188.433202 -339.887306) (xy 188.427106 -339.880194) (xy 188.409462 -339.859264) (xy 188.379739 -339.813295)
			(xy 188.356895 -339.763548) (xy 188.3414 -339.711046) (xy 188.333573 -339.656868) (xy 188.333573 -339.602126)
			(xy 188.341402 -339.547948) (xy 188.356898 -339.495446) (xy 188.379742 -339.445699) (xy 188.409466 -339.399731)
			(xy 188.427106 -339.378798) (xy 188.433202 -339.371686) (xy 188.439552 -339.354668) (xy 188.439552 -339.269324)
			(xy 188.433202 -339.252306) (xy 188.427106 -339.245194) (xy 188.409462 -339.224264) (xy 188.379739 -339.178295)
			(xy 188.356895 -339.128548) (xy 188.3414 -339.076046) (xy 188.333573 -339.021868) (xy 188.333573 -338.967126)
			(xy 188.341402 -338.912948) (xy 188.356898 -338.860446) (xy 188.379742 -338.810699) (xy 188.409466 -338.764731)
			(xy 188.427106 -338.743798) (xy 188.433202 -338.736686) (xy 188.439552 -338.719668) (xy 188.439552 -338.634324)
			(xy 188.433202 -338.617306) (xy 188.427106 -338.610194) (xy 188.409462 -338.589264) (xy 188.379739 -338.543295)
			(xy 188.356895 -338.493548) (xy 188.3414 -338.441046) (xy 188.333573 -338.386868) (xy 188.333573 -338.332126)
			(xy 188.341402 -338.277948) (xy 188.356898 -338.225446) (xy 188.379742 -338.175699) (xy 188.409466 -338.129731)
			(xy 188.427106 -338.108798) (xy 188.433202 -338.101686) (xy 188.439552 -338.084668) (xy 188.439552 -337.999324)
			(xy 188.433202 -337.982306) (xy 188.427106 -337.975194) (xy 188.409462 -337.954264) (xy 188.379739 -337.908295)
			(xy 188.356895 -337.858548) (xy 188.3414 -337.806046) (xy 188.333573 -337.751868) (xy 188.333573 -337.697126)
			(xy 188.341402 -337.642948) (xy 188.356898 -337.590446) (xy 188.379742 -337.540699) (xy 188.409466 -337.494731)
			(xy 188.427106 -337.473798) (xy 188.433202 -337.466686) (xy 188.439552 -337.449668) (xy 188.439552 -337.364324)
			(xy 188.433202 -337.347306) (xy 188.427106 -337.340194) (xy 188.409452 -337.319274) (xy 188.379742 -337.273298)
			(xy 188.356909 -337.223548) (xy 188.341421 -337.171044) (xy 188.333598 -337.116866) (xy 188.333126 -337.089496)
			(xy 188.333552 -337.062242) (xy 188.34131 -337.008287) (xy 188.356668 -336.955987) (xy 188.379314 -336.906404)
			(xy 188.408785 -336.86055) (xy 188.444483 -336.819356) (xy 188.48568 -336.783663) (xy 188.531538 -336.754196)
			(xy 188.581122 -336.731555) (xy 188.633425 -336.716202) (xy 188.687379 -336.708449) (xy 188.714634 -336.707988)
			(xy 188.742272 -336.70848) (xy 188.796968 -336.716472) (xy 188.849939 -336.73227) (xy 188.900078 -336.755543)
			(xy 188.946335 -336.785805) (xy 188.967364 -336.803746) (xy 188.974476 -336.809842) (xy 188.991748 -336.816446)
			(xy 189.0776 -336.816446) (xy 189.094872 -336.809842) (xy 189.101984 -336.803746) (xy 189.123014 -336.785804)
			(xy 189.169265 -336.755531) (xy 189.219403 -336.732253) (xy 189.272376 -336.716458) (xy 189.327075 -336.708479)
			(xy 189.354714 -336.707988) (xy 189.382124 -336.708447) (xy 189.436381 -336.716295) (xy 189.488955 -336.731828)
			(xy 189.538765 -336.754726) (xy 189.584785 -336.784517) (xy 189.626067 -336.820589) (xy 189.644274 -336.841084)
			(xy 189.651132 -336.848958) (xy 189.669166 -336.858102) (xy 189.761622 -336.864706) (xy 189.780672 -336.858356)
			(xy 189.788292 -336.851498) (xy 189.809286 -336.833788) (xy 189.855374 -336.803912) (xy 189.905266 -336.780946)
			(xy 189.957934 -336.765365) (xy 190.01229 -336.75749) (xy 190.039752 -336.75701) (xy 190.067004 -336.7575)
			(xy 190.120955 -336.765251) (xy 190.173254 -336.780602) (xy 190.222835 -336.80324) (xy 190.268689 -336.832705)
			(xy 190.309883 -336.868396) (xy 190.345577 -336.909587) (xy 190.375046 -336.955439) (xy 190.397688 -337.005018)
			(xy 190.413043 -337.057315) (xy 190.420798 -337.111266) (xy 190.42126 -337.138518) (xy 190.420791 -337.165776)
			(xy 190.413022 -337.219736) (xy 190.397658 -337.272042) (xy 190.375011 -337.321632) (xy 190.345543 -337.367497)
			(xy 190.309851 -337.408705) (xy 190.268662 -337.444419) (xy 190.246 -337.459574) (xy 190.239038 -337.464434)
			(xy 190.228512 -337.477738) (xy 190.222947 -337.493763) (xy 190.222632 -337.502246) (xy 190.222632 -337.58759)
			(xy 190.223008 -337.596064) (xy 190.228578 -337.612073) (xy 190.23905 -337.625402) (xy 190.246 -337.630262)
			(xy 190.268664 -337.645414) (xy 190.30986 -337.681122) (xy 190.345555 -337.722328) (xy 190.375024 -337.768194)
			(xy 190.397666 -337.817787) (xy 190.41302 -337.870097) (xy 190.420775 -337.924059) (xy 190.42126 -337.951318)
			(xy 190.420814 -337.978689) (xy 190.412993 -338.032869) (xy 190.3975 -338.085373) (xy 190.374653 -338.13512)
			(xy 190.344924 -338.181085) (xy 190.32728 -338.202016) (xy 190.321184 -338.209128) (xy 190.314834 -338.226146)
			(xy 190.314834 -338.31149) (xy 190.321184 -338.328508) (xy 190.32728 -338.33562) (xy 190.344938 -338.356539)
			(xy 190.374662 -338.402509) (xy 190.397505 -338.452258) (xy 190.413 -338.504762) (xy 190.420827 -338.558942)
			(xy 190.420825 -338.613685) (xy 190.412994 -338.667865) (xy 190.397496 -338.720368) (xy 190.374649 -338.770115)
			(xy 190.344922 -338.816083) (xy 190.32728 -338.837016) (xy 190.321184 -338.844128) (xy 190.314834 -338.861146)
			(xy 190.314834 -338.94649) (xy 190.321184 -338.963508) (xy 190.32728 -338.97062) (xy 190.344892 -338.991574)
			(xy 190.374609 -339.03754) (xy 190.39745 -339.087282) (xy 190.412947 -339.139778) (xy 190.420782 -339.19395)
			(xy 190.42126 -339.221318) (xy 192.058544 -339.221318) (xy 192.05901 -339.193948) (xy 192.066826 -339.139768)
			(xy 192.082315 -339.087265) (xy 192.105157 -339.037518) (xy 192.134882 -338.991551) (xy 192.152524 -338.97062)
			(xy 192.15862 -338.963508) (xy 192.16497 -338.94649) (xy 192.16497 -338.861146) (xy 192.15862 -338.844128)
			(xy 192.152524 -338.837016) (xy 192.134901 -338.816069) (xy 192.105176 -338.770104) (xy 192.08233 -338.72036)
			(xy 192.066832 -338.66786) (xy 192.059002 -338.613683) (xy 192.059 -338.558944) (xy 192.066826 -338.504767)
			(xy 192.08232 -338.452266) (xy 192.105163 -338.40252) (xy 192.134885 -338.356553) (xy 192.152524 -338.33562)
			(xy 192.15862 -338.328508) (xy 192.16497 -338.31149) (xy 192.16497 -338.226146) (xy 192.15862 -338.209128)
			(xy 192.152524 -338.202016) (xy 192.134883 -338.181086) (xy 192.10517 -338.135113) (xy 192.082334 -338.085365)
			(xy 192.066844 -338.032864) (xy 192.059017 -337.978687) (xy 192.058544 -337.951318) (xy 192.059038 -337.924061)
			(xy 192.066803 -337.870102) (xy 192.082162 -337.817796) (xy 192.104805 -337.768207) (xy 192.134269 -337.722341)
			(xy 192.169957 -337.681132) (xy 192.211143 -337.645417) (xy 192.233804 -337.630262) (xy 192.240796 -337.625441)
			(xy 192.251316 -337.612119) (xy 192.256867 -337.596078) (xy 192.257172 -337.58759) (xy 192.257172 -337.502246)
			(xy 192.256881 -337.493763) (xy 192.25128 -337.477747) (xy 192.240772 -337.464424) (xy 192.233804 -337.459574)
			(xy 192.211157 -337.444397) (xy 192.169961 -337.408694) (xy 192.134265 -337.367492) (xy 192.104794 -337.32163)
			(xy 192.082149 -337.272041) (xy 192.066791 -337.219735) (xy 192.059031 -337.165775) (xy 192.058544 -337.138518)
			(xy 192.059095 -337.111269) (xy 192.066848 -337.057327) (xy 192.082198 -337.005036) (xy 192.104834 -336.955462)
			(xy 192.134293 -336.909614) (xy 192.169978 -336.868425) (xy 192.211161 -336.832733) (xy 192.257004 -336.803265)
			(xy 192.306574 -336.780621) (xy 192.358862 -336.765262) (xy 192.412803 -336.7575) (xy 192.440052 -336.75701)
			(xy 192.468271 -336.757497) (xy 192.524093 -336.765807) (xy 192.578081 -336.782251) (xy 192.629056 -336.806472)
			(xy 192.675906 -336.83794) (xy 192.6971 -336.856578) (xy 192.704212 -336.862928) (xy 192.721738 -336.869786)
			(xy 192.809368 -336.869786) (xy 192.827148 -336.862928) (xy 192.83426 -336.856324) (xy 192.855469 -336.837597)
			(xy 192.902388 -336.805982) (xy 192.953462 -336.781643) (xy 193.007571 -336.765115) (xy 193.063528 -336.756761)
			(xy 193.091816 -336.756248) (xy 193.119856 -336.756739) (xy 193.175334 -336.764942) (xy 193.229016 -336.781169)
			(xy 193.279748 -336.805071) (xy 193.32644 -336.836134) (xy 193.347594 -336.854546) (xy 193.354706 -336.86115)
			(xy 193.371978 -336.867754) (xy 193.459354 -336.867754) (xy 193.476626 -336.86115) (xy 193.483738 -336.854546)
			(xy 193.504888 -336.836126) (xy 193.551566 -336.805033) (xy 193.602298 -336.781118) (xy 193.655986 -336.764898)
			(xy 193.711473 -336.756723) (xy 193.739516 -336.756248) (xy 193.766766 -336.756763) (xy 193.82071 -336.76452)
			(xy 193.873002 -336.779875) (xy 193.922576 -336.802515) (xy 193.968424 -336.831979) (xy 194.009613 -336.867667)
			(xy 194.045304 -336.908853) (xy 194.074772 -336.954699) (xy 194.097415 -337.004272) (xy 194.112774 -337.056563)
			(xy 194.120535 -337.110506) (xy 194.121024 -337.137756) (xy 194.120551 -337.165126) (xy 194.112737 -337.219306)
			(xy 194.097251 -337.271809) (xy 194.07441 -337.321557) (xy 194.044686 -337.367523) (xy 194.027044 -337.388454)
			(xy 194.020948 -337.395566) (xy 194.014598 -337.412584) (xy 194.014598 -337.497928) (xy 194.020948 -337.514946)
			(xy 194.027044 -337.522058) (xy 194.044643 -337.543025) (xy 194.074372 -337.588986) (xy 194.097221 -337.638727)
			(xy 194.112722 -337.691224) (xy 194.120556 -337.745398) (xy 194.12056 -337.800136) (xy 194.112736 -337.854311)
			(xy 194.097245 -337.906811) (xy 194.074404 -337.956556) (xy 194.044683 -338.002522) (xy 194.027044 -338.023454)
			(xy 194.020948 -338.030566) (xy 194.014598 -338.047584) (xy 194.014598 -338.132928) (xy 194.020948 -338.149946)
			(xy 194.027044 -338.157058) (xy 194.044643 -338.178025) (xy 194.074372 -338.223986) (xy 194.097221 -338.273727)
			(xy 194.112722 -338.326224) (xy 194.120556 -338.380398) (xy 194.12056 -338.435136) (xy 194.112736 -338.489311)
			(xy 194.097245 -338.541811) (xy 194.074404 -338.591556) (xy 194.044683 -338.637522) (xy 194.027044 -338.658454)
			(xy 194.020948 -338.665566) (xy 194.014598 -338.682584) (xy 194.014598 -338.767928) (xy 194.020948 -338.784946)
			(xy 194.027044 -338.792058) (xy 194.044684 -338.812989) (xy 194.074394 -338.858963) (xy 194.084024 -338.879942)
			(xy 198.275192 -338.879942) (xy 198.279263 -338.82432) (xy 198.291389 -338.769883) (xy 198.311312 -338.717792)
			(xy 198.338608 -338.669157) (xy 198.372694 -338.625014) (xy 198.412843 -338.586305) (xy 198.458201 -338.553854)
			(xy 198.507801 -338.528353) (xy 198.560585 -338.510346) (xy 198.615428 -338.500216) (xy 198.671162 -338.498179)
			(xy 198.726599 -338.504279) (xy 198.780556 -338.518385) (xy 198.831885 -338.540197) (xy 198.879491 -338.569251)
			(xy 198.922359 -338.604926) (xy 198.959576 -338.646463) (xy 198.990349 -338.692976) (xy 199.014021 -338.743473)
			(xy 199.030089 -338.79688) (xy 199.038209 -338.852056) (xy 199.038718 -338.879942) (xy 199.038209 -338.907828)
			(xy 199.030089 -338.963004) (xy 199.014021 -339.016411) (xy 198.990349 -339.066908) (xy 198.959576 -339.113421)
			(xy 198.922359 -339.154958) (xy 198.879491 -339.190633) (xy 198.831885 -339.219687) (xy 198.780556 -339.241499)
			(xy 198.726599 -339.255605) (xy 198.671162 -339.261705) (xy 198.615428 -339.259668) (xy 198.560585 -339.249538)
			(xy 198.507801 -339.231531) (xy 198.458201 -339.20603) (xy 198.412843 -339.173579) (xy 198.372694 -339.13487)
			(xy 198.338608 -339.090727) (xy 198.311312 -339.042092) (xy 198.291389 -338.990001) (xy 198.279263 -338.935564)
			(xy 198.275192 -338.879942) (xy 194.084024 -338.879942) (xy 194.09723 -338.908711) (xy 194.112721 -338.961211)
			(xy 194.12055 -339.015387) (xy 194.121024 -339.042756) (xy 194.12061 -339.068923) (xy 194.113492 -339.120769)
			(xy 194.099345 -339.171153) (xy 194.078433 -339.219125) (xy 194.051152 -339.263784) (xy 194.034918 -339.28431)
			(xy 194.028822 -339.291676) (xy 194.02298 -339.308694) (xy 194.026282 -339.3948) (xy 194.03314 -339.41131)
			(xy 194.039744 -339.418168) (xy 194.059203 -339.439552) (xy 194.092113 -339.487084) (xy 194.117467 -339.539041)
			(xy 194.134685 -339.594231) (xy 194.143371 -339.651389) (xy 194.143884 -339.680296) (xy 194.143419 -339.707666)
			(xy 194.135602 -339.761846) (xy 194.120113 -339.814349) (xy 194.09727 -339.864096) (xy 194.067545 -339.910062)
			(xy 194.049904 -339.930994) (xy 194.043808 -339.938106) (xy 194.037458 -339.955124) (xy 194.037458 -340.040468)
			(xy 194.043808 -340.057486) (xy 194.049904 -340.064598) (xy 194.067556 -340.085519) (xy 194.090967 -340.121748)
			(xy 203.227938 -340.121748) (xy 203.232009 -340.066126) (xy 203.244135 -340.011689) (xy 203.264058 -339.959598)
			(xy 203.291354 -339.910963) (xy 203.32544 -339.86682) (xy 203.365589 -339.828111) (xy 203.410947 -339.79566)
			(xy 203.460547 -339.770159) (xy 203.513331 -339.752152) (xy 203.568174 -339.742022) (xy 203.623908 -339.739985)
			(xy 203.679345 -339.746085) (xy 203.733302 -339.760191) (xy 203.784631 -339.782003) (xy 203.832237 -339.811057)
			(xy 203.875105 -339.846732) (xy 203.912322 -339.888269) (xy 203.943095 -339.934782) (xy 203.966767 -339.985279)
			(xy 203.982835 -340.038686) (xy 203.990955 -340.093862) (xy 203.991464 -340.121748) (xy 203.990955 -340.149634)
			(xy 203.982835 -340.20481) (xy 203.966767 -340.258217) (xy 203.943095 -340.308714) (xy 203.912322 -340.355227)
			(xy 203.875105 -340.396764) (xy 203.832237 -340.432439) (xy 203.784631 -340.461493) (xy 203.733302 -340.483305)
			(xy 203.679345 -340.497411) (xy 203.623908 -340.503511) (xy 203.568174 -340.501474) (xy 203.513331 -340.491344)
			(xy 203.460547 -340.473337) (xy 203.410947 -340.447836) (xy 203.365589 -340.415385) (xy 203.32544 -340.376676)
			(xy 203.291354 -340.332533) (xy 203.264058 -340.283898) (xy 203.244135 -340.231807) (xy 203.232009 -340.17737)
			(xy 203.227938 -340.121748) (xy 194.090967 -340.121748) (xy 194.097266 -340.131495) (xy 194.120099 -340.181245)
			(xy 194.135587 -340.233748) (xy 194.143412 -340.287926) (xy 194.143884 -340.315296) (xy 194.143441 -340.34255)
			(xy 194.135684 -340.396503) (xy 194.120327 -340.448802) (xy 194.097683 -340.498384) (xy 194.068213 -340.544238)
			(xy 194.032518 -340.585432) (xy 193.991322 -340.621125) (xy 193.945467 -340.650593) (xy 193.895884 -340.673234)
			(xy 193.843583 -340.688588) (xy 193.78963 -340.696342) (xy 193.762376 -340.696804) (xy 193.735746 -340.696357)
			(xy 193.683004 -340.688946) (xy 193.631805 -340.674271) (xy 193.583145 -340.652617) (xy 193.53797 -340.624405)
			(xy 193.517266 -340.60765) (xy 193.509392 -340.601046) (xy 193.490596 -340.59495) (xy 193.399918 -340.601808)
			(xy 193.382138 -340.610698) (xy 193.375534 -340.618318) (xy 193.357363 -340.638279) (xy 193.316318 -340.673338)
			(xy 193.270742 -340.702263) (xy 193.221544 -340.724476) (xy 193.169708 -340.739535) (xy 193.116266 -340.747139)
			(xy 193.089276 -340.747604) (xy 193.062024 -340.747145) (xy 193.008075 -340.739385) (xy 192.95578 -340.724026)
			(xy 192.906202 -340.701382) (xy 192.860352 -340.671913) (xy 192.819162 -340.636219) (xy 192.78347 -340.595026)
			(xy 192.754005 -340.549173) (xy 192.731364 -340.499594) (xy 192.716009 -340.447298) (xy 192.708253 -340.393348)
			(xy 192.707768 -340.366096) (xy 192.708215 -340.338725) (xy 192.716035 -340.284544) (xy 192.731528 -340.23204)
			(xy 192.754374 -340.182294) (xy 192.784104 -340.136328) (xy 192.801748 -340.115398) (xy 192.807844 -340.108286)
			(xy 192.814194 -340.091268) (xy 192.814194 -340.005924) (xy 192.807844 -339.988906) (xy 192.801748 -339.981794)
			(xy 192.7841 -339.960869) (xy 192.754388 -339.914895) (xy 192.731553 -339.865146) (xy 192.716064 -339.812643)
			(xy 192.70824 -339.758466) (xy 192.707768 -339.731096) (xy 192.707879 -339.719764) (xy 192.70928 -339.697144)
			(xy 192.710562 -339.685884) (xy 192.712086 -339.672422) (xy 192.701926 -339.648038) (xy 192.612772 -339.577934)
			(xy 192.586356 -339.57387) (xy 192.57391 -339.578442) (xy 192.541622 -339.58982) (xy 192.474278 -339.602088)
			(xy 192.440052 -339.602826) (xy 192.4128 -339.602367) (xy 192.358853 -339.594604) (xy 192.306559 -339.579244)
			(xy 192.256982 -339.556599) (xy 192.211133 -339.527129) (xy 192.169944 -339.491435) (xy 192.134253 -339.450243)
			(xy 192.104787 -339.404391) (xy 192.082145 -339.354813) (xy 192.066789 -339.302518) (xy 192.059031 -339.24857)
			(xy 192.058544 -339.221318) (xy 190.42126 -339.221318) (xy 190.420862 -339.248574) (xy 190.413101 -339.302529)
			(xy 190.39774 -339.354831) (xy 190.375092 -339.404415) (xy 190.345618 -339.45027) (xy 190.309917 -339.491464)
			(xy 190.268717 -339.527157) (xy 190.222857 -339.556624) (xy 190.173269 -339.579263) (xy 190.120965 -339.594615)
			(xy 190.067008 -339.602366) (xy 190.039752 -339.602826) (xy 190.009246 -339.602249) (xy 189.949011 -339.592544)
			(xy 189.919864 -339.583522) (xy 189.907926 -339.579458) (xy 189.883034 -339.583776) (xy 189.79642 -339.649816)
			(xy 189.785752 -339.672676) (xy 189.786514 -339.685376) (xy 189.787022 -339.705696) (xy 189.786573 -339.733067)
			(xy 189.778754 -339.787248) (xy 189.763262 -339.839752) (xy 189.740416 -339.889498) (xy 189.710686 -339.935464)
			(xy 189.693042 -339.956394) (xy 189.686946 -339.963506) (xy 189.680596 -339.980524) (xy 189.680596 -340.065868)
			(xy 189.686946 -340.082886) (xy 189.693042 -340.089998) (xy 189.710701 -340.110914) (xy 189.740408 -340.156892)
			(xy 189.76324 -340.206644) (xy 189.778727 -340.259148) (xy 189.786551 -340.313326) (xy 189.787022 -340.340696)
			(xy 189.786519 -340.367947) (xy 189.778763 -340.421893) (xy 189.763409 -340.474186) (xy 189.740769 -340.523763)
			(xy 189.711305 -340.569612) (xy 189.675615 -340.610802) (xy 189.634427 -340.646494) (xy 189.588579 -340.675961)
			(xy 189.539003 -340.698603) (xy 189.48671 -340.713959) (xy 189.432764 -340.721717) (xy 189.405514 -340.722204)
			(xy 189.376493 -340.721645) (xy 189.319122 -340.712855) (xy 189.263744 -340.695475) (xy 189.211638 -340.669908)
			(xy 189.164006 -340.636742) (xy 189.121948 -340.596744) (xy 189.103762 -340.574122) (xy 189.097412 -340.56574)
			(xy 189.079378 -340.555834) (xy 188.98616 -340.54542) (xy 188.966348 -340.551262) (xy 188.958474 -340.557866)
			(xy 188.937839 -340.574444) (xy 188.892847 -340.60233) (xy 188.844432 -340.623728) (xy 188.793524 -340.638227)
			(xy 188.7411 -340.64555) (xy 188.714634 -340.646004) (xy 188.687382 -340.645513) (xy 188.633432 -340.637761)
			(xy 188.581134 -340.622409) (xy 188.531554 -340.59977) (xy 188.4857 -340.570305) (xy 188.444507 -340.534614)
			(xy 188.408813 -340.493424) (xy 188.379345 -340.447573) (xy 188.356702 -340.397994) (xy 188.341346 -340.345698)
			(xy 188.333589 -340.291748) (xy 188.333126 -340.264496) (xy 185.806373 -340.264496) (xy 185.806842 -340.29142)
			(xy 185.806386 -340.318035) (xy 185.798985 -340.370749) (xy 185.784314 -340.421918) (xy 185.762661 -340.470546)
			(xy 185.74893 -340.49335) (xy 185.743088 -340.502748) (xy 185.740294 -340.52383) (xy 185.766964 -340.617302)
			(xy 185.780426 -340.633558) (xy 185.790332 -340.638384) (xy 185.813987 -340.650488) (xy 185.85794 -340.680349)
			(xy 185.897327 -340.716017) (xy 185.931386 -340.756803) (xy 185.95946 -340.801919) (xy 185.981005 -340.850492)
			(xy 185.995605 -340.901584) (xy 186.002978 -340.954207) (xy 186.003438 -340.980776) (xy 186.002973 -341.008146)
			(xy 185.995157 -341.062326) (xy 185.979669 -341.11483) (xy 185.956826 -341.164577) (xy 185.9271 -341.210543)
			(xy 185.909458 -341.231474) (xy 185.903362 -341.238586) (xy 185.897012 -341.255604) (xy 185.897012 -341.340948)
			(xy 185.903362 -341.357966) (xy 185.909458 -341.365078) (xy 185.927094 -341.386013) (xy 185.956807 -341.431984)
			(xy 185.979645 -341.481731) (xy 185.995136 -341.534231) (xy 185.999578 -341.564976) (xy 187.451746 -341.564976)
			(xy 187.452187 -341.537605) (xy 187.460009 -341.483424) (xy 187.475503 -341.43092) (xy 187.498351 -341.381174)
			(xy 187.528082 -341.335208) (xy 187.545726 -341.314278) (xy 187.551822 -341.307166) (xy 187.558172 -341.290148)
			(xy 187.558172 -341.204804) (xy 187.551822 -341.187786) (xy 187.545726 -341.180674) (xy 187.528112 -341.159721)
			(xy 187.498396 -341.113755) (xy 187.475554 -341.064012) (xy 187.460058 -341.011516) (xy 187.452223 -340.957344)
			(xy 187.451746 -340.929976) (xy 187.452232 -340.902725) (xy 187.459988 -340.848777) (xy 187.475343 -340.796482)
			(xy 187.497985 -340.746905) (xy 187.527451 -340.701055) (xy 187.563142 -340.659864) (xy 187.604333 -340.624173)
			(xy 187.650183 -340.594707) (xy 187.69976 -340.572065) (xy 187.752055 -340.55671) (xy 187.806003 -340.548954)
			(xy 187.860505 -340.548954) (xy 187.914453 -340.55671) (xy 187.966748 -340.572065) (xy 188.016325 -340.594707)
			(xy 188.062175 -340.624173) (xy 188.103366 -340.659864) (xy 188.139057 -340.701055) (xy 188.168523 -340.746905)
			(xy 188.191165 -340.796482) (xy 188.20652 -340.848777) (xy 188.214276 -340.902725) (xy 188.214762 -340.929976)
			(xy 188.214291 -340.957346) (xy 188.206476 -341.011525) (xy 188.190988 -341.064029) (xy 188.168148 -341.113776)
			(xy 188.138423 -341.159743) (xy 188.120782 -341.180674) (xy 188.114686 -341.187786) (xy 188.108336 -341.204804)
			(xy 188.108336 -341.290148) (xy 188.114686 -341.307166) (xy 188.120782 -341.314278) (xy 188.138421 -341.33521)
			(xy 188.168134 -341.381182) (xy 188.19097 -341.43093) (xy 188.206461 -341.483431) (xy 188.214288 -341.537607)
			(xy 188.214762 -341.564976) (xy 188.214276 -341.592227) (xy 188.20652 -341.646175) (xy 188.191165 -341.69847)
			(xy 188.168523 -341.748047) (xy 188.139057 -341.793897) (xy 188.103366 -341.835088) (xy 188.069195 -341.864696)
			(xy 193.232786 -341.864696) (xy 193.233253 -341.837326) (xy 193.241071 -341.783147) (xy 193.25656 -341.730644)
			(xy 193.279402 -341.680897) (xy 193.309125 -341.63493) (xy 193.326766 -341.613998) (xy 193.332862 -341.606886)
			(xy 193.339212 -341.589868) (xy 193.339212 -341.504524) (xy 193.332862 -341.487506) (xy 193.326766 -341.480394)
			(xy 193.309105 -341.459479) (xy 193.279398 -341.413501) (xy 193.256567 -341.363749) (xy 193.241081 -341.311245)
			(xy 193.233257 -341.257066) (xy 193.232786 -341.229696) (xy 193.233272 -341.202445) (xy 193.241028 -341.148497)
			(xy 193.256383 -341.096202) (xy 193.279025 -341.046625) (xy 193.308491 -341.000775) (xy 193.344182 -340.959584)
			(xy 193.385373 -340.923893) (xy 193.431223 -340.894427) (xy 193.4808 -340.871785) (xy 193.533095 -340.85643)
			(xy 193.587043 -340.848674) (xy 193.641545 -340.848674) (xy 193.695493 -340.85643) (xy 193.747788 -340.871785)
			(xy 193.797365 -340.894427) (xy 193.843215 -340.923893) (xy 193.884406 -340.959584) (xy 193.920097 -341.000775)
			(xy 193.949563 -341.046625) (xy 193.972205 -341.096202) (xy 193.98756 -341.148497) (xy 193.995316 -341.202445)
			(xy 193.995802 -341.229696) (xy 193.995333 -341.257066) (xy 193.987516 -341.311245) (xy 193.972027 -341.363748)
			(xy 193.949186 -341.413495) (xy 193.919463 -341.459462) (xy 193.901822 -341.480394) (xy 193.895726 -341.487506)
			(xy 193.889376 -341.504524) (xy 193.889376 -341.589868) (xy 193.895726 -341.606886) (xy 193.901822 -341.613998)
			(xy 193.919477 -341.634917) (xy 193.949186 -341.680894) (xy 193.972018 -341.730645) (xy 193.987506 -341.783148)
			(xy 193.99533 -341.837326) (xy 193.995452 -341.844376) (xy 195.422266 -341.844376) (xy 195.422702 -341.817004)
			(xy 195.430525 -341.762823) (xy 195.44602 -341.710319) (xy 195.468869 -341.660573) (xy 195.498601 -341.614608)
			(xy 195.516246 -341.593678) (xy 195.522342 -341.586566) (xy 195.528692 -341.569548) (xy 195.528692 -341.484204)
			(xy 195.522342 -341.467186) (xy 195.516246 -341.460074) (xy 195.498635 -341.439119) (xy 195.468918 -341.393153)
			(xy 195.446075 -341.343412) (xy 195.430578 -341.290916) (xy 195.422743 -341.236744) (xy 195.422266 -341.209376)
			(xy 195.422752 -341.182125) (xy 195.430508 -341.128177) (xy 195.445863 -341.075882) (xy 195.468505 -341.026305)
			(xy 195.497971 -340.980455) (xy 195.533662 -340.939264) (xy 195.574853 -340.903573) (xy 195.620703 -340.874107)
			(xy 195.67028 -340.851465) (xy 195.722575 -340.83611) (xy 195.776523 -340.828354) (xy 195.831025 -340.828354)
			(xy 195.884973 -340.83611) (xy 195.937268 -340.851465) (xy 195.986845 -340.874107) (xy 196.032695 -340.903573)
			(xy 196.073886 -340.939264) (xy 196.109577 -340.980455) (xy 196.139043 -341.026305) (xy 196.161685 -341.075882)
			(xy 196.17704 -341.128177) (xy 196.184796 -341.182125) (xy 196.185282 -341.209376) (xy 196.184806 -341.236746)
			(xy 196.176991 -341.290925) (xy 196.161505 -341.343428) (xy 196.138665 -341.393175) (xy 196.108942 -341.439142)
			(xy 196.091302 -341.460074) (xy 196.085206 -341.467186) (xy 196.078856 -341.484204) (xy 196.078856 -341.569548)
			(xy 196.085206 -341.586566) (xy 196.091302 -341.593678) (xy 196.108945 -341.614607) (xy 196.138656 -341.660581)
			(xy 196.161491 -341.710329) (xy 196.176981 -341.76283) (xy 196.184809 -341.817007) (xy 196.185282 -341.844376)
			(xy 196.184796 -341.871627) (xy 196.17704 -341.925575) (xy 196.161685 -341.97787) (xy 196.139043 -342.027447)
			(xy 196.109577 -342.073297) (xy 196.073886 -342.114488) (xy 196.032695 -342.150179) (xy 195.986845 -342.179645)
			(xy 195.937268 -342.202287) (xy 195.884973 -342.217642) (xy 195.831025 -342.225398) (xy 195.776523 -342.225398)
			(xy 195.722575 -342.217642) (xy 195.67028 -342.202287) (xy 195.620703 -342.179645) (xy 195.574853 -342.150179)
			(xy 195.533662 -342.114488) (xy 195.497971 -342.073297) (xy 195.468505 -342.027447) (xy 195.445863 -341.97787)
			(xy 195.430508 -341.925575) (xy 195.422752 -341.871627) (xy 195.422266 -341.844376) (xy 193.995452 -341.844376)
			(xy 193.995802 -341.864696) (xy 193.995316 -341.891947) (xy 193.98756 -341.945895) (xy 193.972205 -341.99819)
			(xy 193.949563 -342.047767) (xy 193.920097 -342.093617) (xy 193.884406 -342.134808) (xy 193.843215 -342.170499)
			(xy 193.797365 -342.199965) (xy 193.747788 -342.222607) (xy 193.695493 -342.237962) (xy 193.641545 -342.245718)
			(xy 193.587043 -342.245718) (xy 193.533095 -342.237962) (xy 193.4808 -342.222607) (xy 193.431223 -342.199965)
			(xy 193.385373 -342.170499) (xy 193.344182 -342.134808) (xy 193.308491 -342.093617) (xy 193.279025 -342.047767)
			(xy 193.256383 -341.99819) (xy 193.241028 -341.945895) (xy 193.233272 -341.891947) (xy 193.232786 -341.864696)
			(xy 188.069195 -341.864696) (xy 188.062175 -341.870779) (xy 188.016325 -341.900245) (xy 187.966748 -341.922887)
			(xy 187.914453 -341.938242) (xy 187.860505 -341.945998) (xy 187.806003 -341.945998) (xy 187.752055 -341.938242)
			(xy 187.69976 -341.922887) (xy 187.650183 -341.900245) (xy 187.604333 -341.870779) (xy 187.563142 -341.835088)
			(xy 187.527451 -341.793897) (xy 187.497985 -341.748047) (xy 187.475343 -341.69847) (xy 187.459988 -341.646175)
			(xy 187.452232 -341.592227) (xy 187.451746 -341.564976) (xy 185.999578 -341.564976) (xy 186.002964 -341.588407)
			(xy 186.003438 -341.615776) (xy 186.002952 -341.643027) (xy 185.995196 -341.696975) (xy 185.979841 -341.74927)
			(xy 185.957199 -341.798847) (xy 185.927733 -341.844697) (xy 185.892042 -341.885888) (xy 185.850851 -341.921579)
			(xy 185.805001 -341.951045) (xy 185.755424 -341.973687) (xy 185.703129 -341.989042) (xy 185.649181 -341.996798)
			(xy 185.594679 -341.996798) (xy 185.540731 -341.989042) (xy 185.488436 -341.973687) (xy 185.438859 -341.951045)
			(xy 185.393009 -341.921579) (xy 185.351818 -341.885888) (xy 185.316127 -341.844697) (xy 185.286661 -341.798847)
			(xy 185.264019 -341.74927) (xy 185.248664 -341.696975) (xy 185.240908 -341.643027) (xy 185.240422 -341.615776)
			(xy 185.240869 -341.588405) (xy 185.24869 -341.534225) (xy 185.264184 -341.481721) (xy 185.28703 -341.431975)
			(xy 185.316759 -341.386009) (xy 185.334402 -341.365078) (xy 185.340498 -341.357966) (xy 185.346848 -341.340948)
			(xy 185.346848 -341.255604) (xy 185.340498 -341.238586) (xy 185.334402 -341.231474) (xy 185.316784 -341.210525)
			(xy 185.287069 -341.164557) (xy 185.264229 -341.114813) (xy 185.248733 -341.062317) (xy 185.240899 -341.008144)
			(xy 185.240422 -340.980776) (xy 185.240866 -340.95416) (xy 185.24827 -340.901446) (xy 185.262943 -340.850276)
			(xy 185.284601 -340.801649) (xy 185.298334 -340.778846) (xy 185.304176 -340.769448) (xy 185.30697 -340.748366)
			(xy 185.2803 -340.654894) (xy 185.266838 -340.638638) (xy 185.256932 -340.633812) (xy 185.237436 -340.62388)
			(xy 185.200642 -340.600198) (xy 185.183526 -340.586568) (xy 185.175906 -340.580218) (xy 185.157364 -340.574376)
			(xy 185.067702 -340.581234) (xy 185.050176 -340.58987) (xy 185.043572 -340.597236) (xy 185.025414 -340.616781)
			(xy 184.984579 -340.65111) (xy 184.939358 -340.679413) (xy 184.890633 -340.701136) (xy 184.839356 -340.715856)
			(xy 184.786528 -340.723285) (xy 184.759854 -340.723728) (xy 184.732603 -340.723265) (xy 184.678655 -340.715503)
			(xy 184.626361 -340.700143) (xy 184.576785 -340.677498) (xy 184.530936 -340.648029) (xy 184.489747 -340.612335)
			(xy 184.454056 -340.571143) (xy 184.42459 -340.525292) (xy 184.401948 -340.475715) (xy 184.386592 -340.42342)
			(xy 184.378833 -340.369472) (xy 184.378346 -340.34222) (xy 184.378813 -340.31485) (xy 184.386629 -340.26067)
			(xy 184.402117 -340.208167) (xy 184.424959 -340.15842) (xy 184.454684 -340.112453) (xy 184.472326 -340.091522)
			(xy 184.478422 -340.08441) (xy 184.484772 -340.067392) (xy 184.484772 -339.982048) (xy 184.478422 -339.96503)
			(xy 184.472326 -339.957918) (xy 184.454686 -339.936987) (xy 184.424973 -339.891014) (xy 184.402137 -339.841266)
			(xy 184.386646 -339.788765) (xy 184.378819 -339.734589) (xy 184.378346 -339.70722) (xy 184.378521 -339.692168)
			(xy 184.380933 -339.662161) (xy 184.383172 -339.647276) (xy 184.385204 -339.63356) (xy 184.375298 -339.607906)
			(xy 184.283604 -339.536024) (xy 184.256172 -339.532214) (xy 184.243472 -339.537548) (xy 184.220054 -339.546925)
			(xy 184.171374 -339.560152) (xy 184.121374 -339.566841) (xy 184.096152 -339.567266) (xy 184.068898 -339.566867)
			(xy 184.014945 -339.559103) (xy 183.962646 -339.543739) (xy 183.913066 -339.521089) (xy 183.867213 -339.491614)
			(xy 183.826023 -339.455914) (xy 183.790332 -339.414715) (xy 183.760867 -339.368855) (xy 183.738229 -339.31927)
			(xy 183.722878 -339.266967) (xy 183.715127 -339.213012) (xy 183.714644 -339.185758) (xy 182.20182 -339.185758)
			(xy 182.201306 -339.213009) (xy 182.193555 -339.266958) (xy 182.178205 -339.319254) (xy 182.155568 -339.368833)
			(xy 182.126105 -339.414686) (xy 182.090417 -339.455879) (xy 182.049229 -339.491573) (xy 182.003381 -339.521042)
			(xy 181.953805 -339.543686) (xy 181.901511 -339.559043) (xy 181.847563 -339.566802) (xy 181.820312 -339.567266)
			(xy 181.793841 -339.566818) (xy 181.741411 -339.559475) (xy 181.690499 -339.544957) (xy 181.642082 -339.523542)
			(xy 181.597089 -339.495641) (xy 181.556384 -339.461789) (xy 181.520748 -339.422637) (xy 181.490865 -339.378935)
			(xy 181.478682 -339.35543) (xy 181.47281 -339.34503) (xy 181.453736 -339.330712) (xy 181.442106 -339.327998)
			(xy 181.384194 -339.317838) (xy 181.377336 -339.32495) (xy 181.370821 -339.3323) (xy 181.363366 -339.350449)
			(xy 181.362858 -339.360256) (xy 181.362858 -339.39226) (xy 181.363334 -339.402075) (xy 181.370787 -339.420239)
			(xy 181.377336 -339.427566) (xy 181.397491 -339.449082) (xy 181.431639 -339.497137) (xy 181.457989 -339.549872)
			(xy 181.475914 -339.606033) (xy 181.484988 -339.664282) (xy 181.48554 -339.693758) (xy 181.485064 -339.721128)
			(xy 181.477251 -339.775307) (xy 181.461765 -339.827811) (xy 181.438925 -339.877558) (xy 181.409201 -339.923525)
			(xy 181.39156 -339.944456) (xy 181.385464 -339.951568) (xy 181.379114 -339.968586) (xy 181.379114 -340.05393)
			(xy 181.385464 -340.070948) (xy 181.39156 -340.07806) (xy 181.409188 -340.099001) (xy 181.438903 -340.144971)
			(xy 181.461741 -340.194716) (xy 181.477235 -340.247215) (xy 181.485065 -340.301389) (xy 181.48554 -340.328758)
			(xy 181.485006 -340.356008) (xy 181.477255 -340.409955) (xy 181.461906 -340.46225) (xy 181.439271 -340.511828)
			(xy 181.40981 -340.557679) (xy 181.374124 -340.598872) (xy 181.332939 -340.634566) (xy 181.287093 -340.664035)
			(xy 181.237519 -340.68668) (xy 181.185227 -340.70204) (xy 181.131282 -340.7098) (xy 181.104032 -340.710266)
			(xy 181.076262 -340.70976) (xy 181.021309 -340.70171) (xy 180.968105 -340.685777) (xy 180.917773 -340.662296)
			(xy 180.871379 -340.631764) (xy 180.829902 -340.594827) (xy 180.811678 -340.573868) (xy 180.805074 -340.56574)
			(xy 180.78704 -340.556596) (xy 180.693314 -340.549738) (xy 180.674264 -340.556342) (xy 180.66639 -340.5632)
			(xy 180.663342 -340.565994) (xy 180.655214 -340.573106) (xy 180.64607 -340.59241) (xy 180.643784 -340.68893)
			(xy 180.651912 -340.708742) (xy 180.659786 -340.716108) (xy 180.678093 -340.734151) (xy 180.710129 -340.774351)
			(xy 180.736481 -340.818486) (xy 180.756671 -340.865757) (xy 180.770335 -340.915311) (xy 180.777226 -340.96625)
			(xy 180.777642 -340.991952) (xy 180.777162 -341.019322) (xy 180.76935 -341.073501) (xy 180.753865 -341.126004)
			(xy 180.731026 -341.175752) (xy 180.701303 -341.221718) (xy 180.683662 -341.24265) (xy 180.677566 -341.249762)
			(xy 180.671216 -341.26678) (xy 180.671216 -341.352124) (xy 180.677566 -341.369142) (xy 180.683662 -341.376254)
			(xy 180.701287 -341.397197) (xy 180.731002 -341.443167) (xy 180.753842 -341.492911) (xy 180.769336 -341.545409)
			(xy 180.777167 -341.599584) (xy 180.777642 -341.626952) (xy 180.777156 -341.654203) (xy 180.7694 -341.708151)
			(xy 180.754045 -341.760446) (xy 180.731403 -341.810023) (xy 180.701937 -341.855873) (xy 180.666246 -341.897064)
			(xy 180.625055 -341.932755) (xy 180.579205 -341.962221) (xy 180.529628 -341.984863) (xy 180.477333 -342.000218)
			(xy 180.423385 -342.007974) (xy 180.368883 -342.007974) (xy 180.314935 -342.000218) (xy 180.26264 -341.984863)
			(xy 180.213063 -341.962221) (xy 180.167213 -341.932755) (xy 180.126022 -341.897064) (xy 180.090331 -341.855873)
			(xy 180.060865 -341.810023) (xy 180.038223 -341.760446) (xy 180.022868 -341.708151) (xy 180.015112 -341.654203)
			(xy 180.014626 -341.626952) (xy 178.631342 -341.626952) (xy 178.630856 -341.654203) (xy 178.6231 -341.708151)
			(xy 178.607745 -341.760446) (xy 178.585103 -341.810023) (xy 178.555637 -341.855873) (xy 178.519946 -341.897064)
			(xy 178.478755 -341.932755) (xy 178.432905 -341.962221) (xy 178.383328 -341.984863) (xy 178.331033 -342.000218)
			(xy 178.277085 -342.007974) (xy 178.222583 -342.007974) (xy 178.168635 -342.000218) (xy 178.11634 -341.984863)
			(xy 178.066763 -341.962221) (xy 178.020913 -341.932755) (xy 177.979722 -341.897064) (xy 177.944031 -341.855873)
			(xy 177.914565 -341.810023) (xy 177.891923 -341.760446) (xy 177.876568 -341.708151) (xy 177.868812 -341.654203)
			(xy 177.868326 -341.626952) (xy 177.868816 -341.599583) (xy 177.876627 -341.545404) (xy 177.89211 -341.492901)
			(xy 177.914947 -341.443154) (xy 177.944667 -341.397186) (xy 177.962306 -341.376254) (xy 177.968402 -341.369142)
			(xy 177.974752 -341.352124) (xy 177.974752 -341.26678) (xy 177.968402 -341.249762) (xy 177.962306 -341.24265)
			(xy 177.944678 -341.221709) (xy 177.914964 -341.175739) (xy 177.892126 -341.125994) (xy 177.876632 -341.073495)
			(xy 177.868801 -341.019321) (xy 177.868326 -340.991952) (xy 177.868849 -340.963834) (xy 177.877098 -340.908206)
			(xy 177.893425 -340.854393) (xy 177.917476 -340.803559) (xy 177.94873 -340.756808) (xy 177.98651 -340.715152)
			(xy 178.029996 -340.679494) (xy 178.078245 -340.650608) (xy 178.104038 -340.6394) (xy 178.115319 -340.634138)
			(xy 178.13131 -340.615104) (xy 178.134518 -340.603078) (xy 178.146964 -340.544912) (xy 178.138074 -340.53653)
			(xy 178.130703 -340.529904) (xy 178.112412 -340.52232) (xy 178.102514 -340.521798) (xy 178.07051 -340.521798)
			(xy 178.060603 -340.522268) (xy 178.042302 -340.52987) (xy 178.03495 -340.53653) (xy 178.013388 -340.557093)
			(xy 177.965026 -340.591891) (xy 177.911841 -340.618746) (xy 177.855126 -340.637003) (xy 177.796263 -340.646218)
			(xy 177.766472 -340.646766) (xy 177.739217 -340.646371) (xy 177.685261 -340.638609) (xy 177.632959 -340.623247)
			(xy 177.583376 -340.600599) (xy 177.537521 -340.571124) (xy 177.496328 -340.535423) (xy 177.460634 -340.494223)
			(xy 177.431168 -340.448362) (xy 177.408528 -340.398775) (xy 177.393176 -340.346471) (xy 177.385424 -340.292514)
			(xy 177.384964 -340.265258) (xy 174.337941 -340.265258) (xy 174.337562 -340.289973) (xy 174.329802 -340.343927)
			(xy 174.314442 -340.396227) (xy 174.291795 -340.445809) (xy 174.262323 -340.491664) (xy 174.226624 -340.532857)
			(xy 174.185427 -340.56855) (xy 174.139569 -340.598017) (xy 174.089984 -340.620658) (xy 174.037682 -340.636011)
			(xy 173.983727 -340.643765) (xy 173.956472 -340.644226) (xy 173.928834 -340.643727) (xy 173.874139 -340.635736)
			(xy 173.821168 -340.61994) (xy 173.771029 -340.596668) (xy 173.724771 -340.566409) (xy 173.703742 -340.548468)
			(xy 173.69663 -340.542372) (xy 173.679358 -340.535768) (xy 173.593506 -340.535768) (xy 173.576234 -340.542372)
			(xy 173.569122 -340.548468) (xy 173.567598 -340.549738) (xy 173.559605 -340.557488) (xy 173.550626 -340.577833)
			(xy 173.551046 -340.600068) (xy 173.560787 -340.62006) (xy 173.578039 -340.634094) (xy 173.58868 -340.637368)
			(xy 173.615784 -340.64465) (xy 173.667598 -340.666219) (xy 173.715691 -340.695148) (xy 173.759026 -340.730812)
			(xy 173.796667 -340.772442) (xy 173.827801 -340.819138) (xy 173.851756 -340.869893) (xy 173.868014 -340.92361)
			(xy 173.876226 -340.97913) (xy 173.876716 -341.007192) (xy 173.876266 -341.034563) (xy 173.868447 -341.088744)
			(xy 173.852956 -341.141248) (xy 173.83011 -341.190994) (xy 173.80038 -341.23696) (xy 173.782736 -341.25789)
			(xy 173.77664 -341.265002) (xy 173.77029 -341.28202) (xy 173.77029 -341.367364) (xy 173.77664 -341.384382)
			(xy 173.782736 -341.391494) (xy 173.800391 -341.412413) (xy 173.8301 -341.45839) (xy 173.852932 -341.508141)
			(xy 173.868419 -341.560644) (xy 173.876244 -341.614822) (xy 173.876716 -341.642192) (xy 173.87623 -341.669443)
			(xy 173.868474 -341.723391) (xy 173.853119 -341.775686) (xy 173.830477 -341.825263) (xy 173.801011 -341.871113)
			(xy 173.76532 -341.912304) (xy 173.724129 -341.947995) (xy 173.678279 -341.977461) (xy 173.628702 -342.000103)
			(xy 173.576407 -342.015458) (xy 173.522459 -342.023214) (xy 173.467957 -342.023214) (xy 173.414009 -342.015458)
			(xy 173.361714 -342.000103) (xy 173.312137 -341.977461) (xy 173.266287 -341.947995) (xy 173.225096 -341.912304)
			(xy 173.189405 -341.871113) (xy 173.159939 -341.825263) (xy 173.137297 -341.775686) (xy 173.121942 -341.723391)
			(xy 173.114186 -341.669443) (xy 173.1137 -341.642192) (xy 173.114161 -341.614822) (xy 173.12198 -341.560642)
			(xy 173.137471 -341.508139) (xy 173.160313 -341.458392) (xy 173.190039 -341.412426) (xy 173.20768 -341.391494)
			(xy 173.213776 -341.384382) (xy 173.220126 -341.367364) (xy 173.220126 -341.28202) (xy 173.213776 -341.265002)
			(xy 173.20768 -341.25789) (xy 173.19002 -341.236975) (xy 173.160312 -341.190997) (xy 173.13748 -341.141245)
			(xy 173.121994 -341.088741) (xy 173.114171 -341.034562) (xy 173.1137 -341.007192) (xy 173.11411 -340.981285)
			(xy 173.121135 -340.929949) (xy 173.135041 -340.880036) (xy 173.155572 -340.832463) (xy 173.182352 -340.788105)
			(xy 173.198282 -340.76767) (xy 173.205902 -340.758272) (xy 173.210982 -340.735412) (xy 173.186598 -340.633812)
			(xy 173.171612 -340.616032) (xy 173.16069 -340.610952) (xy 173.135824 -340.599335) (xy 173.089438 -340.569997)
			(xy 173.047738 -340.534313) (xy 173.011585 -340.493018) (xy 172.981725 -340.446967) (xy 172.958776 -340.397111)
			(xy 172.943213 -340.344479) (xy 172.935356 -340.29016) (xy 172.934884 -340.262718) (xy 153.298906 -340.262718)
			(xy 153.298906 -347.260164) (xy 156.09138 -347.260164) (xy 156.095451 -347.204542) (xy 156.107577 -347.150105)
			(xy 156.1275 -347.098014) (xy 156.154796 -347.049379) (xy 156.188882 -347.005236) (xy 156.229031 -346.966527)
			(xy 156.274389 -346.934076) (xy 156.323989 -346.908575) (xy 156.376773 -346.890568) (xy 156.431616 -346.880438)
			(xy 156.48735 -346.878401) (xy 156.542787 -346.884501) (xy 156.596744 -346.898607) (xy 156.648073 -346.920419)
			(xy 156.695679 -346.949473) (xy 156.738547 -346.985148) (xy 156.775764 -347.026685) (xy 156.806537 -347.073198)
			(xy 156.830209 -347.123695) (xy 156.846277 -347.177102) (xy 156.854397 -347.232278) (xy 156.854906 -347.260164)
			(xy 156.854397 -347.28805) (xy 156.846277 -347.343226) (xy 156.830209 -347.396633) (xy 156.806537 -347.44713)
			(xy 156.775764 -347.493643) (xy 156.738547 -347.53518) (xy 156.695679 -347.570855) (xy 156.648073 -347.599909)
			(xy 156.596744 -347.621721) (xy 156.542787 -347.635827) (xy 156.48735 -347.641927) (xy 156.431616 -347.63989)
			(xy 156.376773 -347.62976) (xy 156.323989 -347.611753) (xy 156.274389 -347.586252) (xy 156.229031 -347.553801)
			(xy 156.188882 -347.515092) (xy 156.154796 -347.470949) (xy 156.1275 -347.422314) (xy 156.107577 -347.370223)
			(xy 156.095451 -347.315786) (xy 156.09138 -347.260164) (xy 153.298906 -347.260164) (xy 153.298906 -348.511368)
			(xy 153.299342 -348.521433) (xy 153.307074 -348.540018) (xy 153.313892 -348.547436) (xy 153.620724 -348.854268)
			(xy 153.627568 -348.861667) (xy 153.635289 -348.880266) (xy 153.63571 -348.890336) (xy 153.63571 -348.96806)
			(xy 154.087574 -348.96806) (xy 154.091645 -348.912438) (xy 154.103771 -348.858001) (xy 154.123694 -348.80591)
			(xy 154.15099 -348.757275) (xy 154.185076 -348.713132) (xy 154.225225 -348.674423) (xy 154.270583 -348.641972)
			(xy 154.320183 -348.616471) (xy 154.372967 -348.598464) (xy 154.42781 -348.588334) (xy 154.483544 -348.586297)
			(xy 154.538981 -348.592397) (xy 154.592938 -348.606503) (xy 154.644267 -348.628315) (xy 154.691873 -348.657369)
			(xy 154.734741 -348.693044) (xy 154.771958 -348.734581) (xy 154.802731 -348.781094) (xy 154.826403 -348.831591)
			(xy 154.842471 -348.884998) (xy 154.850591 -348.940174) (xy 154.8511 -348.96806) (xy 154.850591 -348.995946)
			(xy 154.842471 -349.051122) (xy 154.826403 -349.104529) (xy 154.802731 -349.155026) (xy 154.771958 -349.201539)
			(xy 154.734741 -349.243076) (xy 154.701393 -349.270828) (xy 156.242512 -349.270828) (xy 156.243035 -349.240855)
			(xy 156.252356 -349.18164) (xy 156.270834 -349.124615) (xy 156.298015 -349.071187) (xy 156.333227 -349.022675)
			(xy 156.354018 -349.00108) (xy 157.07995 -348.275402) (xy 157.086775 -348.26799) (xy 157.094505 -348.2494)
			(xy 157.094936 -348.239334) (xy 157.094936 -342.678258) (xy 157.095471 -342.648286) (xy 157.104788 -342.589071)
			(xy 157.123263 -342.532046) (xy 157.150441 -342.478618) (xy 157.185651 -342.430105) (xy 157.206442 -342.40851)
			(xy 158.088838 -341.526114) (xy 158.110461 -341.505358) (xy 158.15898 -341.470171) (xy 158.212403 -341.443003)
			(xy 158.269416 -341.424521) (xy 158.328618 -341.41518) (xy 158.358586 -341.414608) (xy 167.718232 -341.414608)
			(xy 167.748204 -341.415158) (xy 167.807418 -341.424472) (xy 167.864442 -341.442944) (xy 167.91787 -341.470119)
			(xy 167.966384 -341.505325) (xy 167.98798 -341.526114) (xy 168.088818 -341.626952) (xy 170.9547 -341.626952)
			(xy 170.955197 -341.599583) (xy 170.963007 -341.545405) (xy 170.978489 -341.492902) (xy 171.001324 -341.443155)
			(xy 171.031042 -341.397187) (xy 171.04868 -341.376254) (xy 171.054776 -341.369142) (xy 171.061126 -341.352124)
			(xy 171.061126 -341.26678) (xy 171.054776 -341.249762) (xy 171.04868 -341.24265) (xy 171.031048 -341.221712)
			(xy 171.001336 -341.175741) (xy 170.978499 -341.125995) (xy 170.963006 -341.073495) (xy 170.955175 -341.019321)
			(xy 170.9547 -340.991952) (xy 170.955186 -340.964701) (xy 170.962942 -340.910753) (xy 170.978297 -340.858458)
			(xy 171.000939 -340.808881) (xy 171.030405 -340.763031) (xy 171.066096 -340.72184) (xy 171.107287 -340.686149)
			(xy 171.153137 -340.656683) (xy 171.202714 -340.634041) (xy 171.255009 -340.618686) (xy 171.308957 -340.61093)
			(xy 171.363459 -340.61093) (xy 171.417407 -340.618686) (xy 171.469702 -340.634041) (xy 171.519279 -340.656683)
			(xy 171.565129 -340.686149) (xy 171.60632 -340.72184) (xy 171.642011 -340.763031) (xy 171.671477 -340.808881)
			(xy 171.694119 -340.858458) (xy 171.709474 -340.910753) (xy 171.71723 -340.964701) (xy 171.717716 -340.991952)
			(xy 171.717242 -341.019322) (xy 171.709429 -341.073502) (xy 171.693943 -341.126006) (xy 171.671103 -341.175753)
			(xy 171.641378 -341.221719) (xy 171.623736 -341.24265) (xy 171.61764 -341.249762) (xy 171.61129 -341.26678)
			(xy 171.61129 -341.352124) (xy 171.61764 -341.369142) (xy 171.623736 -341.376254) (xy 171.641373 -341.397188)
			(xy 171.671084 -341.443161) (xy 171.693919 -341.492908) (xy 171.709411 -341.545408) (xy 171.717241 -341.599583)
			(xy 171.717716 -341.626952) (xy 171.71723 -341.654203) (xy 171.709474 -341.708151) (xy 171.694119 -341.760446)
			(xy 171.671477 -341.810023) (xy 171.642011 -341.855873) (xy 171.60632 -341.897064) (xy 171.565129 -341.932755)
			(xy 171.519279 -341.962221) (xy 171.469702 -341.984863) (xy 171.417407 -342.000218) (xy 171.363459 -342.007974)
			(xy 171.308957 -342.007974) (xy 171.255009 -342.000218) (xy 171.202714 -341.984863) (xy 171.153137 -341.962221)
			(xy 171.107287 -341.932755) (xy 171.066096 -341.897064) (xy 171.030405 -341.855873) (xy 171.000939 -341.810023)
			(xy 170.978297 -341.760446) (xy 170.962942 -341.708151) (xy 170.955186 -341.654203) (xy 170.9547 -341.626952)
			(xy 168.088818 -341.626952) (xy 169.384218 -342.922352) (xy 202.582016 -342.922352) (xy 202.586087 -342.86673)
			(xy 202.598213 -342.812293) (xy 202.618136 -342.760202) (xy 202.645432 -342.711567) (xy 202.679518 -342.667424)
			(xy 202.719667 -342.628715) (xy 202.765025 -342.596264) (xy 202.814625 -342.570763) (xy 202.867409 -342.552756)
			(xy 202.922252 -342.542626) (xy 202.977986 -342.540589) (xy 203.033423 -342.546689) (xy 203.08738 -342.560795)
			(xy 203.138709 -342.582607) (xy 203.186315 -342.611661) (xy 203.229183 -342.647336) (xy 203.2664 -342.688873)
			(xy 203.297173 -342.735386) (xy 203.320845 -342.785883) (xy 203.336913 -342.83929) (xy 203.345033 -342.894466)
			(xy 203.345542 -342.922352) (xy 203.345033 -342.950238) (xy 203.336913 -343.005414) (xy 203.320845 -343.058821)
			(xy 203.297173 -343.109318) (xy 203.2664 -343.155831) (xy 203.229183 -343.197368) (xy 203.186315 -343.233043)
			(xy 203.138709 -343.262097) (xy 203.08738 -343.283909) (xy 203.033423 -343.298015) (xy 202.977986 -343.304115)
			(xy 202.922252 -343.302078) (xy 202.867409 -343.291948) (xy 202.814625 -343.273941) (xy 202.765025 -343.24844)
			(xy 202.719667 -343.215989) (xy 202.679518 -343.17728) (xy 202.645432 -343.133137) (xy 202.618136 -343.084502)
			(xy 202.598213 -343.032411) (xy 202.586087 -342.977974) (xy 202.582016 -342.922352) (xy 169.384218 -342.922352)
			(xy 170.154854 -343.692988) (xy 170.175629 -343.714594) (xy 170.210814 -343.763117) (xy 170.237979 -343.816544)
			(xy 170.256457 -343.873562) (xy 170.265792 -343.932767) (xy 170.26636 -343.962736) (xy 170.26636 -344.8304)
			(xy 201.363834 -344.8304) (xy 201.36434 -344.801482) (xy 201.373069 -344.74431) (xy 201.390329 -344.68911)
			(xy 201.415723 -344.637149) (xy 201.448669 -344.589615) (xy 201.488413 -344.547599) (xy 201.5109 -344.52941)
			(xy 201.519653 -344.521839) (xy 201.529841 -344.501087) (xy 201.530458 -344.489532) (xy 201.530458 -344.409268)
			(xy 201.529863 -344.397703) (xy 201.519687 -344.376931) (xy 201.5109 -344.36939) (xy 201.488412 -344.351205)
			(xy 201.448677 -344.309184) (xy 201.415738 -344.261648) (xy 201.390351 -344.209685) (xy 201.373096 -344.154487)
			(xy 201.364368 -344.097316) (xy 201.363834 -344.0684) (xy 201.36432 -344.041149) (xy 201.372076 -343.987201)
			(xy 201.387431 -343.934906) (xy 201.410073 -343.885329) (xy 201.439539 -343.839479) (xy 201.47523 -343.798288)
			(xy 201.516421 -343.762597) (xy 201.562271 -343.733131) (xy 201.611848 -343.710489) (xy 201.664143 -343.695134)
			(xy 201.718091 -343.687378) (xy 201.772593 -343.687378) (xy 201.826541 -343.695134) (xy 201.878836 -343.710489)
			(xy 201.928413 -343.733131) (xy 201.974263 -343.762597) (xy 202.015454 -343.798288) (xy 202.051145 -343.839479)
			(xy 202.080611 -343.885329) (xy 202.103253 -343.934906) (xy 202.118608 -343.987201) (xy 202.126364 -344.041149)
			(xy 202.12685 -344.0684) (xy 202.126351 -344.097318) (xy 202.11762 -344.154491) (xy 202.10036 -344.209691)
			(xy 202.074965 -344.261653) (xy 202.052577 -344.293952) (xy 205.807816 -344.293952) (xy 205.811887 -344.23833)
			(xy 205.824013 -344.183893) (xy 205.843936 -344.131802) (xy 205.871232 -344.083167) (xy 205.905318 -344.039024)
			(xy 205.945467 -344.000315) (xy 205.990825 -343.967864) (xy 206.040425 -343.942363) (xy 206.093209 -343.924356)
			(xy 206.148052 -343.914226) (xy 206.203786 -343.912189) (xy 206.259223 -343.918289) (xy 206.31318 -343.932395)
			(xy 206.364509 -343.954207) (xy 206.412115 -343.983261) (xy 206.454983 -344.018936) (xy 206.4922 -344.060473)
			(xy 206.522973 -344.106986) (xy 206.546645 -344.157483) (xy 206.562713 -344.21089) (xy 206.570833 -344.266066)
			(xy 206.571342 -344.293952) (xy 206.570833 -344.321838) (xy 206.562713 -344.377014) (xy 206.546645 -344.430421)
			(xy 206.522973 -344.480918) (xy 206.4922 -344.527431) (xy 206.454983 -344.568968) (xy 206.412115 -344.604643)
			(xy 206.364509 -344.633697) (xy 206.31318 -344.655509) (xy 206.259223 -344.669615) (xy 206.203786 -344.675715)
			(xy 206.148052 -344.673678) (xy 206.093209 -344.663548) (xy 206.040425 -344.645541) (xy 205.990825 -344.62004)
			(xy 205.945467 -344.587589) (xy 205.905318 -344.54888) (xy 205.871232 -344.504737) (xy 205.843936 -344.456102)
			(xy 205.824013 -344.404011) (xy 205.811887 -344.349574) (xy 205.807816 -344.293952) (xy 202.052577 -344.293952)
			(xy 202.042017 -344.309186) (xy 202.002272 -344.351201) (xy 201.979784 -344.36939) (xy 201.971028 -344.376958)
			(xy 201.960842 -344.397712) (xy 201.960226 -344.409268) (xy 201.960226 -344.489532) (xy 201.960826 -344.501096)
			(xy 201.970999 -344.521868) (xy 201.979784 -344.52941) (xy 202.002269 -344.547599) (xy 202.042005 -344.589619)
			(xy 202.074944 -344.637154) (xy 202.100332 -344.689116) (xy 202.117588 -344.744314) (xy 202.126316 -344.801484)
			(xy 202.12685 -344.8304) (xy 202.126364 -344.857651) (xy 202.118608 -344.911599) (xy 202.103253 -344.963894)
			(xy 202.080611 -345.013471) (xy 202.051145 -345.059321) (xy 202.015454 -345.100512) (xy 201.974263 -345.136203)
			(xy 201.928413 -345.165669) (xy 201.878836 -345.188311) (xy 201.826541 -345.203666) (xy 201.772593 -345.211422)
			(xy 201.718091 -345.211422) (xy 201.664143 -345.203666) (xy 201.611848 -345.188311) (xy 201.562271 -345.165669)
			(xy 201.516421 -345.136203) (xy 201.47523 -345.100512) (xy 201.439539 -345.059321) (xy 201.410073 -345.013471)
			(xy 201.387431 -344.963894) (xy 201.372076 -344.911599) (xy 201.36432 -344.857651) (xy 201.363834 -344.8304)
			(xy 170.26636 -344.8304) (xy 170.26636 -347.641164) (xy 170.26584 -347.671137) (xy 170.25652 -347.730353)
			(xy 170.238041 -347.787378) (xy 170.21086 -347.840806) (xy 170.175646 -347.889317) (xy 170.154854 -347.910912)
			(xy 169.795444 -348.270322) (xy 169.773819 -348.291076) (xy 169.725302 -348.326265) (xy 169.671879 -348.353435)
			(xy 169.614866 -348.371917) (xy 169.555664 -348.381257) (xy 169.525696 -348.381828) (xy 168.100502 -348.381828)
			(xy 168.073265 -348.381417) (xy 168.019346 -348.373665) (xy 167.96708 -348.358319) (xy 167.917529 -348.33569)
			(xy 167.871703 -348.306239) (xy 167.830534 -348.270567) (xy 167.794862 -348.229399) (xy 167.765411 -348.183573)
			(xy 167.742782 -348.134022) (xy 167.727435 -348.081756) (xy 167.719683 -348.027837) (xy 167.719683 -347.973363)
			(xy 167.727435 -347.919444) (xy 167.742782 -347.867178) (xy 167.765411 -347.817627) (xy 167.794862 -347.771801)
			(xy 167.830534 -347.730633) (xy 167.871703 -347.694961) (xy 167.917529 -347.66551) (xy 167.96708 -347.642881)
			(xy 168.019346 -347.627535) (xy 168.073265 -347.619783) (xy 168.100502 -347.61932) (xy 169.346626 -347.61932)
			(xy 169.3567 -347.61893) (xy 169.375298 -347.611187) (xy 169.382694 -347.604334) (xy 169.488866 -347.498162)
			(xy 169.49571 -347.490765) (xy 169.503429 -347.472164) (xy 169.503852 -347.462094) (xy 169.503852 -344.141806)
			(xy 169.503436 -344.131735) (xy 169.49571 -344.113137) (xy 169.488866 -344.105738) (xy 167.57523 -342.192102)
			(xy 167.567813 -342.185283) (xy 167.549227 -342.177551) (xy 167.539162 -342.177116) (xy 158.537656 -342.177116)
			(xy 158.527584 -342.177514) (xy 158.508986 -342.185253) (xy 158.501588 -342.192102) (xy 157.87243 -342.82126)
			(xy 157.865619 -342.828683) (xy 157.857882 -342.847265) (xy 157.857444 -342.857328) (xy 157.857444 -343.689686)
			(xy 159.75965 -343.689686) (xy 159.760211 -343.66077) (xy 159.768929 -343.6036) (xy 159.786177 -343.548402)
			(xy 159.81156 -343.496439) (xy 159.844498 -343.448905) (xy 159.884233 -343.406887) (xy 159.906716 -343.388696)
			(xy 159.915478 -343.381134) (xy 159.925661 -343.360375) (xy 159.926274 -343.348818) (xy 159.926274 -343.268554)
			(xy 159.925682 -343.256989) (xy 159.915503 -343.236217) (xy 159.906716 -343.228676) (xy 159.884224 -343.210494)
			(xy 159.844489 -343.168473) (xy 159.81155 -343.120937) (xy 159.786163 -343.068973) (xy 159.768909 -343.013774)
			(xy 159.760183 -342.956603) (xy 159.75965 -342.927686) (xy 159.760136 -342.900435) (xy 159.767892 -342.846487)
			(xy 159.783247 -342.794192) (xy 159.805889 -342.744615) (xy 159.835355 -342.698765) (xy 159.871046 -342.657574)
			(xy 159.912237 -342.621883) (xy 159.958087 -342.592417) (xy 160.007664 -342.569775) (xy 160.059959 -342.55442)
			(xy 160.113907 -342.546664) (xy 160.168409 -342.546664) (xy 160.222357 -342.55442) (xy 160.274652 -342.569775)
			(xy 160.324229 -342.592417) (xy 160.370079 -342.621883) (xy 160.41127 -342.657574) (xy 160.446961 -342.698765)
			(xy 160.476427 -342.744615) (xy 160.499069 -342.794192) (xy 160.514424 -342.846487) (xy 160.52218 -342.900435)
			(xy 160.522666 -342.927686) (xy 160.52215 -342.956603) (xy 160.513423 -343.013775) (xy 160.496165 -343.068975)
			(xy 160.470773 -343.120936) (xy 160.437828 -343.16847) (xy 160.398086 -343.210486) (xy 160.3756 -343.228676)
			(xy 160.366853 -343.236253) (xy 160.356662 -343.257) (xy 160.356042 -343.268554) (xy 160.356042 -343.348818)
			(xy 160.356588 -343.360389) (xy 160.366798 -343.381161) (xy 160.3756 -343.388696) (xy 160.398082 -343.406889)
			(xy 160.437817 -343.448909) (xy 160.470756 -343.496443) (xy 160.496145 -343.548404) (xy 160.513401 -343.603601)
			(xy 160.522131 -343.66077) (xy 160.522666 -343.689686) (xy 160.52218 -343.716937) (xy 160.514424 -343.770885)
			(xy 160.499069 -343.82318) (xy 160.486954 -343.849706) (xy 160.851086 -343.849706) (xy 160.855157 -343.794084)
			(xy 160.867283 -343.739647) (xy 160.887206 -343.687556) (xy 160.914502 -343.638921) (xy 160.948588 -343.594778)
			(xy 160.988737 -343.556069) (xy 161.034095 -343.523618) (xy 161.083695 -343.498117) (xy 161.136479 -343.48011)
			(xy 161.191322 -343.46998) (xy 161.247056 -343.467943) (xy 161.302493 -343.474043) (xy 161.35645 -343.488149)
			(xy 161.407779 -343.509961) (xy 161.455385 -343.539015) (xy 161.498253 -343.57469) (xy 161.53547 -343.616227)
			(xy 161.566243 -343.66274) (xy 161.589915 -343.713237) (xy 161.605983 -343.766644) (xy 161.614103 -343.82182)
			(xy 161.614612 -343.849706) (xy 161.614103 -343.877592) (xy 161.605983 -343.932768) (xy 161.589915 -343.986175)
			(xy 161.566243 -344.036672) (xy 161.53547 -344.083185) (xy 161.498253 -344.124722) (xy 161.455385 -344.160397)
			(xy 161.407779 -344.189451) (xy 161.35645 -344.211263) (xy 161.302493 -344.225369) (xy 161.247056 -344.231469)
			(xy 161.191322 -344.229432) (xy 161.136479 -344.219302) (xy 161.083695 -344.201295) (xy 161.034095 -344.175794)
			(xy 160.988737 -344.143343) (xy 160.948588 -344.104634) (xy 160.914502 -344.060491) (xy 160.887206 -344.011856)
			(xy 160.867283 -343.959765) (xy 160.855157 -343.905328) (xy 160.851086 -343.849706) (xy 160.486954 -343.849706)
			(xy 160.476427 -343.872757) (xy 160.446961 -343.918607) (xy 160.41127 -343.959798) (xy 160.370079 -343.995489)
			(xy 160.324229 -344.024955) (xy 160.274652 -344.047597) (xy 160.222357 -344.062952) (xy 160.168409 -344.070708)
			(xy 160.113907 -344.070708) (xy 160.059959 -344.062952) (xy 160.007664 -344.047597) (xy 159.958087 -344.024955)
			(xy 159.912237 -343.995489) (xy 159.871046 -343.959798) (xy 159.835355 -343.918607) (xy 159.805889 -343.872757)
			(xy 159.783247 -343.82318) (xy 159.767892 -343.770885) (xy 159.760136 -343.716937) (xy 159.75965 -343.689686)
			(xy 157.857444 -343.689686) (xy 157.857444 -345.078304) (xy 160.503106 -345.078304) (xy 160.507177 -345.022682)
			(xy 160.519303 -344.968245) (xy 160.539226 -344.916154) (xy 160.566522 -344.867519) (xy 160.600608 -344.823376)
			(xy 160.640757 -344.784667) (xy 160.686115 -344.752216) (xy 160.735715 -344.726715) (xy 160.788499 -344.708708)
			(xy 160.843342 -344.698578) (xy 160.899076 -344.696541) (xy 160.954513 -344.702641) (xy 161.00847 -344.716747)
			(xy 161.059799 -344.738559) (xy 161.107405 -344.767613) (xy 161.150273 -344.803288) (xy 161.18749 -344.844825)
			(xy 161.218263 -344.891338) (xy 161.241935 -344.941835) (xy 161.258003 -344.995242) (xy 161.266123 -345.050418)
			(xy 161.266632 -345.078304) (xy 161.266123 -345.10619) (xy 161.258003 -345.161366) (xy 161.241935 -345.214773)
			(xy 161.218263 -345.26527) (xy 161.18749 -345.311783) (xy 161.150273 -345.35332) (xy 161.107405 -345.388995)
			(xy 161.059799 -345.418049) (xy 161.00847 -345.439861) (xy 160.954513 -345.453967) (xy 160.899076 -345.460067)
			(xy 160.843342 -345.45803) (xy 160.788499 -345.4479) (xy 160.735715 -345.429893) (xy 160.686115 -345.404392)
			(xy 160.640757 -345.371941) (xy 160.600608 -345.333232) (xy 160.566522 -345.289089) (xy 160.539226 -345.240454)
			(xy 160.519303 -345.188363) (xy 160.507177 -345.133926) (xy 160.503106 -345.078304) (xy 157.857444 -345.078304)
			(xy 157.857444 -348.418404) (xy 157.856954 -348.448378) (xy 157.847627 -348.507595) (xy 157.829141 -348.564621)
			(xy 157.801953 -348.618048) (xy 157.766733 -348.666559) (xy 157.745938 -348.688152) (xy 157.626812 -348.807278)
			(xy 158.315912 -348.807278) (xy 158.319983 -348.751656) (xy 158.332109 -348.697219) (xy 158.352032 -348.645128)
			(xy 158.379328 -348.596493) (xy 158.413414 -348.55235) (xy 158.453563 -348.513641) (xy 158.498921 -348.48119)
			(xy 158.548521 -348.455689) (xy 158.601305 -348.437682) (xy 158.656148 -348.427552) (xy 158.711882 -348.425515)
			(xy 158.767319 -348.431615) (xy 158.821276 -348.445721) (xy 158.872605 -348.467533) (xy 158.920211 -348.496587)
			(xy 158.963079 -348.532262) (xy 159.000296 -348.573799) (xy 159.031069 -348.620312) (xy 159.054741 -348.670809)
			(xy 159.070809 -348.724216) (xy 159.078929 -348.779392) (xy 159.079438 -348.807278) (xy 159.078929 -348.835164)
			(xy 159.070809 -348.89034) (xy 159.054741 -348.943747) (xy 159.031069 -348.994244) (xy 159.000296 -349.040757)
			(xy 158.963079 -349.082294) (xy 158.920211 -349.117969) (xy 158.872605 -349.147023) (xy 158.821276 -349.168835)
			(xy 158.767319 -349.182941) (xy 158.711882 -349.189041) (xy 158.656148 -349.187004) (xy 158.601305 -349.176874)
			(xy 158.548521 -349.158867) (xy 158.498921 -349.133366) (xy 158.453563 -349.100915) (xy 158.413414 -349.062206)
			(xy 158.379328 -349.018063) (xy 158.352032 -348.969428) (xy 158.332109 -348.917337) (xy 158.319983 -348.8629)
			(xy 158.315912 -348.807278) (xy 157.626812 -348.807278) (xy 156.893514 -349.540576) (xy 156.871925 -349.561387)
			(xy 156.823421 -349.596641) (xy 156.769998 -349.62387) (xy 156.712971 -349.642402) (xy 156.653747 -349.651781)
			(xy 156.623766 -349.652336) (xy 156.596518 -349.651922) (xy 156.542578 -349.644159) (xy 156.490293 -349.628795)
			(xy 156.440727 -349.606143) (xy 156.394892 -349.576666) (xy 156.35372 -349.540964) (xy 156.31805 -349.499763)
			(xy 156.28861 -349.453904) (xy 156.265998 -349.40432) (xy 156.250676 -349.352023) (xy 156.242956 -349.298076)
			(xy 156.242512 -349.270828) (xy 154.701393 -349.270828) (xy 154.691873 -349.278751) (xy 154.644267 -349.307805)
			(xy 154.592938 -349.329617) (xy 154.538981 -349.343723) (xy 154.483544 -349.349823) (xy 154.42781 -349.347786)
			(xy 154.372967 -349.337656) (xy 154.320183 -349.319649) (xy 154.270583 -349.294148) (xy 154.225225 -349.261697)
			(xy 154.185076 -349.222988) (xy 154.15099 -349.178845) (xy 154.123694 -349.13021) (xy 154.103771 -349.078119)
			(xy 154.091645 -349.023682) (xy 154.087574 -348.96806) (xy 153.63571 -348.96806) (xy 153.63571 -349.236538)
			(xy 153.63614 -349.246605) (xy 153.643866 -349.265198) (xy 153.650696 -349.272606) (xy 154.469592 -350.091502)
			(xy 158.361886 -350.091502) (xy 158.365957 -350.03588) (xy 158.378083 -349.981443) (xy 158.398006 -349.929352)
			(xy 158.425302 -349.880717) (xy 158.459388 -349.836574) (xy 158.499537 -349.797865) (xy 158.544895 -349.765414)
			(xy 158.594495 -349.739913) (xy 158.647279 -349.721906) (xy 158.702122 -349.711776) (xy 158.757856 -349.709739)
			(xy 158.813293 -349.715839) (xy 158.86725 -349.729945) (xy 158.918579 -349.751757) (xy 158.966185 -349.780811)
			(xy 159.009053 -349.816486) (xy 159.04627 -349.858023) (xy 159.077043 -349.904536) (xy 159.100715 -349.955033)
			(xy 159.116783 -350.00844) (xy 159.124903 -350.063616) (xy 159.125412 -350.091502) (xy 159.124903 -350.119388)
			(xy 159.116783 -350.174564) (xy 159.100715 -350.227971) (xy 159.077043 -350.278468) (xy 159.04627 -350.324981)
			(xy 159.009053 -350.366518) (xy 158.966185 -350.402193) (xy 158.918579 -350.431247) (xy 158.86725 -350.453059)
			(xy 158.813293 -350.467165) (xy 158.757856 -350.473265) (xy 158.702122 -350.471228) (xy 158.647279 -350.461098)
			(xy 158.594495 -350.443091) (xy 158.544895 -350.41759) (xy 158.499537 -350.385139) (xy 158.459388 -350.34643)
			(xy 158.425302 -350.302287) (xy 158.398006 -350.253652) (xy 158.378083 -350.201561) (xy 158.365957 -350.147124)
			(xy 158.361886 -350.091502) (xy 154.469592 -350.091502) (xy 155.776168 -351.398078) (xy 158.417512 -351.398078)
			(xy 158.421583 -351.342456) (xy 158.433709 -351.288019) (xy 158.453632 -351.235928) (xy 158.480928 -351.187293)
			(xy 158.515014 -351.14315) (xy 158.555163 -351.104441) (xy 158.600521 -351.07199) (xy 158.650121 -351.046489)
			(xy 158.702905 -351.028482) (xy 158.757748 -351.018352) (xy 158.813482 -351.016315) (xy 158.868919 -351.022415)
			(xy 158.922876 -351.036521) (xy 158.974205 -351.058333) (xy 159.021811 -351.087387) (xy 159.064679 -351.123062)
			(xy 159.101896 -351.164599) (xy 159.132669 -351.211112) (xy 159.156341 -351.261609) (xy 159.172409 -351.315016)
			(xy 159.180529 -351.370192) (xy 159.181038 -351.398078) (xy 159.180529 -351.425964) (xy 159.172409 -351.48114)
			(xy 159.156341 -351.534547) (xy 159.132669 -351.585044) (xy 159.101896 -351.631557) (xy 159.064679 -351.673094)
			(xy 159.021811 -351.708769) (xy 158.974205 -351.737823) (xy 158.922876 -351.759635) (xy 158.868919 -351.773741)
			(xy 158.813482 -351.779841) (xy 158.757748 -351.777804) (xy 158.702905 -351.767674) (xy 158.650121 -351.749667)
			(xy 158.600521 -351.724166) (xy 158.555163 -351.691715) (xy 158.515014 -351.653006) (xy 158.480928 -351.608863)
			(xy 158.453632 -351.560228) (xy 158.433709 -351.508137) (xy 158.421583 -351.4537) (xy 158.417512 -351.398078)
			(xy 155.776168 -351.398078) (xy 155.977844 -351.599754) (xy 155.984688 -351.607153) (xy 155.992412 -351.625752)
			(xy 155.99283 -351.635822) (xy 155.99283 -352.102928) (xy 156.238192 -352.102928) (xy 156.242263 -352.047306)
			(xy 156.254389 -351.992869) (xy 156.274312 -351.940778) (xy 156.301608 -351.892143) (xy 156.335694 -351.848)
			(xy 156.375843 -351.809291) (xy 156.421201 -351.77684) (xy 156.470801 -351.751339) (xy 156.523585 -351.733332)
			(xy 156.578428 -351.723202) (xy 156.634162 -351.721165) (xy 156.689599 -351.727265) (xy 156.743556 -351.741371)
			(xy 156.794885 -351.763183) (xy 156.842491 -351.792237) (xy 156.885359 -351.827912) (xy 156.922576 -351.869449)
			(xy 156.953349 -351.915962) (xy 156.977021 -351.966459) (xy 156.993089 -352.019866) (xy 157.001209 -352.075042)
			(xy 157.001718 -352.102928) (xy 157.001209 -352.130814) (xy 156.993089 -352.18599) (xy 156.977021 -352.239397)
			(xy 156.953349 -352.289894) (xy 156.922576 -352.336407) (xy 156.885359 -352.377944) (xy 156.842491 -352.413619)
			(xy 156.794885 -352.442673) (xy 156.743556 -352.464485) (xy 156.689599 -352.478591) (xy 156.634162 -352.484691)
			(xy 156.578428 -352.482654) (xy 156.523585 -352.472524) (xy 156.470801 -352.454517) (xy 156.421201 -352.429016)
			(xy 156.375843 -352.396565) (xy 156.335694 -352.357856) (xy 156.301608 -352.313713) (xy 156.274312 -352.265078)
			(xy 156.254389 -352.212987) (xy 156.242263 -352.15855) (xy 156.238192 -352.102928) (xy 155.99283 -352.102928)
			(xy 155.99283 -352.526346) (xy 155.993262 -352.536412) (xy 156.000992 -352.555001) (xy 156.007816 -352.562414)
			(xy 156.3624 -352.916998) (xy 156.396182 -352.92157) (xy 156.411168 -352.913188) (xy 156.432634 -352.901597)
			(xy 156.477879 -352.883357) (xy 156.52508 -352.871027) (xy 156.573466 -352.864809) (xy 156.597858 -352.86442)
			(xy 156.625112 -352.86488) (xy 156.679066 -352.872633) (xy 156.731367 -352.887985) (xy 156.780951 -352.910626)
			(xy 156.826807 -352.940093) (xy 156.868003 -352.975787) (xy 156.903698 -353.016981) (xy 156.933167 -353.062837)
			(xy 156.95581 -353.11242) (xy 156.971164 -353.16472) (xy 156.978919 -353.218674) (xy 156.979366 -353.245928)
			(xy 156.978978 -353.27032) (xy 156.972758 -353.318705) (xy 156.960423 -353.365903) (xy 156.942175 -353.411145)
			(xy 156.930598 -353.432618) (xy 156.922216 -353.447604) (xy 156.926788 -353.481386) (xy 157.339792 -353.89439)
			(xy 157.69539 -353.89439) (xy 157.699461 -353.838768) (xy 157.711587 -353.784331) (xy 157.73151 -353.73224)
			(xy 157.758806 -353.683605) (xy 157.792892 -353.639462) (xy 157.833041 -353.600753) (xy 157.878399 -353.568302)
			(xy 157.927999 -353.542801) (xy 157.980783 -353.524794) (xy 158.035626 -353.514664) (xy 158.09136 -353.512627)
			(xy 158.146797 -353.518727) (xy 158.200754 -353.532833) (xy 158.252083 -353.554645) (xy 158.299689 -353.583699)
			(xy 158.342557 -353.619374) (xy 158.379774 -353.660911) (xy 158.410547 -353.707424) (xy 158.434219 -353.757921)
			(xy 158.450287 -353.811328) (xy 158.458407 -353.866504) (xy 158.458916 -353.89439) (xy 158.458407 -353.922276)
			(xy 158.450287 -353.977452) (xy 158.434219 -354.030859) (xy 158.410547 -354.081356) (xy 158.379774 -354.127869)
			(xy 158.342557 -354.169406) (xy 158.299689 -354.205081) (xy 158.252083 -354.234135) (xy 158.200754 -354.255947)
			(xy 158.146797 -354.270053) (xy 158.09136 -354.276153) (xy 158.035626 -354.274116) (xy 157.980783 -354.263986)
			(xy 157.927999 -354.245979) (xy 157.878399 -354.220478) (xy 157.833041 -354.188027) (xy 157.792892 -354.149318)
			(xy 157.758806 -354.105175) (xy 157.73151 -354.05654) (xy 157.711587 -354.004449) (xy 157.699461 -353.950012)
			(xy 157.69539 -353.89439) (xy 157.339792 -353.89439) (xy 157.99816 -354.552758) (xy 158.00556 -354.5596)
			(xy 158.024158 -354.567319) (xy 158.034228 -354.567744) (xy 159.918654 -354.567744) (xy 159.928652 -354.567254)
			(xy 159.947136 -354.559624) (xy 159.961326 -354.545533) (xy 159.965644 -354.536502) (xy 159.971486 -354.522024)
			(xy 159.965644 -354.492052) (xy 159.468312 -353.994974) (xy 159.454503 -353.980493) (xy 159.432312 -353.947202)
			(xy 159.417055 -353.910216) (xy 159.409322 -353.870962) (xy 159.408876 -353.850956) (xy 159.408876 -347.449394)
			(xy 159.409346 -347.429393) (xy 159.417105 -347.390153) (xy 159.432365 -347.353178) (xy 159.45454 -347.319887)
			(xy 159.468312 -347.305376) (xy 160.921446 -345.852242) (xy 160.935947 -345.838442) (xy 160.969227 -345.81621)
			(xy 161.006202 -345.800888) (xy 161.045453 -345.793064) (xy 161.065464 -345.792552) (xy 162.503866 -345.792552)
			(xy 162.513896 -345.79211) (xy 162.532464 -345.784527) (xy 162.539934 -345.77782) (xy 162.707066 -345.610434)
			(xy 162.721565 -345.59663) (xy 162.754843 -345.574392) (xy 162.791818 -345.559066) (xy 162.831072 -345.551242)
			(xy 162.851084 -345.550744) (xy 167.529002 -345.550744) (xy 167.549022 -345.551195) (xy 167.588293 -345.558997)
			(xy 167.625283 -345.57432) (xy 167.658568 -345.596574) (xy 167.67302 -345.610434) (xy 167.982138 -345.919806)
			(xy 168.004998 -345.927172) (xy 168.01719 -345.92514) (xy 168.031953 -345.922977) (xy 168.061706 -345.920688)
			(xy 168.076626 -345.920568) (xy 168.103879 -345.921056) (xy 168.157829 -345.928816) (xy 168.210126 -345.944176)
			(xy 168.259705 -345.966822) (xy 168.305556 -345.996293) (xy 168.346747 -346.03199) (xy 168.382438 -346.073185)
			(xy 168.411903 -346.11904) (xy 168.434542 -346.168622) (xy 168.449895 -346.220921) (xy 168.457648 -346.274872)
			(xy 168.457644 -346.329378) (xy 168.449884 -346.383329) (xy 168.434524 -346.435626) (xy 168.411878 -346.485205)
			(xy 168.382407 -346.531056) (xy 168.346711 -346.572246) (xy 168.305516 -346.607937) (xy 168.259661 -346.637402)
			(xy 168.210079 -346.660042) (xy 168.15778 -346.675394) (xy 168.103828 -346.683148) (xy 168.049322 -346.683144)
			(xy 167.995372 -346.675384) (xy 167.943075 -346.660024) (xy 167.893496 -346.637379) (xy 167.847645 -346.607908)
			(xy 167.806454 -346.572211) (xy 167.770763 -346.531016) (xy 167.741298 -346.485161) (xy 167.718658 -346.435579)
			(xy 167.703306 -346.383281) (xy 167.695552 -346.329329) (xy 167.695118 -346.302076) (xy 167.695243 -346.287156)
			(xy 167.697532 -346.257404) (xy 167.69969 -346.24264) (xy 167.701722 -346.230448) (xy 167.694356 -346.207588)
			(xy 167.45966 -345.972892) (xy 167.452238 -345.966106) (xy 167.433642 -345.958491) (xy 167.423592 -345.95816)
			(xy 166.059612 -345.95816) (xy 166.047572 -345.95877) (xy 166.026103 -345.969659) (xy 166.018464 -345.978988)
			(xy 165.963092 -346.055696) (xy 165.959282 -346.08008) (xy 165.963346 -346.09151) (xy 165.972379 -346.12072)
			(xy 165.982076 -346.181083) (xy 165.98265 -346.211652) (xy 165.982084 -346.242064) (xy 165.972477 -346.302124)
			(xy 165.953451 -346.359895) (xy 165.939978 -346.387166) (xy 165.934136 -346.398088) (xy 165.934136 -346.422472)
			(xy 165.982904 -346.51823) (xy 166.002716 -346.532454) (xy 166.014908 -346.534232) (xy 166.041624 -346.538778)
			(xy 166.093504 -346.554432) (xy 166.142648 -346.577269) (xy 166.188066 -346.60683) (xy 166.228844 -346.642521)
			(xy 166.264161 -346.683623) (xy 166.293307 -346.729308) (xy 166.315695 -346.778659) (xy 166.330874 -346.83068)
			(xy 166.338539 -346.884327) (xy 166.339012 -346.911422) (xy 166.338526 -346.938673) (xy 166.33077 -346.992621)
			(xy 166.315415 -347.044916) (xy 166.292773 -347.094493) (xy 166.263307 -347.140343) (xy 166.227616 -347.181534)
			(xy 166.186425 -347.217225) (xy 166.140575 -347.246691) (xy 166.090998 -347.269333) (xy 166.038703 -347.284688)
			(xy 165.984755 -347.292444) (xy 165.930253 -347.292444) (xy 165.876305 -347.284688) (xy 165.82401 -347.269333)
			(xy 165.774433 -347.246691) (xy 165.728583 -347.217225) (xy 165.687392 -347.181534) (xy 165.651701 -347.140343)
			(xy 165.622235 -347.094493) (xy 165.599593 -347.044916) (xy 165.584238 -346.992621) (xy 165.576482 -346.938673)
			(xy 165.575996 -346.911422) (xy 165.576564 -346.88101) (xy 165.586177 -346.820953) (xy 165.605208 -346.763185)
			(xy 165.618668 -346.735908) (xy 165.62451 -346.724986) (xy 165.62451 -346.700602) (xy 165.575742 -346.604844)
			(xy 165.55593 -346.59062) (xy 165.543738 -346.588842) (xy 165.517021 -346.584298) (xy 165.465137 -346.568649)
			(xy 165.415989 -346.545814) (xy 165.370568 -346.516254) (xy 165.329787 -346.480564) (xy 165.294468 -346.439461)
			(xy 165.265321 -346.393774) (xy 165.242933 -346.344421) (xy 165.227755 -346.292397) (xy 165.220093 -346.238749)
			(xy 165.219634 -346.211652) (xy 165.220222 -346.181084) (xy 165.229925 -346.120725) (xy 165.238938 -346.09151)
			(xy 165.243002 -346.08008) (xy 165.239192 -346.055696) (xy 165.18382 -345.978988) (xy 165.17617 -345.969678)
			(xy 165.154704 -345.958799) (xy 165.142672 -345.95816) (xy 162.956494 -345.95816) (xy 162.946467 -345.958609)
			(xy 162.927911 -345.966204) (xy 162.920426 -345.972892) (xy 162.753294 -346.140278) (xy 162.738797 -346.154086)
			(xy 162.70552 -346.176333) (xy 162.668545 -346.191668) (xy 162.62929 -346.199504) (xy 162.609276 -346.199968)
			(xy 161.170874 -346.199968) (xy 161.160847 -346.200418) (xy 161.142288 -346.208008) (xy 161.134806 -346.2147)
			(xy 159.83077 -347.518736) (xy 159.823922 -347.526133) (xy 159.816189 -347.544732) (xy 159.815784 -347.554804)
			(xy 159.815784 -349.328232) (xy 165.391846 -349.328232) (xy 165.392346 -349.30034) (xy 165.400459 -349.245149)
			(xy 165.416529 -349.19173) (xy 165.440215 -349.141225) (xy 165.47101 -349.094712) (xy 165.508257 -349.053184)
			(xy 165.551158 -349.017529) (xy 165.574726 -349.002604) (xy 165.584124 -348.996762) (xy 165.596316 -348.978728)
			(xy 165.613588 -348.882208) (xy 165.608254 -348.861126) (xy 165.601396 -348.85249) (xy 165.585731 -348.832176)
			(xy 165.55946 -348.788114) (xy 165.539321 -348.740933) (xy 165.525677 -348.691482) (xy 165.518773 -348.640649)
			(xy 165.518338 -348.615) (xy 165.518907 -348.586442) (xy 165.527415 -348.529964) (xy 165.544241 -348.475384)
			(xy 165.569009 -348.423918) (xy 165.601167 -348.376716) (xy 165.620192 -348.355412) (xy 165.62705 -348.348046)
			(xy 165.633908 -348.330012) (xy 165.632384 -348.239334) (xy 165.624764 -348.221554) (xy 165.617652 -348.214442)
			(xy 165.596896 -348.192852) (xy 165.561726 -348.14438) (xy 165.534565 -348.091007) (xy 165.516081 -348.034044)
			(xy 165.506728 -347.974892) (xy 165.506146 -347.944948) (xy 165.506632 -347.917697) (xy 165.514388 -347.863749)
			(xy 165.529743 -347.811454) (xy 165.552385 -347.761877) (xy 165.581851 -347.716027) (xy 165.617542 -347.674836)
			(xy 165.658733 -347.639145) (xy 165.704583 -347.609679) (xy 165.75416 -347.587037) (xy 165.806455 -347.571682)
			(xy 165.860403 -347.563926) (xy 165.914905 -347.563926) (xy 165.968853 -347.571682) (xy 166.021148 -347.587037)
			(xy 166.070725 -347.609679) (xy 166.116575 -347.639145) (xy 166.157766 -347.674836) (xy 166.193457 -347.716027)
			(xy 166.222923 -347.761877) (xy 166.245565 -347.811454) (xy 166.26092 -347.863749) (xy 166.268676 -347.917697)
			(xy 166.269162 -347.944948) (xy 166.268622 -347.973507) (xy 166.260107 -348.029986) (xy 166.243274 -348.084567)
			(xy 166.2185 -348.136032) (xy 166.186336 -348.183232) (xy 166.167308 -348.204536) (xy 166.16045 -348.211902)
			(xy 166.153592 -348.229936) (xy 166.155116 -348.320614) (xy 166.162736 -348.338394) (xy 166.169848 -348.345506)
			(xy 166.190579 -348.367119) (xy 166.225752 -348.415585) (xy 166.252918 -348.468952) (xy 166.271408 -348.52591)
			(xy 166.280768 -348.585058) (xy 166.281354 -348.615) (xy 166.280879 -348.642893) (xy 166.272762 -348.698085)
			(xy 166.256687 -348.751504) (xy 166.232997 -348.80201) (xy 166.202198 -348.848523) (xy 166.164948 -348.89005)
			(xy 166.122043 -348.925703) (xy 166.098474 -348.940628) (xy 166.089076 -348.94647) (xy 166.076884 -348.964504)
			(xy 166.059612 -349.061024) (xy 166.064946 -349.082106) (xy 166.071804 -349.090742) (xy 166.087438 -349.111079)
			(xy 166.113714 -349.155134) (xy 166.133859 -349.202309) (xy 166.14751 -349.251756) (xy 166.154423 -349.302584)
			(xy 166.154862 -349.328232) (xy 166.154275 -349.359057) (xy 166.144345 -349.419902) (xy 166.124751 -349.478355)
			(xy 166.096003 -349.532892) (xy 166.0779 -349.557848) (xy 166.07155 -349.56623) (xy 166.066724 -349.58655)
			(xy 166.082726 -349.680276) (xy 166.094156 -349.697802) (xy 166.102792 -349.703644) (xy 166.121171 -349.716344)
			(xy 168.5704 -349.716344) (xy 168.574471 -349.660722) (xy 168.586597 -349.606285) (xy 168.60652 -349.554194)
			(xy 168.633816 -349.505559) (xy 168.667902 -349.461416) (xy 168.708051 -349.422707) (xy 168.753409 -349.390256)
			(xy 168.803009 -349.364755) (xy 168.855793 -349.346748) (xy 168.910636 -349.336618) (xy 168.96637 -349.334581)
			(xy 169.021807 -349.340681) (xy 169.075764 -349.354787) (xy 169.127093 -349.376599) (xy 169.174699 -349.405653)
			(xy 169.217567 -349.441328) (xy 169.254784 -349.482865) (xy 169.285557 -349.529378) (xy 169.309229 -349.579875)
			(xy 169.325297 -349.633282) (xy 169.333417 -349.688458) (xy 169.333926 -349.716344) (xy 169.333417 -349.74423)
			(xy 169.325297 -349.799406) (xy 169.309229 -349.852813) (xy 169.285557 -349.90331) (xy 169.254784 -349.949823)
			(xy 169.217567 -349.99136) (xy 169.174699 -350.027035) (xy 169.127093 -350.056089) (xy 169.075764 -350.077901)
			(xy 169.021807 -350.092007) (xy 168.96637 -350.098107) (xy 168.910636 -350.09607) (xy 168.855793 -350.08594)
			(xy 168.803009 -350.067933) (xy 168.753409 -350.042432) (xy 168.708051 -350.009981) (xy 168.667902 -349.971272)
			(xy 168.633816 -349.927129) (xy 168.60652 -349.878494) (xy 168.586597 -349.826403) (xy 168.574471 -349.771966)
			(xy 168.5704 -349.716344) (xy 166.121171 -349.716344) (xy 166.124874 -349.718903) (xy 166.164991 -349.754562)
			(xy 166.199711 -349.795494) (xy 166.228348 -349.840891) (xy 166.250337 -349.889854) (xy 166.265242 -349.941417)
			(xy 166.272769 -349.994561) (xy 166.273226 -350.021398) (xy 166.27274 -350.048649) (xy 166.264984 -350.102597)
			(xy 166.249629 -350.154892) (xy 166.226987 -350.204469) (xy 166.197521 -350.250319) (xy 166.16183 -350.29151)
			(xy 166.120639 -350.327201) (xy 166.074789 -350.356667) (xy 166.025212 -350.379309) (xy 165.972917 -350.394664)
			(xy 165.918969 -350.40242) (xy 165.864467 -350.40242) (xy 165.810519 -350.394664) (xy 165.758224 -350.379309)
			(xy 165.708647 -350.356667) (xy 165.662797 -350.327201) (xy 165.621606 -350.29151) (xy 165.585915 -350.250319)
			(xy 165.556449 -350.204469) (xy 165.533807 -350.154892) (xy 165.518452 -350.102597) (xy 165.510696 -350.048649)
			(xy 165.51021 -350.021398) (xy 165.510819 -349.990574) (xy 165.520742 -349.92973) (xy 165.540331 -349.871277)
			(xy 165.569073 -349.81674) (xy 165.587172 -349.791782) (xy 165.593522 -349.7834) (xy 165.598348 -349.76308)
			(xy 165.582346 -349.669354) (xy 165.570916 -349.651828) (xy 165.56228 -349.645986) (xy 165.540159 -349.63078)
			(xy 165.500044 -349.595112) (xy 165.465328 -349.55417) (xy 165.436696 -349.508764) (xy 165.414714 -349.459792)
			(xy 165.399817 -349.408222) (xy 165.392299 -349.355072) (xy 165.391846 -349.328232) (xy 159.815784 -349.328232)
			(xy 159.815784 -350.732344) (xy 168.5704 -350.732344) (xy 168.574471 -350.676722) (xy 168.586597 -350.622285)
			(xy 168.60652 -350.570194) (xy 168.633816 -350.521559) (xy 168.667902 -350.477416) (xy 168.708051 -350.438707)
			(xy 168.753409 -350.406256) (xy 168.803009 -350.380755) (xy 168.855793 -350.362748) (xy 168.910636 -350.352618)
			(xy 168.96637 -350.350581) (xy 169.021807 -350.356681) (xy 169.075764 -350.370787) (xy 169.127093 -350.392599)
			(xy 169.174699 -350.421653) (xy 169.217567 -350.457328) (xy 169.254784 -350.498865) (xy 169.285557 -350.545378)
			(xy 169.309229 -350.595875) (xy 169.325297 -350.649282) (xy 169.333417 -350.704458) (xy 169.333926 -350.732344)
			(xy 169.333417 -350.76023) (xy 169.325297 -350.815406) (xy 169.309229 -350.868813) (xy 169.285557 -350.91931)
			(xy 169.254784 -350.965823) (xy 169.217567 -351.00736) (xy 169.174699 -351.043035) (xy 169.127093 -351.072089)
			(xy 169.075764 -351.093901) (xy 169.021807 -351.108007) (xy 168.96637 -351.114107) (xy 168.910636 -351.11207)
			(xy 168.855793 -351.10194) (xy 168.803009 -351.083933) (xy 168.753409 -351.058432) (xy 168.708051 -351.025981)
			(xy 168.667902 -350.987272) (xy 168.633816 -350.943129) (xy 168.60652 -350.894494) (xy 168.586597 -350.842403)
			(xy 168.574471 -350.787966) (xy 168.5704 -350.732344) (xy 159.815784 -350.732344) (xy 159.815784 -351.144332)
			(xy 159.816449 -351.156405) (xy 159.827449 -351.177897) (xy 159.836866 -351.18548) (xy 159.913574 -351.240852)
			(xy 159.937958 -351.244662) (xy 159.949388 -351.240598) (xy 159.978597 -351.231563) (xy 160.03896 -351.22186)
			(xy 160.06953 -351.221294) (xy 160.09678 -351.221782) (xy 160.150724 -351.229542) (xy 160.203015 -351.244899)
			(xy 160.252588 -351.267542) (xy 160.298434 -351.297009) (xy 160.339621 -351.3327) (xy 160.375309 -351.37389)
			(xy 160.404772 -351.419738) (xy 160.427411 -351.469313) (xy 160.442765 -351.521605) (xy 160.45052 -351.57555)
			(xy 160.45052 -351.63005) (xy 160.447353 -351.652078) (xy 160.907222 -351.652078) (xy 160.907794 -351.623451)
			(xy 160.916361 -351.56684) (xy 160.933285 -351.512143) (xy 160.958185 -351.460586) (xy 160.990505 -351.413325)
			(xy 161.029518 -351.371419) (xy 161.074352 -351.335808) (xy 161.124 -351.307291) (xy 161.177349 -351.286506)
			(xy 161.205164 -351.279714) (xy 161.212276 -351.27819) (xy 161.224722 -351.271332) (xy 161.651696 -350.844358)
			(xy 161.666187 -350.830542) (xy 161.699458 -350.808279) (xy 161.736436 -350.792943) (xy 161.775698 -350.785127)
			(xy 161.795714 -350.784668) (xy 162.522662 -350.784668) (xy 162.542674 -350.785159) (xy 162.581927 -350.792989)
			(xy 162.618901 -350.808317) (xy 162.65218 -350.830555) (xy 162.66668 -350.844358) (xy 163.398834 -351.57664)
			(xy 164.057836 -351.57664) (xy 164.061907 -351.521018) (xy 164.074033 -351.466581) (xy 164.093956 -351.41449)
			(xy 164.121252 -351.365855) (xy 164.155338 -351.321712) (xy 164.195487 -351.283003) (xy 164.240845 -351.250552)
			(xy 164.290445 -351.225051) (xy 164.343229 -351.207044) (xy 164.398072 -351.196914) (xy 164.453806 -351.194877)
			(xy 164.509243 -351.200977) (xy 164.5632 -351.215083) (xy 164.614529 -351.236895) (xy 164.662135 -351.265949)
			(xy 164.705003 -351.301624) (xy 164.74222 -351.343161) (xy 164.772993 -351.389674) (xy 164.796665 -351.440171)
			(xy 164.812733 -351.493578) (xy 164.820853 -351.548754) (xy 164.821362 -351.57664) (xy 164.820853 -351.604526)
			(xy 164.812733 -351.659702) (xy 164.796665 -351.713109) (xy 164.772993 -351.763606) (xy 164.74222 -351.810119)
			(xy 164.705003 -351.851656) (xy 164.662135 -351.887331) (xy 164.614529 -351.916385) (xy 164.5632 -351.938197)
			(xy 164.509243 -351.952303) (xy 164.453806 -351.958403) (xy 164.398072 -351.956366) (xy 164.343229 -351.946236)
			(xy 164.290445 -351.928229) (xy 164.240845 -351.902728) (xy 164.195487 -351.870277) (xy 164.155338 -351.831568)
			(xy 164.121252 -351.787425) (xy 164.093956 -351.73879) (xy 164.074033 -351.686699) (xy 164.061907 -351.632262)
			(xy 164.057836 -351.57664) (xy 163.398834 -351.57664) (xy 164.119306 -352.297238) (xy 164.126705 -352.304078)
			(xy 164.145305 -352.311797) (xy 164.155374 -352.312224) (xy 168.873424 -352.312224) (xy 168.893431 -352.312643)
			(xy 168.932685 -352.320388) (xy 168.969671 -352.335653) (xy 169.002961 -352.357849) (xy 169.017442 -352.37166)
			(xy 169.596018 -352.950272) (xy 178.85537 -352.950272) (xy 178.855839 -352.922325) (xy 178.864009 -352.867032)
			(xy 178.880157 -352.813522) (xy 178.903937 -352.76294) (xy 178.93484 -352.716366) (xy 178.95316 -352.695256)
			(xy 178.95951 -352.688144) (xy 178.966114 -352.670872) (xy 178.966114 -352.584004) (xy 178.95951 -352.566732)
			(xy 178.95316 -352.55962) (xy 178.934864 -352.538536) (xy 178.90404 -352.491993) (xy 178.880329 -352.441454)
			(xy 178.864237 -352.387999) (xy 178.856107 -352.33277) (xy 178.855624 -352.304858) (xy 178.855624 -351.247202)
			(xy 178.856128 -351.217229) (xy 178.865452 -351.158012) (xy 178.883935 -351.100987) (xy 178.91112 -351.04756)
			(xy 178.946336 -350.999048) (xy 178.96713 -350.977454) (xy 179.397914 -350.546924) (xy 179.404738 -350.539511)
			(xy 179.412466 -350.520922) (xy 179.4129 -350.510856) (xy 179.4129 -346.983812) (xy 179.413416 -346.953839)
			(xy 179.422739 -346.894624) (xy 179.441219 -346.837599) (xy 179.468401 -346.784171) (xy 179.503614 -346.735659)
			(xy 179.524406 -346.714064) (xy 180.032406 -346.206064) (xy 180.053993 -346.185251) (xy 180.102496 -346.149996)
			(xy 180.15592 -346.122767) (xy 180.212948 -346.104235) (xy 180.272173 -346.094858) (xy 180.302154 -346.094304)
			(xy 186.611514 -346.094304) (xy 186.641491 -346.094901) (xy 186.700705 -346.104293) (xy 186.757723 -346.122827)
			(xy 186.811141 -346.150047) (xy 186.859647 -346.185285) (xy 186.881262 -346.206064) (xy 187.258198 -346.583)
			(xy 201.363834 -346.583) (xy 201.36434 -346.554082) (xy 201.373069 -346.49691) (xy 201.390329 -346.44171)
			(xy 201.415723 -346.389749) (xy 201.448669 -346.342215) (xy 201.488413 -346.300199) (xy 201.5109 -346.28201)
			(xy 201.519653 -346.274439) (xy 201.529841 -346.253687) (xy 201.530458 -346.242132) (xy 201.530458 -346.161868)
			(xy 201.529863 -346.150303) (xy 201.519687 -346.129531) (xy 201.5109 -346.12199) (xy 201.488412 -346.103805)
			(xy 201.448677 -346.061784) (xy 201.415738 -346.014248) (xy 201.390351 -345.962285) (xy 201.373096 -345.907087)
			(xy 201.364368 -345.849916) (xy 201.363834 -345.821) (xy 201.36432 -345.793749) (xy 201.372076 -345.739801)
			(xy 201.387431 -345.687506) (xy 201.410073 -345.637929) (xy 201.439539 -345.592079) (xy 201.47523 -345.550888)
			(xy 201.516421 -345.515197) (xy 201.562271 -345.485731) (xy 201.611848 -345.463089) (xy 201.664143 -345.447734)
			(xy 201.718091 -345.439978) (xy 201.772593 -345.439978) (xy 201.826541 -345.447734) (xy 201.878836 -345.463089)
			(xy 201.928413 -345.485731) (xy 201.974263 -345.515197) (xy 202.015454 -345.550888) (xy 202.051145 -345.592079)
			(xy 202.080611 -345.637929) (xy 202.103253 -345.687506) (xy 202.118608 -345.739801) (xy 202.126364 -345.793749)
			(xy 202.12685 -345.821) (xy 202.126351 -345.849918) (xy 202.11762 -345.907091) (xy 202.10036 -345.962291)
			(xy 202.074965 -346.014253) (xy 202.042017 -346.061786) (xy 202.002272 -346.103801) (xy 201.979784 -346.12199)
			(xy 201.971028 -346.129558) (xy 201.960842 -346.150312) (xy 201.960226 -346.161868) (xy 201.960226 -346.242132)
			(xy 201.960826 -346.253696) (xy 201.970999 -346.274468) (xy 201.979784 -346.28201) (xy 202.002269 -346.300199)
			(xy 202.042005 -346.342219) (xy 202.074944 -346.389754) (xy 202.100332 -346.441716) (xy 202.117588 -346.496914)
			(xy 202.126316 -346.554084) (xy 202.12685 -346.583) (xy 202.126364 -346.610251) (xy 202.118608 -346.664199)
			(xy 202.103253 -346.716494) (xy 202.080611 -346.766071) (xy 202.051145 -346.811921) (xy 202.015454 -346.853112)
			(xy 201.974263 -346.888803) (xy 201.928413 -346.918269) (xy 201.878836 -346.940911) (xy 201.826541 -346.956266)
			(xy 201.772593 -346.964022) (xy 201.718091 -346.964022) (xy 201.664143 -346.956266) (xy 201.611848 -346.940911)
			(xy 201.562271 -346.918269) (xy 201.516421 -346.888803) (xy 201.47523 -346.853112) (xy 201.439539 -346.811921)
			(xy 201.410073 -346.766071) (xy 201.387431 -346.716494) (xy 201.372076 -346.664199) (xy 201.36432 -346.610251)
			(xy 201.363834 -346.583) (xy 187.258198 -346.583) (xy 187.944046 -347.268848) (xy 203.547 -347.268848)
			(xy 203.547 -347.214352) (xy 203.554755 -347.160411) (xy 203.570108 -347.108122) (xy 203.592745 -347.05855)
			(xy 203.622206 -347.012704) (xy 203.657892 -346.971517) (xy 203.699075 -346.935828) (xy 203.744918 -346.906362)
			(xy 203.794488 -346.88372) (xy 203.846775 -346.868363) (xy 203.900716 -346.860603) (xy 203.927964 -346.860114)
			(xy 203.955334 -346.860598) (xy 204.009512 -346.868411) (xy 204.062015 -346.883896) (xy 204.111762 -346.906733)
			(xy 204.15773 -346.936454) (xy 204.178662 -346.954094) (xy 204.185774 -346.96019) (xy 204.202792 -346.96654)
			(xy 204.288136 -346.96654) (xy 204.305154 -346.96019) (xy 204.312266 -346.954094) (xy 204.333199 -346.936456)
			(xy 204.379172 -346.906745) (xy 204.428919 -346.883908) (xy 204.481419 -346.868417) (xy 204.535595 -346.860588)
			(xy 204.562964 -346.860114) (xy 204.589876 -346.860595) (xy 204.643163 -346.868196) (xy 204.694856 -346.883196)
			(xy 204.743935 -346.905299) (xy 204.766926 -346.919296) (xy 204.775054 -346.924376) (xy 204.793088 -346.927932)
			(xy 204.878686 -346.913708) (xy 204.894688 -346.90431) (xy 204.90053 -346.896944) (xy 204.91875 -346.875108)
			(xy 204.960565 -346.836565) (xy 205.007637 -346.804656) (xy 205.058924 -346.780086) (xy 205.11329 -346.763401)
			(xy 205.16953 -346.75497) (xy 205.197964 -346.75445) (xy 205.225212 -346.755012) (xy 205.279155 -346.762762)
			(xy 205.331446 -346.778111) (xy 205.38102 -346.800744) (xy 205.426869 -346.830203) (xy 205.468058 -346.865887)
			(xy 205.50375 -346.907069) (xy 205.533218 -346.952911) (xy 205.555862 -347.002481) (xy 205.571221 -347.054768)
			(xy 205.578983 -347.10871) (xy 205.579472 -347.135958) (xy 205.578988 -347.163328) (xy 205.571176 -347.217506)
			(xy 205.555691 -347.270009) (xy 205.532853 -347.319757) (xy 205.503132 -347.365724) (xy 205.485492 -347.386656)
			(xy 205.479396 -347.393768) (xy 205.473046 -347.410786) (xy 205.473046 -347.49613) (xy 205.479396 -347.513148)
			(xy 205.485492 -347.52026) (xy 205.503125 -347.541197) (xy 205.532838 -347.587169) (xy 205.555675 -347.636915)
			(xy 205.571168 -347.689414) (xy 205.578997 -347.743589) (xy 205.579472 -347.770958) (xy 205.578986 -347.798209)
			(xy 205.57123 -347.852157) (xy 205.555875 -347.904452) (xy 205.533233 -347.954029) (xy 205.503767 -347.999879)
			(xy 205.468076 -348.04107) (xy 205.426885 -348.076761) (xy 205.381035 -348.106227) (xy 205.331458 -348.128869)
			(xy 205.279163 -348.144224) (xy 205.225215 -348.15198) (xy 205.170713 -348.15198) (xy 205.116765 -348.144224)
			(xy 205.06447 -348.128869) (xy 205.014893 -348.106227) (xy 204.969043 -348.076761) (xy 204.927852 -348.04107)
			(xy 204.892161 -347.999879) (xy 204.862695 -347.954029) (xy 204.840053 -347.904452) (xy 204.824698 -347.852157)
			(xy 204.816942 -347.798209) (xy 204.816456 -347.770958) (xy 204.816584 -347.756551) (xy 204.818749 -347.727819)
			(xy 204.820774 -347.713554) (xy 204.822806 -347.700346) (xy 204.813408 -347.675454) (xy 204.726032 -347.60281)
			(xy 204.69987 -347.597984) (xy 204.68717 -347.602302) (xy 204.657048 -347.612043) (xy 204.594616 -347.62251)
			(xy 204.562964 -347.62313) (xy 204.535592 -347.622702) (xy 204.481411 -347.614878) (xy 204.428907 -347.599381)
			(xy 204.37916 -347.57653) (xy 204.333196 -347.546796) (xy 204.312266 -347.52915) (xy 204.305154 -347.523054)
			(xy 204.288136 -347.516704) (xy 204.202792 -347.516704) (xy 204.185774 -347.523054) (xy 204.178662 -347.52915)
			(xy 204.157711 -347.546766) (xy 204.111744 -347.576483) (xy 204.062002 -347.599324) (xy 204.009505 -347.61482)
			(xy 203.955332 -347.622654) (xy 203.927964 -347.62313) (xy 203.900716 -347.622597) (xy 203.846775 -347.614837)
			(xy 203.794488 -347.59948) (xy 203.744918 -347.576838) (xy 203.699075 -347.547372) (xy 203.657892 -347.511683)
			(xy 203.622206 -347.470496) (xy 203.592745 -347.42465) (xy 203.570108 -347.375078) (xy 203.554755 -347.322789)
			(xy 203.547 -347.268848) (xy 187.944046 -347.268848) (xy 188.176662 -347.501464) (xy 188.197427 -347.523079)
			(xy 188.232613 -347.5716) (xy 188.25978 -347.625025) (xy 188.27826 -347.68204) (xy 188.287598 -347.741244)
			(xy 188.288168 -347.771212) (xy 188.288168 -351.98685) (xy 188.287637 -352.016822) (xy 188.278319 -352.076037)
			(xy 188.259843 -352.133063) (xy 188.232664 -352.186491) (xy 188.197453 -352.235003) (xy 188.176662 -352.256598)
			(xy 187.833254 -352.600006) (xy 187.832238 -352.600768) (xy 187.825425 -352.60819) (xy 187.817688 -352.626772)
			(xy 187.817252 -352.636836) (xy 187.817252 -352.66884) (xy 187.817643 -352.678913) (xy 187.825386 -352.697512)
			(xy 187.832238 -352.704908) (xy 187.853236 -352.726516) (xy 187.888805 -352.775148) (xy 187.916283 -352.828769)
			(xy 187.934986 -352.886043) (xy 187.94445 -352.945546) (xy 187.945014 -352.975672) (xy 187.944528 -353.002923)
			(xy 187.936772 -353.056871) (xy 187.921417 -353.109166) (xy 187.898775 -353.158743) (xy 187.869309 -353.204593)
			(xy 187.833618 -353.245784) (xy 187.792427 -353.281475) (xy 187.749286 -353.3092) (xy 191.564233 -353.3092)
			(xy 191.568401 -353.253584) (xy 191.580811 -353.19921) (xy 191.601187 -353.147293) (xy 191.629072 -353.098992)
			(xy 191.663845 -353.055387) (xy 191.704728 -353.017452) (xy 191.750809 -352.986033) (xy 191.801057 -352.961833)
			(xy 191.854351 -352.945392) (xy 191.9095 -352.937078) (xy 191.937386 -352.936556) (xy 191.963807 -352.937032)
			(xy 192.016121 -352.944479) (xy 192.066859 -352.959241) (xy 192.115004 -352.98102) (xy 192.15959 -353.009381)
			(xy 192.179956 -353.026218) (xy 192.186814 -353.032314) (xy 192.203832 -353.03841) (xy 192.28816 -353.03841)
			(xy 192.305178 -353.032314) (xy 192.312036 -353.026218) (xy 192.332402 -353.009379) (xy 192.376988 -352.981014)
			(xy 192.425132 -352.959227) (xy 192.475869 -352.944456) (xy 192.528184 -352.936996) (xy 192.581028 -352.936996)
			(xy 192.633343 -352.944456) (xy 192.68408 -352.959227) (xy 192.732224 -352.981014) (xy 192.77681 -353.009379)
			(xy 192.797176 -353.026218) (xy 192.804034 -353.032314) (xy 192.821052 -353.03841) (xy 192.90538 -353.03841)
			(xy 192.922398 -353.032314) (xy 192.929256 -353.026218) (xy 192.943154 -353.014639) (xy 192.972794 -352.993899)
			(xy 192.988438 -352.984816) (xy 192.998852 -352.978974) (xy 193.01206 -352.95967) (xy 193.0273 -352.857054)
			(xy 193.020442 -352.834956) (xy 193.012314 -352.82632) (xy 192.992734 -352.804937) (xy 192.959615 -352.757351)
			(xy 192.934083 -352.705299) (xy 192.916729 -352.649981) (xy 192.907952 -352.592672) (xy 192.907412 -352.563684)
			(xy 192.907931 -352.536111) (xy 192.915872 -352.481541) (xy 192.931586 -352.428682) (xy 192.954746 -352.378635)
			(xy 192.98487 -352.332444) (xy 193.021329 -352.291071) (xy 193.042032 -352.272854) (xy 193.050172 -352.265271)
			(xy 193.059513 -352.245105) (xy 193.060066 -352.233992) (xy 193.060066 -352.156776) (xy 193.059538 -352.145661)
			(xy 193.050173 -352.125502) (xy 193.042032 -352.117914) (xy 193.021331 -352.099692) (xy 192.984858 -352.058326)
			(xy 192.954724 -352.012139) (xy 192.931556 -351.962093) (xy 192.915838 -351.909232) (xy 192.907898 -351.854658)
			(xy 192.907412 -351.827084) (xy 192.907898 -351.799833) (xy 192.915654 -351.745885) (xy 192.931009 -351.69359)
			(xy 192.953651 -351.644013) (xy 192.983117 -351.598163) (xy 193.018808 -351.556972) (xy 193.059999 -351.521281)
			(xy 193.105849 -351.491815) (xy 193.155426 -351.469173) (xy 193.207721 -351.453818) (xy 193.261669 -351.446062)
			(xy 193.316171 -351.446062) (xy 193.370119 -351.453818) (xy 193.422414 -351.469173) (xy 193.471991 -351.491815)
			(xy 193.517841 -351.521281) (xy 193.559032 -351.556972) (xy 193.594723 -351.598163) (xy 193.624189 -351.644013)
			(xy 193.646831 -351.69359) (xy 193.662186 -351.745885) (xy 193.669942 -351.799833) (xy 193.670428 -351.827084)
			(xy 193.669942 -351.854658) (xy 193.661992 -351.909229) (xy 193.64627 -351.962088) (xy 193.623104 -352.012134)
			(xy 193.592976 -352.058324) (xy 193.556513 -352.099697) (xy 193.535808 -352.117914) (xy 193.527689 -352.125516)
			(xy 193.518335 -352.145668) (xy 193.517774 -352.156776) (xy 193.517774 -352.233992) (xy 193.518307 -352.245107)
			(xy 193.527668 -352.265267) (xy 193.535808 -352.272854) (xy 193.556502 -352.291084) (xy 193.592973 -352.332449)
			(xy 193.623107 -352.378635) (xy 193.638105 -352.41103) (xy 206.449676 -352.41103) (xy 206.449676 -351.54743)
			(xy 206.450162 -351.520179) (xy 206.457918 -351.466231) (xy 206.473273 -351.413936) (xy 206.495915 -351.364359)
			(xy 206.525381 -351.318509) (xy 206.561072 -351.277318) (xy 206.602263 -351.241627) (xy 206.648113 -351.212161)
			(xy 206.69769 -351.189519) (xy 206.749985 -351.174164) (xy 206.803933 -351.166408) (xy 206.858435 -351.166408)
			(xy 206.912383 -351.174164) (xy 206.964678 -351.189519) (xy 207.014255 -351.212161) (xy 207.060105 -351.241627)
			(xy 207.101296 -351.277318) (xy 207.136987 -351.318509) (xy 207.166453 -351.364359) (xy 207.189095 -351.413936)
			(xy 207.20445 -351.466231) (xy 207.212206 -351.520179) (xy 207.212692 -351.54743) (xy 207.212692 -352.41103)
			(xy 207.212206 -352.438281) (xy 207.20445 -352.492229) (xy 207.189095 -352.544524) (xy 207.166453 -352.594101)
			(xy 207.136987 -352.639951) (xy 207.101296 -352.681142) (xy 207.060105 -352.716833) (xy 207.014255 -352.746299)
			(xy 206.964678 -352.768941) (xy 206.912383 -352.784296) (xy 206.858435 -352.792052) (xy 206.803933 -352.792052)
			(xy 206.749985 -352.784296) (xy 206.69769 -352.768941) (xy 206.648113 -352.746299) (xy 206.602263 -352.716833)
			(xy 206.561072 -352.681142) (xy 206.525381 -352.639951) (xy 206.495915 -352.594101) (xy 206.473273 -352.544524)
			(xy 206.457918 -352.492229) (xy 206.450162 -352.438281) (xy 206.449676 -352.41103) (xy 193.638105 -352.41103)
			(xy 193.646276 -352.428679) (xy 193.661996 -352.481538) (xy 193.66994 -352.53611) (xy 193.670428 -352.563684)
			(xy 193.669837 -352.592875) (xy 193.660932 -352.650574) (xy 193.643341 -352.706243) (xy 193.617476 -352.758583)
			(xy 193.583941 -352.806372) (xy 193.543517 -352.848496) (xy 193.497149 -352.88397) (xy 193.4718 -352.898456)
			(xy 193.461386 -352.904298) (xy 193.447924 -352.923094) (xy 193.43116 -353.025456) (xy 193.437764 -353.047808)
			(xy 193.445638 -353.056444) (xy 193.464098 -353.077219) (xy 193.495309 -353.123201) (xy 193.519344 -353.173309)
			(xy 193.535671 -353.22643) (xy 193.543929 -353.281387) (xy 193.544444 -353.309174) (xy 193.543919 -353.335788)
			(xy 193.536348 -353.388476) (xy 193.521355 -353.43955) (xy 193.499246 -353.48797) (xy 193.470472 -353.53275)
			(xy 193.435617 -353.572981) (xy 193.395392 -353.607841) (xy 193.350615 -353.636621) (xy 193.302198 -353.658737)
			(xy 193.251127 -353.673737) (xy 193.19844 -353.681316) (xy 193.171826 -353.681792) (xy 193.145405 -353.681321)
			(xy 193.09309 -353.673875) (xy 193.042351 -353.659113) (xy 192.994207 -353.637332) (xy 192.949621 -353.608969)
			(xy 192.929256 -353.59213) (xy 192.922398 -353.586034) (xy 192.90538 -353.579938) (xy 192.821052 -353.579938)
			(xy 192.804034 -353.586034) (xy 192.797176 -353.59213) (xy 192.77681 -353.608969) (xy 192.732224 -353.637334)
			(xy 192.68408 -353.659121) (xy 192.633343 -353.673892) (xy 192.581028 -353.681352) (xy 192.528184 -353.681352)
			(xy 192.475869 -353.673892) (xy 192.425132 -353.659121) (xy 192.376988 -353.637334) (xy 192.332402 -353.608969)
			(xy 192.312036 -353.59213) (xy 192.305178 -353.586034) (xy 192.28816 -353.579938) (xy 192.203832 -353.579938)
			(xy 192.186814 -353.586034) (xy 192.179956 -353.59213) (xy 192.159598 -353.608978) (xy 192.115007 -353.637334)
			(xy 192.066861 -353.659112) (xy 192.016122 -353.673877) (xy 191.963808 -353.681334) (xy 191.937386 -353.681792)
			(xy 191.9095 -353.681322) (xy 191.854351 -353.673008) (xy 191.801057 -353.656567) (xy 191.750809 -353.632367)
			(xy 191.704728 -353.600948) (xy 191.663845 -353.563013) (xy 191.629072 -353.519408) (xy 191.601187 -353.471107)
			(xy 191.580811 -353.41919) (xy 191.568401 -353.364816) (xy 191.564233 -353.3092) (xy 187.749286 -353.3092)
			(xy 187.746577 -353.310941) (xy 187.697 -353.333583) (xy 187.644705 -353.348938) (xy 187.590757 -353.356694)
			(xy 187.536255 -353.356694) (xy 187.482307 -353.348938) (xy 187.430012 -353.333583) (xy 187.380435 -353.310941)
			(xy 187.334585 -353.281475) (xy 187.293394 -353.245784) (xy 187.257703 -353.204593) (xy 187.228237 -353.158743)
			(xy 187.205595 -353.109166) (xy 187.19024 -353.056871) (xy 187.182484 -353.002923) (xy 187.181998 -352.975672)
			(xy 187.182485 -352.947726) (xy 187.190654 -352.892435) (xy 187.206799 -352.838926) (xy 187.230574 -352.788343)
			(xy 187.261471 -352.741768) (xy 187.279788 -352.720656) (xy 187.286138 -352.713544) (xy 187.292742 -352.696272)
			(xy 187.292742 -352.609404) (xy 187.286138 -352.592132) (xy 187.279788 -352.58502) (xy 187.261496 -352.563932)
			(xy 187.230671 -352.51739) (xy 187.206959 -352.466853) (xy 187.190865 -352.413399) (xy 187.182735 -352.35817)
			(xy 187.182252 -352.330258) (xy 187.182783 -352.300285) (xy 187.1921 -352.24107) (xy 187.210576 -352.184045)
			(xy 187.237755 -352.130617) (xy 187.272966 -352.082105) (xy 187.293758 -352.06051) (xy 187.510674 -351.843848)
			(xy 187.517482 -351.836422) (xy 187.525221 -351.817843) (xy 187.52566 -351.80778) (xy 187.52566 -347.950282)
			(xy 187.525254 -347.94021) (xy 187.517521 -347.921612) (xy 187.510674 -347.914214) (xy 186.468512 -346.872052)
			(xy 186.461052 -346.865331) (xy 186.442477 -346.857757) (xy 186.432444 -346.85732) (xy 180.481224 -346.85732)
			(xy 180.471177 -346.85767) (xy 180.45258 -346.865272) (xy 180.445156 -346.872052) (xy 180.190394 -347.126814)
			(xy 180.183555 -347.134215) (xy 180.175835 -347.152813) (xy 180.175408 -347.162882) (xy 180.175408 -350.689926)
			(xy 180.17485 -350.719897) (xy 180.165537 -350.779111) (xy 180.147066 -350.836135) (xy 180.119894 -350.889563)
			(xy 180.08469 -350.938077) (xy 180.063902 -350.959674) (xy 179.633118 -351.390204) (xy 179.626286 -351.397611)
			(xy 179.618561 -351.416205) (xy 179.618132 -351.426272) (xy 179.618132 -352.304858) (xy 179.617669 -352.33277)
			(xy 179.609526 -352.387997) (xy 179.593423 -352.441448) (xy 179.569704 -352.491982) (xy 179.538875 -352.538521)
			(xy 179.520596 -352.55962) (xy 179.514246 -352.566732) (xy 179.507642 -352.584004) (xy 179.507642 -352.670872)
			(xy 179.514246 -352.688144) (xy 179.520596 -352.695256) (xy 179.538932 -352.716353) (xy 179.569839 -352.762926)
			(xy 179.593615 -352.813512) (xy 179.609751 -352.867027) (xy 179.617902 -352.922324) (xy 179.618386 -352.950272)
			(xy 179.6179 -352.977523) (xy 179.610144 -353.031471) (xy 179.594789 -353.083766) (xy 179.572147 -353.133343)
			(xy 179.542681 -353.179193) (xy 179.50699 -353.220384) (xy 179.465799 -353.256075) (xy 179.422658 -353.2838)
			(xy 183.237633 -353.2838) (xy 183.241801 -353.228186) (xy 183.25421 -353.173815) (xy 183.274583 -353.1219)
			(xy 183.302466 -353.073601) (xy 183.337236 -353.029997) (xy 183.378116 -352.992062) (xy 183.424192 -352.960642)
			(xy 183.474437 -352.936441) (xy 183.527727 -352.919998) (xy 183.582873 -352.91168) (xy 183.610758 -352.911156)
			(xy 183.63718 -352.91159) (xy 183.689497 -352.919048) (xy 183.740235 -352.933819) (xy 183.788379 -352.955607)
			(xy 183.832963 -352.983977) (xy 183.853328 -353.000818) (xy 183.860186 -353.006914) (xy 183.877204 -353.01301)
			(xy 183.961532 -353.01301) (xy 183.97855 -353.006914) (xy 183.985408 -353.000818) (xy 184.005774 -352.983979)
			(xy 184.05036 -352.955614) (xy 184.098504 -352.933827) (xy 184.149241 -352.919056) (xy 184.201556 -352.911596)
			(xy 184.2544 -352.911596) (xy 184.306715 -352.919056) (xy 184.357452 -352.933827) (xy 184.405596 -352.955614)
			(xy 184.450182 -352.983979) (xy 184.470548 -353.000818) (xy 184.477406 -353.006914) (xy 184.494424 -353.01301)
			(xy 184.578752 -353.01301) (xy 184.59577 -353.006914) (xy 184.602628 -353.000818) (xy 184.614414 -352.990981)
			(xy 184.639338 -352.973051) (xy 184.652412 -352.965004) (xy 184.662064 -352.959162) (xy 184.67451 -352.940366)
			(xy 184.68975 -352.841052) (xy 184.6834 -352.819208) (xy 184.676034 -352.810826) (xy 184.658169 -352.789823)
			(xy 184.62806 -352.743633) (xy 184.604911 -352.69359) (xy 184.589205 -352.640736) (xy 184.58127 -352.586173)
			(xy 184.580784 -352.558604) (xy 184.581258 -352.53103) (xy 184.58921 -352.476458) (xy 184.604933 -352.423598)
			(xy 184.628102 -352.373552) (xy 184.658233 -352.327362) (xy 184.694698 -352.28599) (xy 184.715404 -352.267774)
			(xy 184.72353 -352.260179) (xy 184.73288 -352.240022) (xy 184.733438 -352.228912) (xy 184.733438 -352.151696)
			(xy 184.732908 -352.140581) (xy 184.723545 -352.120421) (xy 184.715404 -352.112834) (xy 184.694707 -352.094608)
			(xy 184.658235 -352.053242) (xy 184.628101 -352.007055) (xy 184.604933 -351.95701) (xy 184.589214 -351.904151)
			(xy 184.581271 -351.849578) (xy 184.580784 -351.822004) (xy 184.58127 -351.794753) (xy 184.589026 -351.740805)
			(xy 184.604381 -351.68851) (xy 184.627023 -351.638933) (xy 184.656489 -351.593083) (xy 184.69218 -351.551892)
			(xy 184.733371 -351.516201) (xy 184.779221 -351.486735) (xy 184.828798 -351.464093) (xy 184.881093 -351.448738)
			(xy 184.935041 -351.440982) (xy 184.989543 -351.440982) (xy 185.043491 -351.448738) (xy 185.095786 -351.464093)
			(xy 185.145363 -351.486735) (xy 185.191213 -351.516201) (xy 185.232404 -351.551892) (xy 185.268095 -351.593083)
			(xy 185.297561 -351.638933) (xy 185.320203 -351.68851) (xy 185.335558 -351.740805) (xy 185.343314 -351.794753)
			(xy 185.3438 -351.822004) (xy 185.343337 -351.849579) (xy 185.335384 -351.904152) (xy 185.319658 -351.957012)
			(xy 185.296488 -352.007057) (xy 185.266355 -352.053247) (xy 185.229887 -352.094618) (xy 185.20918 -352.112834)
			(xy 185.201048 -352.120424) (xy 185.191702 -352.140585) (xy 185.191146 -352.151696) (xy 185.191146 -352.228912)
			(xy 185.191677 -352.240027) (xy 185.20104 -352.260186) (xy 185.20918 -352.267774) (xy 185.229878 -352.286)
			(xy 185.26635 -352.327365) (xy 185.296484 -352.373552) (xy 185.319653 -352.423597) (xy 185.335372 -352.476457)
			(xy 185.343314 -352.53103) (xy 185.3438 -352.558604) (xy 185.343259 -352.587026) (xy 185.334845 -352.643242)
			(xy 185.318173 -352.697584) (xy 185.293614 -352.748848) (xy 185.261712 -352.795894) (xy 185.223177 -352.83768)
			(xy 185.178861 -352.873278) (xy 185.15457 -352.888042) (xy 185.144918 -352.893884) (xy 185.131964 -352.912426)
			(xy 185.1152 -353.011486) (xy 185.121296 -353.03333) (xy 185.128662 -353.041712) (xy 185.145418 -353.062057)
			(xy 185.173643 -353.106568) (xy 185.19531 -353.154615) (xy 185.209986 -353.205236) (xy 185.217379 -353.257421)
			(xy 185.217816 -353.283774) (xy 185.217342 -353.310391) (xy 185.209769 -353.363084) (xy 185.194774 -353.414163)
			(xy 185.172662 -353.462588) (xy 185.143883 -353.507373) (xy 185.109023 -353.547606) (xy 185.068792 -353.582469)
			(xy 185.024009 -353.61125) (xy 184.975586 -353.633366) (xy 184.924508 -353.648364) (xy 184.871815 -353.65594)
			(xy 184.845198 -353.656392) (xy 184.818776 -353.655937) (xy 184.76646 -353.648487) (xy 184.715722 -353.633721)
			(xy 184.667577 -353.611937) (xy 184.622993 -353.58357) (xy 184.602628 -353.56673) (xy 184.59577 -353.560634)
			(xy 184.578752 -353.554538) (xy 184.494424 -353.554538) (xy 184.477406 -353.560634) (xy 184.470548 -353.56673)
			(xy 184.450182 -353.583569) (xy 184.405596 -353.611934) (xy 184.357452 -353.633721) (xy 184.306715 -353.648492)
			(xy 184.2544 -353.655952) (xy 184.201556 -353.655952) (xy 184.149241 -353.648492) (xy 184.098504 -353.633721)
			(xy 184.05036 -353.611934) (xy 184.005774 -353.583569) (xy 183.985408 -353.56673) (xy 183.97855 -353.560634)
			(xy 183.961532 -353.554538) (xy 183.877204 -353.554538) (xy 183.860186 -353.560634) (xy 183.853328 -353.56673)
			(xy 183.832943 -353.583544) (xy 183.78836 -353.611905) (xy 183.74022 -353.63369) (xy 183.689487 -353.648463)
			(xy 183.637178 -353.655929) (xy 183.610758 -353.656392) (xy 183.582873 -353.65592) (xy 183.527727 -353.647602)
			(xy 183.474437 -353.631159) (xy 183.424192 -353.606958) (xy 183.378116 -353.575538) (xy 183.337236 -353.537603)
			(xy 183.302466 -353.493999) (xy 183.274583 -353.4457) (xy 183.25421 -353.393785) (xy 183.241801 -353.339414)
			(xy 183.237633 -353.2838) (xy 179.422658 -353.2838) (xy 179.419949 -353.285541) (xy 179.370372 -353.308183)
			(xy 179.318077 -353.323538) (xy 179.264129 -353.331294) (xy 179.209627 -353.331294) (xy 179.155679 -353.323538)
			(xy 179.103384 -353.308183) (xy 179.053807 -353.285541) (xy 179.007957 -353.256075) (xy 178.966766 -353.220384)
			(xy 178.931075 -353.179193) (xy 178.901609 -353.133343) (xy 178.878967 -353.083766) (xy 178.863612 -353.031471)
			(xy 178.855856 -352.977523) (xy 178.85537 -352.950272) (xy 169.596018 -352.950272) (xy 170.827588 -354.181918)
			(xy 179.813202 -354.181918) (xy 179.817273 -354.126296) (xy 179.829399 -354.071859) (xy 179.849322 -354.019768)
			(xy 179.876618 -353.971133) (xy 179.910704 -353.92699) (xy 179.950853 -353.888281) (xy 179.996211 -353.85583)
			(xy 180.045811 -353.830329) (xy 180.098595 -353.812322) (xy 180.153438 -353.802192) (xy 180.209172 -353.800155)
			(xy 180.264609 -353.806255) (xy 180.318566 -353.820361) (xy 180.369895 -353.842173) (xy 180.417501 -353.871227)
			(xy 180.460369 -353.906902) (xy 180.497586 -353.948439) (xy 180.528359 -353.994952) (xy 180.552031 -354.045449)
			(xy 180.568099 -354.098856) (xy 180.576219 -354.154032) (xy 180.576728 -354.181918) (xy 180.576219 -354.209804)
			(xy 180.568099 -354.26498) (xy 180.552031 -354.318387) (xy 180.528359 -354.368884) (xy 180.497586 -354.415397)
			(xy 180.460369 -354.456934) (xy 180.417501 -354.492609) (xy 180.369895 -354.521663) (xy 180.318566 -354.543475)
			(xy 180.264609 -354.557581) (xy 180.209172 -354.563681) (xy 180.153438 -354.561644) (xy 180.098595 -354.551514)
			(xy 180.045811 -354.533507) (xy 179.996211 -354.508006) (xy 179.950853 -354.475555) (xy 179.910704 -354.436846)
			(xy 179.876618 -354.392703) (xy 179.849322 -354.344068) (xy 179.829399 -354.291977) (xy 179.817273 -354.23754)
			(xy 179.813202 -354.181918) (xy 170.827588 -354.181918) (xy 171.613924 -354.968302) (xy 176.841656 -354.968302)
			(xy 176.845727 -354.91268) (xy 176.857853 -354.858243) (xy 176.877776 -354.806152) (xy 176.905072 -354.757517)
			(xy 176.939158 -354.713374) (xy 176.979307 -354.674665) (xy 177.024665 -354.642214) (xy 177.074265 -354.616713)
			(xy 177.127049 -354.598706) (xy 177.181892 -354.588576) (xy 177.237626 -354.586539) (xy 177.293063 -354.592639)
			(xy 177.34702 -354.606745) (xy 177.398349 -354.628557) (xy 177.445955 -354.657611) (xy 177.488823 -354.693286)
			(xy 177.52604 -354.734823) (xy 177.556813 -354.781336) (xy 177.580485 -354.831833) (xy 177.596553 -354.88524)
			(xy 177.604673 -354.940416) (xy 177.605182 -354.968302) (xy 177.604834 -354.987352) (xy 179.031136 -354.987352)
			(xy 179.035207 -354.93173) (xy 179.047333 -354.877293) (xy 179.067256 -354.825202) (xy 179.094552 -354.776567)
			(xy 179.128638 -354.732424) (xy 179.168787 -354.693715) (xy 179.214145 -354.661264) (xy 179.263745 -354.635763)
			(xy 179.316529 -354.617756) (xy 179.371372 -354.607626) (xy 179.427106 -354.605589) (xy 179.482543 -354.611689)
			(xy 179.5365 -354.625795) (xy 179.587829 -354.647607) (xy 179.635435 -354.676661) (xy 179.678303 -354.712336)
			(xy 179.71552 -354.753873) (xy 179.746293 -354.800386) (xy 179.769965 -354.850883) (xy 179.786033 -354.90429)
			(xy 179.794153 -354.959466) (xy 179.794662 -354.987352) (xy 179.794153 -355.015238) (xy 179.786033 -355.070414)
			(xy 179.769965 -355.123821) (xy 179.746293 -355.174318) (xy 179.71552 -355.220831) (xy 179.678303 -355.262368)
			(xy 179.635435 -355.298043) (xy 179.587829 -355.327097) (xy 179.5365 -355.348909) (xy 179.482543 -355.363015)
			(xy 179.427106 -355.369115) (xy 179.371372 -355.367078) (xy 179.316529 -355.356948) (xy 179.263745 -355.338941)
			(xy 179.214145 -355.31344) (xy 179.168787 -355.280989) (xy 179.128638 -355.24228) (xy 179.094552 -355.198137)
			(xy 179.067256 -355.149502) (xy 179.047333 -355.097411) (xy 179.035207 -355.042974) (xy 179.031136 -354.987352)
			(xy 177.604834 -354.987352) (xy 177.604673 -354.996188) (xy 177.596553 -355.051364) (xy 177.580485 -355.104771)
			(xy 177.556813 -355.155268) (xy 177.52604 -355.201781) (xy 177.488823 -355.243318) (xy 177.445955 -355.278993)
			(xy 177.398349 -355.308047) (xy 177.34702 -355.329859) (xy 177.293063 -355.343965) (xy 177.237626 -355.350065)
			(xy 177.181892 -355.348028) (xy 177.127049 -355.337898) (xy 177.074265 -355.319891) (xy 177.024665 -355.29439)
			(xy 176.979307 -355.261939) (xy 176.939158 -355.22323) (xy 176.905072 -355.179087) (xy 176.877776 -355.130452)
			(xy 176.857853 -355.078361) (xy 176.845727 -355.023924) (xy 176.841656 -354.968302) (xy 171.613924 -354.968302)
			(xy 172.13002 -355.48443) (xy 177.846988 -355.48443) (xy 177.851059 -355.428808) (xy 177.863185 -355.374371)
			(xy 177.883108 -355.32228) (xy 177.910404 -355.273645) (xy 177.94449 -355.229502) (xy 177.984639 -355.190793)
			(xy 178.029997 -355.158342) (xy 178.079597 -355.132841) (xy 178.132381 -355.114834) (xy 178.187224 -355.104704)
			(xy 178.242958 -355.102667) (xy 178.298395 -355.108767) (xy 178.352352 -355.122873) (xy 178.403681 -355.144685)
			(xy 178.451287 -355.173739) (xy 178.494155 -355.209414) (xy 178.531372 -355.250951) (xy 178.562145 -355.297464)
			(xy 178.585817 -355.347961) (xy 178.601885 -355.401368) (xy 178.610005 -355.456544) (xy 178.610514 -355.48443)
			(xy 178.610005 -355.512316) (xy 178.601885 -355.567492) (xy 178.585817 -355.620899) (xy 178.562145 -355.671396)
			(xy 178.531372 -355.717909) (xy 178.500013 -355.752908) (xy 180.572918 -355.752908) (xy 180.573405 -355.725433)
			(xy 180.581296 -355.671054) (xy 180.596916 -355.618371) (xy 180.61994 -355.568478) (xy 180.649892 -355.52241)
			(xy 180.66766 -355.501448) (xy 180.673756 -355.494336) (xy 180.680106 -355.477318) (xy 180.680106 -355.391466)
			(xy 180.673756 -355.374448) (xy 180.66766 -355.367336) (xy 180.649926 -355.34635) (xy 180.619998 -355.300274)
			(xy 180.59698 -355.250386) (xy 180.581347 -355.197714) (xy 180.573422 -355.143347) (xy 180.572918 -355.115876)
			(xy 180.573404 -355.088625) (xy 180.58116 -355.034677) (xy 180.596515 -354.982382) (xy 180.619157 -354.932805)
			(xy 180.648623 -354.886955) (xy 180.684314 -354.845764) (xy 180.725505 -354.810073) (xy 180.771355 -354.780607)
			(xy 180.820932 -354.757965) (xy 180.873227 -354.74261) (xy 180.927175 -354.734854) (xy 180.981677 -354.734854)
			(xy 181.035625 -354.74261) (xy 181.08792 -354.757965) (xy 181.137497 -354.780607) (xy 181.183347 -354.810073)
			(xy 181.224538 -354.845764) (xy 181.260229 -354.886955) (xy 181.289695 -354.932805) (xy 181.312337 -354.982382)
			(xy 181.327692 -355.034677) (xy 181.335448 -355.088625) (xy 181.335934 -355.115876) (xy 181.335425 -355.14335)
			(xy 181.327537 -355.197728) (xy 181.311922 -355.25041) (xy 181.288903 -355.300303) (xy 181.258957 -355.346373)
			(xy 181.241192 -355.367336) (xy 181.235096 -355.374448) (xy 181.228746 -355.391466) (xy 181.228746 -355.477318)
			(xy 181.235096 -355.494336) (xy 181.241192 -355.501448) (xy 181.258958 -355.522408) (xy 181.288883 -355.56849)
			(xy 181.311896 -355.618385) (xy 181.327521 -355.671063) (xy 181.335436 -355.725435) (xy 181.335934 -355.752908)
			(xy 181.335448 -355.780159) (xy 181.327692 -355.834107) (xy 181.312337 -355.886402) (xy 181.289695 -355.935979)
			(xy 181.260229 -355.981829) (xy 181.224538 -356.02302) (xy 181.183347 -356.058711) (xy 181.137497 -356.088177)
			(xy 181.08792 -356.110819) (xy 181.035625 -356.126174) (xy 180.981677 -356.13393) (xy 180.927175 -356.13393)
			(xy 180.873227 -356.126174) (xy 180.820932 -356.110819) (xy 180.771355 -356.088177) (xy 180.725505 -356.058711)
			(xy 180.684314 -356.02302) (xy 180.648623 -355.981829) (xy 180.619157 -355.935979) (xy 180.596515 -355.886402)
			(xy 180.58116 -355.834107) (xy 180.573404 -355.780159) (xy 180.572918 -355.752908) (xy 178.500013 -355.752908)
			(xy 178.494155 -355.759446) (xy 178.451287 -355.795121) (xy 178.403681 -355.824175) (xy 178.352352 -355.845987)
			(xy 178.298395 -355.860093) (xy 178.242958 -355.866193) (xy 178.187224 -355.864156) (xy 178.132381 -355.854026)
			(xy 178.079597 -355.836019) (xy 178.029997 -355.810518) (xy 177.984639 -355.778067) (xy 177.94449 -355.739358)
			(xy 177.910404 -355.695215) (xy 177.883108 -355.64658) (xy 177.863185 -355.594489) (xy 177.851059 -355.540052)
			(xy 177.846988 -355.48443) (xy 172.13002 -355.48443) (xy 173.151038 -356.50551) (xy 173.15843 -356.51236)
			(xy 173.177035 -356.520074) (xy 173.187106 -356.520496) (xy 181.564788 -356.520496) (xy 181.57486 -356.520092)
			(xy 181.59346 -356.512359) (xy 181.600856 -356.50551) (xy 182.455312 -355.6508) (xy 182.463186 -355.63302)
			(xy 182.46344 -355.623368) (xy 182.464917 -355.593832) (xy 182.47584 -355.535713) (xy 182.495593 -355.479973)
			(xy 182.50916 -355.453696) (xy 182.513986 -355.444806) (xy 182.516018 -355.425248) (xy 182.490364 -355.33711)
			(xy 182.477918 -355.321616) (xy 182.469028 -355.316536) (xy 182.461662 -355.312472) (xy 182.45201 -355.30663)
			(xy 182.429912 -355.304598) (xy 182.335424 -355.338126) (xy 182.319422 -355.35362) (xy 182.315358 -355.364034)
			(xy 182.304648 -355.390804) (xy 182.276361 -355.441044) (xy 182.240832 -355.486452) (xy 182.198872 -355.525994)
			(xy 182.151437 -355.558768) (xy 182.099608 -355.584027) (xy 182.044568 -355.601196) (xy 181.98757 -355.609882)
			(xy 181.958742 -355.610414) (xy 181.931488 -355.609942) (xy 181.877533 -355.60219) (xy 181.825231 -355.586837)
			(xy 181.775646 -355.564198) (xy 181.729789 -355.534731) (xy 181.688592 -355.499038) (xy 181.652894 -355.457845)
			(xy 181.623423 -355.411991) (xy 181.600777 -355.362408) (xy 181.585419 -355.310108) (xy 181.577661 -355.256154)
			(xy 181.577661 -355.201646) (xy 181.585419 -355.147692) (xy 181.600777 -355.095392) (xy 181.623423 -355.045809)
			(xy 181.652894 -354.999955) (xy 181.688592 -354.958762) (xy 181.729789 -354.923069) (xy 181.775646 -354.893602)
			(xy 181.825231 -354.870963) (xy 181.877533 -354.85561) (xy 181.931488 -354.847858) (xy 181.958742 -354.847398)
			(xy 181.983978 -354.847777) (xy 182.034013 -354.8544) (xy 182.082733 -354.867579) (xy 182.129284 -354.887081)
			(xy 182.151274 -354.899468) (xy 182.160926 -354.90531) (xy 182.183024 -354.907342) (xy 182.277512 -354.873814)
			(xy 182.293514 -354.85832) (xy 182.297578 -354.847906) (xy 182.308279 -354.821132) (xy 182.336565 -354.770889)
			(xy 182.372094 -354.725479) (xy 182.414055 -354.685936) (xy 182.461492 -354.653162) (xy 182.513322 -354.627904)
			(xy 182.568365 -354.610738) (xy 182.625365 -354.602055) (xy 182.654194 -354.601526) (xy 182.681448 -354.601961)
			(xy 182.735402 -354.609718) (xy 182.787702 -354.625075) (xy 182.837285 -354.647719) (xy 182.88314 -354.67719)
			(xy 182.924333 -354.712887) (xy 182.960027 -354.754083) (xy 182.989494 -354.79994) (xy 183.012135 -354.849524)
			(xy 183.024857 -354.892864) (xy 185.165746 -354.892864) (xy 185.16624 -354.86529) (xy 185.174184 -354.810718)
			(xy 185.189903 -354.757858) (xy 185.213067 -354.707811) (xy 185.243196 -354.661621) (xy 185.27966 -354.62025)
			(xy 185.300366 -354.602034) (xy 185.308475 -354.594424) (xy 185.317832 -354.574278) (xy 185.3184 -354.563172)
			(xy 185.3184 -354.485956) (xy 185.317817 -354.474848) (xy 185.308489 -354.454689) (xy 185.300366 -354.447094)
			(xy 185.279642 -354.428897) (xy 185.243174 -354.387524) (xy 185.213044 -354.341331) (xy 185.189881 -354.291281)
			(xy 185.174167 -354.238416) (xy 185.16623 -354.183839) (xy 185.165746 -354.156264) (xy 185.166244 -354.129014)
			(xy 185.174004 -354.075069) (xy 185.189362 -354.022777) (xy 185.212004 -353.973203) (xy 185.241469 -353.927355)
			(xy 185.277159 -353.886166) (xy 185.318347 -353.850476) (xy 185.364194 -353.821009) (xy 185.413768 -353.798365)
			(xy 185.466059 -353.783007) (xy 185.520004 -353.775245) (xy 185.547254 -353.774756) (xy 185.581544 -353.77628)
			(xy 185.591704 -353.777296) (xy 185.611008 -353.7712) (xy 185.68162 -353.712018) (xy 185.691018 -353.693984)
			(xy 185.692034 -353.683824) (xy 185.695012 -353.655655) (xy 185.708188 -353.600566) (xy 185.729366 -353.548033)
			(xy 185.758082 -353.499209) (xy 185.793704 -353.45517) (xy 185.835447 -353.416884) (xy 185.882395 -353.385194)
			(xy 185.933513 -353.360796) (xy 185.987677 -353.344227) (xy 186.043697 -353.335852) (xy 186.072018 -353.335336)
			(xy 186.090037 -353.335559) (xy 186.125912 -353.338992) (xy 186.143646 -353.342194) (xy 186.153044 -353.343972)
			(xy 186.172094 -353.340162) (xy 186.247278 -353.29241) (xy 186.258708 -353.276662) (xy 186.260994 -353.267264)
			(xy 186.268418 -353.240228) (xy 186.290044 -353.188502) (xy 186.319005 -353.140498) (xy 186.354678 -353.097246)
			(xy 186.396293 -353.059678) (xy 186.442958 -353.028603) (xy 186.493666 -353.004689) (xy 186.547327 -352.98845)
			(xy 186.602786 -352.980236) (xy 186.630818 -352.979736) (xy 186.658073 -352.980138) (xy 186.712029 -352.987899)
			(xy 186.764331 -353.003259) (xy 186.813914 -353.025907) (xy 186.859769 -353.055381) (xy 186.900963 -353.091081)
			(xy 186.936656 -353.132281) (xy 186.966123 -353.178141) (xy 186.988762 -353.227728) (xy 187.004114 -353.280032)
			(xy 187.011866 -353.333989) (xy 187.012326 -353.361244) (xy 187.011813 -353.388817) (xy 187.003869 -353.443387)
			(xy 186.988152 -353.496246) (xy 186.964991 -353.546292) (xy 186.934868 -353.592482) (xy 186.898409 -353.633856)
			(xy 186.877706 -353.652074) (xy 186.869605 -353.659692) (xy 186.860241 -353.679832) (xy 186.859672 -353.690936)
			(xy 186.859672 -353.768152) (xy 186.860228 -353.779264) (xy 186.869573 -353.799424) (xy 186.877706 -353.807014)
			(xy 186.898455 -353.825182) (xy 186.934918 -353.86656) (xy 186.965044 -353.912756) (xy 186.988204 -353.962809)
			(xy 187.003916 -354.015675) (xy 187.011853 -354.070253) (xy 187.011849 -354.125404) (xy 187.003904 -354.17998)
			(xy 186.995775 -354.207318) (xy 188.13983 -354.207318) (xy 188.143901 -354.151696) (xy 188.156027 -354.097259)
			(xy 188.17595 -354.045168) (xy 188.203246 -353.996533) (xy 188.237332 -353.95239) (xy 188.277481 -353.913681)
			(xy 188.322839 -353.88123) (xy 188.372439 -353.855729) (xy 188.425223 -353.837722) (xy 188.480066 -353.827592)
			(xy 188.5358 -353.825555) (xy 188.591237 -353.831655) (xy 188.645194 -353.845761) (xy 188.696523 -353.867573)
			(xy 188.744129 -353.896627) (xy 188.786997 -353.932302) (xy 188.824214 -353.973839) (xy 188.854987 -354.020352)
			(xy 188.878659 -354.070849) (xy 188.894727 -354.124256) (xy 188.902847 -354.179432) (xy 188.903356 -354.207318)
			(xy 188.902847 -354.235204) (xy 188.894727 -354.29038) (xy 188.878659 -354.343787) (xy 188.854987 -354.394284)
			(xy 188.824214 -354.440797) (xy 188.786997 -354.482334) (xy 188.744129 -354.518009) (xy 188.696523 -354.547063)
			(xy 188.645194 -354.568875) (xy 188.591237 -354.582981) (xy 188.5358 -354.589081) (xy 188.480066 -354.587044)
			(xy 188.425223 -354.576914) (xy 188.372439 -354.558907) (xy 188.322839 -354.533406) (xy 188.277481 -354.500955)
			(xy 188.237332 -354.462246) (xy 188.203246 -354.418103) (xy 188.17595 -354.369468) (xy 188.156027 -354.317377)
			(xy 188.143901 -354.26294) (xy 188.13983 -354.207318) (xy 186.995775 -354.207318) (xy 186.988184 -354.232844)
			(xy 186.965016 -354.282894) (xy 186.934884 -354.329086) (xy 186.898415 -354.370458) (xy 186.877706 -354.388674)
			(xy 186.869605 -354.396292) (xy 186.860241 -354.416432) (xy 186.859672 -354.427536) (xy 186.859672 -354.504752)
			(xy 186.860228 -354.515864) (xy 186.869573 -354.536024) (xy 186.877706 -354.543614) (xy 186.898428 -354.561813)
			(xy 186.934897 -354.603184) (xy 186.965028 -354.649377) (xy 186.988192 -354.699427) (xy 187.003906 -354.752292)
			(xy 187.011842 -354.806869) (xy 187.012326 -354.834444) (xy 187.011863 -354.861696) (xy 187.004101 -354.915643)
			(xy 186.988741 -354.967937) (xy 186.966096 -355.017513) (xy 186.936627 -355.063363) (xy 186.902567 -355.102668)
			(xy 187.56071 -355.102668) (xy 187.564781 -355.047046) (xy 187.576907 -354.992609) (xy 187.59683 -354.940518)
			(xy 187.624126 -354.891883) (xy 187.658212 -354.84774) (xy 187.698361 -354.809031) (xy 187.743719 -354.77658)
			(xy 187.793319 -354.751079) (xy 187.846103 -354.733072) (xy 187.900946 -354.722942) (xy 187.95668 -354.720905)
			(xy 188.012117 -354.727005) (xy 188.066074 -354.741111) (xy 188.117403 -354.762923) (xy 188.165009 -354.791977)
			(xy 188.207877 -354.827652) (xy 188.245094 -354.869189) (xy 188.275867 -354.915702) (xy 188.299539 -354.966199)
			(xy 188.315607 -355.019606) (xy 188.323727 -355.074782) (xy 188.324236 -355.102668) (xy 188.323727 -355.130554)
			(xy 188.315607 -355.18573) (xy 188.299539 -355.239137) (xy 188.275867 -355.289634) (xy 188.245094 -355.336147)
			(xy 188.207877 -355.377684) (xy 188.165009 -355.413359) (xy 188.117403 -355.442413) (xy 188.066074 -355.464225)
			(xy 188.012117 -355.478331) (xy 187.95668 -355.484431) (xy 187.900946 -355.482394) (xy 187.846103 -355.472264)
			(xy 187.793319 -355.454257) (xy 187.743719 -355.428756) (xy 187.698361 -355.396305) (xy 187.658212 -355.357596)
			(xy 187.624126 -355.313453) (xy 187.59683 -355.264818) (xy 187.576907 -355.212727) (xy 187.564781 -355.15829)
			(xy 187.56071 -355.102668) (xy 186.902567 -355.102668) (xy 186.900934 -355.104552) (xy 186.859742 -355.140243)
			(xy 186.813891 -355.169709) (xy 186.764313 -355.19235) (xy 186.712018 -355.207707) (xy 186.65807 -355.215465)
			(xy 186.630818 -355.215952) (xy 186.602962 -355.215448) (xy 186.547844 -355.207326) (xy 186.494491 -355.19128)
			(xy 186.444036 -355.167652) (xy 186.397551 -355.136943) (xy 186.356021 -355.099805) (xy 186.320329 -355.057026)
			(xy 186.291232 -355.009514) (xy 186.269348 -354.958279) (xy 186.261756 -354.931472) (xy 186.25947 -354.922582)
			(xy 186.248802 -354.907342) (xy 186.17692 -354.85959) (xy 186.158886 -354.855526) (xy 186.149742 -354.856796)
			(xy 186.136726 -354.858469) (xy 186.110541 -354.860246) (xy 186.097418 -354.860352) (xy 186.083269 -354.860256)
			(xy 186.055046 -354.858223) (xy 186.04103 -354.856288) (xy 186.03087 -354.854764) (xy 186.011312 -354.85959)
			(xy 185.93689 -354.91547) (xy 185.92673 -354.932996) (xy 185.92546 -354.943156) (xy 185.921339 -354.970304)
			(xy 185.906367 -355.023131) (xy 185.883977 -355.073266) (xy 185.854633 -355.119675) (xy 185.818939 -355.161398)
			(xy 185.777633 -355.197574) (xy 185.731569 -355.227457) (xy 185.681697 -355.250428) (xy 185.629048 -355.266013)
			(xy 185.574708 -355.273891) (xy 185.547254 -355.274372) (xy 185.52 -355.273965) (xy 185.466048 -355.266201)
			(xy 185.413749 -355.250838) (xy 185.364169 -355.228189) (xy 185.318317 -355.198715) (xy 185.277127 -355.163015)
			(xy 185.241436 -355.121817) (xy 185.211971 -355.075959) (xy 185.189333 -355.026374) (xy 185.173981 -354.974072)
			(xy 185.166229 -354.920118) (xy 185.165746 -354.892864) (xy 183.024857 -354.892864) (xy 183.027488 -354.901825)
			(xy 183.035241 -354.95578) (xy 183.035702 -354.983034) (xy 183.03504 -355.014597) (xy 183.024654 -355.076862)
			(xy 183.004169 -355.136571) (xy 182.989728 -355.164644) (xy 182.984902 -355.173534) (xy 182.98287 -355.193092)
			(xy 183.008524 -355.28123) (xy 183.02097 -355.296724) (xy 183.02986 -355.301804) (xy 183.054938 -355.31639)
			(xy 183.100822 -355.351886) (xy 183.140799 -355.393923) (xy 183.173948 -355.44153) (xy 183.199503 -355.493609)
			(xy 183.216874 -355.548959) (xy 183.22566 -355.6063) (xy 183.226202 -355.635306) (xy 183.225728 -355.662558)
			(xy 183.21797 -355.716506) (xy 183.202614 -355.768801) (xy 183.198272 -355.778308) (xy 188.899546 -355.778308)
			(xy 188.900026 -355.750833) (xy 188.907918 -355.696453) (xy 188.923539 -355.64377) (xy 188.946565 -355.593877)
			(xy 188.976519 -355.547809) (xy 188.994288 -355.526848) (xy 189.000384 -355.519736) (xy 189.006734 -355.502718)
			(xy 189.006734 -355.416866) (xy 189.000384 -355.399848) (xy 188.994288 -355.392736) (xy 188.976558 -355.371746)
			(xy 188.946629 -355.325672) (xy 188.923609 -355.275785) (xy 188.907976 -355.223114) (xy 188.90005 -355.168747)
			(xy 188.899546 -355.141276) (xy 188.900032 -355.114025) (xy 188.907788 -355.060077) (xy 188.923143 -355.007782)
			(xy 188.945785 -354.958205) (xy 188.975251 -354.912355) (xy 189.010942 -354.871164) (xy 189.052133 -354.835473)
			(xy 189.097983 -354.806007) (xy 189.14756 -354.783365) (xy 189.199855 -354.76801) (xy 189.253803 -354.760254)
			(xy 189.308305 -354.760254) (xy 189.362253 -354.76801) (xy 189.414548 -354.783365) (xy 189.464125 -354.806007)
			(xy 189.509975 -354.835473) (xy 189.551166 -354.871164) (xy 189.586857 -354.912355) (xy 189.616323 -354.958205)
			(xy 189.638965 -355.007782) (xy 189.65432 -355.060077) (xy 189.662076 -355.114025) (xy 189.662562 -355.141276)
			(xy 189.662071 -355.168751) (xy 189.654182 -355.22313) (xy 189.638563 -355.275813) (xy 189.615539 -355.325706)
			(xy 189.585588 -355.371774) (xy 189.56782 -355.392736) (xy 189.561724 -355.399848) (xy 189.555374 -355.416866)
			(xy 189.555374 -355.502718) (xy 189.561724 -355.519736) (xy 189.56782 -355.526848) (xy 189.585591 -355.547805)
			(xy 189.615514 -355.593888) (xy 189.638525 -355.643784) (xy 189.654149 -355.696462) (xy 189.662064 -355.750835)
			(xy 189.662562 -355.778308) (xy 189.662076 -355.805559) (xy 189.65432 -355.859507) (xy 189.638965 -355.911802)
			(xy 189.616323 -355.961379) (xy 189.586857 -356.007229) (xy 189.551166 -356.04842) (xy 189.509975 -356.084111)
			(xy 189.464125 -356.113577) (xy 189.414548 -356.136219) (xy 189.362253 -356.151574) (xy 189.308305 -356.15933)
			(xy 189.253803 -356.15933) (xy 189.199855 -356.151574) (xy 189.14756 -356.136219) (xy 189.097983 -356.113577)
			(xy 189.052133 -356.084111) (xy 189.010942 -356.04842) (xy 188.975251 -356.007229) (xy 188.945785 -355.961379)
			(xy 188.923143 -355.911802) (xy 188.907788 -355.859507) (xy 188.900032 -355.805559) (xy 188.899546 -355.778308)
			(xy 183.198272 -355.778308) (xy 183.179972 -355.818379) (xy 183.150504 -355.86423) (xy 183.114812 -355.90542)
			(xy 183.07362 -355.941112) (xy 183.027769 -355.970578) (xy 182.97819 -355.993218) (xy 182.925894 -356.008573)
			(xy 182.871946 -356.016329) (xy 182.844694 -356.016814) (xy 182.814051 -356.016207) (xy 182.75356 -356.006372)
			(xy 182.724298 -355.997256) (xy 182.710582 -355.992684) (xy 182.682642 -355.999288) (xy 181.814216 -356.867968)
			(xy 181.799705 -356.88174) (xy 181.766414 -356.903916) (xy 181.729439 -356.919176) (xy 181.690199 -356.926935)
			(xy 181.670198 -356.927404) (xy 173.081696 -356.927404) (xy 173.061689 -356.926993) (xy 173.022432 -356.91925)
			(xy 172.985446 -356.903983) (xy 172.952157 -356.881782) (xy 172.937678 -356.867968) (xy 168.804082 -352.734118)
			(xy 168.79668 -352.72728) (xy 168.778082 -352.719558) (xy 168.768014 -352.719132) (xy 164.049964 -352.719132)
			(xy 164.029956 -352.718733) (xy 163.9907 -352.710984) (xy 163.953714 -352.695714) (xy 163.920426 -352.67351)
			(xy 163.905946 -352.659696) (xy 162.45332 -351.206816) (xy 162.445862 -351.200094) (xy 162.427285 -351.192522)
			(xy 162.417252 -351.192084) (xy 162.379406 -351.192084) (xy 162.369066 -351.192563) (xy 162.350041 -351.200662)
			(xy 162.335739 -351.215595) (xy 162.331654 -351.225104) (xy 162.2933 -351.329752) (xy 162.301174 -351.360232)
			(xy 162.313366 -351.370646) (xy 162.333916 -351.388883) (xy 162.370124 -351.430204) (xy 162.400032 -351.47629)
			(xy 162.423021 -351.52619) (xy 162.438615 -351.578871) (xy 162.446493 -351.633244) (xy 162.44697 -351.660714)
			(xy 162.446854 -351.675634) (xy 162.444562 -351.705387) (xy 162.442398 -351.72015) (xy 162.440366 -351.732342)
			(xy 162.447732 -351.755202) (xy 162.836606 -352.143822) (xy 162.850445 -352.158292) (xy 162.872701 -352.191571)
			(xy 162.888029 -352.228556) (xy 162.89584 -352.267822) (xy 162.896296 -352.28784) (xy 162.896296 -353.332796)
			(xy 165.19474 -353.332796) (xy 165.198811 -353.277174) (xy 165.210937 -353.222737) (xy 165.23086 -353.170646)
			(xy 165.258156 -353.122011) (xy 165.292242 -353.077868) (xy 165.332391 -353.039159) (xy 165.377749 -353.006708)
			(xy 165.427349 -352.981207) (xy 165.480133 -352.9632) (xy 165.534976 -352.95307) (xy 165.59071 -352.951033)
			(xy 165.646147 -352.957133) (xy 165.700104 -352.971239) (xy 165.751433 -352.993051) (xy 165.799039 -353.022105)
			(xy 165.841907 -353.05778) (xy 165.879124 -353.099317) (xy 165.909897 -353.14583) (xy 165.933569 -353.196327)
			(xy 165.949637 -353.249734) (xy 165.957757 -353.30491) (xy 165.958266 -353.332796) (xy 165.957757 -353.360682)
			(xy 165.949637 -353.415858) (xy 165.933569 -353.469265) (xy 165.909897 -353.519762) (xy 165.879124 -353.566275)
			(xy 165.841907 -353.607812) (xy 165.799039 -353.643487) (xy 165.751433 -353.672541) (xy 165.700104 -353.694353)
			(xy 165.646147 -353.708459) (xy 165.59071 -353.714559) (xy 165.534976 -353.712522) (xy 165.480133 -353.702392)
			(xy 165.427349 -353.684385) (xy 165.377749 -353.658884) (xy 165.332391 -353.626433) (xy 165.292242 -353.587724)
			(xy 165.258156 -353.543581) (xy 165.23086 -353.494946) (xy 165.210937 -353.442855) (xy 165.198811 -353.388418)
			(xy 165.19474 -353.332796) (xy 162.896296 -353.332796) (xy 162.896296 -353.956366) (xy 162.896632 -353.966415)
			(xy 162.904242 -353.985013) (xy 162.911028 -353.992434) (xy 163.53155 -354.612956) (xy 163.539022 -354.619661)
			(xy 163.557588 -354.627244) (xy 163.567618 -354.627688) (xy 168.594278 -354.627688) (xy 168.614291 -354.628164)
			(xy 168.653545 -354.635998) (xy 168.690519 -354.65133) (xy 168.723797 -354.673573) (xy 168.738296 -354.687378)
			(xy 172.131482 -358.080818) (xy 172.138892 -358.087645) (xy 172.157484 -358.095372) (xy 172.16755 -358.095804)
			(xy 188.154564 -358.095804) (xy 188.164635 -358.095385) (xy 188.183234 -358.087663) (xy 188.190632 -358.080818)
			(xy 190.68415 -355.587046) (xy 190.698555 -355.573304) (xy 190.731625 -355.551147) (xy 190.768369 -355.535834)
			(xy 190.787782 -355.53142) (xy 190.799507 -355.528412) (xy 190.818476 -355.513434) (xy 190.824104 -355.502718)
			(xy 190.835788 -355.479096) (xy 190.840614 -355.470206) (xy 190.842646 -355.450648) (xy 190.816992 -355.36251)
			(xy 190.804546 -355.347016) (xy 190.795656 -355.341936) (xy 190.78829 -355.337872) (xy 190.778638 -355.33203)
			(xy 190.75654 -355.329998) (xy 190.662052 -355.363526) (xy 190.64605 -355.37902) (xy 190.641986 -355.389434)
			(xy 190.631336 -355.41623) (xy 190.603042 -355.466472) (xy 190.567505 -355.511882) (xy 190.525536 -355.551423)
			(xy 190.478092 -355.584194) (xy 190.426255 -355.609449) (xy 190.371206 -355.62661) (xy 190.314201 -355.635287)
			(xy 190.28537 -355.635814) (xy 190.258121 -355.635314) (xy 190.204177 -355.627554) (xy 190.151887 -355.612197)
			(xy 190.102314 -355.589554) (xy 190.056468 -355.560088) (xy 190.015282 -355.524397) (xy 189.979594 -355.483208)
			(xy 189.950131 -355.43736) (xy 189.927493 -355.387785) (xy 189.912139 -355.335494) (xy 189.904384 -355.281549)
			(xy 189.904384 -355.227051) (xy 189.912139 -355.173106) (xy 189.927493 -355.120815) (xy 189.950131 -355.07124)
			(xy 189.979594 -355.025392) (xy 190.015282 -354.984203) (xy 190.056468 -354.948512) (xy 190.102314 -354.919046)
			(xy 190.151887 -354.896403) (xy 190.204177 -354.881046) (xy 190.258121 -354.873286) (xy 190.28537 -354.872798)
			(xy 190.310606 -354.873165) (xy 190.360641 -354.879792) (xy 190.409362 -354.892974) (xy 190.455912 -354.912479)
			(xy 190.477902 -354.924868) (xy 190.487554 -354.93071) (xy 190.509652 -354.932742) (xy 190.60414 -354.899214)
			(xy 190.620142 -354.88372) (xy 190.624206 -354.873306) (xy 190.634884 -354.846522) (xy 190.663173 -354.796278)
			(xy 190.698704 -354.750867) (xy 190.740669 -354.711325) (xy 190.788109 -354.678551) (xy 190.839943 -354.653295)
			(xy 190.894989 -354.636132) (xy 190.951992 -354.627453) (xy 190.980822 -354.626926) (xy 191.008077 -354.627335)
			(xy 191.062032 -354.635095) (xy 191.114333 -354.650456) (xy 191.163915 -354.673103) (xy 191.20977 -354.702577)
			(xy 191.250963 -354.738276) (xy 191.286657 -354.779475) (xy 191.316123 -354.825334) (xy 191.338764 -354.87492)
			(xy 191.351487 -354.918264) (xy 193.492374 -354.918264) (xy 193.492893 -354.890691) (xy 193.500836 -354.836121)
			(xy 193.516551 -354.783263) (xy 193.539711 -354.733217) (xy 193.569834 -354.687026) (xy 193.606292 -354.645652)
			(xy 193.626994 -354.627434) (xy 193.635092 -354.619813) (xy 193.644458 -354.599676) (xy 193.645028 -354.588572)
			(xy 193.645028 -354.511356) (xy 193.644468 -354.500245) (xy 193.635126 -354.480085) (xy 193.626994 -354.472494)
			(xy 193.606276 -354.454291) (xy 193.569806 -354.41292) (xy 193.539675 -354.366729) (xy 193.516511 -354.316679)
			(xy 193.500796 -354.263815) (xy 193.492858 -354.209239) (xy 193.492374 -354.181664) (xy 193.492844 -354.154413)
			(xy 193.500605 -354.100465) (xy 193.515964 -354.048171) (xy 193.538608 -353.998595) (xy 193.568076 -353.952746)
			(xy 193.603769 -353.911557) (xy 193.64496 -353.875866) (xy 193.690811 -353.846399) (xy 193.740388 -353.823758)
			(xy 193.792683 -353.808401) (xy 193.846631 -353.800643) (xy 193.873882 -353.800156) (xy 193.908172 -353.80168)
			(xy 193.918332 -353.802696) (xy 193.937636 -353.7966) (xy 194.008248 -353.737418) (xy 194.017646 -353.719384)
			(xy 194.018662 -353.709224) (xy 194.021613 -353.681051) (xy 194.03479 -353.62596) (xy 194.05597 -353.573425)
			(xy 194.084689 -353.5246) (xy 194.120314 -353.48056) (xy 194.16206 -353.442274) (xy 194.209011 -353.410584)
			(xy 194.260133 -353.386188) (xy 194.314301 -353.369622) (xy 194.370324 -353.36125) (xy 194.398646 -353.360736)
			(xy 194.416665 -353.360955) (xy 194.45254 -353.364391) (xy 194.470274 -353.367594) (xy 194.479672 -353.369372)
			(xy 194.498722 -353.365562) (xy 194.573906 -353.31781) (xy 194.585336 -353.302062) (xy 194.587622 -353.292664)
			(xy 194.59502 -353.26562) (xy 194.616649 -353.213893) (xy 194.645613 -353.165887) (xy 194.681288 -353.122635)
			(xy 194.722907 -353.085068) (xy 194.769575 -353.053993) (xy 194.820286 -353.030081) (xy 194.873951 -353.013845)
			(xy 194.929413 -353.005634) (xy 194.957446 -353.005136) (xy 194.9847 -353.005535) (xy 195.038654 -353.013299)
			(xy 195.090953 -353.028662) (xy 195.140533 -353.051312) (xy 195.186385 -353.080787) (xy 195.227576 -353.116488)
			(xy 195.263267 -353.157687) (xy 195.292731 -353.203546) (xy 195.315369 -353.253132) (xy 195.33072 -353.305435)
			(xy 195.338471 -353.35939) (xy 195.338954 -353.386644) (xy 195.338466 -353.414218) (xy 195.33052 -353.46879)
			(xy 195.314801 -353.521651) (xy 195.291635 -353.571697) (xy 195.261506 -353.617887) (xy 195.22504 -353.659258)
			(xy 195.204334 -353.677474) (xy 195.196221 -353.685081) (xy 195.186866 -353.70523) (xy 195.1863 -353.716336)
			(xy 195.1863 -353.793552) (xy 195.186879 -353.804661) (xy 195.19621 -353.824819) (xy 195.204334 -353.832414)
			(xy 195.225082 -353.850583) (xy 195.261542 -353.891961) (xy 195.291666 -353.938158) (xy 195.314824 -353.988211)
			(xy 195.330535 -354.041077) (xy 195.338471 -354.095653) (xy 195.338467 -354.150804) (xy 195.330523 -354.205379)
			(xy 195.314804 -354.258242) (xy 195.291638 -354.308291) (xy 195.261508 -354.354484) (xy 195.225041 -354.395857)
			(xy 195.204334 -354.414074) (xy 195.196221 -354.421681) (xy 195.186866 -354.44183) (xy 195.1863 -354.452936)
			(xy 195.1863 -354.530152) (xy 195.186879 -354.541261) (xy 195.19621 -354.561419) (xy 195.204334 -354.569014)
			(xy 195.225062 -354.587207) (xy 195.261529 -354.62858) (xy 195.291659 -354.674774) (xy 195.314821 -354.724826)
			(xy 195.330534 -354.777691) (xy 195.33847 -354.832268) (xy 195.338954 -354.859844) (xy 195.338463 -354.887094)
			(xy 195.330702 -354.941039) (xy 195.315344 -354.993331) (xy 195.292701 -355.042906) (xy 195.263234 -355.088753)
			(xy 195.227543 -355.129942) (xy 195.186355 -355.165633) (xy 195.140507 -355.1951) (xy 195.090933 -355.217743)
			(xy 195.038641 -355.233102) (xy 194.984696 -355.240863) (xy 194.957446 -355.241352) (xy 194.92959 -355.240823)
			(xy 194.874473 -355.232705) (xy 194.821121 -355.216663) (xy 194.770667 -355.193038) (xy 194.724181 -355.162332)
			(xy 194.682651 -355.125197) (xy 194.646958 -355.082421) (xy 194.617861 -355.034911) (xy 194.595976 -354.983678)
			(xy 194.588384 -354.956872) (xy 194.586098 -354.947982) (xy 194.57543 -354.932742) (xy 194.503548 -354.88499)
			(xy 194.485514 -354.880926) (xy 194.47637 -354.882196) (xy 194.463354 -354.883866) (xy 194.437169 -354.885645)
			(xy 194.424046 -354.885752) (xy 194.409897 -354.885653) (xy 194.381674 -354.883622) (xy 194.367658 -354.881688)
			(xy 194.357498 -354.880164) (xy 194.33794 -354.88499) (xy 194.263518 -354.94087) (xy 194.253358 -354.958396)
			(xy 194.252088 -354.968556) (xy 194.248037 -354.995716) (xy 194.233061 -355.048548) (xy 194.210665 -355.098688)
			(xy 194.181314 -355.1451) (xy 194.145612 -355.186825) (xy 194.104298 -355.223001) (xy 194.058225 -355.252881)
			(xy 194.008344 -355.275848) (xy 193.955686 -355.291427) (xy 193.901339 -355.299296) (xy 193.873882 -355.299772)
			(xy 193.846627 -355.299362) (xy 193.792672 -355.291601) (xy 193.740371 -355.276241) (xy 193.690789 -355.253594)
			(xy 193.644934 -355.224121) (xy 193.60374 -355.188421) (xy 193.568047 -355.147223) (xy 193.53858 -355.101364)
			(xy 193.51594 -355.051778) (xy 193.500587 -354.999475) (xy 193.492834 -354.945519) (xy 193.492374 -354.918264)
			(xy 191.351487 -354.918264) (xy 191.354117 -354.927223) (xy 191.361869 -354.981179) (xy 191.36233 -355.008434)
			(xy 191.361665 -355.039996) (xy 191.351279 -355.102261) (xy 191.330796 -355.161971) (xy 191.316356 -355.190044)
			(xy 191.31153 -355.198934) (xy 191.309498 -355.218492) (xy 191.335152 -355.30663) (xy 191.347598 -355.322124)
			(xy 191.356488 -355.327204) (xy 191.381573 -355.34178) (xy 191.427455 -355.377278) (xy 191.467431 -355.419317)
			(xy 191.500578 -355.466927) (xy 191.526132 -355.519007) (xy 191.543502 -355.574357) (xy 191.552288 -355.6317)
			(xy 191.55283 -355.660706) (xy 191.552328 -355.687956) (xy 191.544571 -355.741902) (xy 191.529216 -355.794195)
			(xy 191.506576 -355.843771) (xy 191.477111 -355.889621) (xy 191.441422 -355.93081) (xy 191.400233 -355.966502)
			(xy 191.354385 -355.995968) (xy 191.304811 -356.018611) (xy 191.252518 -356.033968) (xy 191.198572 -356.041727)
			(xy 191.171322 -356.042214) (xy 191.14066 -356.041566) (xy 191.080127 -356.031749) (xy 191.021948 -356.012365)
			(xy 190.967624 -355.983915) (xy 190.942722 -355.966014) (xy 190.927228 -355.954584) (xy 190.88989 -355.957378)
			(xy 188.403992 -358.443276) (xy 188.389492 -358.457061) (xy 188.356197 -358.479234) (xy 188.319219 -358.49449)
			(xy 188.279976 -358.502245) (xy 188.259974 -358.502712) (xy 172.06214 -358.502712) (xy 172.042134 -358.502272)
			(xy 172.002879 -358.494537) (xy 171.965893 -358.479279) (xy 171.932603 -358.457086) (xy 171.918122 -358.443276)
			(xy 168.524936 -355.049836) (xy 168.51747 -355.043123) (xy 168.498899 -355.035545) (xy 168.488868 -355.035104)
			(xy 163.462208 -355.035104) (xy 163.442197 -355.034578) (xy 163.402946 -355.02676) (xy 163.365971 -355.011443)
			(xy 163.332691 -354.989213) (xy 163.31819 -354.975414) (xy 162.54857 -354.205794) (xy 162.534751 -354.191305)
			(xy 162.512488 -354.158034) (xy 162.497153 -354.121055) (xy 162.489338 -354.081792) (xy 162.48888 -354.061776)
			(xy 162.48888 -352.39325) (xy 162.488516 -352.383204) (xy 162.480923 -352.364608) (xy 162.474148 -352.357182)
			(xy 162.15995 -352.042984) (xy 162.13709 -352.035618) (xy 162.124898 -352.03765) (xy 162.110134 -352.039804)
			(xy 162.080382 -352.042096) (xy 162.065462 -352.042222) (xy 162.039708 -352.041811) (xy 161.988671 -352.034865)
			(xy 161.939033 -352.021117) (xy 161.891694 -352.000818) (xy 161.847515 -351.974337) (xy 161.807299 -351.942154)
			(xy 161.771778 -351.904855) (xy 161.756344 -351.884234) (xy 161.749232 -351.874328) (xy 161.727896 -351.863152)
			(xy 161.621724 -351.862136) (xy 161.600134 -351.87255) (xy 161.593022 -351.882456) (xy 161.574846 -351.905521)
			(xy 161.532645 -351.946351) (xy 161.484683 -351.980228) (xy 161.432095 -352.006352) (xy 161.376122 -352.024105)
			(xy 161.31809 -352.033066) (xy 161.28873 -352.033586) (xy 161.261477 -352.033117) (xy 161.207525 -352.025363)
			(xy 161.155226 -352.01001) (xy 161.105644 -351.987369) (xy 161.05979 -351.957902) (xy 161.018597 -351.922209)
			(xy 160.982902 -351.881016) (xy 160.953435 -351.835163) (xy 160.930793 -351.785582) (xy 160.915438 -351.733283)
			(xy 160.907684 -351.679331) (xy 160.907222 -351.652078) (xy 160.447353 -351.652078) (xy 160.442765 -351.683995)
			(xy 160.427411 -351.736287) (xy 160.404772 -351.785862) (xy 160.375309 -351.83171) (xy 160.339621 -351.8729)
			(xy 160.298434 -351.908591) (xy 160.252588 -351.938058) (xy 160.203015 -351.960701) (xy 160.150724 -351.976058)
			(xy 160.09678 -351.983818) (xy 160.06953 -351.98431) (xy 160.038961 -351.983729) (xy 159.978597 -351.974038)
			(xy 159.949388 -351.965006) (xy 159.937958 -351.960942) (xy 159.913574 -351.964752) (xy 159.836866 -352.020124)
			(xy 159.827477 -352.027732) (xy 159.816467 -352.049207) (xy 159.815784 -352.061272) (xy 159.815784 -353.286822)
			(xy 159.816204 -353.295631) (xy 159.822249 -353.312184) (xy 159.833519 -353.325732) (xy 159.84093 -353.33051)
			(xy 159.928306 -353.381818) (xy 159.95523 -353.382072) (xy 159.966914 -353.375468) (xy 159.988311 -353.363987)
			(xy 160.033389 -353.345931) (xy 160.080392 -353.333735) (xy 160.128562 -353.327597) (xy 160.152842 -353.327208)
			(xy 160.180091 -353.327697) (xy 160.234033 -353.335459) (xy 160.286322 -353.350818) (xy 160.335893 -353.373461)
			(xy 160.381737 -353.402929) (xy 160.42292 -353.438621) (xy 160.458606 -353.47981) (xy 160.488067 -353.525658)
			(xy 160.510703 -353.575233) (xy 160.526054 -353.627524) (xy 160.533807 -353.681467) (xy 160.53435 -353.708716)
			(xy 160.533859 -353.736436) (xy 160.525843 -353.791293) (xy 160.509969 -353.844411) (xy 160.48657 -353.894671)
			(xy 160.471577 -353.917504) (xy 161.123628 -353.917504) (xy 161.127699 -353.861882) (xy 161.139825 -353.807445)
			(xy 161.159748 -353.755354) (xy 161.187044 -353.706719) (xy 161.22113 -353.662576) (xy 161.261279 -353.623867)
			(xy 161.306637 -353.591416) (xy 161.356237 -353.565915) (xy 161.409021 -353.547908) (xy 161.463864 -353.537778)
			(xy 161.519598 -353.535741) (xy 161.575035 -353.541841) (xy 161.628992 -353.555947) (xy 161.680321 -353.577759)
			(xy 161.727927 -353.606813) (xy 161.770795 -353.642488) (xy 161.808012 -353.684025) (xy 161.838785 -353.730538)
			(xy 161.862457 -353.781035) (xy 161.878525 -353.834442) (xy 161.886645 -353.889618) (xy 161.887154 -353.917504)
			(xy 161.886645 -353.94539) (xy 161.878525 -354.000566) (xy 161.862457 -354.053973) (xy 161.838785 -354.10447)
			(xy 161.808012 -354.150983) (xy 161.770795 -354.19252) (xy 161.727927 -354.228195) (xy 161.680321 -354.257249)
			(xy 161.628992 -354.279061) (xy 161.575035 -354.293167) (xy 161.519598 -354.299267) (xy 161.463864 -354.29723)
			(xy 161.409021 -354.2871) (xy 161.356237 -354.269093) (xy 161.306637 -354.243592) (xy 161.261279 -354.211141)
			(xy 161.22113 -354.172432) (xy 161.187044 -354.128289) (xy 161.159748 -354.079654) (xy 161.139825 -354.027563)
			(xy 161.127699 -353.973126) (xy 161.123628 -353.917504) (xy 160.471577 -353.917504) (xy 160.456141 -353.941013)
			(xy 160.419322 -353.98246) (xy 160.376889 -354.018139) (xy 160.329738 -354.047298) (xy 160.30448 -354.058728)
			(xy 160.292796 -354.063808) (xy 160.277302 -354.083366) (xy 160.259014 -354.178362) (xy 160.257268 -354.190727)
			(xy 160.264608 -354.214564) (xy 160.272984 -354.223828) (xy 160.348676 -354.299266) (xy 160.356042 -354.306106)
			(xy 160.374575 -354.313848) (xy 160.394659 -354.313848) (xy 160.413192 -354.306106) (xy 160.420558 -354.299266)
			(xy 160.55721 -354.162614) (xy 160.564647 -354.15592) (xy 160.583139 -354.148334) (xy 160.603126 -354.148386)
			(xy 160.621578 -354.15607) (xy 160.635695 -354.170219) (xy 160.643336 -354.188688) (xy 160.643824 -354.198682)
			(xy 160.643824 -354.328222) (xy 160.644252 -354.33829) (xy 160.651974 -354.356886) (xy 160.65881 -354.36429)
			(xy 165.10381 -358.80929) (xy 165.111209 -358.816136) (xy 165.129807 -358.823868) (xy 165.139878 -358.824276)
			(xy 173.857412 -358.824276) (xy 173.867482 -358.824701) (xy 173.886085 -358.832415) (xy 173.89348 -358.839262)
			(xy 178.97856 -363.924342) (xy 179.856638 -363.924342) (xy 179.857119 -363.896972) (xy 179.864932 -363.842793)
			(xy 179.880417 -363.79029) (xy 179.903256 -363.740543) (xy 179.932978 -363.694576) (xy 179.950618 -363.673644)
			(xy 179.956714 -363.666532) (xy 179.963064 -363.649514) (xy 179.963064 -363.56417) (xy 179.956714 -363.547152)
			(xy 179.950618 -363.54004) (xy 179.932987 -363.519101) (xy 179.903273 -363.473131) (xy 179.880436 -363.423385)
			(xy 179.864943 -363.370886) (xy 179.857113 -363.316711) (xy 179.856638 -363.289342) (xy 179.857119 -363.261768)
			(xy 179.865067 -363.207195) (xy 179.880788 -363.154335) (xy 179.903955 -363.104289) (xy 179.934085 -363.058099)
			(xy 179.970551 -363.016728) (xy 179.991258 -362.998512) (xy 179.999376 -362.990909) (xy 180.008728 -362.970758)
			(xy 180.009292 -362.95965) (xy 180.009292 -362.882434) (xy 180.008724 -362.871324) (xy 179.999386 -362.851165)
			(xy 179.991258 -362.843572) (xy 179.970522 -362.825388) (xy 179.934055 -362.784013) (xy 179.903927 -362.737817)
			(xy 179.880766 -362.687764) (xy 179.865055 -362.634897) (xy 179.857121 -362.580318) (xy 179.856638 -362.552742)
			(xy 179.857119 -362.525372) (xy 179.864932 -362.471193) (xy 179.880417 -362.41869) (xy 179.903256 -362.368943)
			(xy 179.932978 -362.322976) (xy 179.950618 -362.302044) (xy 179.956714 -362.294932) (xy 179.963064 -362.277914)
			(xy 179.963064 -362.19257) (xy 179.956714 -362.175552) (xy 179.950618 -362.16844) (xy 179.933019 -362.147474)
			(xy 179.903293 -362.101512) (xy 179.880446 -362.051771) (xy 179.864947 -361.999274) (xy 179.857114 -361.9451)
			(xy 179.85711 -361.890363) (xy 179.864933 -361.836188) (xy 179.880423 -361.783689) (xy 179.903263 -361.733944)
			(xy 179.932981 -361.687977) (xy 179.950618 -361.667044) (xy 179.956714 -361.659932) (xy 179.963064 -361.642914)
			(xy 179.963064 -361.55757) (xy 179.956714 -361.540552) (xy 179.950618 -361.53344) (xy 179.933019 -361.512474)
			(xy 179.903293 -361.466512) (xy 179.880446 -361.416771) (xy 179.864947 -361.364274) (xy 179.857114 -361.3101)
			(xy 179.85711 -361.255363) (xy 179.864933 -361.201188) (xy 179.880423 -361.148689) (xy 179.903263 -361.098944)
			(xy 179.932981 -361.052977) (xy 179.950618 -361.032044) (xy 179.956714 -361.024932) (xy 179.963064 -361.007914)
			(xy 179.963064 -360.92257) (xy 179.956714 -360.905552) (xy 179.950618 -360.89844) (xy 179.932987 -360.877501)
			(xy 179.903273 -360.831531) (xy 179.880436 -360.781785) (xy 179.864943 -360.729286) (xy 179.857113 -360.675111)
			(xy 179.856638 -360.647742) (xy 179.857119 -360.620168) (xy 179.865067 -360.565595) (xy 179.880788 -360.512735)
			(xy 179.903955 -360.462689) (xy 179.934085 -360.416499) (xy 179.970551 -360.375128) (xy 179.991258 -360.356912)
			(xy 179.999376 -360.349309) (xy 180.008728 -360.329158) (xy 180.009292 -360.31805) (xy 180.009292 -360.240834)
			(xy 180.008724 -360.229724) (xy 179.999386 -360.209565) (xy 179.991258 -360.201972) (xy 179.970522 -360.183788)
			(xy 179.934055 -360.142413) (xy 179.903927 -360.096217) (xy 179.880766 -360.046164) (xy 179.865055 -359.993297)
			(xy 179.857121 -359.938718) (xy 179.856638 -359.911142) (xy 179.857119 -359.883772) (xy 179.864932 -359.829593)
			(xy 179.880417 -359.77709) (xy 179.903256 -359.727343) (xy 179.932978 -359.681376) (xy 179.950618 -359.660444)
			(xy 179.956714 -359.653332) (xy 179.963064 -359.636314) (xy 179.963064 -359.55097) (xy 179.956714 -359.533952)
			(xy 179.950618 -359.52684) (xy 179.932987 -359.505901) (xy 179.903273 -359.459931) (xy 179.880436 -359.410185)
			(xy 179.864943 -359.357686) (xy 179.857113 -359.303511) (xy 179.856638 -359.276142) (xy 179.857095 -359.248888)
			(xy 179.864847 -359.194935) (xy 179.8802 -359.142634) (xy 179.902841 -359.093051) (xy 179.932309 -359.047195)
			(xy 179.968004 -359.006001) (xy 180.009198 -358.970306) (xy 180.055054 -358.940839) (xy 180.104637 -358.918199)
			(xy 180.156938 -358.902846) (xy 180.210892 -358.895094) (xy 180.238146 -358.894634) (xy 180.265515 -358.895123)
			(xy 180.319694 -358.902934) (xy 180.372197 -358.918418) (xy 180.421944 -358.941254) (xy 180.467912 -358.970975)
			(xy 180.488844 -358.988614) (xy 180.495956 -358.99471) (xy 180.512974 -359.00106) (xy 180.598318 -359.00106)
			(xy 180.615336 -358.99471) (xy 180.622448 -358.988614) (xy 180.643381 -358.970973) (xy 180.689349 -358.941249)
			(xy 180.739095 -358.918403) (xy 180.791597 -358.902907) (xy 180.845775 -358.895078) (xy 180.900517 -358.895078)
			(xy 180.954695 -358.902907) (xy 181.007197 -358.918403) (xy 181.056943 -358.941249) (xy 181.102911 -358.970973)
			(xy 181.123844 -358.988614) (xy 181.130956 -358.99471) (xy 181.147974 -359.00106) (xy 181.233318 -359.00106)
			(xy 181.250336 -358.99471) (xy 181.257448 -358.988614) (xy 181.278381 -358.970973) (xy 181.324349 -358.941249)
			(xy 181.374095 -358.918403) (xy 181.426597 -358.902907) (xy 181.480775 -358.895078) (xy 181.535517 -358.895078)
			(xy 181.589695 -358.902907) (xy 181.642197 -358.918403) (xy 181.691943 -358.941249) (xy 181.737911 -358.970973)
			(xy 181.758844 -358.988614) (xy 181.765956 -358.99471) (xy 181.782974 -359.00106) (xy 181.868318 -359.00106)
			(xy 181.885336 -358.99471) (xy 181.892448 -358.988614) (xy 181.913391 -358.970988) (xy 181.95936 -358.941274)
			(xy 182.009105 -358.918435) (xy 182.061604 -358.902941) (xy 182.115778 -358.89511) (xy 182.143146 -358.894634)
			(xy 182.1704 -358.895035) (xy 182.224353 -358.902799) (xy 182.276652 -358.918162) (xy 182.326232 -358.940812)
			(xy 182.372085 -358.970287) (xy 182.413275 -359.005987) (xy 182.448966 -359.047186) (xy 182.478431 -359.093045)
			(xy 182.501069 -359.14263) (xy 182.51642 -359.194933) (xy 182.524171 -359.248888) (xy 182.524654 -359.276142)
			(xy 182.524165 -359.303512) (xy 182.516355 -359.35769) (xy 182.500871 -359.410193) (xy 182.478034 -359.459941)
			(xy 182.448314 -359.505908) (xy 182.430674 -359.52684) (xy 182.424578 -359.533952) (xy 182.418228 -359.55097)
			(xy 182.418228 -359.636314) (xy 182.424578 -359.653332) (xy 182.430674 -359.660444) (xy 182.448296 -359.68139)
			(xy 182.478012 -359.727358) (xy 182.500851 -359.777102) (xy 182.516346 -359.8296) (xy 182.524178 -359.883774)
			(xy 182.524654 -359.911142) (xy 182.524161 -359.938392) (xy 182.5164 -359.992337) (xy 182.501042 -360.044629)
			(xy 182.4784 -360.094203) (xy 182.448933 -360.140051) (xy 182.413243 -360.18124) (xy 182.372055 -360.216931)
			(xy 182.326207 -360.246398) (xy 182.276633 -360.269041) (xy 182.224341 -360.2844) (xy 182.170396 -360.292161)
			(xy 182.143146 -360.29265) (xy 182.115776 -360.292169) (xy 182.061597 -360.284357) (xy 182.009094 -360.268872)
			(xy 181.959347 -360.246033) (xy 181.91338 -360.216311) (xy 181.892448 -360.19867) (xy 181.885336 -360.192574)
			(xy 181.868318 -360.186224) (xy 181.782974 -360.186224) (xy 181.765956 -360.192574) (xy 181.758844 -360.19867)
			(xy 181.737911 -360.216311) (xy 181.691943 -360.246035) (xy 181.642197 -360.268881) (xy 181.589695 -360.284377)
			(xy 181.535517 -360.292206) (xy 181.480775 -360.292206) (xy 181.426597 -360.284377) (xy 181.374095 -360.268881)
			(xy 181.324349 -360.246035) (xy 181.278381 -360.216311) (xy 181.257448 -360.19867) (xy 181.250336 -360.192574)
			(xy 181.233318 -360.186224) (xy 181.147974 -360.186224) (xy 181.130956 -360.192574) (xy 181.123844 -360.19867)
			(xy 181.102911 -360.216311) (xy 181.056943 -360.246035) (xy 181.007197 -360.268881) (xy 180.954695 -360.284377)
			(xy 180.900517 -360.292206) (xy 180.845775 -360.292206) (xy 180.791597 -360.284377) (xy 180.739095 -360.268881)
			(xy 180.689349 -360.246035) (xy 180.643381 -360.216311) (xy 180.622448 -360.19867) (xy 180.615336 -360.192574)
			(xy 180.598318 -360.186224) (xy 180.512974 -360.186224) (xy 180.495956 -360.192574) (xy 180.488844 -360.19867)
			(xy 180.485034 -360.201972) (xy 180.476922 -360.20958) (xy 180.467567 -360.229728) (xy 180.467 -360.240834)
			(xy 180.467 -360.31805) (xy 180.46758 -360.329158) (xy 180.47691 -360.349317) (xy 180.485034 -360.356912)
			(xy 180.505761 -360.375106) (xy 180.542229 -360.416479) (xy 180.572358 -360.462673) (xy 180.595521 -360.512724)
			(xy 180.611234 -360.565589) (xy 180.61917 -360.620166) (xy 180.619654 -360.647742) (xy 180.619165 -360.675112)
			(xy 180.611355 -360.72929) (xy 180.595871 -360.781793) (xy 180.573034 -360.831541) (xy 180.543314 -360.877508)
			(xy 180.525674 -360.89844) (xy 180.519578 -360.905552) (xy 180.513228 -360.92257) (xy 180.513228 -361.007914)
			(xy 180.519578 -361.024932) (xy 180.525674 -361.032044) (xy 180.543356 -361.052943) (xy 180.573079 -361.098917)
			(xy 180.595922 -361.148669) (xy 180.611415 -361.201176) (xy 180.619239 -361.255359) (xy 180.619235 -361.310104)
			(xy 180.611401 -361.364286) (xy 180.595899 -361.416791) (xy 180.573048 -361.466539) (xy 180.568874 -361.472993)
			(xy 185.652165 -361.472993) (xy 185.655896 -361.419741) (xy 185.667013 -361.367529) (xy 185.685299 -361.317376)
			(xy 185.710397 -361.270262) (xy 185.741818 -361.227107) (xy 185.778948 -361.188752) (xy 185.79973 -361.171998)
			(xy 185.808493 -361.164438) (xy 185.818675 -361.143678) (xy 185.819288 -361.13212) (xy 185.819288 -361.051856)
			(xy 185.818689 -361.040292) (xy 185.808515 -361.01952) (xy 185.79973 -361.011978) (xy 185.777242 -360.993792)
			(xy 185.737506 -360.951772) (xy 185.704567 -360.904236) (xy 185.679179 -360.852274) (xy 185.661924 -360.797075)
			(xy 185.653197 -360.739904) (xy 185.652664 -360.710988) (xy 185.653167 -360.683738) (xy 185.660924 -360.629792)
			(xy 185.676279 -360.577499) (xy 185.69892 -360.527924) (xy 185.728385 -360.482075) (xy 185.764074 -360.440886)
			(xy 185.805262 -360.405194) (xy 185.85111 -360.375727) (xy 185.900684 -360.353085) (xy 185.952976 -360.337727)
			(xy 186.006922 -360.329968) (xy 186.034172 -360.32948) (xy 186.06309 -360.329988) (xy 186.120263 -360.338715)
			(xy 186.175463 -360.355973) (xy 186.227425 -360.381366) (xy 186.274959 -360.414313) (xy 186.316974 -360.454058)
			(xy 186.335162 -360.476546) (xy 186.342737 -360.485294) (xy 186.363486 -360.495483) (xy 186.37504 -360.496104)
			(xy 186.455304 -360.496104) (xy 186.466872 -360.495534) (xy 186.487643 -360.485339) (xy 186.495182 -360.476546)
			(xy 186.51337 -360.45406) (xy 186.555392 -360.414327) (xy 186.602928 -360.38139) (xy 186.654889 -360.356003)
			(xy 186.710087 -360.338746) (xy 186.767256 -360.330016) (xy 186.796172 -360.32948) (xy 186.823424 -360.329981)
			(xy 186.877373 -360.337734) (xy 186.929669 -360.353086) (xy 186.979248 -360.375724) (xy 187.025101 -360.405188)
			(xy 187.066294 -360.440878) (xy 187.101988 -360.482067) (xy 187.131456 -360.527917) (xy 187.1541 -360.577494)
			(xy 187.169457 -360.629788) (xy 187.177216 -360.683736) (xy 187.17768 -360.710988) (xy 187.177161 -360.739905)
			(xy 187.168433 -360.797076) (xy 187.151176 -360.852276) (xy 187.125784 -360.904237) (xy 187.092841 -360.951771)
			(xy 187.0531 -360.993788) (xy 187.030614 -361.011978) (xy 187.021869 -361.019556) (xy 187.011675 -361.040302)
			(xy 187.011056 -361.051856) (xy 187.011056 -361.13212) (xy 187.011653 -361.143685) (xy 187.021827 -361.164458)
			(xy 187.030614 -361.171998) (xy 187.051386 -361.188765) (xy 187.088519 -361.227115) (xy 187.119942 -361.270268)
			(xy 187.145044 -361.31738) (xy 187.163332 -361.367531) (xy 187.17445 -361.419742) (xy 187.178181 -361.472993)
			(xy 187.174452 -361.526244) (xy 187.163336 -361.578455) (xy 187.14505 -361.628607) (xy 187.11995 -361.67572)
			(xy 187.088528 -361.718873) (xy 187.051397 -361.757225) (xy 187.030614 -361.773978) (xy 187.021869 -361.781556)
			(xy 187.011675 -361.802302) (xy 187.011056 -361.813856) (xy 187.011056 -361.89412) (xy 187.011653 -361.905685)
			(xy 187.021827 -361.926458) (xy 187.030614 -361.933998) (xy 187.053099 -361.952187) (xy 187.092834 -361.994207)
			(xy 187.125772 -362.041743) (xy 187.15116 -362.093704) (xy 187.168416 -362.148902) (xy 187.177145 -362.206072)
			(xy 187.17768 -362.234988) (xy 187.177233 -362.262242) (xy 187.169477 -362.316195) (xy 187.154121 -362.368495)
			(xy 187.131478 -362.418077) (xy 187.102009 -362.463931) (xy 187.094223 -362.472916) (xy 190.790826 -362.472916)
			(xy 190.790826 -362.38822) (xy 190.798877 -362.303906) (xy 190.814906 -362.22074) (xy 190.838767 -362.139473)
			(xy 190.870246 -362.060843) (xy 190.909057 -361.985562) (xy 190.954847 -361.91431) (xy 191.007203 -361.847734)
			(xy 191.065651 -361.786436) (xy 191.129661 -361.730971) (xy 191.198653 -361.681842) (xy 191.272003 -361.639493)
			(xy 191.349046 -361.604309) (xy 191.429085 -361.576607) (xy 191.511394 -361.556639) (xy 191.595229 -361.544586)
			(xy 191.67983 -361.540556) (xy 191.764431 -361.544586) (xy 191.848266 -361.556639) (xy 191.930575 -361.576607)
			(xy 192.010614 -361.604309) (xy 192.087657 -361.639493) (xy 192.161007 -361.681842) (xy 192.229999 -361.730971)
			(xy 192.294009 -361.786436) (xy 192.352457 -361.847734) (xy 192.404813 -361.91431) (xy 192.450603 -361.985562)
			(xy 192.489414 -362.060843) (xy 192.520893 -362.139473) (xy 192.544754 -362.22074) (xy 192.560783 -362.303906)
			(xy 192.568834 -362.38822) (xy 192.569338 -362.430568) (xy 192.568834 -362.472916) (xy 192.560783 -362.55723)
			(xy 192.544754 -362.640396) (xy 192.520893 -362.721663) (xy 192.489414 -362.800293) (xy 192.450603 -362.875574)
			(xy 192.404813 -362.946826) (xy 192.352457 -363.013402) (xy 192.294009 -363.0747) (xy 192.229999 -363.130165)
			(xy 192.161007 -363.179294) (xy 192.087657 -363.221643) (xy 192.010614 -363.256827) (xy 191.930575 -363.284529)
			(xy 191.848266 -363.304497) (xy 191.764431 -363.31655) (xy 191.67983 -363.320581) (xy 191.595229 -363.31655)
			(xy 191.511394 -363.304497) (xy 191.429085 -363.284529) (xy 191.349046 -363.256827) (xy 191.272003 -363.221643)
			(xy 191.198653 -363.179294) (xy 191.129661 -363.130165) (xy 191.065651 -363.0747) (xy 191.007203 -363.013402)
			(xy 190.954847 -362.946826) (xy 190.909057 -362.875574) (xy 190.870246 -362.800293) (xy 190.838767 -362.721663)
			(xy 190.814906 -362.640396) (xy 190.798877 -362.55723) (xy 190.790826 -362.472916) (xy 187.094223 -362.472916)
			(xy 187.066313 -362.505125) (xy 187.025118 -362.540819) (xy 186.979263 -362.570286) (xy 186.92968 -362.592927)
			(xy 186.877379 -362.608281) (xy 186.823426 -362.616035) (xy 186.796172 -362.616496) (xy 186.767257 -362.615928)
			(xy 186.710088 -362.607209) (xy 186.65489 -362.589961) (xy 186.602928 -362.564579) (xy 186.555393 -362.531644)
			(xy 186.513374 -362.491912) (xy 186.495182 -362.46943) (xy 186.487636 -362.460653) (xy 186.466865 -362.450481)
			(xy 186.455304 -362.449872) (xy 186.37504 -362.449872) (xy 186.363471 -362.450441) (xy 186.342699 -362.460634)
			(xy 186.335162 -362.46943) (xy 186.317 -362.491938) (xy 186.274973 -362.53167) (xy 186.227432 -362.564605)
			(xy 186.175465 -362.589989) (xy 186.120263 -362.607241) (xy 186.06309 -362.615964) (xy 186.034172 -362.616496)
			(xy 186.00692 -362.616048) (xy 185.95297 -362.608288) (xy 185.900674 -362.592928) (xy 185.851095 -362.570283)
			(xy 185.805245 -362.540813) (xy 185.764054 -362.505117) (xy 185.728363 -362.463923) (xy 185.698898 -362.418069)
			(xy 185.676258 -362.368489) (xy 185.660904 -362.316191) (xy 185.653149 -362.262241) (xy 185.652664 -362.234988)
			(xy 185.653221 -362.206072) (xy 185.661939 -362.148902) (xy 185.679187 -362.093703) (xy 185.704572 -362.04174)
			(xy 185.73751 -361.994206) (xy 185.777246 -361.952188) (xy 185.79973 -361.933998) (xy 185.808493 -361.926438)
			(xy 185.818675 -361.905678) (xy 185.819288 -361.89412) (xy 185.819288 -361.813856) (xy 185.818689 -361.802292)
			(xy 185.808515 -361.78152) (xy 185.79973 -361.773978) (xy 185.778937 -361.757238) (xy 185.741809 -361.718882)
			(xy 185.71039 -361.675725) (xy 185.685293 -361.62861) (xy 185.667009 -361.578457) (xy 185.655894 -361.526245)
			(xy 185.652165 -361.472993) (xy 180.568874 -361.472993) (xy 180.543318 -361.512507) (xy 180.525674 -361.53344)
			(xy 180.519578 -361.540552) (xy 180.513228 -361.55757) (xy 180.513228 -361.642914) (xy 180.519578 -361.659932)
			(xy 180.525674 -361.667044) (xy 180.543356 -361.687943) (xy 180.573079 -361.733917) (xy 180.595922 -361.783669)
			(xy 180.611415 -361.836176) (xy 180.619239 -361.890359) (xy 180.619235 -361.945104) (xy 180.611401 -361.999286)
			(xy 180.595899 -362.051791) (xy 180.573048 -362.101539) (xy 180.543318 -362.147507) (xy 180.525674 -362.16844)
			(xy 180.519578 -362.175552) (xy 180.513228 -362.19257) (xy 180.513228 -362.277914) (xy 180.519578 -362.294932)
			(xy 180.525674 -362.302044) (xy 180.543296 -362.32299) (xy 180.573012 -362.368958) (xy 180.595851 -362.418702)
			(xy 180.611346 -362.4712) (xy 180.619178 -362.525374) (xy 180.619654 -362.552742) (xy 180.619164 -362.580316)
			(xy 180.611219 -362.634888) (xy 180.5955 -362.687748) (xy 180.572334 -362.737795) (xy 180.542205 -362.783985)
			(xy 180.50574 -362.825356) (xy 180.485034 -362.843572) (xy 180.476922 -362.85118) (xy 180.467567 -362.871328)
			(xy 180.467 -362.882434) (xy 180.467 -362.95965) (xy 180.46758 -362.970758) (xy 180.47691 -362.990917)
			(xy 180.485034 -362.998512) (xy 180.488844 -363.001814) (xy 180.495956 -363.00791) (xy 180.512974 -363.01426)
			(xy 180.598318 -363.01426) (xy 180.615336 -363.00791) (xy 180.622448 -363.001814) (xy 180.643381 -362.984173)
			(xy 180.689349 -362.954449) (xy 180.739095 -362.931603) (xy 180.791597 -362.916107) (xy 180.845775 -362.908278)
			(xy 180.900517 -362.908278) (xy 180.954695 -362.916107) (xy 181.007197 -362.931603) (xy 181.056943 -362.954449)
			(xy 181.102911 -362.984173) (xy 181.123844 -363.001814) (xy 181.130956 -363.00791) (xy 181.147974 -363.01426)
			(xy 181.233318 -363.01426) (xy 181.250336 -363.00791) (xy 181.257448 -363.001814) (xy 181.278381 -362.984173)
			(xy 181.324349 -362.954449) (xy 181.374095 -362.931603) (xy 181.426597 -362.916107) (xy 181.480775 -362.908278)
			(xy 181.535517 -362.908278) (xy 181.589695 -362.916107) (xy 181.642197 -362.931603) (xy 181.691943 -362.954449)
			(xy 181.737911 -362.984173) (xy 181.758844 -363.001814) (xy 181.765956 -363.00791) (xy 181.782974 -363.01426)
			(xy 181.868318 -363.01426) (xy 181.885336 -363.00791) (xy 181.892448 -363.001814) (xy 181.913391 -362.984188)
			(xy 181.95936 -362.954474) (xy 182.009105 -362.931635) (xy 182.061604 -362.916141) (xy 182.115778 -362.90831)
			(xy 182.143146 -362.907834) (xy 182.1704 -362.908235) (xy 182.224353 -362.915999) (xy 182.276652 -362.931362)
			(xy 182.326232 -362.954012) (xy 182.372085 -362.983487) (xy 182.413275 -363.019187) (xy 182.448966 -363.060386)
			(xy 182.478431 -363.106245) (xy 182.501069 -363.15583) (xy 182.51642 -363.208133) (xy 182.524171 -363.262088)
			(xy 182.524654 -363.289342) (xy 182.524165 -363.316712) (xy 182.516355 -363.37089) (xy 182.500871 -363.423393)
			(xy 182.478034 -363.473141) (xy 182.448314 -363.519108) (xy 182.430674 -363.54004) (xy 182.424578 -363.547152)
			(xy 182.418228 -363.56417) (xy 182.418228 -363.649514) (xy 182.424578 -363.666532) (xy 182.430674 -363.673644)
			(xy 182.448296 -363.69459) (xy 182.478012 -363.740558) (xy 182.500851 -363.790302) (xy 182.516346 -363.8428)
			(xy 182.524178 -363.896974) (xy 182.524654 -363.924342) (xy 182.524161 -363.951592) (xy 182.5164 -364.005537)
			(xy 182.501042 -364.057829) (xy 182.4784 -364.107403) (xy 182.448933 -364.153251) (xy 182.413243 -364.19444)
			(xy 182.372055 -364.230131) (xy 182.326207 -364.259598) (xy 182.276633 -364.282241) (xy 182.224341 -364.2976)
			(xy 182.170396 -364.305361) (xy 182.143146 -364.30585) (xy 182.115776 -364.305369) (xy 182.061597 -364.297557)
			(xy 182.009094 -364.282072) (xy 181.959347 -364.259233) (xy 181.91338 -364.229511) (xy 181.892448 -364.21187)
			(xy 181.885336 -364.205774) (xy 181.868318 -364.199424) (xy 181.782974 -364.199424) (xy 181.765956 -364.205774)
			(xy 181.758844 -364.21187) (xy 181.737911 -364.229511) (xy 181.691943 -364.259235) (xy 181.642197 -364.282081)
			(xy 181.589695 -364.297577) (xy 181.535517 -364.305406) (xy 181.480775 -364.305406) (xy 181.426597 -364.297577)
			(xy 181.374095 -364.282081) (xy 181.324349 -364.259235) (xy 181.278381 -364.229511) (xy 181.257448 -364.21187)
			(xy 181.250336 -364.205774) (xy 181.233318 -364.199424) (xy 181.147974 -364.199424) (xy 181.130956 -364.205774)
			(xy 181.123844 -364.21187) (xy 181.102911 -364.229511) (xy 181.056943 -364.259235) (xy 181.007197 -364.282081)
			(xy 180.954695 -364.297577) (xy 180.900517 -364.305406) (xy 180.845775 -364.305406) (xy 180.791597 -364.297577)
			(xy 180.739095 -364.282081) (xy 180.689349 -364.259235) (xy 180.643381 -364.229511) (xy 180.622448 -364.21187)
			(xy 180.615336 -364.205774) (xy 180.598318 -364.199424) (xy 180.512974 -364.199424) (xy 180.495956 -364.205774)
			(xy 180.488844 -364.21187) (xy 180.467902 -364.229497) (xy 180.421933 -364.259212) (xy 180.372188 -364.282051)
			(xy 180.319689 -364.297544) (xy 180.265515 -364.305375) (xy 180.238146 -364.30585) (xy 180.210896 -364.305302)
			(xy 180.15695 -364.297552) (xy 180.104657 -364.282204) (xy 180.05508 -364.25957) (xy 180.009228 -364.230111)
			(xy 179.968036 -364.194426) (xy 179.932342 -364.153242) (xy 179.902872 -364.107398) (xy 179.880226 -364.057826)
			(xy 179.864866 -364.005536) (xy 179.857104 -363.951592) (xy 179.856638 -363.924342) (xy 178.97856 -363.924342)
			(xy 180.55717 -365.502952) (xy 180.56457 -365.509793) (xy 180.583169 -365.517509) (xy 180.593238 -365.517938)
			(xy 182.652924 -365.517938) (xy 182.662991 -365.518366) (xy 182.681586 -365.526091) (xy 182.688992 -365.532924)
			(xy 183.518302 -366.362234) (xy 183.525697 -366.369087) (xy 183.544296 -366.376832) (xy 183.55437 -366.37722)
		)
		(stroke
			(width 0)
			(type solid)
		)
		(fill yes)
		(layer "In6.Cu")
		(net "GND")
	)
	(gr_poly
		(pts
			(xy 426.109892 -370.06784) (xy 426.119841 -370.067297) (xy 426.138209 -370.059627) (xy 426.152313 -370.045579)
			(xy 426.156628 -370.036598) (xy 426.160176 -370.027152) (xy 426.160285 -370.00699) (xy 426.152578 -369.988359)
			(xy 426.145706 -369.980972) (xy 425.253404 -369.08867) (xy 425.230242 -369.064769) (xy 425.189728 -369.011962)
			(xy 425.156456 -368.954318) (xy 425.130995 -368.892822) (xy 425.113781 -368.828529) (xy 425.105109 -368.762539)
			(xy 425.10456 -368.72926) (xy 425.10456 -363.954314) (xy 425.105061 -363.922369) (xy 425.113069 -363.858983)
			(xy 425.128958 -363.7971) (xy 425.152477 -363.737696) (xy 425.183257 -363.681709) (xy 425.22081 -363.63002)
			(xy 425.264546 -363.583446) (xy 425.313774 -363.542721) (xy 425.367719 -363.508487) (xy 425.425528 -363.481284)
			(xy 425.486291 -363.461541) (xy 425.54905 -363.449569) (xy 425.612814 -363.445558) (xy 425.676578 -363.449569)
			(xy 425.739337 -363.461541) (xy 425.8001 -363.481284) (xy 425.857909 -363.508487) (xy 425.911854 -363.542721)
			(xy 425.961082 -363.583446) (xy 426.004818 -363.63002) (xy 426.042371 -363.681709) (xy 426.073151 -363.737696)
			(xy 426.09667 -363.7971) (xy 426.112559 -363.858983) (xy 426.120567 -363.922369) (xy 426.121068 -363.954314)
			(xy 426.121068 -364.370296) (xy 431.124356 -364.370296) (xy 431.124356 -364.2856) (xy 431.132407 -364.201286)
			(xy 431.148436 -364.11812) (xy 431.172297 -364.036853) (xy 431.203776 -363.958223) (xy 431.242587 -363.882942)
			(xy 431.288377 -363.81169) (xy 431.340733 -363.745114) (xy 431.399181 -363.683816) (xy 431.463191 -363.628351)
			(xy 431.532183 -363.579222) (xy 431.605533 -363.536873) (xy 431.682576 -363.501689) (xy 431.762615 -363.473987)
			(xy 431.844924 -363.454019) (xy 431.928759 -363.441966) (xy 432.01336 -363.437936) (xy 432.097961 -363.441966)
			(xy 432.181796 -363.454019) (xy 432.264105 -363.473987) (xy 432.344144 -363.501689) (xy 432.421187 -363.536873)
			(xy 432.494537 -363.579222) (xy 432.563529 -363.628351) (xy 432.627539 -363.683816) (xy 432.685987 -363.745114)
			(xy 432.738343 -363.81169) (xy 432.784133 -363.882942) (xy 432.822944 -363.958223) (xy 432.854423 -364.036853)
			(xy 432.878284 -364.11812) (xy 432.894313 -364.201286) (xy 432.902364 -364.2856) (xy 432.902868 -364.327948)
			(xy 432.902364 -364.370296) (xy 432.894313 -364.45461) (xy 432.878284 -364.537776) (xy 432.854423 -364.619043)
			(xy 432.822944 -364.697673) (xy 432.784133 -364.772954) (xy 432.738343 -364.844206) (xy 432.685987 -364.910782)
			(xy 432.627539 -364.97208) (xy 432.563529 -365.027545) (xy 432.494537 -365.076674) (xy 432.421187 -365.119023)
			(xy 432.344144 -365.154207) (xy 432.264105 -365.181909) (xy 432.181796 -365.201877) (xy 432.097961 -365.21393)
			(xy 432.01336 -365.217961) (xy 431.928759 -365.21393) (xy 431.844924 -365.201877) (xy 431.762615 -365.181909)
			(xy 431.682576 -365.154207) (xy 431.605533 -365.119023) (xy 431.532183 -365.076674) (xy 431.463191 -365.027545)
			(xy 431.399181 -364.97208) (xy 431.340733 -364.910782) (xy 431.288377 -364.844206) (xy 431.242587 -364.772954)
			(xy 431.203776 -364.697673) (xy 431.172297 -364.619043) (xy 431.148436 -364.537776) (xy 431.132407 -364.45461)
			(xy 431.124356 -364.370296) (xy 426.121068 -364.370296) (xy 426.121068 -366.54105) (xy 427.288196 -366.54105)
			(xy 427.292267 -366.485428) (xy 427.304393 -366.430991) (xy 427.324316 -366.3789) (xy 427.351612 -366.330265)
			(xy 427.385698 -366.286122) (xy 427.425847 -366.247413) (xy 427.471205 -366.214962) (xy 427.520805 -366.189461)
			(xy 427.573589 -366.171454) (xy 427.628432 -366.161324) (xy 427.684166 -366.159287) (xy 427.739603 -366.165387)
			(xy 427.79356 -366.179493) (xy 427.844889 -366.201305) (xy 427.892495 -366.230359) (xy 427.935363 -366.266034)
			(xy 427.97258 -366.307571) (xy 428.003353 -366.354084) (xy 428.027025 -366.404581) (xy 428.043093 -366.457988)
			(xy 428.051213 -366.513164) (xy 428.051722 -366.54105) (xy 428.051213 -366.568936) (xy 428.043093 -366.624112)
			(xy 428.027025 -366.677519) (xy 428.003353 -366.728016) (xy 427.97258 -366.774529) (xy 427.935363 -366.816066)
			(xy 427.892495 -366.851741) (xy 427.844889 -366.880795) (xy 427.79356 -366.902607) (xy 427.739603 -366.916713)
			(xy 427.684166 -366.922813) (xy 427.628432 -366.920776) (xy 427.573589 -366.910646) (xy 427.520805 -366.892639)
			(xy 427.471205 -366.867138) (xy 427.425847 -366.834687) (xy 427.385698 -366.795978) (xy 427.351612 -366.751835)
			(xy 427.324316 -366.7032) (xy 427.304393 -366.651109) (xy 427.292267 -366.596672) (xy 427.288196 -366.54105)
			(xy 426.121068 -366.54105) (xy 426.121068 -368.249454) (xy 431.997356 -368.249454) (xy 432.001427 -368.193832)
			(xy 432.013553 -368.139395) (xy 432.033476 -368.087304) (xy 432.060772 -368.038669) (xy 432.094858 -367.994526)
			(xy 432.135007 -367.955817) (xy 432.180365 -367.923366) (xy 432.229965 -367.897865) (xy 432.282749 -367.879858)
			(xy 432.337592 -367.869728) (xy 432.393326 -367.867691) (xy 432.448763 -367.873791) (xy 432.50272 -367.887897)
			(xy 432.554049 -367.909709) (xy 432.601655 -367.938763) (xy 432.644523 -367.974438) (xy 432.68174 -368.015975)
			(xy 432.712513 -368.062488) (xy 432.736185 -368.112985) (xy 432.752253 -368.166392) (xy 432.760373 -368.221568)
			(xy 432.760882 -368.249454) (xy 432.760373 -368.27734) (xy 432.752253 -368.332516) (xy 432.736185 -368.385923)
			(xy 432.712513 -368.43642) (xy 432.68174 -368.482933) (xy 432.644523 -368.52447) (xy 432.601655 -368.560145)
			(xy 432.554049 -368.589199) (xy 432.50272 -368.611011) (xy 432.448763 -368.625117) (xy 432.393326 -368.631217)
			(xy 432.337592 -368.62918) (xy 432.282749 -368.61905) (xy 432.229965 -368.601043) (xy 432.180365 -368.575542)
			(xy 432.135007 -368.543091) (xy 432.094858 -368.504382) (xy 432.060772 -368.460239) (xy 432.033476 -368.411604)
			(xy 432.013553 -368.359513) (xy 432.001427 -368.305076) (xy 431.997356 -368.249454) (xy 426.121068 -368.249454)
			(xy 426.121068 -368.497612) (xy 426.121492 -368.507682) (xy 426.129206 -368.526286) (xy 426.136054 -368.53368)
			(xy 427.655482 -370.052854) (xy 427.662883 -370.059693) (xy 427.681482 -370.067405) (xy 427.69155 -370.06784)
			(xy 427.855126 -370.06784) (xy 427.865171 -370.067412) (xy 427.883722 -370.059703) (xy 427.897903 -370.045472)
			(xy 427.902116 -370.036344) (xy 427.908212 -370.02212) (xy 427.902116 -369.992148) (xy 426.935392 -369.025424)
			(xy 426.928788 -369.022122) (xy 426.903299 -369.00768) (xy 426.856687 -368.972198) (xy 426.816041 -368.930011)
			(xy 426.782318 -368.88211) (xy 426.756307 -368.82962) (xy 426.738621 -368.773773) (xy 426.729674 -368.715879)
			(xy 426.729144 -368.686588) (xy 426.729631 -368.659336) (xy 426.737388 -368.605387) (xy 426.752744 -368.553091)
			(xy 426.775385 -368.503512) (xy 426.804851 -368.45766) (xy 426.840542 -368.416467) (xy 426.881731 -368.380772)
			(xy 426.927581 -368.351302) (xy 426.977157 -368.328656) (xy 427.029452 -368.313296) (xy 427.0834 -368.305533)
			(xy 427.110652 -368.30508) (xy 427.139941 -368.305617) (xy 427.19783 -368.314571) (xy 427.253673 -368.332262)
			(xy 427.306158 -368.358275) (xy 427.354055 -368.391998) (xy 427.39624 -368.432641) (xy 427.431722 -368.47925)
			(xy 427.446186 -368.504724) (xy 427.449488 -368.511328) (xy 428.991014 -370.052854) (xy 428.998411 -370.059703)
			(xy 429.01701 -370.06744) (xy 429.027082 -370.06784) (xy 432.07305 -370.06784) (xy 432.083092 -370.067408)
			(xy 432.101636 -370.059694) (xy 432.11581 -370.045463) (xy 432.12004 -370.036344) (xy 432.126136 -370.02212)
			(xy 432.12004 -369.992148) (xy 431.186336 -369.058698) (xy 431.178934 -369.051862) (xy 431.160336 -369.044151)
			(xy 431.150268 -369.043712) (xy 429.137572 -369.043712) (xy 429.13046 -369.045744) (xy 429.104014 -369.05309)
			(xy 429.049699 -369.060998) (xy 429.022256 -369.061492) (xy 429.021748 -369.061492) (xy 428.994494 -369.061032)
			(xy 428.94054 -369.053281) (xy 428.888239 -369.03793) (xy 428.838655 -369.015291) (xy 428.792797 -368.985825)
			(xy 428.751601 -368.950133) (xy 428.715903 -368.908941) (xy 428.686432 -368.863087) (xy 428.663787 -368.813506)
			(xy 428.648429 -368.761207) (xy 428.640671 -368.707254) (xy 428.640671 -368.652746) (xy 428.648429 -368.598793)
			(xy 428.663787 -368.546494) (xy 428.686432 -368.496913) (xy 428.715903 -368.451059) (xy 428.751601 -368.409867)
			(xy 428.792797 -368.374175) (xy 428.838655 -368.344709) (xy 428.888239 -368.32207) (xy 428.94054 -368.306719)
			(xy 428.994494 -368.298968) (xy 429.021748 -368.298476) (xy 429.022256 -368.298476) (xy 429.049699 -368.298972)
			(xy 429.104013 -368.30688) (xy 429.13046 -368.314224) (xy 429.137572 -368.316256) (xy 431.321972 -368.316256)
			(xy 431.350549 -368.316801) (xy 431.406997 -368.325771) (xy 431.461345 -368.343464) (xy 431.512255 -368.369443)
			(xy 431.558473 -368.403068) (xy 431.57902 -368.422936) (xy 431.90668 -368.750596) (xy 432.715414 -368.750596)
			(xy 432.719485 -368.694974) (xy 432.731611 -368.640537) (xy 432.751534 -368.588446) (xy 432.77883 -368.539811)
			(xy 432.812916 -368.495668) (xy 432.853065 -368.456959) (xy 432.898423 -368.424508) (xy 432.948023 -368.399007)
			(xy 433.000807 -368.381) (xy 433.05565 -368.37087) (xy 433.111384 -368.368833) (xy 433.166821 -368.374933)
			(xy 433.220778 -368.389039) (xy 433.272107 -368.410851) (xy 433.319713 -368.439905) (xy 433.362581 -368.47558)
			(xy 433.399798 -368.517117) (xy 433.430571 -368.56363) (xy 433.454243 -368.614127) (xy 433.470311 -368.667534)
			(xy 433.478431 -368.72271) (xy 433.47894 -368.750596) (xy 433.478431 -368.778482) (xy 433.470311 -368.833658)
			(xy 433.454243 -368.887065) (xy 433.430571 -368.937562) (xy 433.399798 -368.984075) (xy 433.362581 -369.025612)
			(xy 433.319713 -369.061287) (xy 433.272107 -369.090341) (xy 433.220778 -369.112153) (xy 433.166821 -369.126259)
			(xy 433.111384 -369.132359) (xy 433.05565 -369.130322) (xy 433.000807 -369.120192) (xy 432.948023 -369.102185)
			(xy 432.898423 -369.076684) (xy 432.853065 -369.044233) (xy 432.812916 -369.005524) (xy 432.77883 -368.961381)
			(xy 432.751534 -368.912746) (xy 432.731611 -368.860655) (xy 432.719485 -368.806218) (xy 432.715414 -368.750596)
			(xy 431.90668 -368.750596) (xy 433.15255 -369.996466) (xy 433.159962 -370.00315) (xy 433.178395 -370.010747)
			(xy 433.198333 -370.010747) (xy 433.216766 -370.00315) (xy 433.224178 -369.996466) (xy 437.142636 -366.078008)
			(xy 437.150036 -366.071166) (xy 437.168634 -366.063444) (xy 437.178704 -366.063022) (xy 442.818012 -366.063022)
			(xy 442.828082 -366.062597) (xy 442.846685 -366.054882) (xy 442.85408 -366.048036) (xy 451.168262 -357.733854)
			(xy 451.175105 -357.726455) (xy 451.182829 -357.707856) (xy 451.183248 -357.697786) (xy 451.183248 -329.88631)
			(xy 451.183077 -329.880301) (xy 451.180247 -329.868622) (xy 451.17766 -329.863196) (xy 451.17582 -329.859722)
			(xy 451.171225 -329.853345) (xy 451.168516 -329.850496) (xy 450.620892 -329.302872) (xy 450.618042 -329.300165)
			(xy 450.611665 -329.29557) (xy 450.608192 -329.293728) (xy 450.602766 -329.29114) (xy 450.591087 -329.288307)
			(xy 450.585078 -329.28814) (xy 447.49212 -329.28814) (xy 447.480368 -329.288743) (xy 447.459326 -329.299213)
			(xy 447.451734 -329.308206) (xy 447.402712 -329.372722) (xy 447.396043 -329.382476) (xy 447.391662 -329.405663)
			(xy 447.39433 -329.417172) (xy 447.400955 -329.442438) (xy 447.408087 -329.49418) (xy 447.408554 -329.520296)
			(xy 447.408068 -329.547547) (xy 447.400312 -329.601495) (xy 447.384957 -329.65379) (xy 447.362315 -329.703367)
			(xy 447.332849 -329.749217) (xy 447.297158 -329.790408) (xy 447.255967 -329.826099) (xy 447.210117 -329.855565)
			(xy 447.16054 -329.878207) (xy 447.108245 -329.893562) (xy 447.054297 -329.901318) (xy 446.999795 -329.901318)
			(xy 446.945847 -329.893562) (xy 446.893552 -329.878207) (xy 446.843975 -329.855565) (xy 446.798125 -329.826099)
			(xy 446.756934 -329.790408) (xy 446.721243 -329.749217) (xy 446.691777 -329.703367) (xy 446.669135 -329.65379)
			(xy 446.65378 -329.601495) (xy 446.646024 -329.547547) (xy 446.645538 -329.520296) (xy 446.645963 -329.494177)
			(xy 446.653097 -329.442429) (xy 446.659762 -329.417172) (xy 446.662369 -329.405659) (xy 446.658011 -329.382487)
			(xy 446.65138 -329.372722) (xy 446.602358 -329.308206) (xy 446.594768 -329.299214) (xy 446.573723 -329.288745)
			(xy 446.561972 -329.28814) (xy 413.937196 -329.28814) (xy 413.92721 -329.288679) (xy 413.908783 -329.296398)
			(xy 413.901382 -329.303126) (xy 410.187394 -333.017114) (xy 412.707074 -333.017114) (xy 412.707574 -332.988196)
			(xy 412.716303 -332.931023) (xy 412.733563 -332.875822) (xy 412.758958 -332.82386) (xy 412.791906 -332.776327)
			(xy 412.831652 -332.734312) (xy 412.85414 -332.716124) (xy 412.862933 -332.708503) (xy 412.873123 -332.687613)
			(xy 412.873698 -332.675992) (xy 412.873698 -332.596236) (xy 412.873182 -332.584601) (xy 412.862977 -332.563692)
			(xy 412.85414 -332.556104) (xy 412.831667 -332.537901) (xy 412.791929 -332.495885) (xy 412.758988 -332.448353)
			(xy 412.733597 -332.396394) (xy 412.716339 -332.341198) (xy 412.707609 -332.284029) (xy 412.707074 -332.255114)
			(xy 412.707591 -332.227864) (xy 412.715345 -332.173918) (xy 412.730698 -332.121625) (xy 412.753336 -332.072049)
			(xy 412.782799 -332.0262) (xy 412.818487 -331.98501) (xy 412.859674 -331.949318) (xy 412.905521 -331.919851)
			(xy 412.955095 -331.897209) (xy 413.007387 -331.881852) (xy 413.061332 -331.874094) (xy 413.088582 -331.873606)
			(xy 413.117288 -331.874143) (xy 413.174055 -331.882716) (xy 413.228895 -331.899701) (xy 413.28057 -331.924715)
			(xy 413.327912 -331.957193) (xy 413.369851 -331.996399) (xy 413.405439 -332.041449) (xy 413.433871 -332.091325)
			(xy 413.454507 -332.144899) (xy 413.4612 -332.172818) (xy 413.46501 -332.190344) (xy 413.492696 -332.212696)
			(xy 414.50641 -332.212696) (xy 414.531394 -332.213307) (xy 414.580402 -332.223048) (xy 414.626572 -332.242156)
			(xy 414.668132 -332.269896) (xy 414.686242 -332.287118) (xy 415.205926 -332.806802) (xy 415.223159 -332.824902)
			(xy 415.2509 -332.866464) (xy 415.270004 -332.912637) (xy 415.27974 -332.961649) (xy 415.280348 -332.986634)
			(xy 415.280348 -335.314799) (xy 418.990283 -335.314799) (xy 418.994013 -335.261548) (xy 419.005129 -335.209336)
			(xy 419.023415 -335.159184) (xy 419.048513 -335.11207) (xy 419.079934 -335.068915) (xy 419.117063 -335.030562)
			(xy 419.137846 -335.013808) (xy 419.146647 -335.006195) (xy 419.156832 -334.985299) (xy 419.157404 -334.973676)
			(xy 419.157404 -334.89392) (xy 419.156837 -334.882292) (xy 419.146668 -334.861382) (xy 419.137846 -334.853788)
			(xy 419.117062 -334.837037) (xy 419.079932 -334.798683) (xy 419.048512 -334.755527) (xy 419.023414 -334.708414)
			(xy 419.005128 -334.658262) (xy 418.994012 -334.60605) (xy 418.990283 -334.552799) (xy 418.994013 -334.499548)
			(xy 419.005129 -334.447336) (xy 419.023415 -334.397184) (xy 419.048513 -334.35007) (xy 419.079934 -334.306915)
			(xy 419.117063 -334.268562) (xy 419.137846 -334.251808) (xy 419.146647 -334.244195) (xy 419.156832 -334.223299)
			(xy 419.157404 -334.211676) (xy 419.157404 -334.13192) (xy 419.156837 -334.120292) (xy 419.146668 -334.099382)
			(xy 419.137846 -334.091788) (xy 419.115346 -334.073617) (xy 419.075614 -334.031592) (xy 419.042678 -333.984052)
			(xy 419.017293 -333.932087) (xy 419.00004 -333.876887) (xy 418.991314 -333.819715) (xy 418.99078 -333.790798)
			(xy 418.991266 -333.763547) (xy 418.999022 -333.709599) (xy 419.014377 -333.657304) (xy 419.037019 -333.607727)
			(xy 419.066485 -333.561877) (xy 419.102176 -333.520686) (xy 419.143367 -333.484995) (xy 419.189217 -333.455529)
			(xy 419.238794 -333.432887) (xy 419.291089 -333.417532) (xy 419.345037 -333.409776) (xy 419.399539 -333.409776)
			(xy 419.453487 -333.417532) (xy 419.505782 -333.432887) (xy 419.555359 -333.455529) (xy 419.601209 -333.484995)
			(xy 419.6424 -333.520686) (xy 419.678091 -333.561877) (xy 419.707557 -333.607727) (xy 419.730199 -333.657304)
			(xy 419.745554 -333.709599) (xy 419.75331 -333.763547) (xy 419.753796 -333.790798) (xy 419.753278 -333.819715)
			(xy 419.744549 -333.876886) (xy 419.727291 -333.932085) (xy 419.701899 -333.984047) (xy 419.668956 -334.031581)
			(xy 419.629215 -334.073598) (xy 419.60673 -334.091788) (xy 419.597927 -334.099398) (xy 419.587744 -334.120297)
			(xy 419.587172 -334.13192) (xy 419.587172 -334.211676) (xy 419.587714 -334.223308) (xy 419.597898 -334.24422)
			(xy 419.60673 -334.251808) (xy 419.627512 -334.268563) (xy 419.664643 -334.306916) (xy 419.696065 -334.35007)
			(xy 419.721165 -334.397183) (xy 419.739452 -334.447335) (xy 419.750569 -334.499547) (xy 419.754299 -334.552799)
			(xy 419.750569 -334.60605) (xy 419.739453 -334.658262) (xy 419.721166 -334.708414) (xy 419.696067 -334.755528)
			(xy 419.664645 -334.798682) (xy 419.627513 -334.837035) (xy 419.60673 -334.853788) (xy 419.597927 -334.861398)
			(xy 419.587744 -334.882297) (xy 419.587172 -334.89392) (xy 419.587172 -334.973676) (xy 419.587714 -334.985308)
			(xy 419.597898 -335.00622) (xy 419.60673 -335.013808) (xy 419.627512 -335.030563) (xy 419.664643 -335.068916)
			(xy 419.696065 -335.11207) (xy 419.721165 -335.159183) (xy 419.739452 -335.209335) (xy 419.745683 -335.238599)
			(xy 421.403283 -335.238599) (xy 421.407013 -335.185348) (xy 421.418129 -335.133136) (xy 421.436415 -335.082984)
			(xy 421.461513 -335.03587) (xy 421.492934 -334.992715) (xy 421.530063 -334.954362) (xy 421.550846 -334.937608)
			(xy 421.559647 -334.929995) (xy 421.569832 -334.909099) (xy 421.570404 -334.897476) (xy 421.570404 -334.81772)
			(xy 421.569837 -334.806092) (xy 421.559668 -334.785182) (xy 421.550846 -334.777588) (xy 421.530062 -334.760837)
			(xy 421.492932 -334.722483) (xy 421.461512 -334.679327) (xy 421.436414 -334.632214) (xy 421.418128 -334.582062)
			(xy 421.407012 -334.52985) (xy 421.403283 -334.476599) (xy 421.407013 -334.423348) (xy 421.418129 -334.371136)
			(xy 421.436415 -334.320984) (xy 421.461513 -334.27387) (xy 421.492934 -334.230715) (xy 421.530063 -334.192362)
			(xy 421.550846 -334.175608) (xy 421.559647 -334.167995) (xy 421.569832 -334.147099) (xy 421.570404 -334.135476)
			(xy 421.570404 -334.05572) (xy 421.569837 -334.044092) (xy 421.559668 -334.023182) (xy 421.550846 -334.015588)
			(xy 421.528346 -333.997417) (xy 421.488614 -333.955392) (xy 421.455678 -333.907852) (xy 421.430293 -333.855887)
			(xy 421.41304 -333.800687) (xy 421.404314 -333.743515) (xy 421.40378 -333.714598) (xy 421.404266 -333.687347)
			(xy 421.412022 -333.633399) (xy 421.427377 -333.581104) (xy 421.450019 -333.531527) (xy 421.479485 -333.485677)
			(xy 421.515176 -333.444486) (xy 421.556367 -333.408795) (xy 421.602217 -333.379329) (xy 421.651794 -333.356687)
			(xy 421.704089 -333.341332) (xy 421.758037 -333.333576) (xy 421.812539 -333.333576) (xy 421.866487 -333.341332)
			(xy 421.918782 -333.356687) (xy 421.968359 -333.379329) (xy 422.014209 -333.408795) (xy 422.0554 -333.444486)
			(xy 422.091091 -333.485677) (xy 422.120557 -333.531527) (xy 422.143199 -333.581104) (xy 422.158554 -333.633399)
			(xy 422.16631 -333.687347) (xy 422.166796 -333.714598) (xy 422.166278 -333.743515) (xy 422.157549 -333.800686)
			(xy 422.140291 -333.855885) (xy 422.114899 -333.907847) (xy 422.081956 -333.955381) (xy 422.042215 -333.997398)
			(xy 422.01973 -334.015588) (xy 422.010927 -334.023198) (xy 422.000744 -334.044097) (xy 422.000172 -334.05572)
			(xy 422.000172 -334.135476) (xy 422.000714 -334.147108) (xy 422.010898 -334.16802) (xy 422.01973 -334.175608)
			(xy 422.040512 -334.192363) (xy 422.077643 -334.230716) (xy 422.109065 -334.27387) (xy 422.134165 -334.320983)
			(xy 422.152452 -334.371135) (xy 422.163569 -334.423347) (xy 422.167299 -334.476599) (xy 422.163569 -334.52985)
			(xy 422.152453 -334.582062) (xy 422.134166 -334.632214) (xy 422.109067 -334.679328) (xy 422.077645 -334.722482)
			(xy 422.040513 -334.760835) (xy 422.01973 -334.777588) (xy 422.010927 -334.785198) (xy 422.000744 -334.806097)
			(xy 422.000172 -334.81772) (xy 422.000172 -334.897476) (xy 422.000714 -334.909108) (xy 422.010898 -334.93002)
			(xy 422.01973 -334.937608) (xy 422.040512 -334.954363) (xy 422.077643 -334.992716) (xy 422.109065 -335.03587)
			(xy 422.134165 -335.082983) (xy 422.152452 -335.133135) (xy 422.163569 -335.185347) (xy 422.167299 -335.238599)
			(xy 425.060883 -335.238599) (xy 425.064613 -335.185348) (xy 425.075729 -335.133136) (xy 425.094015 -335.082984)
			(xy 425.119113 -335.03587) (xy 425.150534 -334.992715) (xy 425.187663 -334.954362) (xy 425.208446 -334.937608)
			(xy 425.217247 -334.929995) (xy 425.227432 -334.909099) (xy 425.228004 -334.897476) (xy 425.228004 -334.81772)
			(xy 425.227437 -334.806092) (xy 425.217268 -334.785182) (xy 425.208446 -334.777588) (xy 425.187662 -334.760837)
			(xy 425.150532 -334.722483) (xy 425.119112 -334.679327) (xy 425.094014 -334.632214) (xy 425.075728 -334.582062)
			(xy 425.064612 -334.52985) (xy 425.060883 -334.476599) (xy 425.064613 -334.423348) (xy 425.075729 -334.371136)
			(xy 425.094015 -334.320984) (xy 425.119113 -334.27387) (xy 425.150534 -334.230715) (xy 425.187663 -334.192362)
			(xy 425.208446 -334.175608) (xy 425.217247 -334.167995) (xy 425.227432 -334.147099) (xy 425.228004 -334.135476)
			(xy 425.228004 -334.05572) (xy 425.227437 -334.044092) (xy 425.217268 -334.023182) (xy 425.208446 -334.015588)
			(xy 425.185946 -333.997417) (xy 425.146214 -333.955392) (xy 425.113278 -333.907852) (xy 425.087893 -333.855887)
			(xy 425.07064 -333.800687) (xy 425.061914 -333.743515) (xy 425.06138 -333.714598) (xy 425.061866 -333.687347)
			(xy 425.069622 -333.633399) (xy 425.084977 -333.581104) (xy 425.107619 -333.531527) (xy 425.137085 -333.485677)
			(xy 425.172776 -333.444486) (xy 425.213967 -333.408795) (xy 425.259817 -333.379329) (xy 425.309394 -333.356687)
			(xy 425.361689 -333.341332) (xy 425.415637 -333.333576) (xy 425.470139 -333.333576) (xy 425.524087 -333.341332)
			(xy 425.576382 -333.356687) (xy 425.625959 -333.379329) (xy 425.671809 -333.408795) (xy 425.713 -333.444486)
			(xy 425.748691 -333.485677) (xy 425.778157 -333.531527) (xy 425.800799 -333.581104) (xy 425.816154 -333.633399)
			(xy 425.82391 -333.687347) (xy 425.824396 -333.714598) (xy 425.823878 -333.743515) (xy 425.815149 -333.800686)
			(xy 425.797891 -333.855885) (xy 425.772499 -333.907847) (xy 425.739556 -333.955381) (xy 425.699815 -333.997398)
			(xy 425.67733 -334.015588) (xy 425.668527 -334.023198) (xy 425.658344 -334.044097) (xy 425.657772 -334.05572)
			(xy 425.657772 -334.135476) (xy 425.658314 -334.147108) (xy 425.668498 -334.16802) (xy 425.67733 -334.175608)
			(xy 425.698112 -334.192363) (xy 425.735243 -334.230716) (xy 425.766665 -334.27387) (xy 425.791765 -334.320983)
			(xy 425.810052 -334.371135) (xy 425.821169 -334.423347) (xy 425.824899 -334.476599) (xy 425.821169 -334.52985)
			(xy 425.810053 -334.582062) (xy 425.791766 -334.632214) (xy 425.766667 -334.679328) (xy 425.735245 -334.722482)
			(xy 425.698113 -334.760835) (xy 425.67733 -334.777588) (xy 425.668527 -334.785198) (xy 425.658344 -334.806097)
			(xy 425.657772 -334.81772) (xy 425.657772 -334.897476) (xy 425.658314 -334.909108) (xy 425.668498 -334.93002)
			(xy 425.67733 -334.937608) (xy 425.698112 -334.954363) (xy 425.735243 -334.992716) (xy 425.766665 -335.03587)
			(xy 425.791765 -335.082983) (xy 425.810052 -335.133135) (xy 425.821169 -335.185347) (xy 425.824899 -335.238599)
			(xy 427.524683 -335.238599) (xy 427.528413 -335.185348) (xy 427.539529 -335.133136) (xy 427.557815 -335.082984)
			(xy 427.582913 -335.03587) (xy 427.614334 -334.992715) (xy 427.651463 -334.954362) (xy 427.672246 -334.937608)
			(xy 427.681047 -334.929995) (xy 427.691232 -334.909099) (xy 427.691804 -334.897476) (xy 427.691804 -334.81772)
			(xy 427.691237 -334.806092) (xy 427.681068 -334.785182) (xy 427.672246 -334.777588) (xy 427.651462 -334.760837)
			(xy 427.614332 -334.722483) (xy 427.582912 -334.679327) (xy 427.557814 -334.632214) (xy 427.539528 -334.582062)
			(xy 427.528412 -334.52985) (xy 427.524683 -334.476599) (xy 427.528413 -334.423348) (xy 427.539529 -334.371136)
			(xy 427.557815 -334.320984) (xy 427.582913 -334.27387) (xy 427.614334 -334.230715) (xy 427.651463 -334.192362)
			(xy 427.672246 -334.175608) (xy 427.681047 -334.167995) (xy 427.691232 -334.147099) (xy 427.691804 -334.135476)
			(xy 427.691804 -334.05572) (xy 427.691237 -334.044092) (xy 427.681068 -334.023182) (xy 427.672246 -334.015588)
			(xy 427.649746 -333.997417) (xy 427.610014 -333.955392) (xy 427.577078 -333.907852) (xy 427.551693 -333.855887)
			(xy 427.53444 -333.800687) (xy 427.525714 -333.743515) (xy 427.52518 -333.714598) (xy 427.525666 -333.687347)
			(xy 427.533422 -333.633399) (xy 427.548777 -333.581104) (xy 427.571419 -333.531527) (xy 427.600885 -333.485677)
			(xy 427.636576 -333.444486) (xy 427.677767 -333.408795) (xy 427.723617 -333.379329) (xy 427.773194 -333.356687)
			(xy 427.825489 -333.341332) (xy 427.879437 -333.333576) (xy 427.933939 -333.333576) (xy 427.987887 -333.341332)
			(xy 428.040182 -333.356687) (xy 428.089759 -333.379329) (xy 428.135609 -333.408795) (xy 428.1768 -333.444486)
			(xy 428.212491 -333.485677) (xy 428.241957 -333.531527) (xy 428.264599 -333.581104) (xy 428.279954 -333.633399)
			(xy 428.28771 -333.687347) (xy 428.288196 -333.714598) (xy 428.287678 -333.743515) (xy 428.278949 -333.800686)
			(xy 428.261691 -333.855885) (xy 428.236299 -333.907847) (xy 428.203356 -333.955381) (xy 428.163615 -333.997398)
			(xy 428.14113 -334.015588) (xy 428.132327 -334.023198) (xy 428.122144 -334.044097) (xy 428.121572 -334.05572)
			(xy 428.121572 -334.135476) (xy 428.122114 -334.147108) (xy 428.132298 -334.16802) (xy 428.14113 -334.175608)
			(xy 428.161912 -334.192363) (xy 428.199043 -334.230716) (xy 428.230465 -334.27387) (xy 428.255565 -334.320983)
			(xy 428.273852 -334.371135) (xy 428.284969 -334.423347) (xy 428.288699 -334.476599) (xy 428.284969 -334.52985)
			(xy 428.273853 -334.582062) (xy 428.255566 -334.632214) (xy 428.230467 -334.679328) (xy 428.199045 -334.722482)
			(xy 428.161913 -334.760835) (xy 428.14113 -334.777588) (xy 428.132327 -334.785198) (xy 428.122144 -334.806097)
			(xy 428.121572 -334.81772) (xy 428.121572 -334.897476) (xy 428.122114 -334.909108) (xy 428.132298 -334.93002)
			(xy 428.14113 -334.937608) (xy 428.161912 -334.954363) (xy 428.199043 -334.992716) (xy 428.230465 -335.03587)
			(xy 428.255565 -335.082983) (xy 428.273852 -335.133135) (xy 428.284969 -335.185347) (xy 428.28692 -335.213199)
			(xy 431.182283 -335.213199) (xy 431.186013 -335.159948) (xy 431.197129 -335.107736) (xy 431.215415 -335.057584)
			(xy 431.240513 -335.01047) (xy 431.271934 -334.967315) (xy 431.309063 -334.928962) (xy 431.329846 -334.912208)
			(xy 431.338647 -334.904595) (xy 431.348832 -334.883699) (xy 431.349404 -334.872076) (xy 431.349404 -334.79232)
			(xy 431.348837 -334.780692) (xy 431.338668 -334.759782) (xy 431.329846 -334.752188) (xy 431.309062 -334.735437)
			(xy 431.271932 -334.697083) (xy 431.240512 -334.653927) (xy 431.215414 -334.606814) (xy 431.197128 -334.556662)
			(xy 431.186012 -334.50445) (xy 431.182283 -334.451199) (xy 431.186013 -334.397948) (xy 431.197129 -334.345736)
			(xy 431.215415 -334.295584) (xy 431.240513 -334.24847) (xy 431.271934 -334.205315) (xy 431.309063 -334.166962)
			(xy 431.329846 -334.150208) (xy 431.338647 -334.142595) (xy 431.348832 -334.121699) (xy 431.349404 -334.110076)
			(xy 431.349404 -334.03032) (xy 431.348837 -334.018692) (xy 431.338668 -333.997782) (xy 431.329846 -333.990188)
			(xy 431.307346 -333.972017) (xy 431.267614 -333.929992) (xy 431.234678 -333.882452) (xy 431.209293 -333.830487)
			(xy 431.19204 -333.775287) (xy 431.183314 -333.718115) (xy 431.18278 -333.689198) (xy 431.183266 -333.661947)
			(xy 431.191022 -333.607999) (xy 431.206377 -333.555704) (xy 431.229019 -333.506127) (xy 431.258485 -333.460277)
			(xy 431.294176 -333.419086) (xy 431.335367 -333.383395) (xy 431.381217 -333.353929) (xy 431.430794 -333.331287)
			(xy 431.483089 -333.315932) (xy 431.537037 -333.308176) (xy 431.591539 -333.308176) (xy 431.645487 -333.315932)
			(xy 431.697782 -333.331287) (xy 431.747359 -333.353929) (xy 431.793209 -333.383395) (xy 431.8344 -333.419086)
			(xy 431.870091 -333.460277) (xy 431.899557 -333.506127) (xy 431.922199 -333.555704) (xy 431.937554 -333.607999)
			(xy 431.94531 -333.661947) (xy 431.945796 -333.689198) (xy 431.945278 -333.718115) (xy 431.936549 -333.775286)
			(xy 431.919291 -333.830485) (xy 431.893899 -333.882447) (xy 431.860956 -333.929981) (xy 431.821215 -333.971998)
			(xy 431.79873 -333.990188) (xy 431.789927 -333.997798) (xy 431.779744 -334.018697) (xy 431.779172 -334.03032)
			(xy 431.779172 -334.110076) (xy 431.779714 -334.121708) (xy 431.789898 -334.14262) (xy 431.79873 -334.150208)
			(xy 431.819512 -334.166963) (xy 431.856643 -334.205316) (xy 431.888065 -334.24847) (xy 431.913165 -334.295583)
			(xy 431.931452 -334.345735) (xy 431.942569 -334.397947) (xy 431.946299 -334.451199) (xy 431.942569 -334.50445)
			(xy 431.931453 -334.556662) (xy 431.913166 -334.606814) (xy 431.888067 -334.653928) (xy 431.856645 -334.697082)
			(xy 431.819513 -334.735435) (xy 431.79873 -334.752188) (xy 431.789927 -334.759798) (xy 431.779744 -334.780697)
			(xy 431.779172 -334.79232) (xy 431.779172 -334.872076) (xy 431.779714 -334.883708) (xy 431.789898 -334.90462)
			(xy 431.79873 -334.912208) (xy 431.819512 -334.928963) (xy 431.856643 -334.967316) (xy 431.888065 -335.01047)
			(xy 431.913165 -335.057583) (xy 431.931452 -335.107735) (xy 431.942569 -335.159947) (xy 431.946299 -335.213199)
			(xy 433.620683 -335.213199) (xy 433.624413 -335.159948) (xy 433.635529 -335.107736) (xy 433.653815 -335.057584)
			(xy 433.678913 -335.01047) (xy 433.710334 -334.967315) (xy 433.747463 -334.928962) (xy 433.768246 -334.912208)
			(xy 433.777047 -334.904595) (xy 433.787232 -334.883699) (xy 433.787804 -334.872076) (xy 433.787804 -334.79232)
			(xy 433.787237 -334.780692) (xy 433.777068 -334.759782) (xy 433.768246 -334.752188) (xy 433.747462 -334.735437)
			(xy 433.710332 -334.697083) (xy 433.678912 -334.653927) (xy 433.653814 -334.606814) (xy 433.635528 -334.556662)
			(xy 433.624412 -334.50445) (xy 433.620683 -334.451199) (xy 433.624413 -334.397948) (xy 433.635529 -334.345736)
			(xy 433.653815 -334.295584) (xy 433.678913 -334.24847) (xy 433.710334 -334.205315) (xy 433.747463 -334.166962)
			(xy 433.768246 -334.150208) (xy 433.777047 -334.142595) (xy 433.787232 -334.121699) (xy 433.787804 -334.110076)
			(xy 433.787804 -334.03032) (xy 433.787237 -334.018692) (xy 433.777068 -333.997782) (xy 433.768246 -333.990188)
			(xy 433.745746 -333.972017) (xy 433.706014 -333.929992) (xy 433.673078 -333.882452) (xy 433.647693 -333.830487)
			(xy 433.63044 -333.775287) (xy 433.621714 -333.718115) (xy 433.62118 -333.689198) (xy 433.621666 -333.661947)
			(xy 433.629422 -333.607999) (xy 433.644777 -333.555704) (xy 433.667419 -333.506127) (xy 433.696885 -333.460277)
			(xy 433.732576 -333.419086) (xy 433.773767 -333.383395) (xy 433.819617 -333.353929) (xy 433.869194 -333.331287)
			(xy 433.921489 -333.315932) (xy 433.975437 -333.308176) (xy 434.029939 -333.308176) (xy 434.083887 -333.315932)
			(xy 434.136182 -333.331287) (xy 434.185759 -333.353929) (xy 434.231609 -333.383395) (xy 434.2728 -333.419086)
			(xy 434.308491 -333.460277) (xy 434.337957 -333.506127) (xy 434.360599 -333.555704) (xy 434.375954 -333.607999)
			(xy 434.38371 -333.661947) (xy 434.384196 -333.689198) (xy 434.383678 -333.718115) (xy 434.374949 -333.775286)
			(xy 434.357691 -333.830485) (xy 434.332299 -333.882447) (xy 434.299356 -333.929981) (xy 434.259615 -333.971998)
			(xy 434.23713 -333.990188) (xy 434.228327 -333.997798) (xy 434.218144 -334.018697) (xy 434.217572 -334.03032)
			(xy 434.217572 -334.110076) (xy 434.218114 -334.121708) (xy 434.228298 -334.14262) (xy 434.23713 -334.150208)
			(xy 434.257912 -334.166963) (xy 434.295043 -334.205316) (xy 434.326465 -334.24847) (xy 434.351565 -334.295583)
			(xy 434.369852 -334.345735) (xy 434.380969 -334.397947) (xy 434.384699 -334.451199) (xy 434.380969 -334.50445)
			(xy 434.369853 -334.556662) (xy 434.351566 -334.606814) (xy 434.326467 -334.653928) (xy 434.295045 -334.697082)
			(xy 434.257913 -334.735435) (xy 434.23713 -334.752188) (xy 434.228327 -334.759798) (xy 434.218144 -334.780697)
			(xy 434.217572 -334.79232) (xy 434.217572 -334.872076) (xy 434.218114 -334.883708) (xy 434.228298 -334.90462)
			(xy 434.23713 -334.912208) (xy 434.257912 -334.928963) (xy 434.295043 -334.967316) (xy 434.326465 -335.01047)
			(xy 434.351565 -335.057583) (xy 434.361999 -335.086199) (xy 437.176683 -335.086199) (xy 437.180413 -335.032948)
			(xy 437.191529 -334.980736) (xy 437.209815 -334.930584) (xy 437.234913 -334.88347) (xy 437.266334 -334.840315)
			(xy 437.303463 -334.801962) (xy 437.324246 -334.785208) (xy 437.333047 -334.777595) (xy 437.343232 -334.756699)
			(xy 437.343804 -334.745076) (xy 437.343804 -334.66532) (xy 437.343237 -334.653692) (xy 437.333068 -334.632782)
			(xy 437.324246 -334.625188) (xy 437.303462 -334.608437) (xy 437.266332 -334.570083) (xy 437.234912 -334.526927)
			(xy 437.209814 -334.479814) (xy 437.191528 -334.429662) (xy 437.180412 -334.37745) (xy 437.176683 -334.324199)
			(xy 437.180413 -334.270948) (xy 437.191529 -334.218736) (xy 437.209815 -334.168584) (xy 437.234913 -334.12147)
			(xy 437.266334 -334.078315) (xy 437.303463 -334.039962) (xy 437.324246 -334.023208) (xy 437.333047 -334.015595)
			(xy 437.343232 -333.994699) (xy 437.343804 -333.983076) (xy 437.343804 -333.90332) (xy 437.343237 -333.891692)
			(xy 437.333068 -333.870782) (xy 437.324246 -333.863188) (xy 437.301746 -333.845017) (xy 437.262014 -333.802992)
			(xy 437.229078 -333.755452) (xy 437.203693 -333.703487) (xy 437.18644 -333.648287) (xy 437.177714 -333.591115)
			(xy 437.17718 -333.562198) (xy 437.177666 -333.534947) (xy 437.185422 -333.480999) (xy 437.200777 -333.428704)
			(xy 437.223419 -333.379127) (xy 437.252885 -333.333277) (xy 437.288576 -333.292086) (xy 437.329767 -333.256395)
			(xy 437.375617 -333.226929) (xy 437.425194 -333.204287) (xy 437.477489 -333.188932) (xy 437.531437 -333.181176)
			(xy 437.585939 -333.181176) (xy 437.639887 -333.188932) (xy 437.692182 -333.204287) (xy 437.741759 -333.226929)
			(xy 437.787609 -333.256395) (xy 437.8288 -333.292086) (xy 437.864491 -333.333277) (xy 437.893957 -333.379127)
			(xy 437.916599 -333.428704) (xy 437.931954 -333.480999) (xy 437.93971 -333.534947) (xy 437.940196 -333.562198)
			(xy 437.939678 -333.591115) (xy 437.930949 -333.648286) (xy 437.913691 -333.703485) (xy 437.888299 -333.755447)
			(xy 437.855356 -333.802981) (xy 437.815615 -333.844998) (xy 437.79313 -333.863188) (xy 437.784327 -333.870798)
			(xy 437.774144 -333.891697) (xy 437.773572 -333.90332) (xy 437.773572 -333.983076) (xy 437.774114 -333.994708)
			(xy 437.784298 -334.01562) (xy 437.79313 -334.023208) (xy 437.813912 -334.039963) (xy 437.851043 -334.078316)
			(xy 437.882465 -334.12147) (xy 437.907565 -334.168583) (xy 437.925852 -334.218735) (xy 437.936969 -334.270947)
			(xy 437.940699 -334.324199) (xy 437.936969 -334.37745) (xy 437.925853 -334.429662) (xy 437.907566 -334.479814)
			(xy 437.882467 -334.526928) (xy 437.851045 -334.570082) (xy 437.813913 -334.608435) (xy 437.79313 -334.625188)
			(xy 437.784327 -334.632798) (xy 437.774144 -334.653697) (xy 437.773572 -334.66532) (xy 437.773572 -334.745076)
			(xy 437.774114 -334.756708) (xy 437.784298 -334.77762) (xy 437.79313 -334.785208) (xy 437.813912 -334.801963)
			(xy 437.851043 -334.840316) (xy 437.882465 -334.88347) (xy 437.907565 -334.930583) (xy 437.925852 -334.980735)
			(xy 437.93587 -335.027786) (xy 439.724279 -335.027786) (xy 439.728011 -334.974532) (xy 439.739131 -334.922319)
			(xy 439.75742 -334.872165) (xy 439.782522 -334.82505) (xy 439.813947 -334.781895) (xy 439.851081 -334.743541)
			(xy 439.871866 -334.726788) (xy 439.88068 -334.719188) (xy 439.890857 -334.698281) (xy 439.891424 -334.686656)
			(xy 439.891424 -334.6069) (xy 439.890897 -334.595266) (xy 439.880702 -334.574355) (xy 439.871866 -334.566768)
			(xy 439.851061 -334.550041) (xy 439.81393 -334.511685) (xy 439.782508 -334.468527) (xy 439.757409 -334.421411)
			(xy 439.739123 -334.371255) (xy 439.728008 -334.319041) (xy 439.724279 -334.265786) (xy 439.728011 -334.212532)
			(xy 439.739131 -334.160319) (xy 439.75742 -334.110165) (xy 439.782522 -334.06305) (xy 439.813947 -334.019895)
			(xy 439.851081 -333.981541) (xy 439.871866 -333.964788) (xy 439.88068 -333.957188) (xy 439.890857 -333.936281)
			(xy 439.891424 -333.924656) (xy 439.891424 -333.8449) (xy 439.890897 -333.833266) (xy 439.880702 -333.812355)
			(xy 439.871866 -333.804768) (xy 439.84936 -333.786604) (xy 439.809628 -333.744577) (xy 439.776692 -333.697037)
			(xy 439.751308 -333.64507) (xy 439.734057 -333.589868) (xy 439.725332 -333.532695) (xy 439.7248 -333.503778)
			(xy 439.725286 -333.476527) (xy 439.733042 -333.422579) (xy 439.748397 -333.370284) (xy 439.771039 -333.320707)
			(xy 439.800505 -333.274857) (xy 439.836196 -333.233666) (xy 439.877387 -333.197975) (xy 439.923237 -333.168509)
			(xy 439.972814 -333.145867) (xy 440.025109 -333.130512) (xy 440.079057 -333.122756) (xy 440.133559 -333.122756)
			(xy 440.187507 -333.130512) (xy 440.239802 -333.145867) (xy 440.289379 -333.168509) (xy 440.335229 -333.197975)
			(xy 440.37642 -333.233666) (xy 440.412111 -333.274857) (xy 440.441577 -333.320707) (xy 440.464219 -333.370284)
			(xy 440.479574 -333.422579) (xy 440.48733 -333.476527) (xy 440.487816 -333.503778) (xy 440.487314 -333.532696)
			(xy 440.478586 -333.589869) (xy 440.461327 -333.64507) (xy 440.435932 -333.697032) (xy 440.402984 -333.744565)
			(xy 440.363238 -333.78658) (xy 440.34075 -333.804768) (xy 440.331959 -333.81239) (xy 440.321768 -333.83328)
			(xy 440.321192 -333.8449) (xy 440.321192 -333.924656) (xy 440.321716 -333.93629) (xy 440.331916 -333.957199)
			(xy 440.34075 -333.964788) (xy 440.361511 -333.981567) (xy 440.39864 -334.019918) (xy 440.430061 -334.06307)
			(xy 440.45516 -334.11018) (xy 440.473447 -334.160329) (xy 440.484564 -334.212538) (xy 440.488296 -334.265786)
			(xy 440.484568 -334.319035) (xy 440.473454 -334.371245) (xy 440.455171 -334.421395) (xy 440.430075 -334.468507)
			(xy 440.398658 -334.511661) (xy 440.361531 -334.550014) (xy 440.34075 -334.566768) (xy 440.331959 -334.57439)
			(xy 440.321768 -334.59528) (xy 440.321192 -334.6069) (xy 440.321192 -334.686656) (xy 440.321716 -334.69829)
			(xy 440.331916 -334.719199) (xy 440.34075 -334.726788) (xy 440.361511 -334.743567) (xy 440.39864 -334.781918)
			(xy 440.430061 -334.82507) (xy 440.45516 -334.87218) (xy 440.473447 -334.922329) (xy 440.484564 -334.974538)
			(xy 440.488296 -335.027786) (xy 440.484568 -335.081035) (xy 440.473454 -335.133245) (xy 440.455171 -335.183395)
			(xy 440.430075 -335.230507) (xy 440.398658 -335.273661) (xy 440.361531 -335.312014) (xy 440.34075 -335.328768)
			(xy 440.331959 -335.33639) (xy 440.321768 -335.35728) (xy 440.321192 -335.3689) (xy 440.321192 -335.448656)
			(xy 440.321716 -335.46029) (xy 440.331916 -335.481199) (xy 440.34075 -335.488788) (xy 440.363238 -335.506973)
			(xy 440.402971 -335.548996) (xy 440.435908 -335.596532) (xy 440.461295 -335.648494) (xy 440.478551 -335.703692)
			(xy 440.48728 -335.760862) (xy 440.487816 -335.789778) (xy 440.48733 -335.817029) (xy 440.479574 -335.870977)
			(xy 440.464219 -335.923272) (xy 440.441577 -335.972849) (xy 440.412111 -336.018699) (xy 440.37642 -336.05989)
			(xy 440.335229 -336.095581) (xy 440.289379 -336.125047) (xy 440.239802 -336.147689) (xy 440.187507 -336.163044)
			(xy 440.133559 -336.1708) (xy 440.079057 -336.1708) (xy 440.025109 -336.163044) (xy 439.972814 -336.147689)
			(xy 439.923237 -336.125047) (xy 439.877387 -336.095581) (xy 439.836196 -336.05989) (xy 439.800505 -336.018699)
			(xy 439.771039 -335.972849) (xy 439.748397 -335.923272) (xy 439.733042 -335.870977) (xy 439.725286 -335.817029)
			(xy 439.7248 -335.789778) (xy 439.725374 -335.760863) (xy 439.734092 -335.703695) (xy 439.751338 -335.648497)
			(xy 439.77672 -335.596535) (xy 439.809653 -335.548999) (xy 439.849385 -335.50698) (xy 439.871866 -335.488788)
			(xy 439.88068 -335.481188) (xy 439.890857 -335.460281) (xy 439.891424 -335.448656) (xy 439.891424 -335.3689)
			(xy 439.890897 -335.357266) (xy 439.880702 -335.336355) (xy 439.871866 -335.328768) (xy 439.851061 -335.312041)
			(xy 439.81393 -335.273685) (xy 439.782508 -335.230527) (xy 439.757409 -335.183411) (xy 439.739123 -335.133255)
			(xy 439.728008 -335.081041) (xy 439.724279 -335.027786) (xy 437.93587 -335.027786) (xy 437.936969 -335.032947)
			(xy 437.940699 -335.086199) (xy 437.936969 -335.13945) (xy 437.925853 -335.191662) (xy 437.907566 -335.241814)
			(xy 437.882467 -335.288928) (xy 437.851045 -335.332082) (xy 437.813913 -335.370435) (xy 437.79313 -335.387188)
			(xy 437.784327 -335.394798) (xy 437.774144 -335.415697) (xy 437.773572 -335.42732) (xy 437.773572 -335.507076)
			(xy 437.774114 -335.518708) (xy 437.784298 -335.53962) (xy 437.79313 -335.547208) (xy 437.815624 -335.565387)
			(xy 437.855357 -335.60741) (xy 437.888294 -335.654948) (xy 437.91368 -335.706911) (xy 437.930934 -335.762111)
			(xy 437.939662 -335.819281) (xy 437.940196 -335.848198) (xy 437.93971 -335.875449) (xy 437.931954 -335.929397)
			(xy 437.916599 -335.981692) (xy 437.893957 -336.031269) (xy 437.864491 -336.077119) (xy 437.8288 -336.11831)
			(xy 437.787609 -336.154001) (xy 437.741759 -336.183467) (xy 437.692182 -336.206109) (xy 437.639887 -336.221464)
			(xy 437.585939 -336.22922) (xy 437.531437 -336.22922) (xy 437.477489 -336.221464) (xy 437.425194 -336.206109)
			(xy 437.375617 -336.183467) (xy 437.329767 -336.154001) (xy 437.288576 -336.11831) (xy 437.252885 -336.077119)
			(xy 437.223419 -336.031269) (xy 437.200777 -335.981692) (xy 437.185422 -335.929397) (xy 437.177666 -335.875449)
			(xy 437.17718 -335.848198) (xy 437.177667 -335.81928) (xy 437.186398 -335.762105) (xy 437.20366 -335.706905)
			(xy 437.229058 -335.654942) (xy 437.262008 -335.60741) (xy 437.301757 -335.565396) (xy 437.324246 -335.547208)
			(xy 437.333047 -335.539595) (xy 437.343232 -335.518699) (xy 437.343804 -335.507076) (xy 437.343804 -335.42732)
			(xy 437.343237 -335.415692) (xy 437.333068 -335.394782) (xy 437.324246 -335.387188) (xy 437.303462 -335.370437)
			(xy 437.266332 -335.332083) (xy 437.234912 -335.288927) (xy 437.209814 -335.241814) (xy 437.191528 -335.191662)
			(xy 437.180412 -335.13945) (xy 437.176683 -335.086199) (xy 434.361999 -335.086199) (xy 434.369852 -335.107735)
			(xy 434.380969 -335.159947) (xy 434.384699 -335.213199) (xy 434.380969 -335.26645) (xy 434.369853 -335.318662)
			(xy 434.351566 -335.368814) (xy 434.326467 -335.415928) (xy 434.295045 -335.459082) (xy 434.257913 -335.497435)
			(xy 434.23713 -335.514188) (xy 434.228327 -335.521798) (xy 434.218144 -335.542697) (xy 434.217572 -335.55432)
			(xy 434.217572 -335.634076) (xy 434.218114 -335.645708) (xy 434.228298 -335.66662) (xy 434.23713 -335.674208)
			(xy 434.259624 -335.692387) (xy 434.299357 -335.73441) (xy 434.332294 -335.781948) (xy 434.35768 -335.833911)
			(xy 434.374934 -335.889111) (xy 434.383662 -335.946281) (xy 434.384196 -335.975198) (xy 434.38371 -336.002449)
			(xy 434.375954 -336.056397) (xy 434.360599 -336.108692) (xy 434.337957 -336.158269) (xy 434.308491 -336.204119)
			(xy 434.2728 -336.24531) (xy 434.231609 -336.281001) (xy 434.185759 -336.310467) (xy 434.136182 -336.333109)
			(xy 434.083887 -336.348464) (xy 434.029939 -336.35622) (xy 433.975437 -336.35622) (xy 433.921489 -336.348464)
			(xy 433.869194 -336.333109) (xy 433.819617 -336.310467) (xy 433.773767 -336.281001) (xy 433.732576 -336.24531)
			(xy 433.696885 -336.204119) (xy 433.667419 -336.158269) (xy 433.644777 -336.108692) (xy 433.629422 -336.056397)
			(xy 433.621666 -336.002449) (xy 433.62118 -335.975198) (xy 433.621667 -335.94628) (xy 433.630398 -335.889105)
			(xy 433.64766 -335.833905) (xy 433.673058 -335.781942) (xy 433.706008 -335.73441) (xy 433.745757 -335.692396)
			(xy 433.768246 -335.674208) (xy 433.777047 -335.666595) (xy 433.787232 -335.645699) (xy 433.787804 -335.634076)
			(xy 433.787804 -335.55432) (xy 433.787237 -335.542692) (xy 433.777068 -335.521782) (xy 433.768246 -335.514188)
			(xy 433.747462 -335.497437) (xy 433.710332 -335.459083) (xy 433.678912 -335.415927) (xy 433.653814 -335.368814)
			(xy 433.635528 -335.318662) (xy 433.624412 -335.26645) (xy 433.620683 -335.213199) (xy 431.946299 -335.213199)
			(xy 431.942569 -335.26645) (xy 431.931453 -335.318662) (xy 431.913166 -335.368814) (xy 431.888067 -335.415928)
			(xy 431.856645 -335.459082) (xy 431.819513 -335.497435) (xy 431.79873 -335.514188) (xy 431.789927 -335.521798)
			(xy 431.779744 -335.542697) (xy 431.779172 -335.55432) (xy 431.779172 -335.634076) (xy 431.779714 -335.645708)
			(xy 431.789898 -335.66662) (xy 431.79873 -335.674208) (xy 431.821224 -335.692387) (xy 431.860957 -335.73441)
			(xy 431.893894 -335.781948) (xy 431.91928 -335.833911) (xy 431.936534 -335.889111) (xy 431.945262 -335.946281)
			(xy 431.945796 -335.975198) (xy 431.94531 -336.002449) (xy 431.937554 -336.056397) (xy 431.922199 -336.108692)
			(xy 431.899557 -336.158269) (xy 431.870091 -336.204119) (xy 431.8344 -336.24531) (xy 431.793209 -336.281001)
			(xy 431.747359 -336.310467) (xy 431.697782 -336.333109) (xy 431.645487 -336.348464) (xy 431.591539 -336.35622)
			(xy 431.537037 -336.35622) (xy 431.483089 -336.348464) (xy 431.430794 -336.333109) (xy 431.381217 -336.310467)
			(xy 431.335367 -336.281001) (xy 431.294176 -336.24531) (xy 431.258485 -336.204119) (xy 431.229019 -336.158269)
			(xy 431.206377 -336.108692) (xy 431.191022 -336.056397) (xy 431.183266 -336.002449) (xy 431.18278 -335.975198)
			(xy 431.183267 -335.94628) (xy 431.191998 -335.889105) (xy 431.20926 -335.833905) (xy 431.234658 -335.781942)
			(xy 431.267608 -335.73441) (xy 431.307357 -335.692396) (xy 431.329846 -335.674208) (xy 431.338647 -335.666595)
			(xy 431.348832 -335.645699) (xy 431.349404 -335.634076) (xy 431.349404 -335.55432) (xy 431.348837 -335.542692)
			(xy 431.338668 -335.521782) (xy 431.329846 -335.514188) (xy 431.309062 -335.497437) (xy 431.271932 -335.459083)
			(xy 431.240512 -335.415927) (xy 431.215414 -335.368814) (xy 431.197128 -335.318662) (xy 431.186012 -335.26645)
			(xy 431.182283 -335.213199) (xy 428.28692 -335.213199) (xy 428.288699 -335.238599) (xy 428.284969 -335.29185)
			(xy 428.273853 -335.344062) (xy 428.255566 -335.394214) (xy 428.230467 -335.441328) (xy 428.199045 -335.484482)
			(xy 428.161913 -335.522835) (xy 428.14113 -335.539588) (xy 428.132327 -335.547198) (xy 428.122144 -335.568097)
			(xy 428.121572 -335.57972) (xy 428.121572 -335.659476) (xy 428.122114 -335.671108) (xy 428.132298 -335.69202)
			(xy 428.14113 -335.699608) (xy 428.163624 -335.717787) (xy 428.203357 -335.75981) (xy 428.236294 -335.807348)
			(xy 428.26168 -335.859311) (xy 428.278934 -335.914511) (xy 428.287662 -335.971681) (xy 428.288196 -336.000598)
			(xy 428.28771 -336.027849) (xy 428.279954 -336.081797) (xy 428.264599 -336.134092) (xy 428.241957 -336.183669)
			(xy 428.212491 -336.229519) (xy 428.1768 -336.27071) (xy 428.135609 -336.306401) (xy 428.089759 -336.335867)
			(xy 428.040182 -336.358509) (xy 427.987887 -336.373864) (xy 427.933939 -336.38162) (xy 427.879437 -336.38162)
			(xy 427.825489 -336.373864) (xy 427.773194 -336.358509) (xy 427.723617 -336.335867) (xy 427.677767 -336.306401)
			(xy 427.636576 -336.27071) (xy 427.600885 -336.229519) (xy 427.571419 -336.183669) (xy 427.548777 -336.134092)
			(xy 427.533422 -336.081797) (xy 427.525666 -336.027849) (xy 427.52518 -336.000598) (xy 427.525667 -335.97168)
			(xy 427.534398 -335.914505) (xy 427.55166 -335.859305) (xy 427.577058 -335.807342) (xy 427.610008 -335.75981)
			(xy 427.649757 -335.717796) (xy 427.672246 -335.699608) (xy 427.681047 -335.691995) (xy 427.691232 -335.671099)
			(xy 427.691804 -335.659476) (xy 427.691804 -335.57972) (xy 427.691237 -335.568092) (xy 427.681068 -335.547182)
			(xy 427.672246 -335.539588) (xy 427.651462 -335.522837) (xy 427.614332 -335.484483) (xy 427.582912 -335.441327)
			(xy 427.557814 -335.394214) (xy 427.539528 -335.344062) (xy 427.528412 -335.29185) (xy 427.524683 -335.238599)
			(xy 425.824899 -335.238599) (xy 425.821169 -335.29185) (xy 425.810053 -335.344062) (xy 425.791766 -335.394214)
			(xy 425.766667 -335.441328) (xy 425.735245 -335.484482) (xy 425.698113 -335.522835) (xy 425.67733 -335.539588)
			(xy 425.668527 -335.547198) (xy 425.658344 -335.568097) (xy 425.657772 -335.57972) (xy 425.657772 -335.659476)
			(xy 425.658314 -335.671108) (xy 425.668498 -335.69202) (xy 425.67733 -335.699608) (xy 425.699824 -335.717787)
			(xy 425.739557 -335.75981) (xy 425.772494 -335.807348) (xy 425.79788 -335.859311) (xy 425.815134 -335.914511)
			(xy 425.823862 -335.971681) (xy 425.824396 -336.000598) (xy 425.82391 -336.027849) (xy 425.816154 -336.081797)
			(xy 425.800799 -336.134092) (xy 425.778157 -336.183669) (xy 425.748691 -336.229519) (xy 425.713 -336.27071)
			(xy 425.671809 -336.306401) (xy 425.625959 -336.335867) (xy 425.576382 -336.358509) (xy 425.524087 -336.373864)
			(xy 425.470139 -336.38162) (xy 425.415637 -336.38162) (xy 425.361689 -336.373864) (xy 425.309394 -336.358509)
			(xy 425.259817 -336.335867) (xy 425.213967 -336.306401) (xy 425.172776 -336.27071) (xy 425.137085 -336.229519)
			(xy 425.107619 -336.183669) (xy 425.084977 -336.134092) (xy 425.069622 -336.081797) (xy 425.061866 -336.027849)
			(xy 425.06138 -336.000598) (xy 425.061867 -335.97168) (xy 425.070598 -335.914505) (xy 425.08786 -335.859305)
			(xy 425.113258 -335.807342) (xy 425.146208 -335.75981) (xy 425.185957 -335.717796) (xy 425.208446 -335.699608)
			(xy 425.217247 -335.691995) (xy 425.227432 -335.671099) (xy 425.228004 -335.659476) (xy 425.228004 -335.57972)
			(xy 425.227437 -335.568092) (xy 425.217268 -335.547182) (xy 425.208446 -335.539588) (xy 425.187662 -335.522837)
			(xy 425.150532 -335.484483) (xy 425.119112 -335.441327) (xy 425.094014 -335.394214) (xy 425.075728 -335.344062)
			(xy 425.064612 -335.29185) (xy 425.060883 -335.238599) (xy 422.167299 -335.238599) (xy 422.163569 -335.29185)
			(xy 422.152453 -335.344062) (xy 422.134166 -335.394214) (xy 422.109067 -335.441328) (xy 422.077645 -335.484482)
			(xy 422.040513 -335.522835) (xy 422.01973 -335.539588) (xy 422.010927 -335.547198) (xy 422.000744 -335.568097)
			(xy 422.000172 -335.57972) (xy 422.000172 -335.659476) (xy 422.000714 -335.671108) (xy 422.010898 -335.69202)
			(xy 422.01973 -335.699608) (xy 422.042224 -335.717787) (xy 422.081957 -335.75981) (xy 422.114894 -335.807348)
			(xy 422.14028 -335.859311) (xy 422.157534 -335.914511) (xy 422.166262 -335.971681) (xy 422.166796 -336.000598)
			(xy 422.16631 -336.027849) (xy 422.158554 -336.081797) (xy 422.143199 -336.134092) (xy 422.120557 -336.183669)
			(xy 422.091091 -336.229519) (xy 422.0554 -336.27071) (xy 422.014209 -336.306401) (xy 421.968359 -336.335867)
			(xy 421.918782 -336.358509) (xy 421.866487 -336.373864) (xy 421.812539 -336.38162) (xy 421.758037 -336.38162)
			(xy 421.704089 -336.373864) (xy 421.651794 -336.358509) (xy 421.602217 -336.335867) (xy 421.556367 -336.306401)
			(xy 421.515176 -336.27071) (xy 421.479485 -336.229519) (xy 421.450019 -336.183669) (xy 421.427377 -336.134092)
			(xy 421.412022 -336.081797) (xy 421.404266 -336.027849) (xy 421.40378 -336.000598) (xy 421.404267 -335.97168)
			(xy 421.412998 -335.914505) (xy 421.43026 -335.859305) (xy 421.455658 -335.807342) (xy 421.488608 -335.75981)
			(xy 421.528357 -335.717796) (xy 421.550846 -335.699608) (xy 421.559647 -335.691995) (xy 421.569832 -335.671099)
			(xy 421.570404 -335.659476) (xy 421.570404 -335.57972) (xy 421.569837 -335.568092) (xy 421.559668 -335.547182)
			(xy 421.550846 -335.539588) (xy 421.530062 -335.522837) (xy 421.492932 -335.484483) (xy 421.461512 -335.441327)
			(xy 421.436414 -335.394214) (xy 421.418128 -335.344062) (xy 421.407012 -335.29185) (xy 421.403283 -335.238599)
			(xy 419.745683 -335.238599) (xy 419.750569 -335.261547) (xy 419.754299 -335.314799) (xy 419.750569 -335.36805)
			(xy 419.739453 -335.420262) (xy 419.721166 -335.470414) (xy 419.696067 -335.517528) (xy 419.664645 -335.560682)
			(xy 419.627513 -335.599035) (xy 419.60673 -335.615788) (xy 419.597927 -335.623398) (xy 419.587744 -335.644297)
			(xy 419.587172 -335.65592) (xy 419.587172 -335.735676) (xy 419.587714 -335.747308) (xy 419.597898 -335.76822)
			(xy 419.60673 -335.775808) (xy 419.629224 -335.793987) (xy 419.668957 -335.83601) (xy 419.701894 -335.883548)
			(xy 419.72728 -335.935511) (xy 419.744534 -335.990711) (xy 419.753262 -336.047881) (xy 419.753796 -336.076798)
			(xy 419.75331 -336.104049) (xy 419.745554 -336.157997) (xy 419.730199 -336.210292) (xy 419.707557 -336.259869)
			(xy 419.678091 -336.305719) (xy 419.6424 -336.34691) (xy 419.601209 -336.382601) (xy 419.555359 -336.412067)
			(xy 419.505782 -336.434709) (xy 419.453487 -336.450064) (xy 419.399539 -336.45782) (xy 419.345037 -336.45782)
			(xy 419.291089 -336.450064) (xy 419.238794 -336.434709) (xy 419.189217 -336.412067) (xy 419.143367 -336.382601)
			(xy 419.102176 -336.34691) (xy 419.066485 -336.305719) (xy 419.037019 -336.259869) (xy 419.014377 -336.210292)
			(xy 418.999022 -336.157997) (xy 418.991266 -336.104049) (xy 418.99078 -336.076798) (xy 418.991267 -336.04788)
			(xy 418.999998 -335.990705) (xy 419.01726 -335.935505) (xy 419.042658 -335.883542) (xy 419.075608 -335.83601)
			(xy 419.115357 -335.793996) (xy 419.137846 -335.775808) (xy 419.146647 -335.768195) (xy 419.156832 -335.747299)
			(xy 419.157404 -335.735676) (xy 419.157404 -335.65592) (xy 419.156837 -335.644292) (xy 419.146668 -335.623382)
			(xy 419.137846 -335.615788) (xy 419.117062 -335.599037) (xy 419.079932 -335.560683) (xy 419.048512 -335.517527)
			(xy 419.023414 -335.470414) (xy 419.005128 -335.420262) (xy 418.994012 -335.36805) (xy 418.990283 -335.314799)
			(xy 415.280348 -335.314799) (xy 415.280348 -340.097364) (xy 420.754302 -340.097364) (xy 420.754746 -340.069993)
			(xy 420.762569 -340.015813) (xy 420.778064 -339.96331) (xy 420.80091 -339.913563) (xy 420.830639 -339.867597)
			(xy 420.848282 -339.846666) (xy 420.848536 -339.846412) (xy 420.854128 -339.839329) (xy 420.86037 -339.822409)
			(xy 420.860728 -339.813392) (xy 420.860728 -339.746336) (xy 420.860348 -339.737322) (xy 420.854116 -339.720405)
			(xy 420.848536 -339.713316) (xy 420.848282 -339.713316) (xy 420.848282 -339.713062) (xy 420.830608 -339.692157)
			(xy 420.800888 -339.646183) (xy 420.778048 -339.596432) (xy 420.762556 -339.543926) (xy 420.754732 -339.489745)
			(xy 420.754736 -339.435001) (xy 420.762568 -339.380821) (xy 420.778067 -339.328317) (xy 420.800914 -339.278569)
			(xy 420.830641 -339.2326) (xy 420.848282 -339.211666) (xy 420.848536 -339.211412) (xy 420.854128 -339.204329)
			(xy 420.86037 -339.187409) (xy 420.860728 -339.178392) (xy 420.860728 -339.111336) (xy 420.860348 -339.102322)
			(xy 420.854116 -339.085405) (xy 420.848536 -339.078316) (xy 420.848282 -339.078316) (xy 420.848282 -339.078062)
			(xy 420.830608 -339.057157) (xy 420.800888 -339.011183) (xy 420.778048 -338.961432) (xy 420.762556 -338.908926)
			(xy 420.754732 -338.854745) (xy 420.754736 -338.800001) (xy 420.762568 -338.745821) (xy 420.778067 -338.693317)
			(xy 420.800914 -338.643569) (xy 420.830641 -338.5976) (xy 420.848282 -338.576666) (xy 420.848536 -338.576412)
			(xy 420.854128 -338.569329) (xy 420.86037 -338.552409) (xy 420.860728 -338.543392) (xy 420.860728 -338.476336)
			(xy 420.860348 -338.467322) (xy 420.854116 -338.450405) (xy 420.848536 -338.443316) (xy 420.848282 -338.443316)
			(xy 420.848282 -338.443062) (xy 420.830608 -338.422157) (xy 420.800888 -338.376183) (xy 420.778048 -338.326432)
			(xy 420.762556 -338.273926) (xy 420.754732 -338.219745) (xy 420.754736 -338.165001) (xy 420.762568 -338.110821)
			(xy 420.778067 -338.058317) (xy 420.800914 -338.008569) (xy 420.830641 -337.9626) (xy 420.848282 -337.941666)
			(xy 420.848536 -337.941412) (xy 420.854128 -337.934329) (xy 420.86037 -337.917409) (xy 420.860728 -337.908392)
			(xy 420.860728 -337.841336) (xy 420.860348 -337.832322) (xy 420.854116 -337.815405) (xy 420.848536 -337.808316)
			(xy 420.848282 -337.808316) (xy 420.848282 -337.808062) (xy 420.830656 -337.78712) (xy 420.800943 -337.741149)
			(xy 420.778104 -337.691404) (xy 420.76261 -337.638906) (xy 420.754778 -337.584732) (xy 420.754302 -337.557364)
			(xy 420.754851 -337.528447) (xy 420.763578 -337.471276) (xy 420.780841 -337.41608) (xy 420.806244 -337.364124)
			(xy 420.839205 -337.316603) (xy 420.858696 -337.295236) (xy 420.864762 -337.288321) (xy 420.871914 -337.271385)
			(xy 420.872666 -337.262216) (xy 420.875714 -337.186016) (xy 420.869872 -337.168744) (xy 420.86403 -337.161632)
			(xy 420.848161 -337.141195) (xy 420.821462 -337.096874) (xy 420.800995 -337.049352) (xy 420.787135 -336.999501)
			(xy 420.780137 -336.948235) (xy 420.779702 -336.922364) (xy 420.780144 -336.895111) (xy 420.787906 -336.841162)
			(xy 420.803266 -336.788865) (xy 420.825912 -336.739287) (xy 420.855383 -336.693437) (xy 420.891079 -336.652247)
			(xy 420.932274 -336.616556) (xy 420.978128 -336.58709) (xy 421.027709 -336.56445) (xy 421.080007 -336.549096)
			(xy 421.133957 -336.541341) (xy 421.16121 -336.540856) (xy 421.188847 -336.54137) (xy 421.243542 -336.549358)
			(xy 421.296512 -336.565151) (xy 421.346651 -336.588419) (xy 421.39291 -336.618675) (xy 421.41394 -336.636614)
			(xy 421.421084 -336.642412) (xy 421.438276 -336.648925) (xy 421.447468 -336.649314) (xy 421.515032 -336.649314)
			(xy 421.52422 -336.648916) (xy 421.541405 -336.642394) (xy 421.54856 -336.636614) (xy 421.56957 -336.618647)
			(xy 421.615825 -336.588375) (xy 421.665968 -336.565101) (xy 421.718946 -336.549313) (xy 421.773649 -336.541341)
			(xy 421.80129 -336.540856) (xy 421.828311 -336.541308) (xy 421.881813 -336.548922) (xy 421.933705 -336.564012)
			(xy 421.982947 -336.586278) (xy 422.028552 -336.615272) (xy 422.069607 -336.650414) (xy 422.087802 -336.670396)
			(xy 422.094914 -336.678524) (xy 422.113964 -336.687414) (xy 422.210484 -336.689446) (xy 422.230296 -336.681318)
			(xy 422.237408 -336.673698) (xy 422.255473 -336.655456) (xy 422.295643 -336.623484) (xy 422.339736 -336.597186)
			(xy 422.386956 -336.577035) (xy 422.436451 -336.563395) (xy 422.487328 -336.556513) (xy 422.512998 -336.556096)
			(xy 422.540251 -336.556557) (xy 422.594202 -336.564314) (xy 422.6465 -336.57967) (xy 422.696081 -336.602313)
			(xy 422.741934 -336.631781) (xy 422.783127 -336.667475) (xy 422.81882 -336.708668) (xy 422.848288 -336.754521)
			(xy 422.870931 -336.804102) (xy 422.886286 -336.8564) (xy 422.894043 -336.910351) (xy 422.894506 -336.937604)
			(xy 422.894013 -336.964847) (xy 422.886256 -337.018779) (xy 422.8709 -337.071058) (xy 422.84826 -337.120618)
			(xy 422.818795 -337.166451) (xy 422.783105 -337.207622) (xy 422.741918 -337.243294) (xy 422.719246 -337.258406)
			(xy 422.712227 -337.26326) (xy 422.70168 -337.276665) (xy 422.696152 -337.292802) (xy 422.695878 -337.301332)
			(xy 422.695878 -337.386676) (xy 422.696171 -337.395198) (xy 422.701733 -337.411309) (xy 422.712255 -337.424718)
			(xy 422.719246 -337.429602) (xy 422.741917 -337.444718) (xy 422.783112 -337.480384) (xy 422.818809 -337.521553)
			(xy 422.848281 -337.567384) (xy 422.870927 -337.616945) (xy 422.886285 -337.669225) (xy 422.894043 -337.723159)
			(xy 422.894506 -337.750404) (xy 422.894041 -337.777774) (xy 422.886223 -337.831953) (xy 422.870733 -337.884456)
			(xy 422.847891 -337.934203) (xy 422.818167 -337.98017) (xy 422.800526 -338.001102) (xy 422.800272 -338.001356)
			(xy 422.794695 -338.008449) (xy 422.788443 -338.025361) (xy 422.78808 -338.034376) (xy 422.78808 -338.101432)
			(xy 422.788426 -338.11045) (xy 422.794682 -338.127367) (xy 422.800272 -338.134452) (xy 422.800526 -338.134452)
			(xy 422.800526 -338.134706) (xy 422.818173 -338.155635) (xy 422.847901 -338.201602) (xy 422.870749 -338.251349)
			(xy 422.886247 -338.303852) (xy 422.894076 -338.358032) (xy 422.894076 -338.412774) (xy 422.886245 -338.466954)
			(xy 422.870747 -338.519457) (xy 422.847898 -338.569203) (xy 422.818169 -338.61517) (xy 422.800526 -338.636102)
			(xy 422.800272 -338.636356) (xy 422.794695 -338.643449) (xy 422.788443 -338.660361) (xy 422.78808 -338.669376)
			(xy 422.78808 -338.736432) (xy 422.788426 -338.74545) (xy 422.794682 -338.762367) (xy 422.800272 -338.769452)
			(xy 422.800526 -338.769452) (xy 422.800526 -338.769706) (xy 422.818185 -338.790622) (xy 422.847893 -338.836599)
			(xy 422.870725 -338.886351) (xy 422.886211 -338.938855) (xy 422.894035 -338.993034) (xy 422.894287 -339.007704)
			(xy 424.464734 -339.007704) (xy 424.465194 -338.980333) (xy 424.473012 -338.926154) (xy 424.488502 -338.87365)
			(xy 424.511345 -338.823903) (xy 424.541072 -338.777937) (xy 424.558714 -338.757006) (xy 424.558968 -338.756752)
			(xy 424.564547 -338.749661) (xy 424.570796 -338.732747) (xy 424.57116 -338.723732) (xy 424.57116 -338.656676)
			(xy 424.570823 -338.647657) (xy 424.564563 -338.63074) (xy 424.558968 -338.623656) (xy 424.558714 -338.623656)
			(xy 424.558714 -338.623402) (xy 424.541078 -338.602466) (xy 424.511354 -338.556498) (xy 424.488509 -338.506753)
			(xy 424.473013 -338.454251) (xy 424.465184 -338.400073) (xy 424.465184 -338.345333) (xy 424.473012 -338.291155)
			(xy 424.488507 -338.238653) (xy 424.511351 -338.188907) (xy 424.541074 -338.142939) (xy 424.558714 -338.122006)
			(xy 424.558968 -338.121752) (xy 424.564547 -338.114661) (xy 424.570796 -338.097747) (xy 424.57116 -338.088732)
			(xy 424.57116 -338.021676) (xy 424.570823 -338.012657) (xy 424.564563 -337.99574) (xy 424.558968 -337.988656)
			(xy 424.558714 -337.988656) (xy 424.558714 -337.988402) (xy 424.541065 -337.967478) (xy 424.511354 -337.921503)
			(xy 424.48852 -337.871754) (xy 424.473031 -337.819251) (xy 424.465206 -337.765074) (xy 424.464734 -337.737704)
			(xy 424.465215 -337.71046) (xy 424.472972 -337.656527) (xy 424.488328 -337.604247) (xy 424.51097 -337.554686)
			(xy 424.540438 -337.508854) (xy 424.57613 -337.467683) (xy 424.61732 -337.432013) (xy 424.639994 -337.416902)
			(xy 424.646998 -337.412026) (xy 424.657552 -337.398633) (xy 424.663086 -337.382504) (xy 424.663362 -337.373976)
			(xy 424.663362 -337.288632) (xy 424.663046 -337.280112) (xy 424.657491 -337.264004) (xy 424.64698 -337.250593)
			(xy 424.639994 -337.245706) (xy 424.617335 -337.230571) (xy 424.576138 -337.19491) (xy 424.540439 -337.153745)
			(xy 424.510965 -337.107917) (xy 424.488317 -337.058359) (xy 424.472957 -337.006081) (xy 424.465198 -336.952148)
			(xy 424.464734 -336.924904) (xy 424.465159 -336.897649) (xy 424.472917 -336.843695) (xy 424.488274 -336.791394)
			(xy 424.510919 -336.741811) (xy 424.540391 -336.695956) (xy 424.576089 -336.654762) (xy 424.617286 -336.619068)
			(xy 424.663144 -336.589601) (xy 424.712729 -336.566961) (xy 424.765032 -336.551609) (xy 424.818987 -336.543856)
			(xy 424.846242 -336.543396) (xy 424.875756 -336.543918) (xy 424.934079 -336.553016) (xy 424.990305 -336.570987)
			(xy 425.043092 -336.597403) (xy 425.091181 -336.631634) (xy 425.112688 -336.651854) (xy 425.11988 -336.658226)
			(xy 425.137638 -336.66553) (xy 425.147232 -336.666078) (xy 425.216828 -336.667602) (xy 425.226554 -336.667368)
			(xy 425.244714 -336.660433) (xy 425.252134 -336.65414) (xy 425.273317 -336.635437) (xy 425.320209 -336.603906)
			(xy 425.37124 -336.579635) (xy 425.425291 -336.563155) (xy 425.481182 -336.554826) (xy 425.509436 -336.554318)
			(xy 425.537075 -336.554801) (xy 425.591771 -336.562795) (xy 425.644742 -336.578594) (xy 425.694881 -336.601869)
			(xy 425.741138 -336.632133) (xy 425.762166 -336.650076) (xy 425.769306 -336.65588) (xy 425.7865 -336.662391)
			(xy 425.795694 -336.662776) (xy 425.863258 -336.662776) (xy 425.872444 -336.662351) (xy 425.889629 -336.655848)
			(xy 425.896786 -336.650076) (xy 425.917819 -336.632138) (xy 425.964069 -336.601863) (xy 426.014206 -336.578584)
			(xy 426.067179 -336.562789) (xy 426.121877 -336.554809) (xy 426.149516 -336.554318) (xy 426.17677 -336.55474)
			(xy 426.230724 -336.5625) (xy 426.283025 -336.577859) (xy 426.332607 -336.600506) (xy 426.378461 -336.629978)
			(xy 426.419654 -336.665676) (xy 426.455348 -336.706873) (xy 426.484815 -336.75273) (xy 426.507455 -336.802315)
			(xy 426.522809 -336.854617) (xy 426.530563 -336.908571) (xy 426.531024 -336.935826) (xy 426.530592 -336.963198)
			(xy 426.522769 -337.017379) (xy 426.507273 -337.069883) (xy 426.484423 -337.11963) (xy 426.45469 -337.165594)
			(xy 426.437044 -337.186524) (xy 426.43679 -337.186778) (xy 426.431205 -337.193866) (xy 426.424958 -337.210782)
			(xy 426.424598 -337.219798) (xy 426.424598 -337.286854) (xy 426.424978 -337.295869) (xy 426.43121 -337.312786)
			(xy 426.43679 -337.319874) (xy 426.437044 -337.319874) (xy 426.437044 -337.320128) (xy 426.454711 -337.34104)
			(xy 426.484437 -337.38701) (xy 426.507283 -337.43676) (xy 426.522778 -337.489265) (xy 426.530605 -337.543447)
			(xy 426.530602 -337.598192) (xy 426.52277 -337.652373) (xy 426.507269 -337.704877) (xy 426.484418 -337.754624)
			(xy 426.454688 -337.800592) (xy 426.437044 -337.821524) (xy 426.43679 -337.821778) (xy 426.431205 -337.828866)
			(xy 426.424958 -337.845782) (xy 426.424598 -337.854798) (xy 426.424598 -337.921854) (xy 426.424978 -337.930869)
			(xy 426.43121 -337.947786) (xy 426.43679 -337.954874) (xy 426.437044 -337.954874) (xy 426.437044 -337.955128)
			(xy 426.454711 -337.97604) (xy 426.484437 -338.02201) (xy 426.507283 -338.07176) (xy 426.522778 -338.124265)
			(xy 426.530605 -338.178447) (xy 426.530602 -338.233192) (xy 426.52277 -338.287373) (xy 426.507269 -338.339877)
			(xy 426.484418 -338.389624) (xy 426.454688 -338.435592) (xy 426.437044 -338.456524) (xy 426.43679 -338.456778)
			(xy 426.431205 -338.463866) (xy 426.424958 -338.480782) (xy 426.424598 -338.489798) (xy 426.424598 -338.556854)
			(xy 426.424978 -338.565869) (xy 426.43121 -338.582786) (xy 426.43679 -338.589874) (xy 426.437044 -338.589874)
			(xy 426.437044 -338.590128) (xy 426.454711 -338.61104) (xy 426.484437 -338.65701) (xy 426.507283 -338.70676)
			(xy 426.522778 -338.759265) (xy 426.530605 -338.813447) (xy 426.530602 -338.868192) (xy 426.52277 -338.922373)
			(xy 426.507269 -338.974877) (xy 426.484418 -339.024624) (xy 426.454688 -339.070592) (xy 426.437044 -339.091524)
			(xy 426.43679 -339.091778) (xy 426.431205 -339.098866) (xy 426.424958 -339.115782) (xy 426.424598 -339.124798)
			(xy 426.424598 -339.191854) (xy 426.424978 -339.200869) (xy 426.43121 -339.217786) (xy 426.43679 -339.224874)
			(xy 426.437044 -339.224874) (xy 426.437044 -339.225128) (xy 426.454711 -339.24604) (xy 426.484437 -339.29201)
			(xy 426.507283 -339.34176) (xy 426.522778 -339.394265) (xy 426.530605 -339.448447) (xy 426.530602 -339.503192)
			(xy 426.52277 -339.557373) (xy 426.507269 -339.609877) (xy 426.484418 -339.659624) (xy 426.454688 -339.705592)
			(xy 426.437044 -339.726524) (xy 426.43679 -339.726778) (xy 426.431205 -339.733866) (xy 426.424958 -339.750782)
			(xy 426.424598 -339.759798) (xy 426.424598 -339.826854) (xy 426.424978 -339.835869) (xy 426.43121 -339.852786)
			(xy 426.43679 -339.859874) (xy 426.437044 -339.859874) (xy 426.437044 -339.860128) (xy 426.45467 -339.88107)
			(xy 426.484382 -339.927041) (xy 426.50722 -339.976786) (xy 426.522715 -340.029284) (xy 426.530548 -340.083458)
			(xy 426.531024 -340.110826) (xy 426.531024 -340.11108) (xy 426.530793 -340.122764) (xy 429.05553 -340.122764)
			(xy 429.055968 -340.095393) (xy 429.063791 -340.041212) (xy 429.079287 -339.988708) (xy 429.102135 -339.938962)
			(xy 429.131866 -339.892997) (xy 429.14951 -339.872066) (xy 429.149764 -339.871812) (xy 429.155359 -339.864732)
			(xy 429.161599 -339.84781) (xy 429.161956 -339.838792) (xy 429.161956 -339.771736) (xy 429.161591 -339.76272)
			(xy 429.15535 -339.745802) (xy 429.149764 -339.738716) (xy 429.14951 -339.738716) (xy 429.14951 -339.738462)
			(xy 429.131835 -339.717557) (xy 429.102113 -339.671584) (xy 429.07927 -339.621833) (xy 429.063778 -339.569327)
			(xy 429.055953 -339.515145) (xy 429.055957 -339.460401) (xy 429.063789 -339.40622) (xy 429.07929 -339.353716)
			(xy 429.102139 -339.303968) (xy 429.131867 -339.257999) (xy 429.14951 -339.237066) (xy 429.149764 -339.236812)
			(xy 429.155359 -339.229732) (xy 429.161599 -339.21281) (xy 429.161956 -339.203792) (xy 429.161956 -339.136736)
			(xy 429.161591 -339.12772) (xy 429.15535 -339.110802) (xy 429.149764 -339.103716) (xy 429.14951 -339.103716)
			(xy 429.14951 -339.103462) (xy 429.131835 -339.082557) (xy 429.102113 -339.036584) (xy 429.07927 -338.986833)
			(xy 429.063778 -338.934327) (xy 429.055953 -338.880145) (xy 429.055957 -338.825401) (xy 429.063789 -338.77122)
			(xy 429.07929 -338.718716) (xy 429.102139 -338.668968) (xy 429.131867 -338.622999) (xy 429.14951 -338.602066)
			(xy 429.149764 -338.601812) (xy 429.155359 -338.594732) (xy 429.161599 -338.57781) (xy 429.161956 -338.568792)
			(xy 429.161956 -338.501736) (xy 429.161591 -338.49272) (xy 429.15535 -338.475802) (xy 429.149764 -338.468716)
			(xy 429.14951 -338.468716) (xy 429.14951 -338.468462) (xy 429.131835 -338.447557) (xy 429.102113 -338.401584)
			(xy 429.07927 -338.351833) (xy 429.063778 -338.299327) (xy 429.055953 -338.245145) (xy 429.055957 -338.190401)
			(xy 429.063789 -338.13622) (xy 429.07929 -338.083716) (xy 429.102139 -338.033968) (xy 429.131867 -337.987999)
			(xy 429.14951 -337.967066) (xy 429.149764 -337.966812) (xy 429.155359 -337.959732) (xy 429.161599 -337.94281)
			(xy 429.161956 -337.933792) (xy 429.161956 -337.866736) (xy 429.161591 -337.85772) (xy 429.15535 -337.840802)
			(xy 429.149764 -337.833716) (xy 429.14951 -337.833716) (xy 429.14951 -337.833462) (xy 429.131835 -337.812557)
			(xy 429.102113 -337.766584) (xy 429.07927 -337.716833) (xy 429.063778 -337.664327) (xy 429.055953 -337.610145)
			(xy 429.055957 -337.555401) (xy 429.063789 -337.50122) (xy 429.07929 -337.448716) (xy 429.102139 -337.398968)
			(xy 429.131867 -337.352999) (xy 429.14951 -337.332066) (xy 429.149764 -337.331812) (xy 429.155359 -337.324732)
			(xy 429.161599 -337.30781) (xy 429.161956 -337.298792) (xy 429.161956 -337.231736) (xy 429.161591 -337.22272)
			(xy 429.15535 -337.205802) (xy 429.149764 -337.198716) (xy 429.14951 -337.198716) (xy 429.14951 -337.198462)
			(xy 429.131888 -337.177516) (xy 429.102173 -337.131547) (xy 429.079334 -337.081803) (xy 429.063839 -337.029306)
			(xy 429.056006 -336.975132) (xy 429.05553 -336.947764) (xy 429.055922 -336.920508) (xy 429.063684 -336.866553)
			(xy 429.079047 -336.814251) (xy 429.101696 -336.764669) (xy 429.131172 -336.718814) (xy 429.166873 -336.67762)
			(xy 429.208073 -336.641927) (xy 429.253934 -336.612461) (xy 429.303521 -336.589821) (xy 429.355825 -336.574469)
			(xy 429.409782 -336.566716) (xy 429.437038 -336.566256) (xy 429.464676 -336.566754) (xy 429.519371 -336.574746)
			(xy 429.572342 -336.590543) (xy 429.62248 -336.613814) (xy 429.668738 -336.644074) (xy 429.689768 -336.662014)
			(xy 429.696904 -336.667824) (xy 429.714102 -336.67433) (xy 429.723296 -336.674714) (xy 429.79086 -336.674714)
			(xy 429.800045 -336.674281) (xy 429.817229 -336.667783) (xy 429.824388 -336.662014) (xy 429.845425 -336.644081)
			(xy 429.891673 -336.613804) (xy 429.941809 -336.590523) (xy 429.994781 -336.574727) (xy 430.049479 -336.566747)
			(xy 430.077118 -336.566256) (xy 430.103911 -336.56672) (xy 430.15697 -336.574227) (xy 430.208459 -336.589076)
			(xy 430.257366 -336.610977) (xy 430.302732 -336.639499) (xy 430.343666 -336.674082) (xy 430.361852 -336.693764)
			(xy 430.369218 -336.701892) (xy 430.388522 -336.710782) (xy 430.474882 -336.71129) (xy 430.485687 -336.71082)
			(xy 430.505417 -336.702002) (xy 430.512982 -336.694272) (xy 430.531135 -336.674865) (xy 430.571932 -336.640812)
			(xy 430.617058 -336.612745) (xy 430.665639 -336.591208) (xy 430.716738 -336.576616) (xy 430.769367 -336.569252)
			(xy 430.795938 -336.568796) (xy 430.82319 -336.569242) (xy 430.87714 -336.577004) (xy 430.929435 -336.592364)
			(xy 430.979013 -336.61501) (xy 431.024863 -336.644481) (xy 431.066053 -336.680176) (xy 431.101744 -336.72137)
			(xy 431.13121 -336.767224) (xy 431.15385 -336.816804) (xy 431.169205 -336.869101) (xy 431.176961 -336.923052)
			(xy 431.177446 -336.950304) (xy 431.177009 -336.97628) (xy 431.169965 -337.027751) (xy 431.155996 -337.077789)
			(xy 431.135359 -337.125465) (xy 431.108438 -337.169896) (xy 431.075731 -337.210259) (xy 431.037845 -337.245806)
			(xy 431.016918 -337.2612) (xy 431.007401 -337.268805) (xy 430.996271 -337.290438) (xy 430.995582 -337.302602)
			(xy 430.995582 -337.385406) (xy 430.996285 -337.397567) (xy 431.007414 -337.41919) (xy 431.016918 -337.426808)
			(xy 431.037848 -337.442196) (xy 431.075726 -337.47775) (xy 431.108427 -337.518117) (xy 431.135345 -337.562549)
			(xy 431.155982 -337.610224) (xy 431.169955 -337.66026) (xy 431.177007 -337.711729) (xy 431.177446 -337.737704)
			(xy 431.176995 -337.765075) (xy 431.169176 -337.819255) (xy 431.153684 -337.871759) (xy 431.130838 -337.921506)
			(xy 431.10111 -337.967471) (xy 431.083466 -337.988402) (xy 431.083212 -337.988656) (xy 431.077639 -337.995752)
			(xy 431.071384 -338.012661) (xy 431.07102 -338.021676) (xy 431.07102 -338.088732) (xy 431.071357 -338.097751)
			(xy 431.077618 -338.114668) (xy 431.083212 -338.121752) (xy 431.083466 -338.121752) (xy 431.083466 -338.122006)
			(xy 431.101111 -338.142935) (xy 431.130836 -338.188904) (xy 431.153682 -338.23865) (xy 431.169178 -338.291153)
			(xy 431.177006 -338.345332) (xy 431.177006 -338.400074) (xy 431.169177 -338.454253) (xy 431.15368 -338.506755)
			(xy 431.130833 -338.556502) (xy 431.101107 -338.602469) (xy 431.083466 -338.623402) (xy 431.083212 -338.623656)
			(xy 431.077639 -338.630752) (xy 431.071384 -338.647661) (xy 431.07102 -338.656676) (xy 431.07102 -338.723732)
			(xy 431.071357 -338.732751) (xy 431.077618 -338.749668) (xy 431.083212 -338.756752) (xy 431.083466 -338.756752)
			(xy 431.083466 -338.757006) (xy 431.101116 -338.777929) (xy 431.130827 -338.823904) (xy 431.153662 -338.873654)
			(xy 431.16915 -338.926156) (xy 431.176974 -338.980334) (xy 431.177446 -339.007704) (xy 432.785774 -339.007704)
			(xy 432.786224 -338.980333) (xy 432.794043 -338.926153) (xy 432.809535 -338.873649) (xy 432.832381 -338.823902)
			(xy 432.86211 -338.777936) (xy 432.879754 -338.757006) (xy 432.880008 -338.756752) (xy 432.88558 -338.749655)
			(xy 432.891835 -338.732746) (xy 432.8922 -338.723732) (xy 432.8922 -338.656676) (xy 432.891854 -338.647658)
			(xy 432.885599 -338.630741) (xy 432.880008 -338.623656) (xy 432.879754 -338.623656) (xy 432.879754 -338.623402)
			(xy 432.862116 -338.602467) (xy 432.832389 -338.5565) (xy 432.809542 -338.506754) (xy 432.794044 -338.454252)
			(xy 432.786215 -338.400074) (xy 432.786214 -338.345332) (xy 432.794043 -338.291153) (xy 432.80954 -338.238651)
			(xy 432.832386 -338.188905) (xy 432.862112 -338.142938) (xy 432.879754 -338.122006) (xy 432.880008 -338.121752)
			(xy 432.88558 -338.114655) (xy 432.891835 -338.097746) (xy 432.8922 -338.088732) (xy 432.8922 -338.021676)
			(xy 432.891854 -338.012658) (xy 432.885599 -337.995741) (xy 432.880008 -337.988656) (xy 432.879754 -337.988656)
			(xy 432.879754 -337.988402) (xy 432.862111 -337.967473) (xy 432.832398 -337.9215) (xy 432.809562 -337.871752)
			(xy 432.794072 -337.81925) (xy 432.786246 -337.765074) (xy 432.785774 -337.737704) (xy 432.786209 -337.711728)
			(xy 432.793252 -337.660256) (xy 432.807221 -337.610218) (xy 432.827858 -337.562542) (xy 432.85478 -337.51811)
			(xy 432.887487 -337.477747) (xy 432.925374 -337.442202) (xy 432.946302 -337.426808) (xy 432.955801 -337.419184)
			(xy 432.966944 -337.397566) (xy 432.967638 -337.385406) (xy 432.967638 -337.302602) (xy 432.966982 -337.290435)
			(xy 432.955818 -337.268813) (xy 432.946302 -337.2612) (xy 432.925358 -337.24583) (xy 432.887484 -337.210271)
			(xy 432.854787 -337.1699) (xy 432.827872 -337.125464) (xy 432.807238 -337.077787) (xy 432.793265 -337.02775)
			(xy 432.786213 -336.97628) (xy 432.785774 -336.950304) (xy 432.786281 -336.923054) (xy 432.794037 -336.869108)
			(xy 432.809391 -336.816814) (xy 432.83203 -336.767238) (xy 432.861494 -336.721389) (xy 432.897183 -336.680199)
			(xy 432.938371 -336.644507) (xy 432.984219 -336.615041) (xy 433.033794 -336.592398) (xy 433.086086 -336.577042)
			(xy 433.140032 -336.569283) (xy 433.167282 -336.568796) (xy 433.197081 -336.569368) (xy 433.255951 -336.578646)
			(xy 433.312664 -336.596962) (xy 433.36584 -336.623873) (xy 433.414186 -336.658722) (xy 433.43576 -336.679286)
			(xy 433.442618 -336.686144) (xy 433.460906 -336.694018) (xy 433.540916 -336.695288) (xy 433.550726 -336.694999)
			(xy 433.569022 -336.687954) (xy 433.576476 -336.681572) (xy 433.597798 -336.662565) (xy 433.64499 -336.630391)
			(xy 433.69645 -336.605608) (xy 433.751028 -336.588771) (xy 433.807506 -336.580254) (xy 433.836064 -336.579718)
			(xy 433.863703 -336.580185) (xy 433.9184 -336.588182) (xy 433.971372 -336.603985) (xy 434.02151 -336.627264)
			(xy 434.067766 -336.657532) (xy 434.088794 -336.675476) (xy 434.095956 -336.68125) (xy 434.113133 -336.687779)
			(xy 434.122322 -336.688176) (xy 434.189886 -336.688176) (xy 434.199073 -336.687765) (xy 434.216258 -336.681252)
			(xy 434.223414 -336.675476) (xy 434.244436 -336.657525) (xy 434.290689 -336.627252) (xy 434.340829 -336.603975)
			(xy 434.393804 -336.588183) (xy 434.448504 -336.580207) (xy 434.476144 -336.579718) (xy 434.503398 -336.580137)
			(xy 434.557349 -336.5879) (xy 434.609647 -336.603262) (xy 434.659226 -336.62591) (xy 434.705077 -336.655384)
			(xy 434.746268 -336.691082) (xy 434.781958 -336.732279) (xy 434.811423 -336.778136) (xy 434.834062 -336.827719)
			(xy 434.849415 -336.88002) (xy 434.857168 -336.933972) (xy 434.857652 -336.961226) (xy 434.857213 -336.988597)
			(xy 434.84939 -337.042778) (xy 434.833896 -337.095282) (xy 434.811048 -337.145028) (xy 434.781317 -337.190994)
			(xy 434.763672 -337.211924) (xy 434.763418 -337.212178) (xy 434.757837 -337.219268) (xy 434.751587 -337.236182)
			(xy 434.751226 -337.245198) (xy 434.751226 -337.312254) (xy 434.751599 -337.321269) (xy 434.757835 -337.338187)
			(xy 434.763418 -337.345274) (xy 434.763672 -337.345274) (xy 434.763672 -337.345528) (xy 434.781338 -337.36644)
			(xy 434.811062 -337.412411) (xy 434.833906 -337.462161) (xy 434.8494 -337.514666) (xy 434.857226 -337.568848)
			(xy 434.857224 -337.623591) (xy 434.849392 -337.677772) (xy 434.833892 -337.730276) (xy 434.811043 -337.780023)
			(xy 434.781315 -337.825991) (xy 434.763672 -337.846924) (xy 434.763418 -337.847178) (xy 434.757837 -337.854268)
			(xy 434.751587 -337.871182) (xy 434.751226 -337.880198) (xy 434.751226 -337.947254) (xy 434.751599 -337.956269)
			(xy 434.757835 -337.973187) (xy 434.763418 -337.980274) (xy 434.763672 -337.980274) (xy 434.763672 -337.980528)
			(xy 434.781338 -338.00144) (xy 434.811062 -338.047411) (xy 434.833906 -338.097161) (xy 434.8494 -338.149666)
			(xy 434.857226 -338.203848) (xy 434.857224 -338.258591) (xy 434.849392 -338.312772) (xy 434.833892 -338.365276)
			(xy 434.811043 -338.415023) (xy 434.781315 -338.460991) (xy 434.763672 -338.481924) (xy 434.763418 -338.482178)
			(xy 434.757837 -338.489268) (xy 434.751587 -338.506182) (xy 434.751226 -338.515198) (xy 434.751226 -338.582254)
			(xy 434.751599 -338.591269) (xy 434.757835 -338.608187) (xy 434.763418 -338.615274) (xy 434.763672 -338.615274)
			(xy 434.763672 -338.615528) (xy 434.781338 -338.63644) (xy 434.811062 -338.682411) (xy 434.833906 -338.732161)
			(xy 434.8494 -338.784666) (xy 434.857226 -338.838848) (xy 434.857224 -338.893591) (xy 434.849392 -338.947772)
			(xy 434.833892 -339.000276) (xy 434.811043 -339.050023) (xy 434.781315 -339.095991) (xy 434.763672 -339.116924)
			(xy 434.763418 -339.117178) (xy 434.757837 -339.124268) (xy 434.751587 -339.141182) (xy 434.751226 -339.150198)
			(xy 434.751226 -339.217254) (xy 434.751599 -339.226269) (xy 434.757835 -339.243187) (xy 434.763418 -339.250274)
			(xy 434.763672 -339.250274) (xy 434.763672 -339.250528) (xy 434.781338 -339.27144) (xy 434.811062 -339.317411)
			(xy 434.833906 -339.367161) (xy 434.8494 -339.419666) (xy 434.857226 -339.473848) (xy 434.857224 -339.528591)
			(xy 434.849392 -339.582772) (xy 434.833892 -339.635276) (xy 434.811043 -339.685023) (xy 434.781315 -339.730991)
			(xy 434.763672 -339.751924) (xy 434.763418 -339.752178) (xy 434.757837 -339.759268) (xy 434.751587 -339.776182)
			(xy 434.751226 -339.785198) (xy 434.751226 -339.852254) (xy 434.751599 -339.861269) (xy 434.757835 -339.878187)
			(xy 434.763418 -339.885274) (xy 434.763672 -339.885274) (xy 434.763672 -339.885528) (xy 434.781286 -339.90648)
			(xy 434.811003 -339.952447) (xy 434.833844 -340.002189) (xy 434.849341 -340.054686) (xy 434.857175 -340.108858)
			(xy 434.857386 -340.120986) (xy 435.837076 -340.120986) (xy 435.837515 -340.093615) (xy 435.845337 -340.039434)
			(xy 435.860831 -339.98693) (xy 435.883679 -339.937183) (xy 435.913411 -339.891218) (xy 435.931056 -339.870288)
			(xy 435.93131 -339.870034) (xy 435.93689 -339.862943) (xy 435.94314 -339.84603) (xy 435.943502 -339.837014)
			(xy 435.943502 -339.769958) (xy 435.943117 -339.760944) (xy 435.936889 -339.744027) (xy 435.93131 -339.736938)
			(xy 435.931056 -339.736938) (xy 435.931056 -339.736684) (xy 435.9134 -339.715763) (xy 435.883674 -339.669794)
			(xy 435.860828 -339.620046) (xy 435.845331 -339.567542) (xy 435.837503 -339.513361) (xy 435.837505 -339.458618)
			(xy 435.845336 -339.404438) (xy 435.860835 -339.351934) (xy 435.883684 -339.302188) (xy 435.913413 -339.25622)
			(xy 435.931056 -339.235288) (xy 435.93131 -339.235034) (xy 435.93689 -339.227943) (xy 435.94314 -339.21103)
			(xy 435.943502 -339.202014) (xy 435.943502 -339.134958) (xy 435.943117 -339.125944) (xy 435.936889 -339.109027)
			(xy 435.93131 -339.101938) (xy 435.931056 -339.101938) (xy 435.931056 -339.101684) (xy 435.9134 -339.080763)
			(xy 435.883674 -339.034794) (xy 435.860828 -338.985046) (xy 435.845331 -338.932542) (xy 435.837503 -338.878361)
			(xy 435.837505 -338.823618) (xy 435.845336 -338.769438) (xy 435.860835 -338.716934) (xy 435.883684 -338.667188)
			(xy 435.913413 -338.62122) (xy 435.931056 -338.600288) (xy 435.93131 -338.600034) (xy 435.93689 -338.592943)
			(xy 435.94314 -338.57603) (xy 435.943502 -338.567014) (xy 435.943502 -338.499958) (xy 435.943117 -338.490944)
			(xy 435.936889 -338.474027) (xy 435.93131 -338.466938) (xy 435.931056 -338.466938) (xy 435.931056 -338.466684)
			(xy 435.9134 -338.445763) (xy 435.883674 -338.399794) (xy 435.860828 -338.350046) (xy 435.845331 -338.297542)
			(xy 435.837503 -338.243361) (xy 435.837505 -338.188618) (xy 435.845336 -338.134438) (xy 435.860835 -338.081934)
			(xy 435.883684 -338.032188) (xy 435.913413 -337.98622) (xy 435.931056 -337.965288) (xy 435.93131 -337.965034)
			(xy 435.93689 -337.957943) (xy 435.94314 -337.94103) (xy 435.943502 -337.932014) (xy 435.943502 -337.864958)
			(xy 435.943117 -337.855944) (xy 435.936889 -337.839027) (xy 435.93131 -337.831938) (xy 435.931056 -337.831938)
			(xy 435.931056 -337.831684) (xy 435.9134 -337.810763) (xy 435.883674 -337.764794) (xy 435.860828 -337.715046)
			(xy 435.845331 -337.662542) (xy 435.837503 -337.608361) (xy 435.837505 -337.553618) (xy 435.845336 -337.499438)
			(xy 435.860835 -337.446934) (xy 435.883684 -337.397188) (xy 435.913413 -337.35122) (xy 435.931056 -337.330288)
			(xy 435.93131 -337.330034) (xy 435.93689 -337.322943) (xy 435.94314 -337.30603) (xy 435.943502 -337.297014)
			(xy 435.943502 -337.229958) (xy 435.943117 -337.220944) (xy 435.936889 -337.204027) (xy 435.93131 -337.196938)
			(xy 435.931056 -337.196938) (xy 435.931056 -337.196684) (xy 435.913436 -337.175737) (xy 435.883722 -337.129768)
			(xy 435.860883 -337.080024) (xy 435.845388 -337.027527) (xy 435.837553 -336.973354) (xy 435.837076 -336.945986)
			(xy 435.837565 -336.918735) (xy 435.845323 -336.864788) (xy 435.860679 -336.812495) (xy 435.88332 -336.762918)
			(xy 435.912787 -336.717069) (xy 435.948478 -336.675879) (xy 435.989667 -336.640188) (xy 436.035517 -336.610721)
			(xy 436.085093 -336.58808) (xy 436.137386 -336.572723) (xy 436.191333 -336.564965) (xy 436.218584 -336.564478)
			(xy 436.246221 -336.565002) (xy 436.300915 -336.572987) (xy 436.353886 -336.588777) (xy 436.404025 -336.612043)
			(xy 436.450284 -336.642298) (xy 436.471314 -336.660236) (xy 436.478464 -336.666026) (xy 436.495651 -336.672544)
			(xy 436.504842 -336.672936) (xy 436.572406 -336.672936) (xy 436.581592 -336.672521) (xy 436.598776 -336.66601)
			(xy 436.605934 -336.660236) (xy 436.626943 -336.642269) (xy 436.6732 -336.612) (xy 436.723343 -336.588727)
			(xy 436.776321 -336.572938) (xy 436.831024 -336.564965) (xy 436.858664 -336.564478) (xy 436.885915 -336.564989)
			(xy 436.939864 -336.57274) (xy 436.99216 -336.588091) (xy 437.041739 -336.610729) (xy 437.087592 -336.640191)
			(xy 437.128784 -336.67588) (xy 437.164479 -336.717068) (xy 437.193947 -336.762917) (xy 437.216591 -336.812493)
			(xy 437.231949 -336.864787) (xy 437.239708 -336.918735) (xy 437.240172 -336.945986) (xy 437.239705 -336.973356)
			(xy 437.231888 -337.027536) (xy 437.2164 -337.080039) (xy 437.193558 -337.129786) (xy 437.163833 -337.175752)
			(xy 437.146192 -337.196684) (xy 437.145938 -337.196938) (xy 437.140364 -337.204033) (xy 437.134111 -337.220944)
			(xy 437.133746 -337.229958) (xy 437.133746 -337.297014) (xy 437.134086 -337.306033) (xy 437.140344 -337.32295)
			(xy 437.145938 -337.330034) (xy 437.146192 -337.330034) (xy 437.146192 -337.330288) (xy 437.163818 -337.351232)
			(xy 437.193542 -337.397198) (xy 437.216387 -337.446943) (xy 437.231884 -337.499443) (xy 437.239713 -337.55362)
			(xy 437.239715 -337.608359) (xy 437.231888 -337.662536) (xy 437.216395 -337.715037) (xy 437.193552 -337.764783)
			(xy 437.163831 -337.810751) (xy 437.146192 -337.831684) (xy 437.145938 -337.831938) (xy 437.140364 -337.839033)
			(xy 437.134111 -337.855944) (xy 437.133746 -337.864958) (xy 437.133746 -337.932014) (xy 437.134086 -337.941033)
			(xy 437.140344 -337.95795) (xy 437.145938 -337.965034) (xy 437.146192 -337.965034) (xy 437.146192 -337.965288)
			(xy 437.163818 -337.986232) (xy 437.193542 -338.032198) (xy 437.216387 -338.081943) (xy 437.231884 -338.134443)
			(xy 437.239713 -338.18862) (xy 437.239715 -338.243359) (xy 437.231888 -338.297536) (xy 437.216395 -338.350037)
			(xy 437.193552 -338.399783) (xy 437.163831 -338.445751) (xy 437.146192 -338.466684) (xy 437.145938 -338.466938)
			(xy 437.140364 -338.474033) (xy 437.134111 -338.490944) (xy 437.133746 -338.499958) (xy 437.133746 -338.567014)
			(xy 437.134086 -338.576033) (xy 437.140344 -338.59295) (xy 437.145938 -338.600034) (xy 437.146192 -338.600034)
			(xy 437.146192 -338.600288) (xy 437.163818 -338.621232) (xy 437.193542 -338.667198) (xy 437.216387 -338.716943)
			(xy 437.231884 -338.769443) (xy 437.239713 -338.82362) (xy 437.239715 -338.878359) (xy 437.231888 -338.932536)
			(xy 437.216395 -338.985037) (xy 437.193552 -339.034783) (xy 437.163831 -339.080751) (xy 437.146192 -339.101684)
			(xy 437.145938 -339.101938) (xy 437.140364 -339.109033) (xy 437.134111 -339.125944) (xy 437.133746 -339.134958)
			(xy 437.133746 -339.202014) (xy 437.134086 -339.211033) (xy 437.140344 -339.22795) (xy 437.145938 -339.235034)
			(xy 437.146192 -339.235034) (xy 437.146192 -339.235288) (xy 437.163818 -339.256232) (xy 437.193542 -339.302198)
			(xy 437.216387 -339.351943) (xy 437.231884 -339.404443) (xy 437.239713 -339.45862) (xy 437.239715 -339.513359)
			(xy 437.231888 -339.567536) (xy 437.216395 -339.620037) (xy 437.193552 -339.669783) (xy 437.163831 -339.715751)
			(xy 437.146192 -339.736684) (xy 437.145938 -339.736938) (xy 437.140364 -339.744033) (xy 437.134111 -339.760944)
			(xy 437.133746 -339.769958) (xy 437.133746 -339.837014) (xy 437.134086 -339.846033) (xy 437.140344 -339.86295)
			(xy 437.145938 -339.870034) (xy 437.146192 -339.870034) (xy 437.146192 -339.870288) (xy 437.163838 -339.891215)
			(xy 437.193549 -339.937189) (xy 437.216384 -339.986938) (xy 437.231873 -340.03944) (xy 437.239699 -340.093616)
			(xy 437.240172 -340.120986) (xy 437.239659 -340.148188) (xy 437.231907 -340.202038) (xy 437.216586 -340.254242)
			(xy 437.194007 -340.30374) (xy 437.164628 -340.349531) (xy 437.129044 -340.390686) (xy 437.087977 -340.42637)
			(xy 437.042258 -340.455861) (xy 436.992814 -340.47856) (xy 436.966868 -340.486746) (xy 436.966614 -340.486746)
			(xy 436.956579 -340.490366) (xy 436.94044 -340.504282) (xy 436.935372 -340.51367) (xy 436.898288 -340.59241)
			(xy 436.898034 -340.614) (xy 436.902352 -340.62416) (xy 436.912016 -340.647857) (xy 436.925586 -340.697204)
			(xy 436.932425 -340.747923) (xy 436.932832 -340.773512) (xy 436.932832 -340.773766) (xy 436.932363 -340.801136)
			(xy 436.924548 -340.855316) (xy 436.909061 -340.90782) (xy 436.886219 -340.957567) (xy 436.856494 -341.003533)
			(xy 436.838852 -341.024464) (xy 436.838598 -341.024718) (xy 436.832998 -341.031795) (xy 436.826759 -341.048719)
			(xy 436.826406 -341.057738) (xy 436.826406 -341.124794) (xy 436.826765 -341.133811) (xy 436.833011 -341.150728)
			(xy 436.838598 -341.157814) (xy 436.838852 -341.157814) (xy 436.838852 -341.158068) (xy 436.856482 -341.179007)
			(xy 436.886197 -341.224977) (xy 436.909035 -341.274723) (xy 436.924528 -341.327222) (xy 436.932358 -341.381397)
			(xy 436.932832 -341.408766) (xy 436.932346 -341.436017) (xy 436.92459 -341.489965) (xy 436.909235 -341.54226)
			(xy 436.886593 -341.591837) (xy 436.857127 -341.637687) (xy 436.821436 -341.678878) (xy 436.780245 -341.714569)
			(xy 436.734395 -341.744035) (xy 436.684818 -341.766677) (xy 436.632523 -341.782032) (xy 436.578575 -341.789788)
			(xy 436.524073 -341.789788) (xy 436.470125 -341.782032) (xy 436.41783 -341.766677) (xy 436.368253 -341.744035)
			(xy 436.322403 -341.714569) (xy 436.281212 -341.678878) (xy 436.245521 -341.637687) (xy 436.216055 -341.591837)
			(xy 436.193413 -341.54226) (xy 436.178058 -341.489965) (xy 436.170302 -341.436017) (xy 436.169816 -341.408766)
			(xy 436.170258 -341.381395) (xy 436.178081 -341.327215) (xy 436.193576 -341.274711) (xy 436.216423 -341.224965)
			(xy 436.246152 -341.178999) (xy 436.263796 -341.158068) (xy 436.26405 -341.157814) (xy 436.269643 -341.150732)
			(xy 436.275885 -341.133812) (xy 436.276242 -341.124794) (xy 436.276242 -341.057738) (xy 436.275879 -341.048721)
			(xy 436.269637 -341.031804) (xy 436.26405 -341.024718) (xy 436.263796 -341.024718) (xy 436.263796 -341.024464)
			(xy 436.246173 -341.003519) (xy 436.216459 -340.95755) (xy 436.19362 -340.907806) (xy 436.178125 -340.855308)
			(xy 436.170292 -340.801134) (xy 436.169816 -340.773766) (xy 436.169816 -340.773258) (xy 436.170225 -340.748587)
			(xy 436.176626 -340.69966) (xy 436.189278 -340.651966) (xy 436.198264 -340.628986) (xy 436.201923 -340.618596)
			(xy 436.201008 -340.596612) (xy 436.196486 -340.586568) (xy 436.156354 -340.507828) (xy 436.139336 -340.494366)
			(xy 436.128414 -340.491572) (xy 436.1011 -340.484369) (xy 436.04878 -340.463081) (xy 436.000172 -340.434309)
			(xy 435.956338 -340.398684) (xy 435.918238 -340.356983) (xy 435.886704 -340.31012) (xy 435.862426 -340.259118)
			(xy 435.845936 -340.205094) (xy 435.837593 -340.149228) (xy 435.837076 -340.120986) (xy 434.857386 -340.120986)
			(xy 434.857652 -340.136226) (xy 434.857149 -340.164182) (xy 434.848973 -340.219492) (xy 434.832815 -340.273018)
			(xy 434.80902 -340.323614) (xy 434.778097 -340.370196) (xy 434.740709 -340.411768) (xy 434.697655 -340.44744)
			(xy 434.67401 -340.462362) (xy 434.673756 -340.462616) (xy 434.664346 -340.469166) (xy 434.651956 -340.488424)
			(xy 434.64988 -340.4997) (xy 434.640228 -340.578948) (xy 434.639371 -340.590539) (xy 434.646905 -340.612498)
			(xy 434.654706 -340.621112) (xy 434.675432 -340.642729) (xy 434.710608 -340.691193) (xy 434.737775 -340.744559)
			(xy 434.756266 -340.801517) (xy 434.765626 -340.860664) (xy 434.766212 -340.890606) (xy 434.765747 -340.917976)
			(xy 434.757928 -340.972155) (xy 434.742439 -341.024658) (xy 434.719597 -341.074405) (xy 434.689873 -341.120372)
			(xy 434.672232 -341.141304) (xy 434.671978 -341.141558) (xy 434.6664 -341.148651) (xy 434.660149 -341.165563)
			(xy 434.659786 -341.174578) (xy 434.659786 -341.241634) (xy 434.66013 -341.250652) (xy 434.666387 -341.267569)
			(xy 434.671978 -341.274654) (xy 434.672232 -341.274654) (xy 434.672232 -341.274908) (xy 434.689893 -341.295822)
			(xy 434.719601 -341.3418) (xy 434.742432 -341.391552) (xy 434.757918 -341.444057) (xy 434.765741 -341.498236)
			(xy 434.766212 -341.525606) (xy 434.765726 -341.552857) (xy 434.75797 -341.606805) (xy 434.742615 -341.6591)
			(xy 434.719973 -341.708677) (xy 434.690507 -341.754527) (xy 434.654816 -341.795718) (xy 434.613625 -341.831409)
			(xy 434.567775 -341.860875) (xy 434.518198 -341.883517) (xy 434.465903 -341.898872) (xy 434.411955 -341.906628)
			(xy 434.357453 -341.906628) (xy 434.303505 -341.898872) (xy 434.25121 -341.883517) (xy 434.201633 -341.860875)
			(xy 434.155783 -341.831409) (xy 434.114592 -341.795718) (xy 434.078901 -341.754527) (xy 434.049435 -341.708677)
			(xy 434.026793 -341.6591) (xy 434.011438 -341.606805) (xy 434.003682 -341.552857) (xy 434.003196 -341.525606)
			(xy 434.003667 -341.498236) (xy 434.011483 -341.444057) (xy 434.026972 -341.391554) (xy 434.049812 -341.341807)
			(xy 434.079535 -341.29584) (xy 434.097176 -341.274908) (xy 434.09743 -341.274654) (xy 434.103003 -341.267559)
			(xy 434.109257 -341.250648) (xy 434.109622 -341.241634) (xy 434.109622 -341.174578) (xy 434.109271 -341.165561)
			(xy 434.103019 -341.148644) (xy 434.09743 -341.141558) (xy 434.097176 -341.141558) (xy 434.097176 -341.141304)
			(xy 434.079522 -341.120384) (xy 434.049813 -341.074408) (xy 434.02698 -341.024657) (xy 434.011493 -340.972154)
			(xy 434.003668 -340.917976) (xy 434.003196 -340.890606) (xy 434.003668 -340.863812) (xy 434.011167 -340.810753)
			(xy 434.026017 -340.759264) (xy 434.047926 -340.710361) (xy 434.076464 -340.665005) (xy 434.111068 -340.624089)
			(xy 434.151058 -340.588418) (xy 434.195646 -340.558695) (xy 434.219604 -340.54669) (xy 434.227168 -340.542771)
			(xy 434.239271 -340.530791) (xy 434.246733 -340.515484) (xy 434.248052 -340.507066) (xy 434.255164 -340.447122)
			(xy 434.234336 -340.431374) (xy 434.226716 -340.425024) (xy 434.208174 -340.419182) (xy 434.128418 -340.425278)
			(xy 434.118713 -340.426409) (xy 434.101206 -340.435048) (xy 434.094382 -340.442042) (xy 434.076221 -340.461583)
			(xy 434.035386 -340.495913) (xy 433.990166 -340.524215) (xy 433.941442 -340.545939) (xy 433.890165 -340.56066)
			(xy 433.837338 -340.568091) (xy 433.810664 -340.568534) (xy 433.783413 -340.568056) (xy 433.729466 -340.560295)
			(xy 433.677173 -340.544937) (xy 433.627597 -340.522293) (xy 433.581749 -340.492826) (xy 433.540559 -340.457134)
			(xy 433.504868 -340.415943) (xy 433.475402 -340.370094) (xy 433.45276 -340.320517) (xy 433.437403 -340.268224)
			(xy 433.429644 -340.214277) (xy 433.429156 -340.187026) (xy 433.429624 -340.159656) (xy 433.437439 -340.105476)
			(xy 433.452927 -340.052972) (xy 433.475769 -340.003226) (xy 433.505494 -339.957259) (xy 433.523136 -339.936328)
			(xy 433.52339 -339.936074) (xy 433.528951 -339.92897) (xy 433.535213 -339.912067) (xy 433.535582 -339.903054)
			(xy 433.535582 -339.835998) (xy 433.53523 -339.826981) (xy 433.528979 -339.810063) (xy 433.52339 -339.802978)
			(xy 433.523136 -339.802978) (xy 433.523136 -339.802724) (xy 433.5055 -339.781789) (xy 433.475787 -339.735818)
			(xy 433.45295 -339.686071) (xy 433.437458 -339.633571) (xy 433.42963 -339.579395) (xy 433.429156 -339.552026)
			(xy 433.429156 -339.551264) (xy 433.429377 -339.533245) (xy 433.432811 -339.49737) (xy 433.436014 -339.479636)
			(xy 433.438808 -339.466174) (xy 433.429664 -339.440012) (xy 433.340764 -339.365082) (xy 433.313586 -339.360256)
			(xy 433.300886 -339.365082) (xy 433.268694 -339.376299) (xy 433.201618 -339.388436) (xy 433.167536 -339.389212)
			(xy 433.167282 -339.389212) (xy 433.14003 -339.388739) (xy 433.086083 -339.38098) (xy 433.033788 -339.365623)
			(xy 432.984211 -339.34298) (xy 432.938361 -339.313512) (xy 432.897171 -339.277819) (xy 432.861479 -339.236628)
			(xy 432.832013 -339.190777) (xy 432.809372 -339.141199) (xy 432.794017 -339.088904) (xy 432.78626 -339.034956)
			(xy 432.785774 -339.007704) (xy 431.177446 -339.007704) (xy 431.176926 -339.034954) (xy 431.16917 -339.088898)
			(xy 431.153816 -339.14119) (xy 431.131177 -339.190765) (xy 431.101714 -339.236613) (xy 431.066026 -339.277802)
			(xy 431.02484 -339.313494) (xy 430.978995 -339.342961) (xy 430.929422 -339.365604) (xy 430.877131 -339.380963)
			(xy 430.823188 -339.388724) (xy 430.795938 -339.389212) (xy 430.769797 -339.388796) (xy 430.718005 -339.381658)
			(xy 430.667673 -339.367512) (xy 430.643538 -339.357462) (xy 430.630584 -339.351874) (xy 430.602898 -339.35543)
			(xy 430.510188 -339.428836) (xy 430.500536 -339.454998) (xy 430.503076 -339.468968) (xy 430.50604 -339.486086)
			(xy 430.509218 -339.520684) (xy 430.509426 -339.538056) (xy 430.509426 -339.538564) (xy 430.508957 -339.565934)
			(xy 430.501143 -339.620114) (xy 430.485655 -339.672618) (xy 430.462814 -339.722365) (xy 430.433088 -339.768331)
			(xy 430.415446 -339.789262) (xy 430.415192 -339.789516) (xy 430.409592 -339.796593) (xy 430.403354 -339.813517)
			(xy 430.403 -339.822536) (xy 430.403 -339.889592) (xy 430.403361 -339.898608) (xy 430.409606 -339.915525)
			(xy 430.415192 -339.922612) (xy 430.415446 -339.922612) (xy 430.415446 -339.922866) (xy 430.433074 -339.943807)
			(xy 430.46279 -339.989777) (xy 430.485628 -340.039522) (xy 430.501122 -340.092021) (xy 430.508952 -340.146195)
			(xy 430.509426 -340.173564) (xy 430.508911 -340.200815) (xy 430.50116 -340.254763) (xy 430.485809 -340.307059)
			(xy 430.463172 -340.356638) (xy 430.43371 -340.40249) (xy 430.398021 -340.443683) (xy 430.356834 -340.479377)
			(xy 430.310985 -340.508846) (xy 430.26141 -340.53149) (xy 430.209116 -340.546848) (xy 430.155169 -340.554607)
			(xy 430.127918 -340.555072) (xy 430.100148 -340.554573) (xy 430.045195 -340.546522) (xy 429.99199 -340.530587)
			(xy 429.941659 -340.507104) (xy 429.895264 -340.476571) (xy 429.853788 -340.439633) (xy 429.835564 -340.418674)
			(xy 429.82896 -340.4108) (xy 429.810926 -340.401656) (xy 429.717454 -340.394544) (xy 429.697896 -340.401148)
			(xy 429.690276 -340.408006) (xy 429.669251 -340.426064) (xy 429.622928 -340.45649) (xy 429.572688 -340.479887)
			(xy 429.519588 -340.495762) (xy 429.464749 -340.503779) (xy 429.437038 -340.504272) (xy 429.409784 -340.503809)
			(xy 429.355832 -340.496057) (xy 429.303532 -340.480703) (xy 429.253949 -340.458063) (xy 429.208094 -340.428595)
			(xy 429.1669 -340.392901) (xy 429.131206 -340.351707) (xy 429.101738 -340.305853) (xy 429.079097 -340.25627)
			(xy 429.063744 -340.20397) (xy 429.055991 -340.150018) (xy 429.05553 -340.122764) (xy 426.530793 -340.122764)
			(xy 426.530436 -340.140878) (xy 426.521166 -340.199748) (xy 426.502834 -340.256453) (xy 426.489876 -340.283292)
			(xy 426.484542 -340.293706) (xy 426.484288 -340.317074) (xy 426.523404 -340.400386) (xy 426.528816 -340.410627)
			(xy 426.5468 -340.425184) (xy 426.557948 -340.428326) (xy 426.585683 -340.43513) (xy 426.638853 -340.45597)
			(xy 426.688319 -340.484506) (xy 426.732978 -340.520099) (xy 426.771829 -340.561954) (xy 426.804004 -340.609135)
			(xy 426.828784 -340.660586) (xy 426.845614 -340.715157) (xy 426.854118 -340.771628) (xy 426.85462 -340.800182)
			(xy 426.854163 -340.827553) (xy 426.846346 -340.881733) (xy 426.830856 -340.934237) (xy 426.808012 -340.983984)
			(xy 426.778283 -341.029949) (xy 426.76064 -341.05088) (xy 426.760386 -341.051134) (xy 426.754819 -341.058234)
			(xy 426.748561 -341.075141) (xy 426.748194 -341.084154) (xy 426.748194 -341.15121) (xy 426.748548 -341.160227)
			(xy 426.754798 -341.177144) (xy 426.760386 -341.18423) (xy 426.76064 -341.18423) (xy 426.76064 -341.184484)
			(xy 426.778292 -341.205406) (xy 426.808 -341.251382) (xy 426.830833 -341.301132) (xy 426.846322 -341.353635)
			(xy 426.850763 -341.384382) (xy 428.175928 -341.384382) (xy 428.176377 -341.357011) (xy 428.184198 -341.302831)
			(xy 428.19969 -341.250327) (xy 428.222536 -341.200581) (xy 428.252265 -341.154615) (xy 428.269908 -341.133684)
			(xy 428.270162 -341.13343) (xy 428.275749 -341.126344) (xy 428.281994 -341.109427) (xy 428.282354 -341.10041)
			(xy 428.282354 -341.033354) (xy 428.281981 -341.024339) (xy 428.275746 -341.007421) (xy 428.270162 -341.000334)
			(xy 428.269908 -341.000334) (xy 428.269908 -341.00008) (xy 428.252294 -340.979128) (xy 428.222578 -340.93316)
			(xy 428.199737 -340.883418) (xy 428.18424 -340.830922) (xy 428.176406 -340.77675) (xy 428.175928 -340.749382)
			(xy 428.176414 -340.722131) (xy 428.18417 -340.668183) (xy 428.199525 -340.615888) (xy 428.222167 -340.566311)
			(xy 428.251633 -340.520461) (xy 428.287324 -340.47927) (xy 428.328515 -340.443579) (xy 428.374365 -340.414113)
			(xy 428.423942 -340.391471) (xy 428.476237 -340.376116) (xy 428.530185 -340.36836) (xy 428.584687 -340.36836)
			(xy 428.638635 -340.376116) (xy 428.69093 -340.391471) (xy 428.740507 -340.414113) (xy 428.786357 -340.443579)
			(xy 428.827548 -340.47927) (xy 428.863239 -340.520461) (xy 428.892705 -340.566311) (xy 428.915347 -340.615888)
			(xy 428.930702 -340.668183) (xy 428.938458 -340.722131) (xy 428.938944 -340.749382) (xy 428.938481 -340.776752)
			(xy 428.930665 -340.830932) (xy 428.915176 -340.883436) (xy 428.892333 -340.933183) (xy 428.862606 -340.979149)
			(xy 428.844964 -341.00008) (xy 428.84471 -341.000334) (xy 428.839146 -341.007436) (xy 428.832885 -341.024341)
			(xy 428.832518 -341.033354) (xy 428.832518 -341.10041) (xy 428.832866 -341.109428) (xy 428.839119 -341.126345)
			(xy 428.84471 -341.13343) (xy 428.844964 -341.13343) (xy 428.844964 -341.133684) (xy 428.862603 -341.154616)
			(xy 428.892316 -341.200588) (xy 428.915153 -341.250336) (xy 428.930644 -341.302837) (xy 428.938471 -341.357013)
			(xy 428.938944 -341.384382) (xy 428.938458 -341.411633) (xy 428.930702 -341.465581) (xy 428.915347 -341.517876)
			(xy 428.892705 -341.567453) (xy 428.863239 -341.613303) (xy 428.827548 -341.654494) (xy 428.786357 -341.690185)
			(xy 428.740507 -341.719651) (xy 428.69093 -341.742293) (xy 428.638635 -341.757648) (xy 428.584687 -341.765404)
			(xy 428.530185 -341.765404) (xy 428.476237 -341.757648) (xy 428.423942 -341.742293) (xy 428.374365 -341.719651)
			(xy 428.328515 -341.690185) (xy 428.287324 -341.654494) (xy 428.251633 -341.613303) (xy 428.222167 -341.567453)
			(xy 428.199525 -341.517876) (xy 428.18417 -341.465581) (xy 428.176414 -341.411633) (xy 428.175928 -341.384382)
			(xy 426.850763 -341.384382) (xy 426.854148 -341.407812) (xy 426.85462 -341.435182) (xy 426.854134 -341.462433)
			(xy 426.846378 -341.516381) (xy 426.831023 -341.568676) (xy 426.808381 -341.618253) (xy 426.778915 -341.664103)
			(xy 426.743224 -341.705294) (xy 426.702033 -341.740985) (xy 426.656183 -341.770451) (xy 426.606606 -341.793093)
			(xy 426.554311 -341.808448) (xy 426.500363 -341.816204) (xy 426.445861 -341.816204) (xy 426.391913 -341.808448)
			(xy 426.339618 -341.793093) (xy 426.290041 -341.770451) (xy 426.244191 -341.740985) (xy 426.203 -341.705294)
			(xy 426.167309 -341.664103) (xy 426.137843 -341.618253) (xy 426.115201 -341.568676) (xy 426.099846 -341.516381)
			(xy 426.09209 -341.462433) (xy 426.091604 -341.435182) (xy 426.092059 -341.407811) (xy 426.099879 -341.353632)
			(xy 426.115371 -341.301128) (xy 426.138215 -341.251382) (xy 426.167942 -341.205415) (xy 426.185584 -341.184484)
			(xy 426.185838 -341.18423) (xy 426.191422 -341.177142) (xy 426.197669 -341.160226) (xy 426.19803 -341.15121)
			(xy 426.19803 -341.084154) (xy 426.197641 -341.075141) (xy 426.191415 -341.058224) (xy 426.185838 -341.051134)
			(xy 426.185584 -341.051134) (xy 426.185584 -341.05088) (xy 426.167966 -341.029931) (xy 426.138252 -340.983962)
			(xy 426.115412 -340.934219) (xy 426.099916 -340.881722) (xy 426.092082 -340.82755) (xy 426.091604 -340.800182)
			(xy 426.091604 -340.799928) (xy 426.092192 -340.77013) (xy 426.101462 -340.71126) (xy 426.119794 -340.654555)
			(xy 426.132752 -340.627716) (xy 426.138086 -340.617302) (xy 426.13834 -340.593934) (xy 426.099224 -340.510622)
			(xy 426.093796 -340.500391) (xy 426.075823 -340.485829) (xy 426.06468 -340.482682) (xy 426.036135 -340.475641)
			(xy 425.981486 -340.453963) (xy 425.930807 -340.424163) (xy 425.907708 -340.405974) (xy 425.900088 -340.399624)
			(xy 425.881546 -340.393782) (xy 425.80179 -340.399878) (xy 425.792092 -340.401044) (xy 425.774582 -340.409658)
			(xy 425.767754 -340.416642) (xy 425.749607 -340.436197) (xy 425.708769 -340.470525) (xy 425.663546 -340.498826)
			(xy 425.614819 -340.520548) (xy 425.56354 -340.535266) (xy 425.510711 -340.542693) (xy 425.484036 -340.543134)
			(xy 425.456785 -340.542611) (xy 425.402838 -340.53486) (xy 425.350543 -340.51951) (xy 425.300964 -340.496873)
			(xy 425.255112 -340.467411) (xy 425.21392 -340.431724) (xy 425.178226 -340.390537) (xy 425.148756 -340.34469)
			(xy 425.126112 -340.295116) (xy 425.110753 -340.242823) (xy 425.102993 -340.188877) (xy 425.102528 -340.161626)
			(xy 425.103002 -340.134256) (xy 425.110817 -340.080077) (xy 425.126304 -340.027574) (xy 425.149144 -339.977827)
			(xy 425.178867 -339.93186) (xy 425.196508 -339.910928) (xy 425.196762 -339.910674) (xy 425.202331 -339.903576)
			(xy 425.208587 -339.886668) (xy 425.208954 -339.877654) (xy 425.208954 -339.810598) (xy 425.208608 -339.80158)
			(xy 425.202354 -339.784663) (xy 425.196762 -339.777578) (xy 425.196508 -339.777578) (xy 425.196508 -339.777324)
			(xy 425.178868 -339.756393) (xy 425.149156 -339.71042) (xy 425.12632 -339.660672) (xy 425.110829 -339.608171)
			(xy 425.103002 -339.553995) (xy 425.102528 -339.526626) (xy 425.102647 -339.514206) (xy 425.1043 -339.489422)
			(xy 425.10583 -339.477096) (xy 425.107608 -339.464142) (xy 425.097702 -339.439758) (xy 425.010072 -339.36813)
			(xy 424.984164 -339.363812) (xy 424.971718 -339.36813) (xy 424.941478 -339.377952) (xy 424.878792 -339.388554)
			(xy 424.847004 -339.389212) (xy 424.846242 -339.389212) (xy 424.81899 -339.388706) (xy 424.765041 -339.380954)
			(xy 424.712744 -339.365604) (xy 424.663165 -339.342967) (xy 424.617312 -339.313503) (xy 424.576118 -339.277814)
			(xy 424.540424 -339.236625) (xy 424.510955 -339.190776) (xy 424.488312 -339.141199) (xy 424.472955 -339.088904)
			(xy 424.465198 -339.034956) (xy 424.464734 -339.007704) (xy 422.894287 -339.007704) (xy 422.894506 -339.020404)
			(xy 422.894026 -339.047655) (xy 422.886269 -339.101603) (xy 422.870913 -339.153898) (xy 422.848271 -339.203476)
			(xy 422.818804 -339.249326) (xy 422.783112 -339.290517) (xy 422.741922 -339.326208) (xy 422.696071 -339.355674)
			(xy 422.646493 -339.378315) (xy 422.594198 -339.39367) (xy 422.540249 -339.401426) (xy 422.512998 -339.401912)
			(xy 422.486081 -339.4015) (xy 422.432782 -339.393939) (xy 422.381077 -339.378954) (xy 422.331995 -339.356843)
			(xy 422.286512 -339.328046) (xy 422.245533 -339.293135) (xy 422.209874 -339.252807) (xy 422.180244 -339.207861)
			(xy 422.16832 -339.183726) (xy 422.162646 -339.173243) (xy 422.143819 -339.15867) (xy 422.132252 -339.155786)
			(xy 422.074594 -339.144356) (xy 422.060116 -339.158326) (xy 422.060116 -339.211666) (xy 422.060573 -339.221484)
			(xy 422.068038 -339.239648) (xy 422.074594 -339.246972) (xy 422.094761 -339.268477) (xy 422.128905 -339.316536)
			(xy 422.155252 -339.369274) (xy 422.173175 -339.425437) (xy 422.182247 -339.483687) (xy 422.182798 -339.513164)
			(xy 422.182311 -339.540533) (xy 422.174499 -339.594712) (xy 422.159014 -339.647215) (xy 422.136177 -339.696962)
			(xy 422.106457 -339.74293) (xy 422.088818 -339.763862) (xy 422.088564 -339.764116) (xy 422.082961 -339.771191)
			(xy 422.076725 -339.788117) (xy 422.076372 -339.797136) (xy 422.076372 -339.864192) (xy 422.076739 -339.873208)
			(xy 422.08298 -339.890124) (xy 422.088564 -339.897212) (xy 422.088818 -339.897212) (xy 422.088818 -339.897466)
			(xy 422.106457 -339.918398) (xy 422.136169 -339.964371) (xy 422.159004 -340.014119) (xy 422.174495 -340.066619)
			(xy 422.182324 -340.120795) (xy 422.182798 -340.148164) (xy 422.182311 -340.175416) (xy 422.174559 -340.229367)
			(xy 422.159207 -340.281665) (xy 422.136568 -340.331246) (xy 422.107103 -340.3771) (xy 422.071411 -340.418293)
			(xy 422.03022 -340.453987) (xy 421.984369 -340.483455) (xy 421.934789 -340.506098) (xy 421.882492 -340.521453)
			(xy 421.828542 -340.529209) (xy 421.80129 -340.529672) (xy 421.772613 -340.529168) (xy 421.715904 -340.520594)
			(xy 421.661119 -340.503624) (xy 421.609492 -340.478642) (xy 421.562188 -340.446211) (xy 421.520273 -340.407063)
			(xy 421.502078 -340.384892) (xy 421.495134 -340.377042) (xy 421.476655 -340.367203) (xy 421.466264 -340.365842)
			(xy 421.410892 -340.361524) (xy 421.404034 -340.368636) (xy 421.40378 -340.36889) (xy 421.396302 -340.377175)
			(xy 421.388669 -340.398121) (xy 421.389048 -340.409276) (xy 421.397176 -340.498938) (xy 421.408606 -340.518496)
			(xy 421.418004 -340.524846) (xy 421.439584 -340.540141) (xy 421.478668 -340.57578) (xy 421.512453 -340.616477)
			(xy 421.540292 -340.661452) (xy 421.56165 -340.709842) (xy 421.576118 -340.760718) (xy 421.583419 -340.813105)
			(xy 421.583866 -340.839552) (xy 421.583323 -340.868717) (xy 421.574438 -340.926367) (xy 421.556882 -340.981993)
			(xy 421.531064 -341.034299) (xy 421.514778 -341.0585) (xy 421.50919 -341.066374) (xy 421.504618 -341.085678)
			(xy 421.518588 -341.174578) (xy 421.528494 -341.191342) (xy 421.536114 -341.197184) (xy 421.558892 -341.215394)
			(xy 421.599226 -341.257505) (xy 421.632684 -341.305263) (xy 421.658486 -341.357555) (xy 421.67603 -341.413165)
			(xy 421.68491 -341.470796) (xy 421.685466 -341.499952) (xy 421.68498 -341.527203) (xy 421.677224 -341.581151)
			(xy 421.661869 -341.633446) (xy 421.639227 -341.683023) (xy 421.609761 -341.728873) (xy 421.57407 -341.770064)
			(xy 421.532879 -341.805755) (xy 421.487029 -341.835221) (xy 421.437452 -341.857863) (xy 421.385157 -341.873218)
			(xy 421.331209 -341.880974) (xy 421.276707 -341.880974) (xy 421.222759 -341.873218) (xy 421.170464 -341.857863)
			(xy 421.120887 -341.835221) (xy 421.075037 -341.805755) (xy 421.033846 -341.770064) (xy 420.998155 -341.728873)
			(xy 420.968689 -341.683023) (xy 420.946047 -341.633446) (xy 420.930692 -341.581151) (xy 420.922936 -341.527203)
			(xy 420.92245 -341.499952) (xy 420.922992 -341.470787) (xy 420.931877 -341.413137) (xy 420.949434 -341.357511)
			(xy 420.975252 -341.305205) (xy 420.991538 -341.281004) (xy 420.997126 -341.27313) (xy 421.001698 -341.253826)
			(xy 420.987728 -341.164926) (xy 420.977822 -341.148162) (xy 420.970202 -341.14232) (xy 420.947409 -341.12413)
			(xy 420.907079 -341.082012) (xy 420.873626 -341.034249) (xy 420.847827 -340.981953) (xy 420.830285 -340.926342)
			(xy 420.821406 -340.868708) (xy 420.82085 -340.839552) (xy 420.821456 -340.809358) (xy 420.830974 -340.749724)
			(xy 420.849765 -340.692334) (xy 420.87736 -340.638619) (xy 420.91307 -340.589921) (xy 420.934134 -340.56828)
			(xy 420.934388 -340.568026) (xy 420.941867 -340.559743) (xy 420.949497 -340.538795) (xy 420.94912 -340.52764)
			(xy 420.940992 -340.437978) (xy 420.929562 -340.41842) (xy 420.920164 -340.41207) (xy 420.898585 -340.396775)
			(xy 420.859502 -340.361135) (xy 420.825718 -340.320437) (xy 420.797879 -340.275462) (xy 420.776521 -340.227073)
			(xy 420.762052 -340.176197) (xy 420.75475 -340.123811) (xy 420.754302 -340.097364) (xy 415.280348 -340.097364)
			(xy 415.280348 -341.499952) (xy 416.60445 -341.499952) (xy 416.604987 -341.471036) (xy 416.613709 -341.413864)
			(xy 416.630962 -341.358665) (xy 416.65635 -341.306703) (xy 416.689292 -341.259169) (xy 416.729031 -341.217152)
			(xy 416.751516 -341.198962) (xy 416.760333 -341.191365) (xy 416.770511 -341.170456) (xy 416.771074 -341.15883)
			(xy 416.771074 -341.079074) (xy 416.770545 -341.067441) (xy 416.76035 -341.046531) (xy 416.751516 -341.038942)
			(xy 416.729056 -341.020723) (xy 416.689319 -340.97871) (xy 416.656376 -340.931181) (xy 416.630984 -340.879225)
			(xy 416.613723 -340.824032) (xy 416.604988 -340.766866) (xy 416.60445 -340.737952) (xy 416.604936 -340.710701)
			(xy 416.612692 -340.656753) (xy 416.628047 -340.604458) (xy 416.650689 -340.554881) (xy 416.680155 -340.509031)
			(xy 416.715846 -340.46784) (xy 416.757037 -340.432149) (xy 416.802887 -340.402683) (xy 416.852464 -340.380041)
			(xy 416.904759 -340.364686) (xy 416.958707 -340.35693) (xy 417.013209 -340.35693) (xy 417.067157 -340.364686)
			(xy 417.119452 -340.380041) (xy 417.169029 -340.402683) (xy 417.214879 -340.432149) (xy 417.25607 -340.46784)
			(xy 417.291761 -340.509031) (xy 417.321227 -340.554881) (xy 417.343869 -340.604458) (xy 417.359224 -340.656753)
			(xy 417.36698 -340.710701) (xy 417.367466 -340.737952) (xy 417.366926 -340.766868) (xy 417.358203 -340.824039)
			(xy 417.340951 -340.879238) (xy 417.315563 -340.9312) (xy 417.282623 -340.978734) (xy 417.242884 -341.020752)
			(xy 417.2204 -341.038942) (xy 417.211584 -341.046541) (xy 417.201405 -341.067448) (xy 417.200842 -341.079074)
			(xy 417.200842 -341.15883) (xy 417.201363 -341.170465) (xy 417.211563 -341.191375) (xy 417.2204 -341.198962)
			(xy 417.242865 -341.217174) (xy 417.282602 -341.25919) (xy 417.315543 -341.30672) (xy 417.340934 -341.358677)
			(xy 417.358195 -341.413871) (xy 417.366928 -341.471037) (xy 417.367466 -341.499952) (xy 418.76345 -341.499952)
			(xy 418.763987 -341.471036) (xy 418.772709 -341.413864) (xy 418.789962 -341.358665) (xy 418.81535 -341.306703)
			(xy 418.848292 -341.259169) (xy 418.888031 -341.217152) (xy 418.910516 -341.198962) (xy 418.919333 -341.191365)
			(xy 418.929511 -341.170456) (xy 418.930074 -341.15883) (xy 418.930074 -341.079074) (xy 418.929545 -341.067441)
			(xy 418.91935 -341.046531) (xy 418.910516 -341.038942) (xy 418.888056 -341.020723) (xy 418.848319 -340.97871)
			(xy 418.815376 -340.931181) (xy 418.789984 -340.879225) (xy 418.772723 -340.824032) (xy 418.763988 -340.766866)
			(xy 418.76345 -340.737952) (xy 418.763936 -340.710701) (xy 418.771692 -340.656753) (xy 418.787047 -340.604458)
			(xy 418.809689 -340.554881) (xy 418.839155 -340.509031) (xy 418.874846 -340.46784) (xy 418.916037 -340.432149)
			(xy 418.961887 -340.402683) (xy 419.011464 -340.380041) (xy 419.063759 -340.364686) (xy 419.117707 -340.35693)
			(xy 419.172209 -340.35693) (xy 419.226157 -340.364686) (xy 419.278452 -340.380041) (xy 419.328029 -340.402683)
			(xy 419.373879 -340.432149) (xy 419.41507 -340.46784) (xy 419.450761 -340.509031) (xy 419.480227 -340.554881)
			(xy 419.502869 -340.604458) (xy 419.518224 -340.656753) (xy 419.52598 -340.710701) (xy 419.526466 -340.737952)
			(xy 419.525926 -340.766868) (xy 419.517203 -340.824039) (xy 419.499951 -340.879238) (xy 419.474563 -340.9312)
			(xy 419.441623 -340.978734) (xy 419.401884 -341.020752) (xy 419.3794 -341.038942) (xy 419.370584 -341.046541)
			(xy 419.360405 -341.067448) (xy 419.359842 -341.079074) (xy 419.359842 -341.15883) (xy 419.360363 -341.170465)
			(xy 419.370563 -341.191375) (xy 419.3794 -341.198962) (xy 419.401865 -341.217174) (xy 419.441602 -341.25919)
			(xy 419.474543 -341.30672) (xy 419.499934 -341.358677) (xy 419.517195 -341.413871) (xy 419.525928 -341.471037)
			(xy 419.526466 -341.499952) (xy 419.52598 -341.527203) (xy 419.518224 -341.581151) (xy 419.502869 -341.633446)
			(xy 419.480227 -341.683023) (xy 419.450761 -341.728873) (xy 419.41507 -341.770064) (xy 419.373879 -341.805755)
			(xy 419.328029 -341.835221) (xy 419.278452 -341.857863) (xy 419.226157 -341.873218) (xy 419.172209 -341.880974)
			(xy 419.117707 -341.880974) (xy 419.063759 -341.873218) (xy 419.011464 -341.857863) (xy 418.961887 -341.835221)
			(xy 418.916037 -341.805755) (xy 418.874846 -341.770064) (xy 418.839155 -341.728873) (xy 418.809689 -341.683023)
			(xy 418.787047 -341.633446) (xy 418.771692 -341.581151) (xy 418.763936 -341.527203) (xy 418.76345 -341.499952)
			(xy 417.367466 -341.499952) (xy 417.36698 -341.527203) (xy 417.359224 -341.581151) (xy 417.343869 -341.633446)
			(xy 417.321227 -341.683023) (xy 417.291761 -341.728873) (xy 417.25607 -341.770064) (xy 417.214879 -341.805755)
			(xy 417.169029 -341.835221) (xy 417.119452 -341.857863) (xy 417.067157 -341.873218) (xy 417.013209 -341.880974)
			(xy 416.958707 -341.880974) (xy 416.904759 -341.873218) (xy 416.852464 -341.857863) (xy 416.802887 -341.835221)
			(xy 416.757037 -341.805755) (xy 416.715846 -341.770064) (xy 416.680155 -341.728873) (xy 416.650689 -341.683023)
			(xy 416.628047 -341.633446) (xy 416.612692 -341.581151) (xy 416.604936 -341.527203) (xy 416.60445 -341.499952)
			(xy 415.280348 -341.499952) (xy 415.280348 -342.359742) (xy 415.280739 -342.369815) (xy 415.288482 -342.388414)
			(xy 415.295334 -342.39581) (xy 418.340286 -345.440762) (xy 418.35751 -345.45887) (xy 418.38525 -345.500431)
			(xy 418.404356 -345.546601) (xy 418.414097 -345.59561) (xy 418.414708 -345.620594) (xy 418.414708 -352.769678)
			(xy 419.579552 -352.769678) (xy 419.580029 -352.741732) (xy 419.588198 -352.686439) (xy 419.604344 -352.632929)
			(xy 419.628122 -352.582347) (xy 419.659023 -352.535773) (xy 419.677342 -352.514662) (xy 419.68326 -352.5075)
			(xy 419.689897 -352.490163) (xy 419.690296 -352.48088) (xy 419.690296 -352.40341) (xy 419.683692 -352.386138)
			(xy 419.677342 -352.379026) (xy 419.65905 -352.357926) (xy 419.628163 -352.311405) (xy 419.60439 -352.260877)
			(xy 419.588241 -352.207422) (xy 419.580059 -352.152184) (xy 419.579552 -352.124264) (xy 419.579552 -351.73412)
			(xy 419.580157 -351.704143) (xy 419.589544 -351.644929) (xy 419.608076 -351.587911) (xy 419.635295 -351.534492)
			(xy 419.670533 -351.485987) (xy 419.691312 -351.464372) (xy 419.796214 -351.359724) (xy 419.803038 -351.352311)
			(xy 419.810766 -351.333722) (xy 419.8112 -351.323656) (xy 419.8112 -348.672404) (xy 419.811783 -348.642485)
			(xy 419.821152 -348.583385) (xy 419.839645 -348.526476) (xy 419.866807 -348.473157) (xy 419.90197 -348.42474)
			(xy 419.922706 -348.403164) (xy 420.211758 -348.114366) (xy 420.2186 -348.106967) (xy 420.22632 -348.088367)
			(xy 420.226744 -348.078298) (xy 420.226744 -346.522802) (xy 420.227313 -346.492882) (xy 420.236684 -346.433781)
			(xy 420.255179 -346.376871) (xy 420.282345 -346.323553) (xy 420.317512 -346.275137) (xy 420.33825 -346.253562)
			(xy 420.84625 -345.745562) (xy 420.867837 -345.724841) (xy 420.916262 -345.689699) (xy 420.96958 -345.662547)
			(xy 421.026482 -345.644051) (xy 421.085574 -345.634663) (xy 421.11549 -345.634056) (xy 427.930818 -345.634056)
			(xy 427.960738 -345.634609) (xy 428.019841 -345.643983) (xy 428.076751 -345.662482) (xy 428.130069 -345.689651)
			(xy 428.178484 -345.724822) (xy 428.200058 -345.745562) (xy 429.224186 -346.76969) (xy 429.244934 -346.791251)
			(xy 429.280071 -346.839685) (xy 429.307217 -346.893009) (xy 429.325707 -346.949916) (xy 429.335088 -347.009012)
			(xy 429.335692 -347.03893) (xy 429.335692 -348.21368) (xy 429.335101 -348.243599) (xy 429.325734 -348.302699)
			(xy 429.307243 -348.359608) (xy 429.280083 -348.412927) (xy 429.244921 -348.461344) (xy 429.224186 -348.48292)
			(xy 428.741078 -348.965774) (xy 428.734254 -348.973186) (xy 428.726525 -348.991776) (xy 428.726092 -349.001842)
			(xy 428.726092 -352.093022) (xy 428.725528 -352.122942) (xy 428.716154 -352.182043) (xy 428.697657 -352.238953)
			(xy 428.670491 -352.292271) (xy 428.635323 -352.340686) (xy 428.614586 -352.362262) (xy 428.557436 -352.419412)
			(xy 428.556674 -352.420174) (xy 428.54973 -352.427601) (xy 428.541876 -352.446338) (xy 428.541434 -352.456496)
			(xy 428.541434 -352.488246) (xy 428.541879 -352.498313) (xy 428.549585 -352.516912) (xy 428.55642 -352.524314)
			(xy 428.577436 -352.545906) (xy 428.612998 -352.594544) (xy 428.640472 -352.648169) (xy 428.659171 -352.705446)
			(xy 428.668633 -352.764952) (xy 428.669196 -352.795078) (xy 428.66871 -352.822329) (xy 428.660954 -352.876277)
			(xy 428.645599 -352.928572) (xy 428.622957 -352.978149) (xy 428.593491 -353.023999) (xy 428.5578 -353.06519)
			(xy 428.516609 -353.100881) (xy 428.473477 -353.1286) (xy 432.288439 -353.1286) (xy 432.292607 -353.072986)
			(xy 432.305016 -353.018615) (xy 432.32539 -352.9667) (xy 432.353273 -352.918401) (xy 432.388044 -352.874798)
			(xy 432.428924 -352.836863) (xy 432.475001 -352.805444) (xy 432.525246 -352.781244) (xy 432.578537 -352.764802)
			(xy 432.633683 -352.756485) (xy 432.661568 -352.755962) (xy 432.687991 -352.756389) (xy 432.740307 -352.763848)
			(xy 432.791046 -352.778621) (xy 432.83919 -352.800411) (xy 432.883773 -352.828782) (xy 432.904138 -352.845624)
			(xy 432.910996 -352.851466) (xy 432.928014 -352.857816) (xy 433.012342 -352.857816) (xy 433.02936 -352.851466)
			(xy 433.036218 -352.845624) (xy 433.056584 -352.828785) (xy 433.10117 -352.80042) (xy 433.149314 -352.778633)
			(xy 433.200051 -352.763862) (xy 433.252366 -352.756402) (xy 433.30521 -352.756402) (xy 433.357525 -352.763862)
			(xy 433.408262 -352.778633) (xy 433.456406 -352.80042) (xy 433.500992 -352.828785) (xy 433.521358 -352.845624)
			(xy 433.528216 -352.851466) (xy 433.545234 -352.857816) (xy 433.629562 -352.857816) (xy 433.64658 -352.851466)
			(xy 433.653438 -352.845624) (xy 433.66733 -352.834037) (xy 433.696974 -352.813302) (xy 433.71262 -352.804222)
			(xy 433.72246 -352.798068) (xy 433.735679 -352.779015) (xy 433.73802 -352.767646) (xy 433.751482 -352.67646)
			(xy 433.744624 -352.654362) (xy 433.736496 -352.645726) (xy 433.716915 -352.624343) (xy 433.683797 -352.576757)
			(xy 433.658266 -352.524705) (xy 433.640912 -352.469387) (xy 433.632134 -352.412078) (xy 433.631594 -352.38309)
			(xy 433.632124 -352.355518) (xy 433.640063 -352.300948) (xy 433.655776 -352.248089) (xy 433.678934 -352.198043)
			(xy 433.709055 -352.151852) (xy 433.745512 -352.110478) (xy 433.766214 -352.09226) (xy 433.77431 -352.084723)
			(xy 433.783652 -352.064698) (xy 433.784248 -352.053652) (xy 433.784248 -351.975928) (xy 433.783681 -351.964878)
			(xy 433.774317 -351.944856) (xy 433.766214 -351.93732) (xy 433.745512 -351.919099) (xy 433.709041 -351.877732)
			(xy 433.678907 -351.831545) (xy 433.655739 -351.781499) (xy 433.640021 -351.728638) (xy 433.63208 -351.674064)
			(xy 433.631594 -351.64649) (xy 433.63208 -351.619239) (xy 433.639836 -351.565291) (xy 433.655191 -351.512996)
			(xy 433.677833 -351.463419) (xy 433.707299 -351.417569) (xy 433.74299 -351.376378) (xy 433.784181 -351.340687)
			(xy 433.830031 -351.311221) (xy 433.879608 -351.288579) (xy 433.931903 -351.273224) (xy 433.985851 -351.265468)
			(xy 434.040353 -351.265468) (xy 434.094301 -351.273224) (xy 434.146596 -351.288579) (xy 434.196173 -351.311221)
			(xy 434.242023 -351.340687) (xy 434.283214 -351.376378) (xy 434.318905 -351.417569) (xy 434.348371 -351.463419)
			(xy 434.371013 -351.512996) (xy 434.386368 -351.565291) (xy 434.394124 -351.619239) (xy 434.39461 -351.64649)
			(xy 434.394134 -351.674064) (xy 434.386183 -351.728636) (xy 434.37046 -351.781496) (xy 434.347292 -351.831542)
			(xy 434.317161 -351.877732) (xy 434.280696 -351.919104) (xy 434.25999 -351.93732) (xy 434.251904 -351.944865)
			(xy 434.242556 -351.964884) (xy 434.241956 -351.975928) (xy 434.241956 -352.053652) (xy 434.242533 -352.064701)
			(xy 434.25189 -352.084723) (xy 434.25999 -352.09226) (xy 434.280683 -352.110491) (xy 434.317155 -352.151855)
			(xy 434.34729 -352.198041) (xy 434.370459 -352.248085) (xy 434.386179 -352.300944) (xy 434.394123 -352.355516)
			(xy 434.39461 -352.38309) (xy 434.394033 -352.412282) (xy 434.385126 -352.469981) (xy 434.367534 -352.525651)
			(xy 434.341667 -352.577991) (xy 434.308129 -352.625781) (xy 434.267703 -352.667904) (xy 434.221332 -352.703377)
			(xy 434.195982 -352.717862) (xy 434.186054 -352.723917) (xy 434.172559 -352.742825) (xy 434.170074 -352.754184)
			(xy 434.155088 -352.845116) (xy 434.161946 -352.867214) (xy 434.16982 -352.87585) (xy 434.18828 -352.896625)
			(xy 434.219491 -352.942607) (xy 434.243527 -352.992715) (xy 434.259854 -353.045836) (xy 434.268111 -353.100793)
			(xy 434.268626 -353.12858) (xy 434.268147 -353.155197) (xy 434.260574 -353.207889) (xy 434.245579 -353.258968)
			(xy 434.223467 -353.307392) (xy 434.194688 -353.352176) (xy 434.159829 -353.392409) (xy 434.119599 -353.427271)
			(xy 434.074817 -353.456053) (xy 434.026394 -353.478169) (xy 433.975317 -353.493168) (xy 433.922625 -353.500745)
			(xy 433.896008 -353.501198) (xy 433.869586 -353.500736) (xy 433.817271 -353.493287) (xy 433.766532 -353.478523)
			(xy 433.718388 -353.45674) (xy 433.673803 -353.428375) (xy 433.653438 -353.411536) (xy 433.64658 -353.405694)
			(xy 433.629562 -353.399344) (xy 433.545234 -353.399344) (xy 433.528216 -353.405694) (xy 433.521358 -353.411536)
			(xy 433.500992 -353.428375) (xy 433.456406 -353.45674) (xy 433.408262 -353.478527) (xy 433.357525 -353.493298)
			(xy 433.30521 -353.500758) (xy 433.252366 -353.500758) (xy 433.200051 -353.493298) (xy 433.149314 -353.478527)
			(xy 433.10117 -353.45674) (xy 433.056584 -353.428375) (xy 433.036218 -353.411536) (xy 433.02936 -353.405694)
			(xy 433.012342 -353.399344) (xy 432.928014 -353.399344) (xy 432.910996 -353.405694) (xy 432.904138 -353.411536)
			(xy 432.883751 -353.428346) (xy 432.839168 -353.456708) (xy 432.791029 -353.478494) (xy 432.740297 -353.493268)
			(xy 432.687988 -353.500734) (xy 432.661568 -353.501198) (xy 432.633683 -353.500715) (xy 432.578537 -353.492398)
			(xy 432.525246 -353.475956) (xy 432.475001 -353.451756) (xy 432.428924 -353.420337) (xy 432.388044 -353.382402)
			(xy 432.353273 -353.338799) (xy 432.32539 -353.2905) (xy 432.305016 -353.238585) (xy 432.292607 -353.184214)
			(xy 432.288439 -353.1286) (xy 428.473477 -353.1286) (xy 428.470759 -353.130347) (xy 428.421182 -353.152989)
			(xy 428.368887 -353.168344) (xy 428.314939 -353.1761) (xy 428.260437 -353.1761) (xy 428.206489 -353.168344)
			(xy 428.154194 -353.152989) (xy 428.104617 -353.130347) (xy 428.058767 -353.100881) (xy 428.017576 -353.06519)
			(xy 427.981885 -353.023999) (xy 427.952419 -352.978149) (xy 427.929777 -352.928572) (xy 427.914422 -352.876277)
			(xy 427.906666 -352.822329) (xy 427.90618 -352.795078) (xy 427.906675 -352.767133) (xy 427.914843 -352.711842)
			(xy 427.930986 -352.658333) (xy 427.954759 -352.60775) (xy 427.985654 -352.561174) (xy 428.00397 -352.540062)
			(xy 428.009879 -352.532893) (xy 428.016524 -352.515562) (xy 428.016924 -352.50628) (xy 428.016924 -352.42881)
			(xy 428.01032 -352.411538) (xy 428.00397 -352.404426) (xy 427.985683 -352.383322) (xy 427.954794 -352.336802)
			(xy 427.93102 -352.286276) (xy 427.914869 -352.232822) (xy 427.906687 -352.177584) (xy 427.90618 -352.149664)
			(xy 427.906563 -352.124831) (xy 427.913022 -352.075586) (xy 427.925813 -352.027595) (xy 427.94472 -351.981668)
			(xy 427.956726 -351.959926) (xy 427.959887 -351.954124) (xy 427.963362 -351.941383) (xy 427.963584 -351.93478)
			(xy 427.963584 -348.822264) (xy 427.964209 -348.792347) (xy 427.973569 -348.733248) (xy 427.992052 -348.67634)
			(xy 428.019205 -348.623021) (xy 428.054359 -348.574602) (xy 428.07509 -348.553024) (xy 428.558198 -348.07017)
			(xy 428.565043 -348.062774) (xy 428.57276 -348.044172) (xy 428.573184 -348.034102) (xy 428.573184 -347.218508)
			(xy 428.572759 -347.208439) (xy 428.565038 -347.189841) (xy 428.558198 -347.18244) (xy 427.787308 -346.41155)
			(xy 427.779893 -346.404728) (xy 427.761306 -346.396996) (xy 427.75124 -346.396564) (xy 421.295068 -346.396564)
			(xy 421.284995 -346.396956) (xy 421.266396 -346.404698) (xy 421.259 -346.41155) (xy 421.004238 -346.666312)
			(xy 420.997406 -346.673718) (xy 420.98968 -346.692313) (xy 420.989252 -346.70238) (xy 420.989252 -348.257876)
			(xy 420.98867 -348.287795) (xy 420.979303 -348.346896) (xy 420.96081 -348.403806) (xy 420.933648 -348.457125)
			(xy 420.898483 -348.505541) (xy 420.877746 -348.527116) (xy 420.588694 -348.815914) (xy 420.581855 -348.823315)
			(xy 420.574135 -348.841913) (xy 420.573708 -348.851982) (xy 420.573708 -351.503234) (xy 420.573084 -351.533151)
			(xy 420.563724 -351.59225) (xy 420.545241 -351.649158) (xy 420.518088 -351.702478) (xy 420.482934 -351.750896)
			(xy 420.462202 -351.772474) (xy 420.357554 -351.877122) (xy 420.350705 -351.884515) (xy 420.342992 -351.90312)
			(xy 420.342568 -351.91319) (xy 420.342568 -352.124264) (xy 420.342062 -352.152184) (xy 420.333873 -352.207421)
			(xy 420.317723 -352.260876) (xy 420.293956 -352.311406) (xy 420.26308 -352.357935) (xy 420.244778 -352.379026)
			(xy 420.238867 -352.386193) (xy 420.232225 -352.403526) (xy 420.231824 -352.412808) (xy 420.231824 -352.490278)
			(xy 420.238428 -352.50755) (xy 420.244778 -352.514662) (xy 420.263114 -352.535759) (xy 420.294022 -352.582331)
			(xy 420.317798 -352.632917) (xy 420.333934 -352.686433) (xy 420.342084 -352.74173) (xy 420.342568 -352.769678)
			(xy 420.342082 -352.796929) (xy 420.334326 -352.850877) (xy 420.318971 -352.903172) (xy 420.296329 -352.952749)
			(xy 420.266863 -352.998599) (xy 420.231172 -353.03979) (xy 420.189981 -353.075481) (xy 420.146849 -353.1032)
			(xy 423.961713 -353.1032) (xy 423.965882 -353.047576) (xy 423.978295 -352.993194) (xy 423.998676 -352.94127)
			(xy 424.026567 -352.892964) (xy 424.061348 -352.849355) (xy 424.10224 -352.811417) (xy 424.14833 -352.779998)
			(xy 424.198588 -352.755799) (xy 424.251892 -352.739362) (xy 424.30705 -352.731054) (xy 424.33494 -352.730562)
			(xy 424.361362 -352.731005) (xy 424.413678 -352.73846) (xy 424.464416 -352.753229) (xy 424.51256 -352.775016)
			(xy 424.557145 -352.803384) (xy 424.57751 -352.820224) (xy 424.584368 -352.826066) (xy 424.601386 -352.832416)
			(xy 424.685714 -352.832416) (xy 424.702732 -352.826066) (xy 424.70959 -352.820224) (xy 424.729956 -352.803385)
			(xy 424.774542 -352.77502) (xy 424.822686 -352.753233) (xy 424.873423 -352.738462) (xy 424.925738 -352.731002)
			(xy 424.978582 -352.731002) (xy 425.030897 -352.738462) (xy 425.081634 -352.753233) (xy 425.129778 -352.77502)
			(xy 425.174364 -352.803385) (xy 425.19473 -352.820224) (xy 425.201588 -352.826066) (xy 425.218606 -352.832416)
			(xy 425.302934 -352.832416) (xy 425.319952 -352.826066) (xy 425.32681 -352.820224) (xy 425.340704 -352.80864)
			(xy 425.370347 -352.787903) (xy 425.385992 -352.778822) (xy 425.395827 -352.77266) (xy 425.409049 -352.753613)
			(xy 425.411392 -352.742246) (xy 425.424854 -352.65106) (xy 425.417996 -352.628962) (xy 425.409868 -352.620326)
			(xy 425.390283 -352.598948) (xy 425.357166 -352.55136) (xy 425.331637 -352.499306) (xy 425.314283 -352.443987)
			(xy 425.305506 -352.386678) (xy 425.304966 -352.35769) (xy 425.305471 -352.330117) (xy 425.313412 -352.275545)
			(xy 425.329128 -352.222684) (xy 425.352291 -352.172638) (xy 425.382418 -352.126448) (xy 425.418881 -352.085076)
			(xy 425.439586 -352.06686) (xy 425.447677 -352.059319) (xy 425.457023 -352.039297) (xy 425.45762 -352.028252)
			(xy 425.45762 -351.950528) (xy 425.457062 -351.939477) (xy 425.447692 -351.919454) (xy 425.439586 -351.91192)
			(xy 425.418879 -351.893705) (xy 425.382409 -351.852337) (xy 425.352276 -351.806147) (xy 425.32911 -351.7561)
			(xy 425.313393 -351.703239) (xy 425.305452 -351.648664) (xy 425.304966 -351.62109) (xy 425.305452 -351.593839)
			(xy 425.313208 -351.539891) (xy 425.328563 -351.487596) (xy 425.351205 -351.438019) (xy 425.380671 -351.392169)
			(xy 425.416362 -351.350978) (xy 425.457553 -351.315287) (xy 425.503403 -351.285821) (xy 425.55298 -351.263179)
			(xy 425.605275 -351.247824) (xy 425.659223 -351.240068) (xy 425.713725 -351.240068) (xy 425.767673 -351.247824)
			(xy 425.819968 -351.263179) (xy 425.869545 -351.285821) (xy 425.915395 -351.315287) (xy 425.956586 -351.350978)
			(xy 425.992277 -351.392169) (xy 426.021743 -351.438019) (xy 426.044385 -351.487596) (xy 426.05974 -351.539891)
			(xy 426.067496 -351.593839) (xy 426.067982 -351.62109) (xy 426.067516 -351.648665) (xy 426.059564 -351.703238)
			(xy 426.04384 -351.756098) (xy 426.02067 -351.806144) (xy 425.990537 -351.852333) (xy 425.954069 -351.893704)
			(xy 425.933362 -351.91192) (xy 425.925271 -351.919461) (xy 425.915927 -351.939483) (xy 425.915328 -351.950528)
			(xy 425.915328 -352.028252) (xy 425.915914 -352.039299) (xy 425.925266 -352.059321) (xy 425.933362 -352.06686)
			(xy 425.954049 -352.085097) (xy 425.990523 -352.126459) (xy 426.020659 -352.172644) (xy 426.043829 -352.222687)
			(xy 426.05955 -352.275545) (xy 426.067495 -352.330117) (xy 426.067982 -352.35769) (xy 426.06742 -352.386882)
			(xy 426.058512 -352.444583) (xy 426.040918 -352.500254) (xy 426.015049 -352.552595) (xy 425.981509 -352.600384)
			(xy 425.94108 -352.642507) (xy 425.894706 -352.677978) (xy 425.869354 -352.692462) (xy 425.859421 -352.698509)
			(xy 425.84593 -352.717423) (xy 425.843446 -352.728784) (xy 425.82846 -352.819716) (xy 425.835318 -352.841814)
			(xy 425.843192 -352.85045) (xy 425.861647 -352.871229) (xy 425.89286 -352.91721) (xy 425.916897 -352.967316)
			(xy 425.933226 -353.020437) (xy 425.941483 -353.075393) (xy 425.941998 -353.10318) (xy 425.941547 -353.129798)
			(xy 425.933973 -353.182493) (xy 425.918976 -353.233574) (xy 425.896862 -353.282) (xy 425.868081 -353.326785)
			(xy 425.833219 -353.367019) (xy 425.792985 -353.401881) (xy 425.7482 -353.430662) (xy 425.699774 -353.452776)
			(xy 425.648693 -353.467773) (xy 425.595998 -353.475347) (xy 425.56938 -353.475798) (xy 425.542958 -353.475352)
			(xy 425.490642 -353.4679) (xy 425.439903 -353.453132) (xy 425.391759 -353.431345) (xy 425.347175 -353.402977)
			(xy 425.32681 -353.386136) (xy 425.319952 -353.380294) (xy 425.302934 -353.373944) (xy 425.218606 -353.373944)
			(xy 425.201588 -353.380294) (xy 425.19473 -353.386136) (xy 425.174364 -353.402975) (xy 425.129778 -353.43134)
			(xy 425.081634 -353.453127) (xy 425.030897 -353.467898) (xy 424.978582 -353.475358) (xy 424.925738 -353.475358)
			(xy 424.873423 -353.467898) (xy 424.822686 -353.453127) (xy 424.774542 -353.43134) (xy 424.729956 -353.402975)
			(xy 424.70959 -353.386136) (xy 424.702732 -353.380294) (xy 424.685714 -353.373944) (xy 424.601386 -353.373944)
			(xy 424.584368 -353.380294) (xy 424.57751 -353.386136) (xy 424.557133 -353.40296) (xy 424.512547 -353.431319)
			(xy 424.464405 -353.453102) (xy 424.413671 -353.467873) (xy 424.36136 -353.475336) (xy 424.33494 -353.475798)
			(xy 424.30705 -353.475346) (xy 424.251892 -353.467038) (xy 424.198588 -353.450601) (xy 424.14833 -353.426402)
			(xy 424.10224 -353.394983) (xy 424.061348 -353.357045) (xy 424.026567 -353.313436) (xy 423.998676 -353.26513)
			(xy 423.978295 -353.213206) (xy 423.965882 -353.158824) (xy 423.961713 -353.1032) (xy 420.146849 -353.1032)
			(xy 420.144131 -353.104947) (xy 420.094554 -353.127589) (xy 420.042259 -353.142944) (xy 419.988311 -353.1507)
			(xy 419.933809 -353.1507) (xy 419.879861 -353.142944) (xy 419.827566 -353.127589) (xy 419.777989 -353.104947)
			(xy 419.732139 -353.075481) (xy 419.690948 -353.03979) (xy 419.655257 -352.998599) (xy 419.625791 -352.952749)
			(xy 419.603149 -352.903172) (xy 419.587794 -352.850877) (xy 419.580038 -352.796929) (xy 419.579552 -352.769678)
			(xy 418.414708 -352.769678) (xy 418.414708 -354.001324) (xy 420.537384 -354.001324) (xy 420.541455 -353.945702)
			(xy 420.553581 -353.891265) (xy 420.573504 -353.839174) (xy 420.6008 -353.790539) (xy 420.634886 -353.746396)
			(xy 420.675035 -353.707687) (xy 420.720393 -353.675236) (xy 420.769993 -353.649735) (xy 420.822777 -353.631728)
			(xy 420.87762 -353.621598) (xy 420.933354 -353.619561) (xy 420.988791 -353.625661) (xy 421.042748 -353.639767)
			(xy 421.094077 -353.661579) (xy 421.141683 -353.690633) (xy 421.184551 -353.726308) (xy 421.221768 -353.767845)
			(xy 421.252541 -353.814358) (xy 421.276213 -353.864855) (xy 421.292281 -353.918262) (xy 421.300401 -353.973438)
			(xy 421.30091 -354.001324) (xy 421.300401 -354.02921) (xy 421.292281 -354.084386) (xy 421.276213 -354.137793)
			(xy 421.252541 -354.18829) (xy 421.221768 -354.234803) (xy 421.184551 -354.27634) (xy 421.141683 -354.312015)
			(xy 421.094077 -354.341069) (xy 421.042748 -354.362881) (xy 420.988791 -354.376987) (xy 420.933354 -354.383087)
			(xy 420.87762 -354.38105) (xy 420.822777 -354.37092) (xy 420.769993 -354.352913) (xy 420.720393 -354.327412)
			(xy 420.675035 -354.294961) (xy 420.634886 -354.256252) (xy 420.6008 -354.212109) (xy 420.573504 -354.163474)
			(xy 420.553581 -354.111383) (xy 420.541455 -354.056946) (xy 420.537384 -354.001324) (xy 418.414708 -354.001324)
			(xy 418.414708 -354.474018) (xy 418.415238 -354.484548) (xy 418.423719 -354.503828) (xy 418.439212 -354.518098)
			(xy 418.448998 -354.522024) (xy 418.55517 -354.5586) (xy 418.586158 -354.54971) (xy 418.596318 -354.536756)
			(xy 418.61451 -354.514488) (xy 418.656443 -354.475146) (xy 418.703808 -354.442546) (xy 418.755532 -354.417429)
			(xy 418.81044 -354.400362) (xy 418.867288 -354.391734) (xy 418.896038 -354.391214) (xy 418.923289 -354.391658)
			(xy 418.977236 -354.39942) (xy 419.029529 -354.414779) (xy 419.079104 -354.437424) (xy 419.124953 -354.466893)
			(xy 419.166141 -354.502586) (xy 419.20183 -354.543778) (xy 419.231295 -354.589629) (xy 419.253934 -354.639207)
			(xy 419.269288 -354.691501) (xy 419.277044 -354.745449) (xy 419.277044 -354.799951) (xy 419.269288 -354.853899)
			(xy 419.256729 -354.896674) (xy 419.958264 -354.896674) (xy 419.962335 -354.841052) (xy 419.974461 -354.786615)
			(xy 419.994384 -354.734524) (xy 420.02168 -354.685889) (xy 420.055766 -354.641746) (xy 420.095915 -354.603037)
			(xy 420.141273 -354.570586) (xy 420.190873 -354.545085) (xy 420.243657 -354.527078) (xy 420.2985 -354.516948)
			(xy 420.354234 -354.514911) (xy 420.409671 -354.521011) (xy 420.463628 -354.535117) (xy 420.514957 -354.556929)
			(xy 420.562563 -354.585983) (xy 420.605431 -354.621658) (xy 420.642648 -354.663195) (xy 420.673421 -354.709708)
			(xy 420.697093 -354.760205) (xy 420.713161 -354.813612) (xy 420.721281 -354.868788) (xy 420.72179 -354.896674)
			(xy 420.721281 -354.92456) (xy 420.713161 -354.979736) (xy 420.697093 -355.033143) (xy 420.673421 -355.08364)
			(xy 420.642648 -355.130153) (xy 420.605431 -355.17169) (xy 420.562563 -355.207365) (xy 420.514957 -355.236419)
			(xy 420.463628 -355.258231) (xy 420.409671 -355.272337) (xy 420.354234 -355.278437) (xy 420.2985 -355.2764)
			(xy 420.243657 -355.26627) (xy 420.190873 -355.248263) (xy 420.141273 -355.222762) (xy 420.095915 -355.190311)
			(xy 420.055766 -355.151602) (xy 420.02168 -355.107459) (xy 419.994384 -355.058824) (xy 419.974461 -355.006733)
			(xy 419.962335 -354.952296) (xy 419.958264 -354.896674) (xy 419.256729 -354.896674) (xy 419.253934 -354.906193)
			(xy 419.231295 -354.955771) (xy 419.20183 -355.001622) (xy 419.166141 -355.042814) (xy 419.124953 -355.078507)
			(xy 419.079104 -355.107976) (xy 419.029529 -355.130621) (xy 418.977236 -355.14598) (xy 418.923289 -355.153742)
			(xy 418.896038 -355.15423) (xy 418.867291 -355.153692) (xy 418.81045 -355.145045) (xy 418.755549 -355.127972)
			(xy 418.703829 -355.102858) (xy 418.65646 -355.070271) (xy 418.614514 -355.03095) (xy 418.596318 -355.008688)
			(xy 418.586158 -354.995734) (xy 418.55517 -354.986844) (xy 418.448998 -355.02342) (xy 418.439206 -355.027341)
			(xy 418.423695 -355.041599) (xy 418.415231 -355.060892) (xy 418.414708 -355.071426) (xy 418.414708 -355.572314)
			(xy 421.2971 -355.572314) (xy 421.297595 -355.54484) (xy 421.305484 -355.49046) (xy 421.321103 -355.437778)
			(xy 421.344125 -355.387885) (xy 421.374075 -355.341816) (xy 421.391842 -355.320854) (xy 421.392096 -355.3206)
			(xy 421.397688 -355.313517) (xy 421.403932 -355.296598) (xy 421.404288 -355.28758) (xy 421.404288 -355.220016)
			(xy 421.403926 -355.211) (xy 421.397682 -355.194082) (xy 421.392096 -355.186996) (xy 421.391588 -355.186488)
			(xy 421.373851 -355.165545) (xy 421.343969 -355.119511) (xy 421.321004 -355.069665) (xy 421.30543 -355.017039)
			(xy 421.29757 -354.962723) (xy 421.2971 -354.935282) (xy 421.297586 -354.908031) (xy 421.305342 -354.854083)
			(xy 421.320697 -354.801788) (xy 421.343339 -354.752211) (xy 421.372805 -354.706361) (xy 421.408496 -354.66517)
			(xy 421.449687 -354.629479) (xy 421.495537 -354.600013) (xy 421.545114 -354.577371) (xy 421.597409 -354.562016)
			(xy 421.651357 -354.55426) (xy 421.705859 -354.55426) (xy 421.759807 -354.562016) (xy 421.812102 -354.577371)
			(xy 421.861679 -354.600013) (xy 421.907529 -354.629479) (xy 421.94872 -354.66517) (xy 421.984411 -354.706361)
			(xy 422.013877 -354.752211) (xy 422.036519 -354.801788) (xy 422.051874 -354.854083) (xy 422.05963 -354.908031)
			(xy 422.060116 -354.935282) (xy 422.059615 -354.962756) (xy 422.051726 -355.017135) (xy 422.036109 -355.069817)
			(xy 422.013088 -355.11971) (xy 421.98314 -355.165779) (xy 421.965374 -355.186742) (xy 421.96512 -355.186996)
			(xy 421.95952 -355.194073) (xy 421.953283 -355.210997) (xy 421.952928 -355.220016) (xy 421.952928 -355.28758)
			(xy 421.953289 -355.296597) (xy 421.959533 -355.313514) (xy 421.96512 -355.3206) (xy 421.965628 -355.321108)
			(xy 421.98335 -355.342064) (xy 422.013237 -355.388093) (xy 422.036206 -355.437935) (xy 422.051783 -355.490559)
			(xy 422.059645 -355.544874) (xy 422.060116 -355.572314) (xy 422.05963 -355.599565) (xy 422.051874 -355.653513)
			(xy 422.036519 -355.705808) (xy 422.013877 -355.755385) (xy 421.984411 -355.801235) (xy 421.94872 -355.842426)
			(xy 421.907529 -355.878117) (xy 421.861679 -355.907583) (xy 421.812102 -355.930225) (xy 421.759807 -355.94558)
			(xy 421.705859 -355.953336) (xy 421.651357 -355.953336) (xy 421.597409 -355.94558) (xy 421.545114 -355.930225)
			(xy 421.495537 -355.907583) (xy 421.449687 -355.878117) (xy 421.408496 -355.842426) (xy 421.372805 -355.801235)
			(xy 421.343339 -355.755385) (xy 421.320697 -355.705808) (xy 421.305342 -355.653513) (xy 421.297586 -355.599565)
			(xy 421.2971 -355.572314) (xy 418.414708 -355.572314) (xy 418.414708 -356.446074) (xy 418.414135 -356.47106)
			(xy 418.404382 -356.52007) (xy 418.385263 -356.56624) (xy 418.357513 -356.607798) (xy 418.340286 -356.625906)
			(xy 417.789106 -357.177086) (xy 417.784788 -357.181404) (xy 417.776406 -357.189278) (xy 417.768532 -357.21036)
			(xy 417.775644 -357.311706) (xy 417.78682 -357.331264) (xy 417.796218 -357.337868) (xy 417.817254 -357.353268)
			(xy 417.855372 -357.388835) (xy 417.888288 -357.429263) (xy 417.915388 -357.473799) (xy 417.936167 -357.521613)
			(xy 417.950238 -357.571811) (xy 417.957338 -357.623459) (xy 417.957762 -357.649526) (xy 417.957369 -357.676782)
			(xy 417.949607 -357.730738) (xy 417.934246 -357.78304) (xy 417.911597 -357.832623) (xy 417.882122 -357.878478)
			(xy 417.846421 -357.919672) (xy 417.80522 -357.955365) (xy 417.75936 -357.984831) (xy 417.709772 -358.007471)
			(xy 417.657467 -358.022823) (xy 417.60351 -358.030574) (xy 417.576254 -358.031034) (xy 417.549014 -358.030566)
			(xy 417.49509 -358.02281) (xy 417.442816 -358.007464) (xy 417.393258 -357.984838) (xy 417.347421 -357.955392)
			(xy 417.306239 -357.919727) (xy 417.270548 -357.878567) (xy 417.241075 -357.832748) (xy 417.218418 -357.783203)
			(xy 417.203039 -357.730939) (xy 417.195251 -357.677019) (xy 417.194746 -357.64978) (xy 417.194746 -357.649272)
			(xy 417.195 -357.63327) (xy 417.195762 -357.619046) (xy 417.182046 -357.5939) (xy 417.078668 -357.535226)
			(xy 417.05022 -357.535988) (xy 417.038282 -357.543862) (xy 417.014993 -357.558385) (xy 416.965141 -357.58134)
			(xy 416.912517 -357.596928) (xy 416.858205 -357.60483) (xy 416.830764 -357.60533) (xy 416.83051 -357.60533)
			(xy 416.80326 -357.604812) (xy 416.749315 -357.597058) (xy 416.697022 -357.581705) (xy 416.647446 -357.559067)
			(xy 416.601597 -357.529604) (xy 416.560407 -357.493916) (xy 416.524716 -357.452729) (xy 416.495249 -357.406882)
			(xy 416.472606 -357.357308) (xy 416.457249 -357.305017) (xy 416.44949 -357.251072) (xy 416.449002 -357.223822)
			(xy 416.449535 -357.194906) (xy 416.458261 -357.137735) (xy 416.475516 -357.082537) (xy 416.500905 -357.030575)
			(xy 416.533846 -356.983041) (xy 416.573584 -356.941023) (xy 416.596068 -356.922832) (xy 416.604862 -356.915213)
			(xy 416.61505 -356.894321) (xy 416.615626 -356.8827) (xy 416.615626 -356.802944) (xy 416.615131 -356.791306)
			(xy 416.604914 -356.770395) (xy 416.596068 -356.762812) (xy 416.573584 -356.744622) (xy 416.53385 -356.702601)
			(xy 416.500912 -356.655066) (xy 416.475524 -356.603104) (xy 416.458268 -356.547907) (xy 416.449538 -356.490738)
			(xy 416.449002 -356.461822) (xy 416.449476 -356.434569) (xy 416.45723 -356.380618) (xy 416.472584 -356.32832)
			(xy 416.495224 -356.278739) (xy 416.524691 -356.232885) (xy 416.560384 -356.191692) (xy 416.601576 -356.155998)
			(xy 416.647429 -356.12653) (xy 416.697009 -356.103888) (xy 416.749306 -356.088533) (xy 416.803257 -356.080777)
			(xy 416.83051 -356.080314) (xy 416.859485 -356.080829) (xy 416.916765 -356.089615) (xy 416.97206 -356.106954)
			(xy 417.024101 -356.132447) (xy 417.071694 -356.16551) (xy 417.113745 -356.205384) (xy 417.14929 -356.251152)
			(xy 417.177513 -356.301766) (xy 417.188142 -356.328726) (xy 417.19373 -356.343966) (xy 417.219638 -356.362)
			(xy 417.324794 -356.362) (xy 417.334866 -356.361598) (xy 417.353466 -356.353864) (xy 417.360862 -356.347014)
			(xy 417.510214 -356.197662) (xy 417.517065 -356.190271) (xy 417.524778 -356.171665) (xy 417.5252 -356.161594)
			(xy 417.5252 -345.905074) (xy 417.524815 -345.895) (xy 417.517069 -345.876401) (xy 417.510214 -345.869006)
			(xy 414.465262 -342.824054) (xy 414.448053 -342.805932) (xy 414.420309 -342.764377) (xy 414.401198 -342.718211)
			(xy 414.391453 -342.669205) (xy 414.39084 -342.644222) (xy 414.39084 -333.302102) (xy 414.390429 -333.292031)
			(xy 414.3827 -333.273432) (xy 414.375854 -333.266034) (xy 414.22701 -333.11719) (xy 414.219602 -333.110361)
			(xy 414.201009 -333.102635) (xy 414.190942 -333.102204) (xy 413.499046 -333.102204) (xy 413.488389 -333.102815)
			(xy 413.468915 -333.11148) (xy 413.454629 -333.1273) (xy 413.450786 -333.137256) (xy 413.441992 -333.162278)
			(xy 413.41847 -333.209813) (xy 413.388593 -333.253634) (xy 413.352936 -333.292895) (xy 413.312186 -333.32684)
			(xy 413.267127 -333.354815) (xy 413.218629 -333.376282) (xy 413.167626 -333.390826) (xy 413.1151 -333.398168)
			(xy 413.088582 -333.398622) (xy 413.061331 -333.398139) (xy 413.007384 -333.39038) (xy 412.95509 -333.375024)
			(xy 412.905514 -333.352381) (xy 412.859664 -333.322915) (xy 412.818474 -333.287223) (xy 412.782783 -333.246033)
			(xy 412.753317 -333.200183) (xy 412.730675 -333.150606) (xy 412.715319 -333.098312) (xy 412.707561 -333.044365)
			(xy 412.707074 -333.017114) (xy 410.187394 -333.017114) (xy 408.892248 -334.31226) (xy 408.875656 -334.328275)
			(xy 408.838615 -334.355742) (xy 408.797939 -334.377466) (xy 408.754511 -334.392974) (xy 408.731974 -334.397858)
			(xy 408.724608 -334.399382) (xy 408.718004 -334.402938) (xy 408.714671 -334.404742) (xy 408.708545 -334.409202)
			(xy 408.705812 -334.411828) (xy 406.294336 -336.823304) (xy 406.29163 -336.826155) (xy 406.287038 -336.832534)
			(xy 406.285192 -336.836004) (xy 406.282605 -336.84143) (xy 406.279773 -336.85311) (xy 406.279604 -336.859118)
			(xy 406.279604 -338.731606) (xy 408.156664 -338.731606) (xy 408.157118 -338.704235) (xy 408.164936 -338.650055)
			(xy 408.180427 -338.597551) (xy 408.203272 -338.547804) (xy 408.233001 -338.501839) (xy 408.250644 -338.480908)
			(xy 408.250898 -338.480654) (xy 408.256468 -338.473556) (xy 408.262725 -338.456648) (xy 408.26309 -338.447634)
			(xy 408.26309 -338.380578) (xy 408.262746 -338.37156) (xy 408.256489 -338.354643) (xy 408.250898 -338.347558)
			(xy 408.250644 -338.347558) (xy 408.250644 -338.347304) (xy 408.233 -338.326376) (xy 408.203288 -338.280402)
			(xy 408.180452 -338.230654) (xy 408.164962 -338.178152) (xy 408.157136 -338.123976) (xy 408.156664 -338.096606)
			(xy 408.15715 -338.069355) (xy 408.164906 -338.015407) (xy 408.180261 -337.963112) (xy 408.202903 -337.913535)
			(xy 408.232369 -337.867685) (xy 408.26806 -337.826494) (xy 408.309251 -337.790803) (xy 408.355101 -337.761337)
			(xy 408.404678 -337.738695) (xy 408.456973 -337.72334) (xy 408.510921 -337.715584) (xy 408.565423 -337.715584)
			(xy 408.619371 -337.72334) (xy 408.671666 -337.738695) (xy 408.721243 -337.761337) (xy 408.767093 -337.790803)
			(xy 408.808284 -337.826494) (xy 408.843975 -337.867685) (xy 408.873441 -337.913535) (xy 408.896083 -337.963112)
			(xy 408.911438 -338.015407) (xy 408.919194 -338.069355) (xy 408.91968 -338.096606) (xy 408.919222 -338.123977)
			(xy 408.911403 -338.178156) (xy 408.895912 -338.23066) (xy 408.873069 -338.280406) (xy 408.843342 -338.326373)
			(xy 408.8257 -338.347304) (xy 408.825446 -338.347558) (xy 408.819864 -338.354648) (xy 408.813616 -338.371562)
			(xy 408.813254 -338.380578) (xy 408.813254 -338.447634) (xy 408.813583 -338.456654) (xy 408.819849 -338.473571)
			(xy 408.825446 -338.480654) (xy 408.8257 -338.480654) (xy 408.8257 -338.480908) (xy 408.843356 -338.501826)
			(xy 408.873066 -338.547803) (xy 408.895898 -338.597554) (xy 408.911385 -338.650058) (xy 408.919209 -338.704236)
			(xy 408.91968 -338.731606) (xy 408.919194 -338.758857) (xy 408.911438 -338.812805) (xy 408.896083 -338.8651)
			(xy 408.873441 -338.914677) (xy 408.843975 -338.960527) (xy 408.808284 -339.001718) (xy 408.767093 -339.037409)
			(xy 408.721243 -339.066875) (xy 408.671666 -339.089517) (xy 408.619371 -339.104872) (xy 408.565423 -339.112628)
			(xy 408.510921 -339.112628) (xy 408.456973 -339.104872) (xy 408.404678 -339.089517) (xy 408.355101 -339.066875)
			(xy 408.309251 -339.037409) (xy 408.26806 -339.001718) (xy 408.232369 -338.960527) (xy 408.202903 -338.914677)
			(xy 408.180261 -338.8651) (xy 408.164906 -338.812805) (xy 408.15715 -338.758857) (xy 408.156664 -338.731606)
			(xy 406.279604 -338.731606) (xy 406.279604 -354.613972) (xy 416.45408 -354.613972) (xy 416.458151 -354.55835)
			(xy 416.470277 -354.503913) (xy 416.4902 -354.451822) (xy 416.517496 -354.403187) (xy 416.551582 -354.359044)
			(xy 416.591731 -354.320335) (xy 416.637089 -354.287884) (xy 416.686689 -354.262383) (xy 416.739473 -354.244376)
			(xy 416.794316 -354.234246) (xy 416.85005 -354.232209) (xy 416.905487 -354.238309) (xy 416.959444 -354.252415)
			(xy 417.010773 -354.274227) (xy 417.058379 -354.303281) (xy 417.101247 -354.338956) (xy 417.138464 -354.380493)
			(xy 417.169237 -354.427006) (xy 417.192909 -354.477503) (xy 417.208977 -354.53091) (xy 417.217097 -354.586086)
			(xy 417.217606 -354.613972) (xy 417.217097 -354.641858) (xy 417.208977 -354.697034) (xy 417.192909 -354.750441)
			(xy 417.169237 -354.800938) (xy 417.138464 -354.847451) (xy 417.101247 -354.888988) (xy 417.058379 -354.924663)
			(xy 417.010773 -354.953717) (xy 416.959444 -354.975529) (xy 416.905487 -354.989635) (xy 416.85005 -354.995735)
			(xy 416.794316 -354.993698) (xy 416.739473 -354.983568) (xy 416.686689 -354.965561) (xy 416.637089 -354.94006)
			(xy 416.591731 -354.907609) (xy 416.551582 -354.8689) (xy 416.517496 -354.824757) (xy 416.4902 -354.776122)
			(xy 416.470277 -354.724031) (xy 416.458151 -354.669594) (xy 416.45408 -354.613972) (xy 406.279604 -354.613972)
			(xy 406.279604 -355.312218) (xy 406.279839 -355.320015) (xy 406.284489 -355.334894) (xy 406.288748 -355.341428)
			(xy 406.293066 -355.347524) (xy 406.305258 -355.356922) (xy 406.312878 -355.359716) (xy 406.338406 -355.369595)
			(xy 406.386562 -355.395618) (xy 406.430506 -355.428254) (xy 406.469335 -355.466834) (xy 406.502254 -355.510567)
			(xy 406.528586 -355.558555) (xy 406.547791 -355.609812) (xy 406.559475 -355.663288) (xy 406.563397 -355.717885)
			(xy 406.559479 -355.772482) (xy 406.547799 -355.825959) (xy 406.528598 -355.877218) (xy 406.50227 -355.925208)
			(xy 406.469355 -355.968943) (xy 406.430529 -356.007526) (xy 406.386588 -356.040166) (xy 406.338433 -356.066192)
			(xy 406.312878 -356.075996) (xy 406.312624 -356.075996) (xy 406.305423 -356.078969) (xy 406.293135 -356.088535)
			(xy 406.288494 -356.094792) (xy 406.284176 -356.100888) (xy 406.279604 -356.11562) (xy 406.279604 -356.338378)
			(xy 406.28028 -356.350445) (xy 406.291294 -356.371918) (xy 406.300686 -356.379526) (xy 406.377648 -356.434898)
			(xy 406.401778 -356.438708) (xy 406.413462 -356.434644) (xy 406.442892 -356.425386) (xy 406.503774 -356.415426)
			(xy 406.53462 -356.414832) (xy 406.534874 -356.414832) (xy 406.562125 -356.415293) (xy 406.616073 -356.423047)
			(xy 406.668369 -356.438399) (xy 406.717947 -356.461037) (xy 406.763799 -356.490502) (xy 406.80499 -356.526192)
			(xy 406.840683 -356.567381) (xy 406.87015 -356.61323) (xy 406.892792 -356.662807) (xy 406.908148 -356.715101)
			(xy 406.915905 -356.769049) (xy 406.915905 -356.823551) (xy 406.908148 -356.877499) (xy 406.892792 -356.929793)
			(xy 406.87015 -356.97937) (xy 406.840683 -357.025219) (xy 406.80499 -357.066408) (xy 406.763799 -357.102098)
			(xy 406.717947 -357.131563) (xy 406.668369 -357.154201) (xy 406.616073 -357.169553) (xy 406.562125 -357.177307)
			(xy 406.534874 -357.177848) (xy 406.53462 -357.177848) (xy 406.503775 -357.177236) (xy 406.442893 -357.167288)
			(xy 406.413462 -357.158036) (xy 406.401778 -357.153972) (xy 406.377648 -357.157782) (xy 406.300686 -357.213154)
			(xy 406.291314 -357.220771) (xy 406.280335 -357.242245) (xy 406.279604 -357.254302) (xy 406.279604 -358.836214)
			(xy 417.824664 -358.836214) (xy 417.828735 -358.780592) (xy 417.840861 -358.726155) (xy 417.860784 -358.674064)
			(xy 417.88808 -358.625429) (xy 417.922166 -358.581286) (xy 417.962315 -358.542577) (xy 418.007673 -358.510126)
			(xy 418.057273 -358.484625) (xy 418.110057 -358.466618) (xy 418.1649 -358.456488) (xy 418.220634 -358.454451)
			(xy 418.276071 -358.460551) (xy 418.330028 -358.474657) (xy 418.381357 -358.496469) (xy 418.428963 -358.525523)
			(xy 418.471831 -358.561198) (xy 418.509048 -358.602735) (xy 418.539821 -358.649248) (xy 418.563493 -358.699745)
			(xy 418.579561 -358.753152) (xy 418.587681 -358.808328) (xy 418.58819 -358.836214) (xy 418.587681 -358.8641)
			(xy 418.579561 -358.919276) (xy 418.563493 -358.972683) (xy 418.539821 -359.02318) (xy 418.509048 -359.069693)
			(xy 418.471831 -359.11123) (xy 418.428963 -359.146905) (xy 418.381357 -359.175959) (xy 418.330028 -359.197771)
			(xy 418.276071 -359.211877) (xy 418.220634 -359.217977) (xy 418.1649 -359.21594) (xy 418.110057 -359.20581)
			(xy 418.057273 -359.187803) (xy 418.007673 -359.162302) (xy 417.962315 -359.129851) (xy 417.922166 -359.091142)
			(xy 417.88808 -359.046999) (xy 417.860784 -358.998364) (xy 417.840861 -358.946273) (xy 417.828735 -358.891836)
			(xy 417.824664 -358.836214) (xy 406.279604 -358.836214) (xy 406.279604 -358.878886) (xy 406.28697 -358.886252)
			(xy 406.28697 -360.7943) (xy 412.920178 -360.7943) (xy 412.924249 -360.738678) (xy 412.936375 -360.684241)
			(xy 412.956298 -360.63215) (xy 412.983594 -360.583515) (xy 413.01768 -360.539372) (xy 413.057829 -360.500663)
			(xy 413.103187 -360.468212) (xy 413.152787 -360.442711) (xy 413.205571 -360.424704) (xy 413.260414 -360.414574)
			(xy 413.316148 -360.412537) (xy 413.371585 -360.418637) (xy 413.425542 -360.432743) (xy 413.476871 -360.454555)
			(xy 413.524477 -360.483609) (xy 413.567345 -360.519284) (xy 413.604562 -360.560821) (xy 413.635335 -360.607334)
			(xy 413.659007 -360.657831) (xy 413.675075 -360.711238) (xy 413.683195 -360.766414) (xy 413.683704 -360.7943)
			(xy 413.683195 -360.822186) (xy 413.675075 -360.877362) (xy 413.659007 -360.930769) (xy 413.635335 -360.981266)
			(xy 413.604562 -361.027779) (xy 413.567345 -361.069316) (xy 413.524477 -361.104991) (xy 413.476871 -361.134045)
			(xy 413.425542 -361.155857) (xy 413.371585 -361.169963) (xy 413.316148 -361.176063) (xy 413.260414 -361.174026)
			(xy 413.205571 -361.163896) (xy 413.152787 -361.145889) (xy 413.103187 -361.120388) (xy 413.057829 -361.087937)
			(xy 413.01768 -361.049228) (xy 412.983594 -361.005085) (xy 412.956298 -360.95645) (xy 412.936375 -360.904359)
			(xy 412.924249 -360.849922) (xy 412.920178 -360.7943) (xy 406.28697 -360.7943) (xy 406.28697 -361.3023)
			(xy 414.979356 -361.3023) (xy 414.983427 -361.246678) (xy 414.995553 -361.192241) (xy 415.015476 -361.14015)
			(xy 415.042772 -361.091515) (xy 415.076858 -361.047372) (xy 415.117007 -361.008663) (xy 415.162365 -360.976212)
			(xy 415.211965 -360.950711) (xy 415.264749 -360.932704) (xy 415.319592 -360.922574) (xy 415.375326 -360.920537)
			(xy 415.430763 -360.926637) (xy 415.48472 -360.940743) (xy 415.536049 -360.962555) (xy 415.583655 -360.991609)
			(xy 415.626523 -361.027284) (xy 415.66374 -361.068821) (xy 415.694513 -361.115334) (xy 415.718185 -361.165831)
			(xy 415.734253 -361.219238) (xy 415.742373 -361.274414) (xy 415.742882 -361.3023) (xy 415.742373 -361.330186)
			(xy 415.734253 -361.385362) (xy 415.718185 -361.438769) (xy 415.694513 -361.489266) (xy 415.66374 -361.535779)
			(xy 415.626523 -361.577316) (xy 415.583655 -361.612991) (xy 415.536049 -361.642045) (xy 415.48472 -361.663857)
			(xy 415.430763 -361.677963) (xy 415.375326 -361.684063) (xy 415.319592 -361.682026) (xy 415.264749 -361.671896)
			(xy 415.211965 -361.653889) (xy 415.162365 -361.628388) (xy 415.117007 -361.595937) (xy 415.076858 -361.557228)
			(xy 415.042772 -361.513085) (xy 415.015476 -361.46445) (xy 414.995553 -361.412359) (xy 414.983427 -361.357922)
			(xy 414.979356 -361.3023) (xy 406.28697 -361.3023) (xy 406.28697 -361.443016) (xy 406.287395 -361.453086)
			(xy 406.29511 -361.471689) (xy 406.301956 -361.479084) (xy 407.627836 -362.804964) (xy 412.9311 -362.804964)
			(xy 412.935171 -362.749342) (xy 412.947297 -362.694905) (xy 412.96722 -362.642814) (xy 412.994516 -362.594179)
			(xy 413.028602 -362.550036) (xy 413.068751 -362.511327) (xy 413.114109 -362.478876) (xy 413.163709 -362.453375)
			(xy 413.216493 -362.435368) (xy 413.271336 -362.425238) (xy 413.32707 -362.423201) (xy 413.382507 -362.429301)
			(xy 413.436464 -362.443407) (xy 413.487793 -362.465219) (xy 413.535399 -362.494273) (xy 413.578267 -362.529948)
			(xy 413.615484 -362.571485) (xy 413.646257 -362.617998) (xy 413.669929 -362.668495) (xy 413.685997 -362.721902)
			(xy 413.694117 -362.777078) (xy 413.694626 -362.804964) (xy 413.694117 -362.83285) (xy 413.685997 -362.888026)
			(xy 413.669929 -362.941433) (xy 413.646257 -362.99193) (xy 413.615484 -363.038443) (xy 413.578267 -363.07998)
			(xy 413.535399 -363.115655) (xy 413.487793 -363.144709) (xy 413.436464 -363.166521) (xy 413.382507 -363.180627)
			(xy 413.32707 -363.186727) (xy 413.271336 -363.18469) (xy 413.216493 -363.17456) (xy 413.163709 -363.156553)
			(xy 413.114109 -363.131052) (xy 413.068751 -363.098601) (xy 413.028602 -363.059892) (xy 412.994516 -363.015749)
			(xy 412.96722 -362.967114) (xy 412.947297 -362.915023) (xy 412.935171 -362.860586) (xy 412.9311 -362.804964)
			(xy 407.627836 -362.804964) (xy 408.179016 -363.356144) (xy 415.065208 -363.356144) (xy 415.069279 -363.300522)
			(xy 415.081405 -363.246085) (xy 415.101328 -363.193994) (xy 415.128624 -363.145359) (xy 415.16271 -363.101216)
			(xy 415.202859 -363.062507) (xy 415.248217 -363.030056) (xy 415.297817 -363.004555) (xy 415.350601 -362.986548)
			(xy 415.405444 -362.976418) (xy 415.461178 -362.974381) (xy 415.516615 -362.980481) (xy 415.570572 -362.994587)
			(xy 415.621901 -363.016399) (xy 415.669507 -363.045453) (xy 415.712375 -363.081128) (xy 415.748502 -363.121448)
			(xy 416.0139 -363.121448) (xy 416.0139 -360.830114) (xy 416.014401 -360.810175) (xy 416.022188 -360.771064)
			(xy 416.037445 -360.73422) (xy 416.05959 -360.701055) (xy 416.073336 -360.686604) (xy 417.229544 -359.530396)
			(xy 417.244017 -359.516677) (xy 417.277185 -359.49455) (xy 417.314021 -359.479289) (xy 417.353119 -359.471476)
			(xy 417.373054 -359.47096) (xy 418.64534 -359.47096) (xy 418.655413 -359.470566) (xy 418.674011 -359.462824)
			(xy 418.681408 -359.455974) (xy 421.150034 -356.987094) (xy 421.164499 -356.973249) (xy 421.19778 -356.950994)
			(xy 421.234766 -356.935667) (xy 421.274034 -356.927859) (xy 421.294052 -356.927404) (xy 423.481754 -356.927404)
			(xy 423.491824 -356.92698) (xy 423.510423 -356.919261) (xy 423.517822 -356.912418) (xy 423.808398 -356.622096)
			(xy 423.815232 -356.614691) (xy 423.822955 -356.596096) (xy 423.823384 -356.586028) (xy 423.823384 -355.863906)
			(xy 423.82296 -355.853837) (xy 423.815239 -355.835239) (xy 423.808398 -355.827838) (xy 423.789856 -355.809296)
			(xy 423.782162 -355.802307) (xy 423.76282 -355.794736) (xy 423.742061 -355.795419) (xy 423.732452 -355.79939)
			(xy 423.732198 -355.79939) (xy 423.706553 -355.811002) (xy 423.652699 -355.827392) (xy 423.597022 -355.835698)
			(xy 423.568876 -355.83622) (xy 423.541625 -355.835745) (xy 423.487677 -355.827985) (xy 423.435383 -355.812628)
			(xy 423.385807 -355.789984) (xy 423.339957 -355.760517) (xy 423.298767 -355.724824) (xy 423.263076 -355.683634)
			(xy 423.23361 -355.637783) (xy 423.210968 -355.588206) (xy 423.195612 -355.535911) (xy 423.187855 -355.481963)
			(xy 423.187368 -355.454712) (xy 423.188012 -355.423149) (xy 423.198407 -355.360883) (xy 423.218898 -355.301174)
			(xy 423.233342 -355.273102) (xy 423.238168 -355.264212) (xy 423.2402 -355.244654) (xy 423.21734 -355.166168)
			(xy 423.214126 -355.156733) (xy 423.201692 -355.141179) (xy 423.19321 -355.135942) (xy 423.185844 -355.131878)
			(xy 423.175938 -355.126036) (xy 423.154094 -355.124004) (xy 423.059352 -355.157532) (xy 423.043604 -355.173026)
			(xy 423.03954 -355.18344) (xy 423.028848 -355.210218) (xy 423.000558 -355.260458) (xy 422.965027 -355.305867)
			(xy 422.923064 -355.345408) (xy 422.875626 -355.378181) (xy 422.823795 -355.403439) (xy 422.768753 -355.420605)
			(xy 422.711753 -355.429289) (xy 422.682924 -355.42982) (xy 422.655671 -355.429334) (xy 422.601719 -355.42158)
			(xy 422.54942 -355.406227) (xy 422.499838 -355.383586) (xy 422.453984 -355.35412) (xy 422.412789 -355.318428)
			(xy 422.377094 -355.277236) (xy 422.347625 -355.231383) (xy 422.324981 -355.181803) (xy 422.309625 -355.129504)
			(xy 422.301867 -355.075553) (xy 422.301867 -355.021047) (xy 422.309625 -354.967096) (xy 422.324981 -354.914797)
			(xy 422.347625 -354.865217) (xy 422.377094 -354.819364) (xy 422.412789 -354.778172) (xy 422.453984 -354.74248)
			(xy 422.499838 -354.713014) (xy 422.54942 -354.690373) (xy 422.601719 -354.67502) (xy 422.655671 -354.667266)
			(xy 422.682924 -354.666804) (xy 422.683178 -354.666804) (xy 422.708381 -354.667218) (xy 422.758348 -354.673854)
			(xy 422.807003 -354.687027) (xy 422.853493 -354.706505) (xy 422.875456 -354.718874) (xy 422.885362 -354.724716)
			(xy 422.907206 -354.726748) (xy 423.001948 -354.69322) (xy 423.017696 -354.677726) (xy 423.02176 -354.667312)
			(xy 423.032479 -354.640545) (xy 423.060763 -354.590304) (xy 423.096289 -354.544893) (xy 423.138247 -354.50535)
			(xy 423.185681 -354.472575) (xy 423.23751 -354.447315) (xy 423.29255 -354.430147) (xy 423.349548 -354.421463)
			(xy 423.378376 -354.420932) (xy 423.40563 -354.421378) (xy 423.459584 -354.429133) (xy 423.511884 -354.444488)
			(xy 423.561467 -354.46713) (xy 423.607322 -354.496599) (xy 423.648516 -354.532295) (xy 423.68421 -354.573491)
			(xy 423.713678 -354.619347) (xy 423.736318 -354.668931) (xy 423.74904 -354.71227) (xy 425.889928 -354.71227)
			(xy 425.890432 -354.684697) (xy 425.898375 -354.630125) (xy 425.914092 -354.577266) (xy 425.937255 -354.527219)
			(xy 425.967381 -354.481029) (xy 426.003843 -354.439656) (xy 426.024548 -354.42144) (xy 426.032613 -354.413876)
			(xy 426.041971 -354.393871) (xy 426.042582 -354.382832) (xy 426.042582 -354.305108) (xy 426.042015 -354.294058)
			(xy 426.032649 -354.274037) (xy 426.024548 -354.2665) (xy 426.003843 -354.248282) (xy 425.96737 -354.206916)
			(xy 425.937236 -354.160728) (xy 425.914069 -354.110681) (xy 425.898352 -354.057819) (xy 425.890413 -354.003245)
			(xy 425.889928 -353.97567) (xy 425.890327 -353.948415) (xy 425.898089 -353.89446) (xy 425.913451 -353.842158)
			(xy 425.936099 -353.792576) (xy 425.965574 -353.746721) (xy 426.001274 -353.705528) (xy 426.042474 -353.669834)
			(xy 426.088334 -353.640368) (xy 426.13792 -353.617728) (xy 426.190224 -353.602375) (xy 426.244181 -353.594622)
			(xy 426.271436 -353.594162) (xy 426.271944 -353.594162) (xy 426.305726 -353.595686) (xy 426.315886 -353.596702)
			(xy 426.33519 -353.590606) (xy 426.398182 -353.537774) (xy 426.405459 -353.531038) (xy 426.414749 -353.513543)
			(xy 426.416216 -353.503738) (xy 426.416216 -353.502976) (xy 426.419155 -353.474826) (xy 426.432351 -353.419787)
			(xy 426.453537 -353.367303) (xy 426.482247 -353.318526) (xy 426.517851 -353.274529) (xy 426.559567 -353.236277)
			(xy 426.606478 -353.20461) (xy 426.657554 -353.180225) (xy 426.711673 -353.163657) (xy 426.767647 -353.155269)
			(xy 426.795946 -353.154742) (xy 426.7962 -353.154742) (xy 426.814219 -353.154968) (xy 426.850094 -353.158399)
			(xy 426.867828 -353.1616) (xy 426.87748 -353.163378) (xy 426.89653 -353.159822) (xy 426.97146 -353.111816)
			(xy 426.98289 -353.096068) (xy 426.985176 -353.08667) (xy 426.99262 -353.05964) (xy 427.014245 -353.007915)
			(xy 427.043203 -352.959911) (xy 427.078873 -352.91666) (xy 427.120486 -352.879092) (xy 427.167147 -352.848016)
			(xy 427.217853 -352.8241) (xy 427.271512 -352.80786) (xy 427.326969 -352.799644) (xy 427.355 -352.799142)
			(xy 427.382255 -352.799555) (xy 427.43621 -352.807314) (xy 427.488512 -352.822672) (xy 427.538096 -352.845318)
			(xy 427.583951 -352.874791) (xy 427.625145 -352.91049) (xy 427.660839 -352.951689) (xy 427.690306 -352.997548)
			(xy 427.712945 -353.047135) (xy 427.728297 -353.099438) (xy 427.736048 -353.153395) (xy 427.736508 -353.18065)
			(xy 427.736005 -353.208223) (xy 427.72806 -353.262794) (xy 427.712342 -353.315653) (xy 427.689179 -353.365699)
			(xy 427.659053 -353.41189) (xy 427.622592 -353.453263) (xy 427.601888 -353.47148) (xy 427.59382 -353.479041)
			(xy 427.584462 -353.499048) (xy 427.583854 -353.510088) (xy 427.583854 -353.587812) (xy 427.584454 -353.598858)
			(xy 427.593795 -353.61888) (xy 427.601888 -353.62642) (xy 427.62261 -353.64462) (xy 427.65908 -353.685991)
			(xy 427.689211 -353.732183) (xy 427.712375 -353.782233) (xy 427.728089 -353.835098) (xy 427.736025 -353.889675)
			(xy 427.736508 -353.91725) (xy 427.736005 -353.944823) (xy 427.72806 -353.999394) (xy 427.719933 -354.026724)
			(xy 428.864012 -354.026724) (xy 428.868083 -353.971102) (xy 428.880209 -353.916665) (xy 428.900132 -353.864574)
			(xy 428.927428 -353.815939) (xy 428.961514 -353.771796) (xy 429.001663 -353.733087) (xy 429.047021 -353.700636)
			(xy 429.096621 -353.675135) (xy 429.149405 -353.657128) (xy 429.204248 -353.646998) (xy 429.259982 -353.644961)
			(xy 429.315419 -353.651061) (xy 429.369376 -353.665167) (xy 429.420705 -353.686979) (xy 429.468311 -353.716033)
			(xy 429.511179 -353.751708) (xy 429.548396 -353.793245) (xy 429.579169 -353.839758) (xy 429.602841 -353.890255)
			(xy 429.618909 -353.943662) (xy 429.627029 -353.998838) (xy 429.627538 -354.026724) (xy 429.627029 -354.05461)
			(xy 429.618909 -354.109786) (xy 429.602841 -354.163193) (xy 429.579169 -354.21369) (xy 429.548396 -354.260203)
			(xy 429.511179 -354.30174) (xy 429.468311 -354.337415) (xy 429.420705 -354.366469) (xy 429.369376 -354.388281)
			(xy 429.315419 -354.402387) (xy 429.259982 -354.408487) (xy 429.204248 -354.40645) (xy 429.149405 -354.39632)
			(xy 429.096621 -354.378313) (xy 429.047021 -354.352812) (xy 429.001663 -354.320361) (xy 428.961514 -354.281652)
			(xy 428.927428 -354.237509) (xy 428.900132 -354.188874) (xy 428.880209 -354.136783) (xy 428.868083 -354.082346)
			(xy 428.864012 -354.026724) (xy 427.719933 -354.026724) (xy 427.712342 -354.052253) (xy 427.689179 -354.102299)
			(xy 427.659053 -354.14849) (xy 427.622592 -354.189863) (xy 427.601888 -354.20808) (xy 427.59382 -354.215641)
			(xy 427.584462 -354.235648) (xy 427.583854 -354.246688) (xy 427.583854 -354.324412) (xy 427.584454 -354.335458)
			(xy 427.593795 -354.35548) (xy 427.601888 -354.36302) (xy 427.62261 -354.38122) (xy 427.65908 -354.422591)
			(xy 427.689211 -354.468783) (xy 427.712375 -354.518833) (xy 427.728089 -354.571698) (xy 427.736025 -354.626275)
			(xy 427.736508 -354.65385) (xy 427.735998 -354.681102) (xy 427.728248 -354.735051) (xy 427.712898 -354.787348)
			(xy 427.690262 -354.836928) (xy 427.660799 -354.882781) (xy 427.626756 -354.922074) (xy 428.284892 -354.922074)
			(xy 428.288963 -354.866452) (xy 428.301089 -354.812015) (xy 428.321012 -354.759924) (xy 428.348308 -354.711289)
			(xy 428.382394 -354.667146) (xy 428.422543 -354.628437) (xy 428.467901 -354.595986) (xy 428.517501 -354.570485)
			(xy 428.570285 -354.552478) (xy 428.625128 -354.542348) (xy 428.680862 -354.540311) (xy 428.736299 -354.546411)
			(xy 428.790256 -354.560517) (xy 428.841585 -354.582329) (xy 428.889191 -354.611383) (xy 428.932059 -354.647058)
			(xy 428.969276 -354.688595) (xy 429.000049 -354.735108) (xy 429.023721 -354.785605) (xy 429.039789 -354.839012)
			(xy 429.047909 -354.894188) (xy 429.048418 -354.922074) (xy 429.047909 -354.94996) (xy 429.039789 -355.005136)
			(xy 429.023721 -355.058543) (xy 429.000049 -355.10904) (xy 428.969276 -355.155553) (xy 428.932059 -355.19709)
			(xy 428.889191 -355.232765) (xy 428.841585 -355.261819) (xy 428.790256 -355.283631) (xy 428.736299 -355.297737)
			(xy 428.680862 -355.303837) (xy 428.625128 -355.3018) (xy 428.570285 -355.29167) (xy 428.517501 -355.273663)
			(xy 428.467901 -355.248162) (xy 428.422543 -355.215711) (xy 428.382394 -355.177002) (xy 428.348308 -355.132859)
			(xy 428.321012 -355.084224) (xy 428.301089 -355.032133) (xy 428.288963 -354.977696) (xy 428.284892 -354.922074)
			(xy 427.626756 -354.922074) (xy 427.62511 -354.923974) (xy 427.583921 -354.959669) (xy 427.538072 -354.989138)
			(xy 427.488495 -355.011781) (xy 427.4362 -355.027137) (xy 427.382252 -355.034895) (xy 427.355 -355.035358)
			(xy 427.327143 -355.034866) (xy 427.272025 -355.026741) (xy 427.218672 -355.010694) (xy 427.168218 -354.987064)
			(xy 427.121732 -354.956353) (xy 427.080203 -354.919213) (xy 427.044511 -354.876433) (xy 427.015414 -354.828921)
			(xy 426.99353 -354.777685) (xy 426.985938 -354.750878) (xy 426.983652 -354.741988) (xy 426.972984 -354.726748)
			(xy 426.901102 -354.678996) (xy 426.883068 -354.674932) (xy 426.873924 -354.676202) (xy 426.860907 -354.677867)
			(xy 426.834723 -354.67965) (xy 426.8216 -354.679758) (xy 426.807451 -354.679665) (xy 426.779228 -354.67763)
			(xy 426.765212 -354.675694) (xy 426.755306 -354.67417) (xy 426.735494 -354.678996) (xy 426.661072 -354.734876)
			(xy 426.650912 -354.752402) (xy 426.649642 -354.762562) (xy 426.645543 -354.789713) (xy 426.630569 -354.842542)
			(xy 426.608178 -354.892679) (xy 426.578831 -354.939088) (xy 426.543134 -354.980811) (xy 426.501826 -355.016988)
			(xy 426.455759 -355.046869) (xy 426.405885 -355.069839) (xy 426.353233 -355.085422) (xy 426.298891 -355.093298)
			(xy 426.271436 -355.093778) (xy 426.244183 -355.093311) (xy 426.19023 -355.085558) (xy 426.137931 -355.070205)
			(xy 426.088349 -355.047565) (xy 426.042494 -355.018098) (xy 426.0013 -354.982404) (xy 425.965606 -354.941211)
			(xy 425.936138 -354.895357) (xy 425.913497 -354.845775) (xy 425.898143 -354.793476) (xy 425.890389 -354.739523)
			(xy 425.889928 -354.71227) (xy 423.74904 -354.71227) (xy 423.751671 -354.721232) (xy 423.759423 -354.775186)
			(xy 423.759884 -354.80244) (xy 423.759227 -354.834003) (xy 423.748839 -354.896268) (xy 423.728352 -354.955977)
			(xy 423.71391 -354.98405) (xy 423.709084 -354.99294) (xy 423.707052 -355.012498) (xy 423.729912 -355.090984)
			(xy 423.733163 -355.100403) (xy 423.745571 -355.115965) (xy 423.754042 -355.12121) (xy 423.777463 -355.134762)
			(xy 423.820599 -355.167428) (xy 423.858683 -355.205865) (xy 423.890949 -355.249302) (xy 423.916747 -355.296865)
			(xy 423.935561 -355.347598) (xy 423.941748 -355.37394) (xy 423.943272 -355.381306) (xy 423.95013 -355.394006)
			(xy 424.154073 -355.597714) (xy 429.623728 -355.597714) (xy 429.624216 -355.570239) (xy 429.632106 -355.51586)
			(xy 429.647726 -355.463177) (xy 429.67075 -355.413284) (xy 429.700702 -355.367216) (xy 429.71847 -355.346254)
			(xy 429.718724 -355.346) (xy 429.724319 -355.33892) (xy 429.73056 -355.321998) (xy 429.730916 -355.31298)
			(xy 429.730916 -355.245416) (xy 429.730548 -355.2364) (xy 429.724308 -355.219483) (xy 429.718724 -355.212396)
			(xy 429.718216 -355.211888) (xy 429.700483 -355.190941) (xy 429.6706 -355.144909) (xy 429.647633 -355.095064)
			(xy 429.632059 -355.042439) (xy 429.624198 -354.988123) (xy 429.623728 -354.960682) (xy 429.624214 -354.933431)
			(xy 429.63197 -354.879483) (xy 429.647325 -354.827188) (xy 429.669967 -354.777611) (xy 429.699433 -354.731761)
			(xy 429.735124 -354.69057) (xy 429.776315 -354.654879) (xy 429.822165 -354.625413) (xy 429.871742 -354.602771)
			(xy 429.924037 -354.587416) (xy 429.977985 -354.57966) (xy 430.032487 -354.57966) (xy 430.086435 -354.587416)
			(xy 430.13873 -354.602771) (xy 430.188307 -354.625413) (xy 430.234157 -354.654879) (xy 430.275348 -354.69057)
			(xy 430.311039 -354.731761) (xy 430.340505 -354.777611) (xy 430.363147 -354.827188) (xy 430.378502 -354.879483)
			(xy 430.386258 -354.933431) (xy 430.386744 -354.960682) (xy 430.386261 -354.988157) (xy 430.37837 -355.042537)
			(xy 430.36275 -355.09522) (xy 430.339724 -355.145113) (xy 430.309771 -355.191181) (xy 430.292002 -355.212142)
			(xy 430.291748 -355.212396) (xy 430.286151 -355.219475) (xy 430.279912 -355.236398) (xy 430.279556 -355.245416)
			(xy 430.279556 -355.31298) (xy 430.27991 -355.321997) (xy 430.286158 -355.338915) (xy 430.291748 -355.346)
			(xy 430.292256 -355.346508) (xy 430.309982 -355.36746) (xy 430.339867 -355.413491) (xy 430.362836 -355.463334)
			(xy 430.378412 -355.515958) (xy 430.386273 -355.570273) (xy 430.386744 -355.597714) (xy 430.386258 -355.624965)
			(xy 430.378502 -355.678913) (xy 430.363147 -355.731208) (xy 430.340505 -355.780785) (xy 430.311039 -355.826635)
			(xy 430.275348 -355.867826) (xy 430.234157 -355.903517) (xy 430.188307 -355.932983) (xy 430.13873 -355.955625)
			(xy 430.086435 -355.97098) (xy 430.032487 -355.978736) (xy 429.977985 -355.978736) (xy 429.924037 -355.97098)
			(xy 429.871742 -355.955625) (xy 429.822165 -355.932983) (xy 429.776315 -355.903517) (xy 429.735124 -355.867826)
			(xy 429.699433 -355.826635) (xy 429.669967 -355.780785) (xy 429.647325 -355.731208) (xy 429.63197 -355.678913)
			(xy 429.624214 -355.624965) (xy 429.623728 -355.597714) (xy 424.154073 -355.597714) (xy 424.170856 -355.614478)
			(xy 424.184583 -355.628944) (xy 424.206711 -355.662114) (xy 424.22197 -355.698951) (xy 424.229779 -355.738052)
			(xy 424.230292 -355.757988) (xy 424.230292 -356.691946) (xy 424.229802 -356.711885) (xy 424.222007 -356.750995)
			(xy 424.206746 -356.787838) (xy 424.184602 -356.821004) (xy 424.170856 -356.835456) (xy 423.731182 -357.27513)
			(xy 423.716698 -357.288955) (xy 423.683425 -357.311217) (xy 423.646444 -357.32655) (xy 423.607181 -357.334363)
			(xy 423.587164 -357.33482) (xy 421.399462 -357.33482) (xy 421.38939 -357.33522) (xy 421.370792 -357.342958)
			(xy 421.363394 -357.349806) (xy 418.894768 -359.818432) (xy 418.880321 -359.83218) (xy 418.847145 -359.854305)
			(xy 418.810301 -359.869558) (xy 418.771196 -359.877359) (xy 418.751258 -359.877868) (xy 417.478972 -359.877868)
			(xy 417.468899 -359.878261) (xy 417.4503 -359.886002) (xy 417.442904 -359.892854) (xy 416.435794 -360.899964)
			(xy 416.428976 -360.907382) (xy 416.421244 -360.925967) (xy 416.420808 -360.936032) (xy 416.420808 -363.01553)
			(xy 416.421216 -363.025601) (xy 416.428948 -363.044199) (xy 416.435794 -363.051598) (xy 418.222684 -364.838234)
			(xy 418.234723 -364.850821) (xy 418.25478 -364.879294) (xy 418.262562 -364.894876) (xy 418.265903 -364.901328)
			(xy 418.275583 -364.912156) (xy 418.281612 -364.916212) (xy 418.304692 -364.931238) (xy 418.346619 -364.966945)
			(xy 418.38298 -365.008309) (xy 418.413018 -365.054468) (xy 418.43611 -365.104466) (xy 418.451776 -365.157263)
			(xy 418.459691 -365.211764) (xy 418.460073 -365.233553) (xy 418.820558 -365.233553) (xy 418.820558 -365.179047)
			(xy 418.828315 -365.125097) (xy 418.843671 -365.072799) (xy 418.866313 -365.023219) (xy 418.895781 -364.977367)
			(xy 418.931474 -364.936174) (xy 418.972667 -364.900481) (xy 419.018519 -364.871013) (xy 419.068099 -364.848371)
			(xy 419.120397 -364.833015) (xy 419.174347 -364.825258) (xy 419.2016 -364.824772) (xy 419.227265 -364.825172)
			(xy 419.278132 -364.832048) (xy 419.327616 -364.845688) (xy 419.374821 -364.865846) (xy 419.418894 -364.892158)
			(xy 419.459037 -364.924146) (xy 419.494524 -364.961233) (xy 419.509956 -364.981744) (xy 419.517609 -364.991046)
			(xy 419.539076 -365.001907) (xy 419.551104 -365.002572) (xy 419.742874 -365.002572) (xy 419.752943 -365.002141)
			(xy 419.771541 -364.994425) (xy 419.778942 -364.987586) (xy 421.117014 -363.649768) (xy 421.123862 -363.642375)
			(xy 421.131577 -363.62377) (xy 421.132 -363.6137) (xy 421.132 -359.730802) (xy 421.132494 -359.710863)
			(xy 421.140283 -359.671752) (xy 421.155543 -359.634908) (xy 421.177689 -359.601743) (xy 421.191436 -359.587292)
			(xy 422.569894 -358.208834) (xy 422.584382 -358.195014) (xy 422.617654 -358.172753) (xy 422.654634 -358.157419)
			(xy 422.693896 -358.149603) (xy 422.713912 -358.149144) (xy 425.757848 -358.149144) (xy 425.767916 -358.148706)
			(xy 425.786515 -358.140996) (xy 425.793916 -358.134158) (xy 426.70857 -357.219504) (xy 426.723033 -357.205774)
			(xy 426.756205 -357.183649) (xy 426.793043 -357.168391) (xy 426.832144 -357.160582) (xy 426.85208 -357.160068)
			(xy 431.398172 -357.160068) (xy 431.408241 -357.159636) (xy 431.426839 -357.151921) (xy 431.43424 -357.145082)
			(xy 432.045618 -356.533704) (xy 432.052451 -356.526299) (xy 432.060174 -356.507703) (xy 432.060604 -356.497636)
			(xy 432.060604 -355.954076) (xy 432.060216 -355.944002) (xy 432.052472 -355.925403) (xy 432.045618 -355.918008)
			(xy 431.989992 -355.862382) (xy 431.967132 -355.855016) (xy 431.95494 -355.857048) (xy 431.940177 -355.859209)
			(xy 431.910424 -355.861496) (xy 431.895504 -355.86162) (xy 431.868253 -355.861119) (xy 431.814307 -355.853363)
			(xy 431.762013 -355.838009) (xy 431.712437 -355.815369) (xy 431.666587 -355.785904) (xy 431.625397 -355.750214)
			(xy 431.589705 -355.709026) (xy 431.560239 -355.663177) (xy 431.537597 -355.613602) (xy 431.522241 -355.561309)
			(xy 431.514483 -355.507363) (xy 431.513996 -355.480112) (xy 431.514637 -355.448548) (xy 431.525032 -355.386283)
			(xy 431.545525 -355.326574) (xy 431.55997 -355.298502) (xy 431.564796 -355.289612) (xy 431.566828 -355.270054)
			(xy 431.543968 -355.191568) (xy 431.540744 -355.182138) (xy 431.528316 -355.166582) (xy 431.519838 -355.161342)
			(xy 431.512472 -355.157278) (xy 431.502566 -355.151436) (xy 431.480722 -355.149404) (xy 431.38598 -355.182932)
			(xy 431.370232 -355.198426) (xy 431.366168 -355.20884) (xy 431.355453 -355.235608) (xy 431.327166 -355.285847)
			(xy 431.291637 -355.331255) (xy 431.249678 -355.370797) (xy 431.202244 -355.403571) (xy 431.150416 -355.428831)
			(xy 431.095377 -355.446) (xy 431.03838 -355.454687) (xy 431.009552 -355.45522) (xy 430.982304 -355.454706)
			(xy 430.928363 -355.446945) (xy 430.876076 -355.431586) (xy 430.826506 -355.408943) (xy 430.780663 -355.379476)
			(xy 430.73948 -355.343786) (xy 430.703795 -355.302598) (xy 430.674334 -355.256752) (xy 430.651697 -355.207179)
			(xy 430.636345 -355.15489) (xy 430.62859 -355.100948) (xy 430.62859 -355.046452) (xy 430.636345 -354.99251)
			(xy 430.651697 -354.940221) (xy 430.674334 -354.890648) (xy 430.703795 -354.844802) (xy 430.73948 -354.803614)
			(xy 430.780663 -354.767924) (xy 430.826506 -354.738457) (xy 430.876076 -354.715814) (xy 430.928363 -354.700455)
			(xy 430.982304 -354.692694) (xy 431.009552 -354.692204) (xy 431.009806 -354.692204) (xy 431.03501 -354.692606)
			(xy 431.084977 -354.699246) (xy 431.133632 -354.712421) (xy 431.180122 -354.731903) (xy 431.202084 -354.744274)
			(xy 431.21199 -354.750116) (xy 431.233834 -354.752148) (xy 431.328576 -354.71862) (xy 431.344324 -354.703126)
			(xy 431.348388 -354.692712) (xy 431.359084 -354.665935) (xy 431.38737 -354.615692) (xy 431.422899 -354.570282)
			(xy 431.464861 -354.530738) (xy 431.512299 -354.497964) (xy 431.56413 -354.472707) (xy 431.619174 -354.455542)
			(xy 431.676175 -354.446861) (xy 431.705004 -354.446332) (xy 431.732259 -354.446752) (xy 431.786213 -354.45451)
			(xy 431.838514 -354.469869) (xy 431.888097 -354.492515) (xy 431.933952 -354.521987) (xy 431.975146 -354.557685)
			(xy 432.01084 -354.598883) (xy 432.040306 -354.644741) (xy 432.062947 -354.694327) (xy 432.075669 -354.73767)
			(xy 434.216556 -354.73767) (xy 434.21705 -354.710096) (xy 434.224994 -354.655524) (xy 434.240712 -354.602664)
			(xy 434.263877 -354.552617) (xy 434.294005 -354.506427) (xy 434.33047 -354.465056) (xy 434.351176 -354.44684)
			(xy 434.359246 -354.43928) (xy 434.3686 -354.419272) (xy 434.36921 -354.408232) (xy 434.36921 -354.330508)
			(xy 434.368634 -354.31946) (xy 434.359274 -354.299439) (xy 434.351176 -354.2919) (xy 434.330457 -354.273698)
			(xy 434.293988 -354.232326) (xy 434.263858 -354.186135) (xy 434.240693 -354.136085) (xy 434.224979 -354.083221)
			(xy 434.217041 -354.028645) (xy 434.216556 -354.00107) (xy 434.21705 -353.97382) (xy 434.224809 -353.919874)
			(xy 434.240167 -353.867582) (xy 434.262809 -353.818007) (xy 434.292275 -353.772158) (xy 434.327965 -353.730969)
			(xy 434.369153 -353.695278) (xy 434.415001 -353.665811) (xy 434.464576 -353.643169) (xy 434.516868 -353.627811)
			(xy 434.570814 -353.62005) (xy 434.598064 -353.619562) (xy 434.598572 -353.619562) (xy 434.632354 -353.621086)
			(xy 434.642514 -353.622102) (xy 434.661818 -353.616006) (xy 434.72481 -353.563174) (xy 434.732091 -353.556442)
			(xy 434.741377 -353.538944) (xy 434.742844 -353.529138) (xy 434.742844 -353.528376) (xy 434.745854 -353.500235)
			(xy 434.759046 -353.445202) (xy 434.780227 -353.392723) (xy 434.80893 -353.34395) (xy 434.844526 -353.299955)
			(xy 434.886233 -353.261703) (xy 434.933135 -353.230035) (xy 434.984202 -353.205645) (xy 435.038312 -353.18907)
			(xy 435.094278 -353.180674) (xy 435.122574 -353.180142) (xy 435.122828 -353.180142) (xy 435.140847 -353.180364)
			(xy 435.176722 -353.183798) (xy 435.194456 -353.187) (xy 435.204108 -353.188778) (xy 435.223158 -353.185222)
			(xy 435.298088 -353.137216) (xy 435.309518 -353.121468) (xy 435.311804 -353.11207) (xy 435.319223 -353.085032)
			(xy 435.340849 -353.033306) (xy 435.369811 -352.985301) (xy 435.405483 -352.942049) (xy 435.4471 -352.904481)
			(xy 435.493765 -352.873406) (xy 435.544474 -352.849492) (xy 435.598136 -352.833254) (xy 435.653596 -352.825042)
			(xy 435.681628 -352.824542) (xy 435.708884 -352.824929) (xy 435.76284 -352.832691) (xy 435.815143 -352.848053)
			(xy 435.864726 -352.870703) (xy 435.910582 -352.900178) (xy 435.951775 -352.93588) (xy 435.987469 -352.977081)
			(xy 436.016935 -353.022942) (xy 436.039574 -353.072531) (xy 436.054926 -353.124836) (xy 436.062677 -353.178794)
			(xy 436.063136 -353.20605) (xy 436.062658 -353.233624) (xy 436.054711 -353.288198) (xy 436.03899 -353.341058)
			(xy 436.015823 -353.391105) (xy 435.985691 -353.437295) (xy 435.949223 -353.478665) (xy 435.928516 -353.49688)
			(xy 435.920452 -353.504446) (xy 435.911091 -353.524449) (xy 435.910482 -353.535488) (xy 435.910482 -353.613212)
			(xy 435.911073 -353.624259) (xy 435.92042 -353.644282) (xy 435.928516 -353.65182) (xy 435.949243 -353.670014)
			(xy 435.985712 -353.711386) (xy 436.015841 -353.75758) (xy 436.039004 -353.807632) (xy 436.054717 -353.860497)
			(xy 436.062653 -353.915074) (xy 436.063136 -353.94265) (xy 436.062658 -353.970224) (xy 436.054711 -354.024798)
			(xy 436.03899 -354.077658) (xy 436.015823 -354.127705) (xy 435.985691 -354.173895) (xy 435.949223 -354.215265)
			(xy 435.928516 -354.23348) (xy 435.920452 -354.241046) (xy 435.911091 -354.261049) (xy 435.910482 -354.272088)
			(xy 435.910482 -354.349812) (xy 435.911073 -354.360859) (xy 435.92042 -354.380882) (xy 435.928516 -354.38842)
			(xy 435.949243 -354.406614) (xy 435.985712 -354.447986) (xy 436.015841 -354.49418) (xy 436.039004 -354.544232)
			(xy 436.054717 -354.597097) (xy 436.062653 -354.651674) (xy 436.063136 -354.67925) (xy 436.062598 -354.7065)
			(xy 436.054849 -354.760447) (xy 436.039501 -354.812742) (xy 436.016866 -354.86232) (xy 435.987406 -354.908172)
			(xy 435.95172 -354.949365) (xy 435.910535 -354.985059) (xy 435.864689 -355.014528) (xy 435.815115 -355.037173)
			(xy 435.762823 -355.052532) (xy 435.708878 -355.060293) (xy 435.681628 -355.060758) (xy 435.653772 -355.060241)
			(xy 435.598655 -355.05212) (xy 435.545303 -355.036076) (xy 435.494848 -355.01245) (xy 435.448363 -354.981742)
			(xy 435.406833 -354.944606) (xy 435.37114 -354.901828) (xy 435.342043 -354.854318) (xy 435.320158 -354.803084)
			(xy 435.312566 -354.776278) (xy 435.31028 -354.767388) (xy 435.299612 -354.752148) (xy 435.22773 -354.704396)
			(xy 435.209696 -354.700332) (xy 435.200552 -354.701602) (xy 435.187536 -354.703274) (xy 435.161351 -354.705052)
			(xy 435.148228 -354.705158) (xy 435.134079 -354.705062) (xy 435.105856 -354.703029) (xy 435.09184 -354.701094)
			(xy 435.081934 -354.69957) (xy 435.062122 -354.704396) (xy 434.9877 -354.760276) (xy 434.97754 -354.777802)
			(xy 434.97627 -354.787962) (xy 434.972144 -354.815109) (xy 434.957172 -354.867935) (xy 434.934782 -354.91807)
			(xy 434.905438 -354.964478) (xy 434.869745 -355.006201) (xy 434.82844 -355.042377) (xy 434.782376 -355.07226)
			(xy 434.732505 -355.095231) (xy 434.679857 -355.110817) (xy 434.625518 -355.118696) (xy 434.598064 -355.119178)
			(xy 434.57081 -355.118756) (xy 434.516859 -355.110993) (xy 434.464561 -355.095632) (xy 434.414982 -355.072985)
			(xy 434.36913 -355.043512) (xy 434.32794 -355.007814) (xy 434.292249 -354.966617) (xy 434.262784 -354.92076)
			(xy 434.240145 -354.871177) (xy 434.224793 -354.818876) (xy 434.21704 -354.764924) (xy 434.216556 -354.73767)
			(xy 432.075669 -354.73767) (xy 432.078299 -354.74663) (xy 432.086051 -354.800585) (xy 432.086512 -354.82784)
			(xy 432.085851 -354.859403) (xy 432.075464 -354.921668) (xy 432.054979 -354.981377) (xy 432.040538 -355.00945)
			(xy 432.035712 -355.01834) (xy 432.03368 -355.037898) (xy 432.05654 -355.116384) (xy 432.05978 -355.125808)
			(xy 432.072196 -355.141368) (xy 432.08067 -355.14661) (xy 432.105753 -355.161188) (xy 432.151636 -355.196686)
			(xy 432.191613 -355.238724) (xy 432.224761 -355.286333) (xy 432.250315 -355.338413) (xy 432.267685 -355.393763)
			(xy 432.276471 -355.451106) (xy 432.277012 -355.480112) (xy 432.276896 -355.495032) (xy 432.274604 -355.524785)
			(xy 432.27244 -355.539548) (xy 432.270662 -355.551486) (xy 432.278028 -355.5746) (xy 432.408076 -355.704648)
			(xy 432.421792 -355.719124) (xy 432.443921 -355.752291) (xy 432.459183 -355.789125) (xy 432.466996 -355.828223)
			(xy 432.467512 -355.848158) (xy 432.467512 -356.603554) (xy 432.467049 -356.623495) (xy 432.45925 -356.662607)
			(xy 432.443981 -356.699451) (xy 432.421827 -356.732614) (xy 432.408076 -356.747064) (xy 431.6476 -357.50754)
			(xy 431.633141 -357.521275) (xy 431.599969 -357.543402) (xy 431.563129 -357.558659) (xy 431.524026 -357.566465)
			(xy 431.50409 -357.566976) (xy 426.957998 -357.566976) (xy 426.947926 -357.56738) (xy 426.929327 -357.575114)
			(xy 426.92193 -357.581962) (xy 426.007276 -358.49687) (xy 425.992801 -358.510704) (xy 425.959524 -358.532963)
			(xy 425.922541 -358.548293) (xy 425.883275 -358.556104) (xy 425.863258 -358.55656) (xy 422.819322 -358.55656)
			(xy 422.809252 -358.556981) (xy 422.790653 -358.564703) (xy 422.783254 -358.571546) (xy 422.004236 -359.35031)
			(xy 421.997352 -359.357851) (xy 421.989745 -359.376785) (xy 421.990104 -359.397186) (xy 421.993822 -359.406698)
			(xy 422.038526 -359.508044) (xy 422.064942 -359.524554) (xy 422.08069 -359.523792) (xy 422.081198 -359.523792)
			(xy 422.098724 -359.523284) (xy 422.099232 -359.523284) (xy 422.12647 -359.523816) (xy 422.180389 -359.531599)
			(xy 422.232652 -359.546973) (xy 422.282197 -359.569625) (xy 422.328015 -359.599095) (xy 422.369175 -359.634784)
			(xy 422.404839 -359.675964) (xy 422.434282 -359.7218) (xy 422.456906 -359.771358) (xy 422.472249 -359.82363)
			(xy 422.474058 -359.836212) (xy 424.433236 -359.836212) (xy 424.437307 -359.78059) (xy 424.449433 -359.726153)
			(xy 424.469356 -359.674062) (xy 424.496652 -359.625427) (xy 424.530738 -359.581284) (xy 424.570887 -359.542575)
			(xy 424.616245 -359.510124) (xy 424.665845 -359.484623) (xy 424.718629 -359.466616) (xy 424.773472 -359.456486)
			(xy 424.829206 -359.454449) (xy 424.884643 -359.460549) (xy 424.9386 -359.474655) (xy 424.989929 -359.496467)
			(xy 425.037535 -359.525521) (xy 425.080403 -359.561196) (xy 425.11762 -359.602733) (xy 425.148393 -359.649246)
			(xy 425.172065 -359.699743) (xy 425.188133 -359.75315) (xy 425.196253 -359.808326) (xy 425.196762 -359.836212)
			(xy 425.196253 -359.864098) (xy 425.188133 -359.919274) (xy 425.172065 -359.972681) (xy 425.148393 -360.023178)
			(xy 425.11762 -360.069691) (xy 425.080403 -360.111228) (xy 425.037535 -360.146903) (xy 424.989929 -360.175957)
			(xy 424.9386 -360.197769) (xy 424.884643 -360.211875) (xy 424.829206 -360.217975) (xy 424.773472 -360.215938)
			(xy 424.718629 -360.205808) (xy 424.665845 -360.187801) (xy 424.616245 -360.1623) (xy 424.570887 -360.129849)
			(xy 424.530738 -360.09114) (xy 424.496652 -360.046997) (xy 424.469356 -359.998362) (xy 424.449433 -359.946271)
			(xy 424.437307 -359.891834) (xy 424.433236 -359.836212) (xy 422.474058 -359.836212) (xy 422.48 -359.877553)
			(xy 422.480486 -359.904792) (xy 422.48 -359.932043) (xy 422.472244 -359.985991) (xy 422.456889 -360.038286)
			(xy 422.434247 -360.087863) (xy 422.404781 -360.133713) (xy 422.36909 -360.174904) (xy 422.327899 -360.210595)
			(xy 422.282049 -360.240061) (xy 422.232472 -360.262703) (xy 422.180177 -360.278058) (xy 422.126229 -360.285814)
			(xy 422.071727 -360.285814) (xy 422.017779 -360.278058) (xy 421.965484 -360.262703) (xy 421.915907 -360.240061)
			(xy 421.870057 -360.210595) (xy 421.828866 -360.174904) (xy 421.793175 -360.133713) (xy 421.763709 -360.087863)
			(xy 421.741067 -360.038286) (xy 421.725712 -359.985991) (xy 421.717956 -359.932043) (xy 421.71747 -359.904792)
			(xy 421.71747 -359.904538) (xy 421.718011 -359.875973) (xy 421.726545 -359.819484) (xy 421.743398 -359.764896)
			(xy 421.755316 -359.73893) (xy 421.762428 -359.724198) (xy 421.757094 -359.692448) (xy 421.74541 -359.680764)
			(xy 421.737998 -359.67408) (xy 421.719565 -359.666483) (xy 421.699627 -359.666483) (xy 421.681194 -359.67408)
			(xy 421.673782 -359.680764) (xy 421.553894 -359.800652) (xy 421.547082 -359.808074) (xy 421.539346 -359.826656)
			(xy 421.538908 -359.83672) (xy 421.538908 -361.741212) (xy 421.89019 -361.741212) (xy 421.8907 -361.712991)
			(xy 421.899014 -361.657165) (xy 421.915463 -361.603173) (xy 421.939686 -361.552194) (xy 421.971156 -361.50534)
			(xy 422.009186 -361.463634) (xy 422.052946 -361.427986) (xy 422.10148 -361.399174) (xy 422.153729 -361.377828)
			(xy 422.18102 -361.370626) (xy 422.191942 -361.367832) (xy 422.209214 -361.354116) (xy 422.248838 -361.274106)
			(xy 422.253266 -361.263942) (xy 422.253787 -361.241801) (xy 422.249854 -361.231434) (xy 422.249854 -361.230926)
			(xy 422.239755 -361.206756) (xy 422.225511 -361.156347) (xy 422.218303 -361.104463) (xy 422.21785 -361.078272)
			(xy 422.218336 -361.051021) (xy 422.226092 -360.997073) (xy 422.241447 -360.944778) (xy 422.264089 -360.895201)
			(xy 422.293555 -360.849351) (xy 422.329246 -360.80816) (xy 422.370437 -360.772469) (xy 422.416287 -360.743003)
			(xy 422.465864 -360.720361) (xy 422.518159 -360.705006) (xy 422.572107 -360.69725) (xy 422.626609 -360.69725)
			(xy 422.680557 -360.705006) (xy 422.732852 -360.720361) (xy 422.762937 -360.734101) (xy 435.087517 -360.734101)
			(xy 435.091247 -360.680849) (xy 435.102365 -360.628636) (xy 435.120653 -360.578484) (xy 435.145754 -360.53137)
			(xy 435.177178 -360.488216) (xy 435.214312 -360.449865) (xy 435.235096 -360.433112) (xy 435.243887 -360.425489)
			(xy 435.25408 -360.4046) (xy 435.254654 -360.39298) (xy 435.254654 -360.313224) (xy 435.254103 -360.301593)
			(xy 435.243924 -360.280683) (xy 435.235096 -360.273092) (xy 435.212608 -360.254907) (xy 435.172873 -360.212885)
			(xy 435.139935 -360.165349) (xy 435.114547 -360.113387) (xy 435.097292 -360.058189) (xy 435.088564 -360.001018)
			(xy 435.08803 -359.972102) (xy 435.088457 -359.944847) (xy 435.096215 -359.890893) (xy 435.111573 -359.838592)
			(xy 435.134218 -359.78901) (xy 435.163689 -359.743155) (xy 435.199387 -359.701961) (xy 435.240584 -359.666267)
			(xy 435.286441 -359.6368) (xy 435.336026 -359.61416) (xy 435.388329 -359.598807) (xy 435.442283 -359.591055)
			(xy 435.469538 -359.590594) (xy 435.498455 -359.591121) (xy 435.555627 -359.599844) (xy 435.610828 -359.617097)
			(xy 435.66279 -359.642487) (xy 435.710324 -359.675431) (xy 435.752339 -359.715174) (xy 435.770528 -359.73766)
			(xy 435.778122 -359.74648) (xy 435.799033 -359.756654) (xy 435.81066 -359.757218) (xy 435.890416 -359.757218)
			(xy 435.902046 -359.756667) (xy 435.922955 -359.746486) (xy 435.930548 -359.73766) (xy 435.948758 -359.715193)
			(xy 435.990775 -359.675459) (xy 436.038307 -359.642519) (xy 436.090264 -359.617128) (xy 436.145457 -359.599868)
			(xy 436.202623 -359.591133) (xy 436.231538 -359.590594) (xy 436.25879 -359.591042) (xy 436.312739 -359.598804)
			(xy 436.365035 -359.614164) (xy 436.414612 -359.63681) (xy 436.460463 -359.66628) (xy 436.501653 -359.701976)
			(xy 436.537344 -359.743169) (xy 436.566809 -359.789023) (xy 436.58945 -359.838603) (xy 436.604804 -359.8909)
			(xy 436.61256 -359.94485) (xy 436.613046 -359.972102) (xy 436.61255 -360.00102) (xy 436.603819 -360.058193)
			(xy 436.586558 -360.113393) (xy 436.561162 -360.165355) (xy 436.528214 -360.212888) (xy 436.488468 -360.254903)
			(xy 436.46598 -360.273092) (xy 436.457183 -360.280709) (xy 436.446994 -360.301602) (xy 436.446422 -360.313224)
			(xy 436.446422 -360.39298) (xy 436.446979 -360.40461) (xy 436.457154 -360.42552) (xy 436.46598 -360.433112)
			(xy 436.486763 -360.449864) (xy 436.52389 -360.488219) (xy 436.555308 -360.531375) (xy 436.580404 -360.578488)
			(xy 436.598689 -360.62864) (xy 436.609804 -360.680851) (xy 436.613533 -360.734101) (xy 436.609804 -360.787352)
			(xy 436.598688 -360.839562) (xy 436.580403 -360.889714) (xy 436.555307 -360.936827) (xy 436.523888 -360.979983)
			(xy 436.486761 -361.018338) (xy 436.46598 -361.035092) (xy 436.457183 -361.042709) (xy 436.446994 -361.063602)
			(xy 436.446422 -361.075224) (xy 436.446422 -361.15498) (xy 436.446979 -361.16661) (xy 436.457154 -361.18752)
			(xy 436.46598 -361.195112) (xy 436.488465 -361.213301) (xy 436.528201 -361.255321) (xy 436.56114 -361.302856)
			(xy 436.586529 -361.354818) (xy 436.603784 -361.410016) (xy 436.612512 -361.467186) (xy 436.613046 -361.496102)
			(xy 436.612524 -361.523352) (xy 436.604768 -361.577296) (xy 436.589415 -361.629588) (xy 436.566776 -361.679162)
			(xy 436.537313 -361.725011) (xy 436.501626 -361.7662) (xy 436.46044 -361.801892) (xy 436.414594 -361.831359)
			(xy 436.365022 -361.854002) (xy 436.312731 -361.869361) (xy 436.258788 -361.877122) (xy 436.231538 -361.87761)
			(xy 436.20262 -361.877098) (xy 436.145447 -361.868373) (xy 436.090247 -361.851116) (xy 436.038285 -361.825723)
			(xy 435.990751 -361.792776) (xy 435.948737 -361.753031) (xy 435.930548 -361.730544) (xy 435.92292 -361.721759)
			(xy 435.902035 -361.711565) (xy 435.890416 -361.710986) (xy 435.81066 -361.710986) (xy 435.799028 -361.711521)
			(xy 435.778119 -361.721713) (xy 435.770528 -361.730544) (xy 435.752332 -361.753023) (xy 435.710312 -361.792757)
			(xy 435.662778 -361.825695) (xy 435.610818 -361.851084) (xy 435.555622 -361.868341) (xy 435.498454 -361.877073)
			(xy 435.469538 -361.87761) (xy 435.442286 -361.877109) (xy 435.388337 -361.869358) (xy 435.33604 -361.854006)
			(xy 435.28646 -361.831369) (xy 435.240607 -361.801905) (xy 435.199414 -361.766215) (xy 435.163719 -361.725025)
			(xy 435.134251 -361.679175) (xy 435.111608 -361.629598) (xy 435.096251 -361.577302) (xy 435.088494 -361.523354)
			(xy 435.08803 -361.496102) (xy 435.088539 -361.467185) (xy 435.097268 -361.410012) (xy 435.114527 -361.354813)
			(xy 435.139921 -361.302851) (xy 435.172866 -361.255317) (xy 435.212609 -361.213301) (xy 435.235096 -361.195112)
			(xy 435.243887 -361.187489) (xy 435.25408 -361.1666) (xy 435.254654 -361.15498) (xy 435.254654 -361.075224)
			(xy 435.254103 -361.063593) (xy 435.243924 -361.042683) (xy 435.235096 -361.035092) (xy 435.214314 -361.018337)
			(xy 435.17718 -360.979986) (xy 435.145755 -360.936832) (xy 435.120654 -360.889719) (xy 435.102366 -360.839566)
			(xy 435.091248 -360.787354) (xy 435.087517 -360.734101) (xy 422.762937 -360.734101) (xy 422.782429 -360.743003)
			(xy 422.828279 -360.772469) (xy 422.86947 -360.80816) (xy 422.905161 -360.849351) (xy 422.934627 -360.895201)
			(xy 422.957269 -360.944778) (xy 422.972624 -360.997073) (xy 422.98038 -361.051021) (xy 422.980866 -361.078272)
			(xy 422.980375 -361.106494) (xy 422.972062 -361.162322) (xy 422.955613 -361.216317) (xy 422.931389 -361.267298)
			(xy 422.899916 -361.314153) (xy 422.861883 -361.355859) (xy 422.81812 -361.391506) (xy 422.769582 -361.420316)
			(xy 422.717329 -361.441658) (xy 422.690036 -361.448858) (xy 422.679114 -361.451652) (xy 422.661842 -361.465368)
			(xy 422.627501 -361.53471) (xy 424.407836 -361.53471) (xy 424.411907 -361.479088) (xy 424.424033 -361.424651)
			(xy 424.443956 -361.37256) (xy 424.471252 -361.323925) (xy 424.505338 -361.279782) (xy 424.545487 -361.241073)
			(xy 424.590845 -361.208622) (xy 424.640445 -361.183121) (xy 424.693229 -361.165114) (xy 424.748072 -361.154984)
			(xy 424.803806 -361.152947) (xy 424.859243 -361.159047) (xy 424.9132 -361.173153) (xy 424.964529 -361.194965)
			(xy 425.012135 -361.224019) (xy 425.055003 -361.259694) (xy 425.09222 -361.301231) (xy 425.122993 -361.347744)
			(xy 425.146665 -361.398241) (xy 425.162733 -361.451648) (xy 425.170853 -361.506824) (xy 425.171362 -361.53471)
			(xy 425.170853 -361.562596) (xy 425.162733 -361.617772) (xy 425.146665 -361.671179) (xy 425.122993 -361.721676)
			(xy 425.09222 -361.768189) (xy 425.055003 -361.809726) (xy 425.012135 -361.845401) (xy 424.971544 -361.870174)
			(xy 431.124356 -361.870174) (xy 431.124356 -361.785478) (xy 431.132407 -361.701164) (xy 431.148436 -361.617998)
			(xy 431.172297 -361.536731) (xy 431.203776 -361.458101) (xy 431.242587 -361.38282) (xy 431.288377 -361.311568)
			(xy 431.340733 -361.244992) (xy 431.399181 -361.183694) (xy 431.463191 -361.128229) (xy 431.532183 -361.0791)
			(xy 431.605533 -361.036751) (xy 431.682576 -361.001567) (xy 431.762615 -360.973865) (xy 431.844924 -360.953897)
			(xy 431.928759 -360.941844) (xy 432.01336 -360.937814) (xy 432.097961 -360.941844) (xy 432.181796 -360.953897)
			(xy 432.264105 -360.973865) (xy 432.344144 -361.001567) (xy 432.421187 -361.036751) (xy 432.494537 -361.0791)
			(xy 432.563529 -361.128229) (xy 432.627539 -361.183694) (xy 432.685987 -361.244992) (xy 432.738343 -361.311568)
			(xy 432.784133 -361.38282) (xy 432.822944 -361.458101) (xy 432.854423 -361.536731) (xy 432.878284 -361.617998)
			(xy 432.894313 -361.701164) (xy 432.902364 -361.785478) (xy 432.902868 -361.827826) (xy 432.902364 -361.870174)
			(xy 432.894313 -361.954488) (xy 432.878284 -362.037654) (xy 432.854423 -362.118921) (xy 432.822944 -362.197551)
			(xy 432.784133 -362.272832) (xy 432.738343 -362.344084) (xy 432.685987 -362.41066) (xy 432.627539 -362.471958)
			(xy 432.563529 -362.527423) (xy 432.494537 -362.576552) (xy 432.421187 -362.618901) (xy 432.344144 -362.654085)
			(xy 432.264105 -362.681787) (xy 432.181796 -362.701755) (xy 432.097961 -362.713808) (xy 432.01336 -362.717839)
			(xy 431.928759 -362.713808) (xy 431.844924 -362.701755) (xy 431.762615 -362.681787) (xy 431.682576 -362.654085)
			(xy 431.605533 -362.618901) (xy 431.532183 -362.576552) (xy 431.463191 -362.527423) (xy 431.399181 -362.471958)
			(xy 431.340733 -362.41066) (xy 431.288377 -362.344084) (xy 431.242587 -362.272832) (xy 431.203776 -362.197551)
			(xy 431.172297 -362.118921) (xy 431.148436 -362.037654) (xy 431.132407 -361.954488) (xy 431.124356 -361.870174)
			(xy 424.971544 -361.870174) (xy 424.964529 -361.874455) (xy 424.9132 -361.896267) (xy 424.859243 -361.910373)
			(xy 424.803806 -361.916473) (xy 424.748072 -361.914436) (xy 424.693229 -361.904306) (xy 424.640445 -361.886299)
			(xy 424.590845 -361.860798) (xy 424.545487 -361.828347) (xy 424.505338 -361.789638) (xy 424.471252 -361.745495)
			(xy 424.443956 -361.69686) (xy 424.424033 -361.644769) (xy 424.411907 -361.590332) (xy 424.407836 -361.53471)
			(xy 422.627501 -361.53471) (xy 422.622218 -361.545378) (xy 422.617797 -361.555545) (xy 422.61727 -361.577684)
			(xy 422.621202 -361.58805) (xy 422.621202 -361.588558) (xy 422.631299 -361.612729) (xy 422.645543 -361.663137)
			(xy 422.652752 -361.715021) (xy 422.653206 -361.741212) (xy 422.653111 -361.751457) (xy 422.651969 -361.771915)
			(xy 422.65092 -361.782106) (xy 422.649904 -361.792266) (xy 422.655746 -361.812078) (xy 422.715944 -361.88396)
			(xy 422.734232 -361.893358) (xy 422.744392 -361.89412) (xy 422.772852 -361.89667) (xy 422.828568 -361.909356)
			(xy 422.88177 -361.930208) (xy 422.931268 -361.95876) (xy 422.975955 -361.994372) (xy 423.014833 -362.03625)
			(xy 423.047032 -362.083456) (xy 423.071833 -362.134936) (xy 423.088681 -362.189537) (xy 423.097199 -362.246041)
			(xy 423.097706 -362.274612) (xy 423.097235 -362.301594) (xy 423.089605 -362.355016) (xy 423.074527 -362.406832)
			(xy 423.052302 -362.456007) (xy 423.023372 -362.501561) (xy 422.988314 -362.542588) (xy 422.947828 -362.578267)
			(xy 422.902721 -362.607889) (xy 422.878504 -362.619798) (xy 422.870122 -362.623608) (xy 422.857422 -362.63707)
			(xy 422.823132 -362.716318) (xy 422.82237 -362.734352) (xy 422.825164 -362.743242) (xy 422.825164 -362.74375)
			(xy 422.83404 -362.772598) (xy 422.843603 -362.832191) (xy 422.844214 -362.862368) (xy 422.843728 -362.889619)
			(xy 422.837786 -362.930948) (xy 439.741056 -362.930948) (xy 439.741537 -362.903578) (xy 439.749349 -362.849399)
			(xy 439.764834 -362.796896) (xy 439.787673 -362.747148) (xy 439.817395 -362.701182) (xy 439.835036 -362.68025)
			(xy 439.83529 -362.679996) (xy 439.840883 -362.672914) (xy 439.847126 -362.655994) (xy 439.847482 -362.646976)
			(xy 439.847482 -362.57992) (xy 439.84712 -362.570904) (xy 439.840876 -362.553986) (xy 439.83529 -362.5469)
			(xy 439.835036 -362.5469) (xy 439.835036 -362.546646) (xy 439.817411 -362.525703) (xy 439.787695 -362.479734)
			(xy 439.764856 -362.429989) (xy 439.749362 -362.377491) (xy 439.741531 -362.323317) (xy 439.741056 -362.295948)
			(xy 439.7416 -362.268698) (xy 439.749349 -362.214752) (xy 439.764697 -362.162458) (xy 439.787332 -362.11288)
			(xy 439.816791 -362.067028) (xy 439.852477 -362.025836) (xy 439.893661 -361.990142) (xy 439.939506 -361.960672)
			(xy 439.989079 -361.938027) (xy 440.04137 -361.922667) (xy 440.095314 -361.914906) (xy 440.122564 -361.91444)
			(xy 440.149934 -361.914917) (xy 440.204113 -361.922731) (xy 440.256616 -361.938217) (xy 440.306363 -361.961056)
			(xy 440.35233 -361.990779) (xy 440.373262 -362.00842) (xy 440.373516 -362.008674) (xy 440.380588 -362.014282)
			(xy 440.397516 -362.020514) (xy 440.406536 -362.020866) (xy 440.473592 -362.020866) (xy 440.482609 -362.020512)
			(xy 440.499527 -362.014263) (xy 440.506612 -362.008674) (xy 440.506612 -362.00842) (xy 440.506866 -362.00842)
			(xy 440.527799 -361.990779) (xy 440.573767 -361.961055) (xy 440.623513 -361.938209) (xy 440.676015 -361.922713)
			(xy 440.730193 -361.914884) (xy 440.784935 -361.914884) (xy 440.839113 -361.922713) (xy 440.891615 -361.938209)
			(xy 440.941361 -361.961055) (xy 440.987329 -361.990779) (xy 441.008262 -362.00842) (xy 441.008516 -362.008674)
			(xy 441.015588 -362.014282) (xy 441.032516 -362.020514) (xy 441.041536 -362.020866) (xy 441.108592 -362.020866)
			(xy 441.117609 -362.020512) (xy 441.134527 -362.014263) (xy 441.141612 -362.008674) (xy 441.141612 -362.00842)
			(xy 441.141866 -362.00842) (xy 441.162799 -361.990779) (xy 441.208767 -361.961055) (xy 441.258513 -361.938209)
			(xy 441.311015 -361.922713) (xy 441.365193 -361.914884) (xy 441.419935 -361.914884) (xy 441.474113 -361.922713)
			(xy 441.526615 -361.938209) (xy 441.576361 -361.961055) (xy 441.622329 -361.990779) (xy 441.643262 -362.00842)
			(xy 441.643516 -362.008674) (xy 441.650588 -362.014282) (xy 441.667516 -362.020514) (xy 441.676536 -362.020866)
			(xy 441.743592 -362.020866) (xy 441.752609 -362.020512) (xy 441.769527 -362.014263) (xy 441.776612 -362.008674)
			(xy 441.776866 -362.00842) (xy 441.780676 -362.005118) (xy 441.788794 -361.997516) (xy 441.798146 -361.977364)
			(xy 441.79871 -361.966256) (xy 441.79871 -361.888786) (xy 441.798091 -361.877743) (xy 441.788761 -361.857722)
			(xy 441.780676 -361.850178) (xy 441.759946 -361.831987) (xy 441.723478 -361.790614) (xy 441.693349 -361.744419)
			(xy 441.670187 -361.694367) (xy 441.654474 -361.641501) (xy 441.646539 -361.586924) (xy 441.646056 -361.559348)
			(xy 441.646537 -361.531978) (xy 441.654349 -361.477799) (xy 441.669834 -361.425296) (xy 441.692673 -361.375548)
			(xy 441.722395 -361.329582) (xy 441.740036 -361.30865) (xy 441.74029 -361.308396) (xy 441.745883 -361.301314)
			(xy 441.752126 -361.284394) (xy 441.752482 -361.275376) (xy 441.752482 -361.20832) (xy 441.75212 -361.199304)
			(xy 441.745876 -361.182386) (xy 441.74029 -361.1753) (xy 441.740036 -361.1753) (xy 441.740036 -361.175046)
			(xy 441.722442 -361.154075) (xy 441.692715 -361.108114) (xy 441.669866 -361.058374) (xy 441.654365 -361.005878)
			(xy 441.646532 -360.951705) (xy 441.646527 -360.896968) (xy 441.65435 -360.842793) (xy 441.66984 -360.790293)
			(xy 441.69268 -360.740549) (xy 441.722398 -360.694582) (xy 441.740036 -360.67365) (xy 441.74029 -360.673396)
			(xy 441.745883 -360.666314) (xy 441.752126 -360.649394) (xy 441.752482 -360.640376) (xy 441.752482 -360.57332)
			(xy 441.75212 -360.564304) (xy 441.745876 -360.547386) (xy 441.74029 -360.5403) (xy 441.740036 -360.5403)
			(xy 441.740036 -360.540046) (xy 441.722442 -360.519075) (xy 441.692715 -360.473114) (xy 441.669866 -360.423374)
			(xy 441.654365 -360.370878) (xy 441.646532 -360.316705) (xy 441.646527 -360.261968) (xy 441.65435 -360.207793)
			(xy 441.66984 -360.155293) (xy 441.69268 -360.105549) (xy 441.722398 -360.059582) (xy 441.740036 -360.03865)
			(xy 441.74029 -360.038396) (xy 441.745883 -360.031314) (xy 441.752126 -360.014394) (xy 441.752482 -360.005376)
			(xy 441.752482 -359.93832) (xy 441.75212 -359.929304) (xy 441.745876 -359.912386) (xy 441.74029 -359.9053)
			(xy 441.740036 -359.9053) (xy 441.740036 -359.905046) (xy 441.722411 -359.884103) (xy 441.692695 -359.838134)
			(xy 441.669856 -359.788389) (xy 441.654362 -359.735891) (xy 441.646531 -359.681717) (xy 441.646056 -359.654348)
			(xy 441.646535 -359.626774) (xy 441.654482 -359.572201) (xy 441.670203 -359.51934) (xy 441.693371 -359.469294)
			(xy 441.723502 -359.423104) (xy 441.759969 -359.381733) (xy 441.780676 -359.363518) (xy 441.788756 -359.355967)
			(xy 441.798104 -359.335952) (xy 441.79871 -359.32491) (xy 441.79871 -359.24744) (xy 441.798164 -359.236327)
			(xy 441.788813 -359.216166) (xy 441.780676 -359.208578) (xy 441.776866 -359.205276) (xy 441.776612 -359.205022)
			(xy 441.769533 -359.199425) (xy 441.75261 -359.193187) (xy 441.743592 -359.19283) (xy 441.676536 -359.19283)
			(xy 441.66752 -359.193198) (xy 441.650603 -359.199437) (xy 441.643516 -359.205022) (xy 441.643516 -359.205276)
			(xy 441.643262 -359.205276) (xy 441.622329 -359.222917) (xy 441.576361 -359.252641) (xy 441.526615 -359.275487)
			(xy 441.474113 -359.290983) (xy 441.419935 -359.298812) (xy 441.365193 -359.298812) (xy 441.311015 -359.290983)
			(xy 441.258513 -359.275487) (xy 441.208767 -359.252641) (xy 441.162799 -359.222917) (xy 441.141866 -359.205276)
			(xy 441.141612 -359.205022) (xy 441.134533 -359.199425) (xy 441.11761 -359.193187) (xy 441.108592 -359.19283)
			(xy 441.041536 -359.19283) (xy 441.03252 -359.193198) (xy 441.015603 -359.199437) (xy 441.008516 -359.205022)
			(xy 441.008516 -359.205276) (xy 441.008262 -359.205276) (xy 440.987329 -359.222917) (xy 440.941361 -359.252641)
			(xy 440.891615 -359.275487) (xy 440.839113 -359.290983) (xy 440.784935 -359.298812) (xy 440.730193 -359.298812)
			(xy 440.676015 -359.290983) (xy 440.623513 -359.275487) (xy 440.573767 -359.252641) (xy 440.527799 -359.222917)
			(xy 440.506866 -359.205276) (xy 440.506612 -359.205022) (xy 440.499533 -359.199425) (xy 440.48261 -359.193187)
			(xy 440.473592 -359.19283) (xy 440.406536 -359.19283) (xy 440.39752 -359.193198) (xy 440.380603 -359.199437)
			(xy 440.373516 -359.205022) (xy 440.373516 -359.205276) (xy 440.373262 -359.205276) (xy 440.352314 -359.222896)
			(xy 440.306346 -359.252611) (xy 440.256603 -359.275451) (xy 440.204105 -359.290947) (xy 440.149932 -359.29878)
			(xy 440.122564 -359.299256) (xy 440.095314 -359.298756) (xy 440.041369 -359.290996) (xy 439.989078 -359.275638)
			(xy 439.939504 -359.252997) (xy 439.893656 -359.223531) (xy 439.852467 -359.187841) (xy 439.816776 -359.146654)
			(xy 439.787309 -359.100807) (xy 439.764666 -359.051233) (xy 439.749307 -358.998942) (xy 439.741545 -358.944998)
			(xy 439.741056 -358.917748) (xy 439.741537 -358.890378) (xy 439.749349 -358.836199) (xy 439.764834 -358.783696)
			(xy 439.787673 -358.733948) (xy 439.817395 -358.687982) (xy 439.835036 -358.66705) (xy 439.83529 -358.666796)
			(xy 439.840883 -358.659714) (xy 439.847126 -358.642794) (xy 439.847482 -358.633776) (xy 439.847482 -358.56672)
			(xy 439.84712 -358.557704) (xy 439.840876 -358.540786) (xy 439.83529 -358.5337) (xy 439.835036 -358.5337)
			(xy 439.835036 -358.533446) (xy 439.817411 -358.512503) (xy 439.787695 -358.466534) (xy 439.764856 -358.416789)
			(xy 439.749362 -358.364291) (xy 439.741531 -358.310117) (xy 439.741056 -358.282748) (xy 439.7416 -358.255498)
			(xy 439.749349 -358.201552) (xy 439.764697 -358.149258) (xy 439.787332 -358.09968) (xy 439.816791 -358.053828)
			(xy 439.852477 -358.012636) (xy 439.893661 -357.976942) (xy 439.939506 -357.947472) (xy 439.989079 -357.924827)
			(xy 440.04137 -357.909467) (xy 440.095314 -357.901706) (xy 440.122564 -357.90124) (xy 440.149934 -357.901717)
			(xy 440.204113 -357.909531) (xy 440.256616 -357.925017) (xy 440.306363 -357.947856) (xy 440.35233 -357.977579)
			(xy 440.373262 -357.99522) (xy 440.373516 -357.995474) (xy 440.380588 -358.001082) (xy 440.397516 -358.007314)
			(xy 440.406536 -358.007666) (xy 440.473592 -358.007666) (xy 440.482609 -358.007312) (xy 440.499527 -358.001063)
			(xy 440.506612 -357.995474) (xy 440.506612 -357.99522) (xy 440.506866 -357.99522) (xy 440.527799 -357.977579)
			(xy 440.573767 -357.947855) (xy 440.623513 -357.925009) (xy 440.676015 -357.909513) (xy 440.730193 -357.901684)
			(xy 440.784935 -357.901684) (xy 440.839113 -357.909513) (xy 440.891615 -357.925009) (xy 440.941361 -357.947855)
			(xy 440.987329 -357.977579) (xy 441.008262 -357.99522) (xy 441.008516 -357.995474) (xy 441.015588 -358.001082)
			(xy 441.032516 -358.007314) (xy 441.041536 -358.007666) (xy 441.108592 -358.007666) (xy 441.117609 -358.007312)
			(xy 441.134527 -358.001063) (xy 441.141612 -357.995474) (xy 441.141612 -357.99522) (xy 441.141866 -357.99522)
			(xy 441.162799 -357.977579) (xy 441.208767 -357.947855) (xy 441.258513 -357.925009) (xy 441.311015 -357.909513)
			(xy 441.365193 -357.901684) (xy 441.419935 -357.901684) (xy 441.474113 -357.909513) (xy 441.526615 -357.925009)
			(xy 441.576361 -357.947855) (xy 441.622329 -357.977579) (xy 441.643262 -357.99522) (xy 441.643516 -357.995474)
			(xy 441.650588 -358.001082) (xy 441.667516 -358.007314) (xy 441.676536 -358.007666) (xy 441.743592 -358.007666)
			(xy 441.752609 -358.007312) (xy 441.769527 -358.001063) (xy 441.776612 -357.995474) (xy 441.776612 -357.99522)
			(xy 441.776866 -357.99522) (xy 441.797799 -357.977579) (xy 441.843767 -357.947855) (xy 441.893513 -357.925009)
			(xy 441.946015 -357.909513) (xy 442.000193 -357.901684) (xy 442.054935 -357.901684) (xy 442.109113 -357.909513)
			(xy 442.161615 -357.925009) (xy 442.211361 -357.947855) (xy 442.257329 -357.977579) (xy 442.278262 -357.99522)
			(xy 442.278516 -357.995474) (xy 442.285588 -358.001082) (xy 442.302516 -358.007314) (xy 442.311536 -358.007666)
			(xy 442.378592 -358.007666) (xy 442.387609 -358.007312) (xy 442.404527 -358.001063) (xy 442.411612 -357.995474)
			(xy 442.411612 -357.99522) (xy 442.411866 -357.99522) (xy 442.432803 -357.977586) (xy 442.478774 -357.947873)
			(xy 442.52852 -357.925036) (xy 442.58102 -357.909543) (xy 442.635195 -357.901714) (xy 442.662564 -357.90124)
			(xy 442.689818 -357.901689) (xy 442.743772 -357.909442) (xy 442.796073 -357.924796) (xy 442.845656 -357.947438)
			(xy 442.891512 -357.976907) (xy 442.932706 -358.012602) (xy 442.968401 -358.053798) (xy 442.997868 -358.099654)
			(xy 443.020508 -358.149238) (xy 443.03586 -358.20154) (xy 443.043612 -358.255494) (xy 443.044072 -358.282748)
			(xy 443.043582 -358.310117) (xy 443.035771 -358.364296) (xy 443.020288 -358.416799) (xy 442.997451 -358.466546)
			(xy 442.967731 -358.512514) (xy 442.950092 -358.533446) (xy 442.949838 -358.5337) (xy 442.944238 -358.540777)
			(xy 442.938001 -358.557701) (xy 442.937646 -358.56672) (xy 442.937646 -358.633776) (xy 442.938005 -358.642793)
			(xy 442.94425 -358.65971) (xy 442.949838 -358.666796) (xy 442.950092 -358.666796) (xy 442.950092 -358.66705)
			(xy 442.96772 -358.687991) (xy 442.997434 -358.733961) (xy 443.020272 -358.783707) (xy 443.035766 -358.836205)
			(xy 443.043597 -358.890379) (xy 443.044072 -358.917748) (xy 443.04358 -358.945322) (xy 443.035634 -358.999894)
			(xy 443.019915 -359.052754) (xy 442.99675 -359.1028) (xy 442.966622 -359.14899) (xy 442.930158 -359.190362)
			(xy 442.909452 -359.208578) (xy 442.901379 -359.216135) (xy 442.892025 -359.236145) (xy 442.891418 -359.247186)
			(xy 442.891418 -359.32491) (xy 442.892031 -359.335954) (xy 442.901364 -359.355976) (xy 442.909452 -359.363518)
			(xy 442.930165 -359.381727) (xy 442.966638 -359.423095) (xy 442.996771 -359.469285) (xy 443.019936 -359.519334)
			(xy 443.035652 -359.572197) (xy 443.043589 -359.626773) (xy 443.044072 -359.654348) (xy 443.043582 -359.681717)
			(xy 443.035771 -359.735896) (xy 443.020288 -359.788399) (xy 442.997451 -359.838146) (xy 442.967731 -359.884114)
			(xy 442.950092 -359.905046) (xy 442.949838 -359.9053) (xy 442.944238 -359.912377) (xy 442.938001 -359.929301)
			(xy 442.937646 -359.93832) (xy 442.937646 -360.005376) (xy 442.938005 -360.014393) (xy 442.94425 -360.03131)
			(xy 442.949838 -360.038396) (xy 442.950092 -360.038396) (xy 442.950092 -360.03865) (xy 442.967779 -360.059545)
			(xy 442.9975 -360.10552) (xy 443.020342 -360.155272) (xy 443.035833 -360.20778) (xy 443.043657 -360.261963)
			(xy 443.043652 -360.316709) (xy 443.035818 -360.370891) (xy 443.020316 -360.423395) (xy 442.997465 -360.473144)
			(xy 442.967735 -360.519113) (xy 442.950092 -360.540046) (xy 442.949838 -360.5403) (xy 442.944238 -360.547377)
			(xy 442.938001 -360.564301) (xy 442.937646 -360.57332) (xy 442.937646 -360.640376) (xy 442.938005 -360.649393)
			(xy 442.94425 -360.66631) (xy 442.949838 -360.673396) (xy 442.950092 -360.673396) (xy 442.950092 -360.67365)
			(xy 442.967779 -360.694545) (xy 442.9975 -360.74052) (xy 443.020342 -360.790272) (xy 443.035833 -360.84278)
			(xy 443.043657 -360.896963) (xy 443.043652 -360.951709) (xy 443.035818 -361.005891) (xy 443.020316 -361.058395)
			(xy 442.997465 -361.108144) (xy 442.967735 -361.154113) (xy 442.950092 -361.175046) (xy 442.949838 -361.1753)
			(xy 442.944238 -361.182377) (xy 442.938001 -361.199301) (xy 442.937646 -361.20832) (xy 442.937646 -361.275376)
			(xy 442.938005 -361.284393) (xy 442.94425 -361.30131) (xy 442.949838 -361.308396) (xy 442.950092 -361.308396)
			(xy 442.950092 -361.30865) (xy 442.96772 -361.329591) (xy 442.997434 -361.375561) (xy 443.020272 -361.425307)
			(xy 443.035766 -361.477805) (xy 443.043597 -361.531979) (xy 443.044072 -361.559348) (xy 443.043667 -361.586602)
			(xy 443.035903 -361.640555) (xy 443.02054 -361.692853) (xy 442.99789 -361.742433) (xy 442.968416 -361.788285)
			(xy 442.932716 -361.829475) (xy 442.891517 -361.865166) (xy 442.845659 -361.894631) (xy 442.796074 -361.917269)
			(xy 442.743772 -361.932621) (xy 442.689818 -361.940373) (xy 442.662564 -361.940856) (xy 442.635192 -361.940422)
			(xy 442.581012 -361.932598) (xy 442.528508 -361.917102) (xy 442.478761 -361.894253) (xy 442.432796 -361.864521)
			(xy 442.411866 -361.846876) (xy 442.411612 -361.846622) (xy 442.404533 -361.841025) (xy 442.38761 -361.834787)
			(xy 442.378592 -361.83443) (xy 442.311536 -361.83443) (xy 442.30252 -361.834798) (xy 442.285603 -361.841037)
			(xy 442.278516 -361.846622) (xy 442.278262 -361.846876) (xy 442.274452 -361.850178) (xy 442.26634 -361.857786)
			(xy 442.256984 -361.877934) (xy 442.256418 -361.88904) (xy 442.256418 -361.96651) (xy 442.257031 -361.977554)
			(xy 442.266364 -361.997576) (xy 442.274452 -362.005118) (xy 442.295165 -362.023327) (xy 442.331638 -362.064695)
			(xy 442.361771 -362.110885) (xy 442.384936 -362.160934) (xy 442.400652 -362.213797) (xy 442.408589 -362.268373)
			(xy 442.409072 -362.295948) (xy 442.408667 -362.323202) (xy 442.400903 -362.377155) (xy 442.38554 -362.429453)
			(xy 442.36289 -362.479033) (xy 442.333416 -362.524885) (xy 442.297716 -362.566075) (xy 442.256517 -362.601766)
			(xy 442.210659 -362.631231) (xy 442.161074 -362.653869) (xy 442.108772 -362.669221) (xy 442.054818 -362.676973)
			(xy 442.027564 -362.677456) (xy 441.998087 -362.676888) (xy 441.939835 -362.667827) (xy 441.88367 -362.649912)
			(xy 441.83093 -362.623569) (xy 441.782872 -362.589424) (xy 441.761372 -362.569252) (xy 441.754047 -362.562706)
			(xy 441.735879 -362.555269) (xy 441.726066 -362.554774) (xy 441.672726 -362.554774) (xy 441.665868 -362.56214)
			(xy 441.659319 -362.569463) (xy 441.651883 -362.587632) (xy 441.65139 -362.597446) (xy 441.65139 -362.62945)
			(xy 441.651862 -362.639266) (xy 441.659317 -362.65743) (xy 441.665868 -362.664756) (xy 441.686023 -362.686272)
			(xy 441.72017 -362.734327) (xy 441.746519 -362.787062) (xy 441.764445 -362.843223) (xy 441.77352 -362.901472)
			(xy 441.774072 -362.930948) (xy 441.773667 -362.958202) (xy 441.765903 -363.012155) (xy 441.75054 -363.064453)
			(xy 441.72789 -363.114033) (xy 441.698416 -363.159885) (xy 441.662716 -363.201075) (xy 441.621517 -363.236766)
			(xy 441.575659 -363.266231) (xy 441.526074 -363.288869) (xy 441.473772 -363.304221) (xy 441.419818 -363.311973)
			(xy 441.392564 -363.312456) (xy 441.365192 -363.312022) (xy 441.311012 -363.304198) (xy 441.258508 -363.288702)
			(xy 441.208761 -363.265853) (xy 441.162796 -363.236121) (xy 441.141866 -363.218476) (xy 441.141612 -363.218222)
			(xy 441.134533 -363.212625) (xy 441.11761 -363.206387) (xy 441.108592 -363.20603) (xy 441.041536 -363.20603)
			(xy 441.03252 -363.206398) (xy 441.015603 -363.212637) (xy 441.008516 -363.218222) (xy 441.008262 -363.218476)
			(xy 440.987329 -363.236117) (xy 440.941361 -363.265841) (xy 440.891615 -363.288687) (xy 440.839113 -363.304183)
			(xy 440.784935 -363.312012) (xy 440.730193 -363.312012) (xy 440.676015 -363.304183) (xy 440.623513 -363.288687)
			(xy 440.573767 -363.265841) (xy 440.527799 -363.236117) (xy 440.506866 -363.218476) (xy 440.506612 -363.218222)
			(xy 440.499533 -363.212625) (xy 440.48261 -363.206387) (xy 440.473592 -363.20603) (xy 440.406536 -363.20603)
			(xy 440.39752 -363.206398) (xy 440.380603 -363.212637) (xy 440.373516 -363.218222) (xy 440.373516 -363.218476)
			(xy 440.373262 -363.218476) (xy 440.352314 -363.236096) (xy 440.306346 -363.265811) (xy 440.256603 -363.288651)
			(xy 440.204105 -363.304147) (xy 440.149932 -363.31198) (xy 440.122564 -363.312456) (xy 440.095314 -363.311956)
			(xy 440.041369 -363.304196) (xy 439.989078 -363.288838) (xy 439.939504 -363.266197) (xy 439.893656 -363.236731)
			(xy 439.852467 -363.201041) (xy 439.816776 -363.159854) (xy 439.787309 -363.114007) (xy 439.764666 -363.064433)
			(xy 439.749307 -363.012142) (xy 439.741545 -362.958198) (xy 439.741056 -362.930948) (xy 422.837786 -362.930948)
			(xy 422.835972 -362.943567) (xy 422.820617 -362.995862) (xy 422.797975 -363.045439) (xy 422.768509 -363.091289)
			(xy 422.732818 -363.13248) (xy 422.691627 -363.168171) (xy 422.645777 -363.197637) (xy 422.5962 -363.220279)
			(xy 422.543905 -363.235634) (xy 422.489957 -363.24339) (xy 422.435455 -363.24339) (xy 422.381507 -363.235634)
			(xy 422.329212 -363.220279) (xy 422.279635 -363.197637) (xy 422.233785 -363.168171) (xy 422.192594 -363.13248)
			(xy 422.156903 -363.091289) (xy 422.127437 -363.045439) (xy 422.104795 -362.995862) (xy 422.08944 -362.943567)
			(xy 422.081684 -362.889619) (xy 422.081198 -362.862368) (xy 422.081733 -362.835388) (xy 422.089352 -362.781968)
			(xy 422.10442 -362.730155) (xy 422.126636 -362.68098) (xy 422.155557 -362.635425) (xy 422.190606 -362.594397)
			(xy 422.231085 -362.558716) (xy 422.276186 -362.529092) (xy 422.3004 -362.517182) (xy 422.308782 -362.513372)
			(xy 422.321482 -362.49991) (xy 422.355772 -362.420662) (xy 422.356534 -362.402628) (xy 422.35374 -362.393738)
			(xy 422.35374 -362.39323) (xy 422.344882 -362.364377) (xy 422.335307 -362.304788) (xy 422.33469 -362.274612)
			(xy 422.334779 -362.264367) (xy 422.335925 -362.243909) (xy 422.336976 -362.233718) (xy 422.337992 -362.223558)
			(xy 422.33215 -362.203746) (xy 422.271952 -362.131864) (xy 422.253664 -362.122466) (xy 422.243504 -362.121704)
			(xy 422.215055 -362.119049) (xy 422.159343 -362.106377) (xy 422.106143 -362.085539) (xy 422.056646 -362.057001)
			(xy 422.011958 -362.021401) (xy 421.973078 -361.979535) (xy 421.940876 -361.932339) (xy 421.916072 -361.880869)
			(xy 421.899221 -361.826275) (xy 421.890699 -361.769779) (xy 421.89019 -361.741212) (xy 421.538908 -361.741212)
			(xy 421.538908 -363.719618) (xy 421.538424 -363.739558) (xy 421.530632 -363.778669) (xy 421.515369 -363.815513)
			(xy 421.49322 -363.848677) (xy 421.479472 -363.863128) (xy 420.835074 -364.507526) (xy 424.072048 -364.507526)
			(xy 424.076119 -364.451904) (xy 424.088245 -364.397467) (xy 424.108168 -364.345376) (xy 424.135464 -364.296741)
			(xy 424.16955 -364.252598) (xy 424.209699 -364.213889) (xy 424.255057 -364.181438) (xy 424.304657 -364.155937)
			(xy 424.357441 -364.13793) (xy 424.412284 -364.1278) (xy 424.468018 -364.125763) (xy 424.523455 -364.131863)
			(xy 424.577412 -364.145969) (xy 424.628741 -364.167781) (xy 424.676347 -364.196835) (xy 424.719215 -364.23251)
			(xy 424.756432 -364.274047) (xy 424.787205 -364.32056) (xy 424.810877 -364.371057) (xy 424.826945 -364.424464)
			(xy 424.835065 -364.47964) (xy 424.835574 -364.507526) (xy 424.835065 -364.535412) (xy 424.826945 -364.590588)
			(xy 424.810877 -364.643995) (xy 424.787205 -364.694492) (xy 424.756432 -364.741005) (xy 424.719215 -364.782542)
			(xy 424.676347 -364.818217) (xy 424.628741 -364.847271) (xy 424.577412 -364.869083) (xy 424.523455 -364.883189)
			(xy 424.468018 -364.889289) (xy 424.412284 -364.887252) (xy 424.357441 -364.877122) (xy 424.304657 -364.859115)
			(xy 424.255057 -364.833614) (xy 424.209699 -364.801163) (xy 424.16955 -364.762454) (xy 424.135464 -364.718311)
			(xy 424.108168 -364.669676) (xy 424.088245 -364.617585) (xy 424.076119 -364.563148) (xy 424.072048 -364.507526)
			(xy 420.835074 -364.507526) (xy 420.231824 -365.110776) (xy 420.772588 -365.110776) (xy 420.776659 -365.055154)
			(xy 420.788785 -365.000717) (xy 420.808708 -364.948626) (xy 420.836004 -364.899991) (xy 420.87009 -364.855848)
			(xy 420.910239 -364.817139) (xy 420.955597 -364.784688) (xy 421.005197 -364.759187) (xy 421.057981 -364.74118)
			(xy 421.112824 -364.73105) (xy 421.168558 -364.729013) (xy 421.223995 -364.735113) (xy 421.277952 -364.749219)
			(xy 421.329281 -364.771031) (xy 421.376887 -364.800085) (xy 421.419755 -364.83576) (xy 421.456972 -364.877297)
			(xy 421.487745 -364.92381) (xy 421.511417 -364.974307) (xy 421.527485 -365.027714) (xy 421.535605 -365.08289)
			(xy 421.536114 -365.110776) (xy 421.535605 -365.138662) (xy 421.527485 -365.193838) (xy 421.511417 -365.247245)
			(xy 421.487745 -365.297742) (xy 421.456972 -365.344255) (xy 421.419755 -365.385792) (xy 421.376887 -365.421467)
			(xy 421.329281 -365.450521) (xy 421.277952 -365.472333) (xy 421.223995 -365.486439) (xy 421.168558 -365.492539)
			(xy 421.112824 -365.490502) (xy 421.057981 -365.480372) (xy 421.005197 -365.462365) (xy 420.955597 -365.436864)
			(xy 420.910239 -365.404413) (xy 420.87009 -365.365704) (xy 420.836004 -365.321561) (xy 420.808708 -365.272926)
			(xy 420.788785 -365.220835) (xy 420.776659 -365.166398) (xy 420.772588 -365.110776) (xy 420.231824 -365.110776)
			(xy 419.992302 -365.350298) (xy 419.97782 -365.364125) (xy 419.944545 -365.386383) (xy 419.907564 -365.401715)
			(xy 419.868301 -365.40953) (xy 419.848284 -365.409988) (xy 419.551104 -365.409988) (xy 419.539058 -365.410578)
			(xy 419.517573 -365.421463) (xy 419.509956 -365.430816) (xy 419.491902 -365.454712) (xy 419.449517 -365.497025)
			(xy 419.401041 -365.532194) (xy 419.347664 -365.559356) (xy 419.290699 -365.577844) (xy 419.231545 -365.587203)
			(xy 419.2016 -365.587788) (xy 419.174347 -365.587342) (xy 419.120397 -365.579585) (xy 419.068099 -365.564229)
			(xy 419.018519 -365.541587) (xy 418.972667 -365.512119) (xy 418.931474 -365.476426) (xy 418.895781 -365.435233)
			(xy 418.866313 -365.389381) (xy 418.843671 -365.339801) (xy 418.828315 -365.287503) (xy 418.820558 -365.233553)
			(xy 418.460073 -365.233553) (xy 418.460174 -365.2393) (xy 418.459688 -365.266551) (xy 418.451932 -365.320499)
			(xy 418.436577 -365.372794) (xy 418.413935 -365.422371) (xy 418.384469 -365.468221) (xy 418.348778 -365.509412)
			(xy 418.307587 -365.545103) (xy 418.261737 -365.574569) (xy 418.21216 -365.597211) (xy 418.159865 -365.612566)
			(xy 418.105917 -365.620322) (xy 418.051415 -365.620322) (xy 417.997467 -365.612566) (xy 417.945172 -365.597211)
			(xy 417.895595 -365.574569) (xy 417.849745 -365.545103) (xy 417.808554 -365.509412) (xy 417.772863 -365.468221)
			(xy 417.743397 -365.422371) (xy 417.720755 -365.372794) (xy 417.7054 -365.320499) (xy 417.697644 -365.266551)
			(xy 417.697158 -365.2393) (xy 417.697696 -365.209861) (xy 417.706754 -365.151682) (xy 417.724639 -365.095586)
			(xy 417.750927 -365.042901) (xy 417.767516 -365.018574) (xy 417.772409 -365.011083) (xy 417.777136 -364.993841)
			(xy 417.775616 -364.976027) (xy 417.768034 -364.959835) (xy 417.761928 -364.953296) (xy 417.072318 -364.26394)
			(xy 417.064784 -364.257041) (xy 417.045876 -364.249353) (xy 417.025466 -364.249607) (xy 417.01593 -364.253272)
			(xy 416.914838 -364.297722) (xy 416.898074 -364.324392) (xy 416.898836 -364.339886) (xy 416.898836 -364.340394)
			(xy 416.899344 -364.357158) (xy 416.899344 -364.357666) (xy 416.898816 -364.384904) (xy 416.89103 -364.438821)
			(xy 416.875653 -364.491083) (xy 416.852998 -364.540626) (xy 416.823527 -364.586443) (xy 416.787839 -364.627601)
			(xy 416.746658 -364.663265) (xy 416.700824 -364.692709) (xy 416.651267 -364.715333) (xy 416.598996 -364.730679)
			(xy 416.545074 -364.738433) (xy 416.517836 -364.73892) (xy 416.490585 -364.738411) (xy 416.436636 -364.730659)
			(xy 416.38434 -364.715309) (xy 416.33476 -364.692671) (xy 416.288908 -364.663208) (xy 416.247715 -364.627519)
			(xy 416.212021 -364.586331) (xy 416.182552 -364.540482) (xy 416.159908 -364.490905) (xy 416.144551 -364.438611)
			(xy 416.136792 -364.384663) (xy 416.136328 -364.357412) (xy 416.136789 -364.330171) (xy 416.144538 -364.276243)
			(xy 416.15988 -364.223966) (xy 416.182504 -364.174403) (xy 416.211949 -364.128563) (xy 416.247616 -364.087379)
			(xy 416.288779 -364.051687) (xy 416.334601 -364.022215) (xy 416.38415 -363.999561) (xy 416.436418 -363.984187)
			(xy 416.490341 -363.976405) (xy 416.517582 -363.975904) (xy 416.51809 -363.975904) (xy 416.535108 -363.976412)
			(xy 416.545322 -363.976385) (xy 416.564457 -363.969301) (xy 416.579328 -363.95533) (xy 416.583876 -363.946186)
			(xy 416.621976 -363.859318) (xy 416.625732 -363.849802) (xy 416.62601 -363.82936) (xy 416.618254 -363.810444)
			(xy 416.611308 -363.80293) (xy 416.073336 -363.264958) (xy 416.059624 -363.250478) (xy 416.037494 -363.217313)
			(xy 416.022231 -363.18048) (xy 416.014417 -363.141382) (xy 416.0139 -363.121448) (xy 415.748502 -363.121448)
			(xy 415.749592 -363.122665) (xy 415.780365 -363.169178) (xy 415.804037 -363.219675) (xy 415.820105 -363.273082)
			(xy 415.828225 -363.328258) (xy 415.828734 -363.356144) (xy 415.828225 -363.38403) (xy 415.820105 -363.439206)
			(xy 415.804037 -363.492613) (xy 415.780365 -363.54311) (xy 415.749592 -363.589623) (xy 415.712375 -363.63116)
			(xy 415.669507 -363.666835) (xy 415.621901 -363.695889) (xy 415.570572 -363.717701) (xy 415.516615 -363.731807)
			(xy 415.461178 -363.737907) (xy 415.405444 -363.73587) (xy 415.350601 -363.72574) (xy 415.297817 -363.707733)
			(xy 415.248217 -363.682232) (xy 415.202859 -363.649781) (xy 415.16271 -363.611072) (xy 415.128624 -363.566929)
			(xy 415.101328 -363.518294) (xy 415.081405 -363.466203) (xy 415.069279 -363.411766) (xy 415.065208 -363.356144)
			(xy 408.179016 -363.356144) (xy 408.902408 -364.079536) (xy 412.440372 -364.079536) (xy 412.444443 -364.023914)
			(xy 412.456569 -363.969477) (xy 412.476492 -363.917386) (xy 412.503788 -363.868751) (xy 412.537874 -363.824608)
			(xy 412.578023 -363.785899) (xy 412.623381 -363.753448) (xy 412.672981 -363.727947) (xy 412.725765 -363.70994)
			(xy 412.780608 -363.69981) (xy 412.836342 -363.697773) (xy 412.891779 -363.703873) (xy 412.945736 -363.717979)
			(xy 412.997065 -363.739791) (xy 413.044671 -363.768845) (xy 413.087539 -363.80452) (xy 413.124756 -363.846057)
			(xy 413.155529 -363.89257) (xy 413.179201 -363.943067) (xy 413.195269 -363.996474) (xy 413.203389 -364.05165)
			(xy 413.203898 -364.079536) (xy 413.203389 -364.107422) (xy 413.195269 -364.162598) (xy 413.179201 -364.216005)
			(xy 413.155529 -364.266502) (xy 413.124756 -364.313015) (xy 413.087539 -364.354552) (xy 413.044671 -364.390227)
			(xy 412.997065 -364.419281) (xy 412.945736 -364.441093) (xy 412.891779 -364.455199) (xy 412.836342 -364.461299)
			(xy 412.780608 -364.459262) (xy 412.725765 -364.449132) (xy 412.672981 -364.431125) (xy 412.623381 -364.405624)
			(xy 412.578023 -364.373173) (xy 412.537874 -364.334464) (xy 412.503788 -364.290321) (xy 412.476492 -364.241686)
			(xy 412.456569 -364.189595) (xy 412.444443 -364.135158) (xy 412.440372 -364.079536) (xy 408.902408 -364.079536)
			(xy 409.700984 -364.878112) (xy 414.96564 -364.878112) (xy 414.969711 -364.82249) (xy 414.981837 -364.768053)
			(xy 415.00176 -364.715962) (xy 415.029056 -364.667327) (xy 415.063142 -364.623184) (xy 415.103291 -364.584475)
			(xy 415.148649 -364.552024) (xy 415.198249 -364.526523) (xy 415.251033 -364.508516) (xy 415.305876 -364.498386)
			(xy 415.36161 -364.496349) (xy 415.417047 -364.502449) (xy 415.471004 -364.516555) (xy 415.522333 -364.538367)
			(xy 415.569939 -364.567421) (xy 415.612807 -364.603096) (xy 415.650024 -364.644633) (xy 415.680797 -364.691146)
			(xy 415.704469 -364.741643) (xy 415.720537 -364.79505) (xy 415.728657 -364.850226) (xy 415.729166 -364.878112)
			(xy 415.728657 -364.905998) (xy 415.720537 -364.961174) (xy 415.704469 -365.014581) (xy 415.680797 -365.065078)
			(xy 415.650024 -365.111591) (xy 415.612807 -365.153128) (xy 415.569939 -365.188803) (xy 415.522333 -365.217857)
			(xy 415.471004 -365.239669) (xy 415.417047 -365.253775) (xy 415.36161 -365.259875) (xy 415.305876 -365.257838)
			(xy 415.251033 -365.247708) (xy 415.198249 -365.229701) (xy 415.148649 -365.2042) (xy 415.103291 -365.171749)
			(xy 415.063142 -365.13304) (xy 415.029056 -365.088897) (xy 415.00176 -365.040262) (xy 414.981837 -364.988171)
			(xy 414.969711 -364.933734) (xy 414.96564 -364.878112) (xy 409.700984 -364.878112) (xy 410.78531 -365.962438)
			(xy 411.78302 -365.962438) (xy 411.787091 -365.906816) (xy 411.799217 -365.852379) (xy 411.81914 -365.800288)
			(xy 411.846436 -365.751653) (xy 411.880522 -365.70751) (xy 411.920671 -365.668801) (xy 411.966029 -365.63635)
			(xy 412.015629 -365.610849) (xy 412.068413 -365.592842) (xy 412.123256 -365.582712) (xy 412.17899 -365.580675)
			(xy 412.234427 -365.586775) (xy 412.288384 -365.600881) (xy 412.339713 -365.622693) (xy 412.387319 -365.651747)
			(xy 412.417899 -365.677196) (xy 416.787582 -365.677196) (xy 416.791653 -365.621574) (xy 416.803779 -365.567137)
			(xy 416.823702 -365.515046) (xy 416.850998 -365.466411) (xy 416.885084 -365.422268) (xy 416.925233 -365.383559)
			(xy 416.970591 -365.351108) (xy 417.020191 -365.325607) (xy 417.072975 -365.3076) (xy 417.127818 -365.29747)
			(xy 417.183552 -365.295433) (xy 417.238989 -365.301533) (xy 417.292946 -365.315639) (xy 417.344275 -365.337451)
			(xy 417.391881 -365.366505) (xy 417.434749 -365.40218) (xy 417.471966 -365.443717) (xy 417.502739 -365.49023)
			(xy 417.526411 -365.540727) (xy 417.542479 -365.594134) (xy 417.550599 -365.64931) (xy 417.551108 -365.677196)
			(xy 417.550599 -365.705082) (xy 417.542479 -365.760258) (xy 417.526411 -365.813665) (xy 417.502739 -365.864162)
			(xy 417.471966 -365.910675) (xy 417.434749 -365.952212) (xy 417.391881 -365.987887) (xy 417.344275 -366.016941)
			(xy 417.292946 -366.038753) (xy 417.238989 -366.052859) (xy 417.183552 -366.058959) (xy 417.127818 -366.056922)
			(xy 417.072975 -366.046792) (xy 417.020191 -366.028785) (xy 416.970591 -366.003284) (xy 416.925233 -365.970833)
			(xy 416.885084 -365.932124) (xy 416.850998 -365.887981) (xy 416.823702 -365.839346) (xy 416.803779 -365.787255)
			(xy 416.791653 -365.732818) (xy 416.787582 -365.677196) (xy 412.417899 -365.677196) (xy 412.430187 -365.687422)
			(xy 412.467404 -365.728959) (xy 412.498177 -365.775472) (xy 412.521849 -365.825969) (xy 412.537917 -365.879376)
			(xy 412.546037 -365.934552) (xy 412.546546 -365.962438) (xy 412.546037 -365.990324) (xy 412.537917 -366.0455)
			(xy 412.521849 -366.098907) (xy 412.498177 -366.149404) (xy 412.467404 -366.195917) (xy 412.430187 -366.237454)
			(xy 412.387319 -366.273129) (xy 412.339713 -366.302183) (xy 412.288384 -366.323995) (xy 412.234427 -366.338101)
			(xy 412.17899 -366.344201) (xy 412.123256 -366.342164) (xy 412.068413 -366.332034) (xy 412.015629 -366.314027)
			(xy 411.966029 -366.288526) (xy 411.920671 -366.256075) (xy 411.880522 -366.217366) (xy 411.846436 -366.173223)
			(xy 411.81914 -366.124588) (xy 411.799217 -366.072497) (xy 411.787091 -366.01806) (xy 411.78302 -365.962438)
			(xy 410.78531 -365.962438) (xy 411.602936 -366.780064) (xy 412.411162 -366.780064) (xy 412.415233 -366.724442)
			(xy 412.427359 -366.670005) (xy 412.447282 -366.617914) (xy 412.474578 -366.569279) (xy 412.508664 -366.525136)
			(xy 412.548813 -366.486427) (xy 412.594171 -366.453976) (xy 412.643771 -366.428475) (xy 412.696555 -366.410468)
			(xy 412.751398 -366.400338) (xy 412.807132 -366.398301) (xy 412.862569 -366.404401) (xy 412.916526 -366.418507)
			(xy 412.967855 -366.440319) (xy 413.015461 -366.469373) (xy 413.058329 -366.505048) (xy 413.095546 -366.546585)
			(xy 413.126319 -366.593098) (xy 413.149991 -366.643595) (xy 413.166059 -366.697002) (xy 413.174179 -366.752178)
			(xy 413.174688 -366.780064) (xy 413.174179 -366.80795) (xy 413.167256 -366.854994) (xy 423.83532 -366.854994)
			(xy 423.839391 -366.799372) (xy 423.851517 -366.744935) (xy 423.87144 -366.692844) (xy 423.898736 -366.644209)
			(xy 423.932822 -366.600066) (xy 423.972971 -366.561357) (xy 424.018329 -366.528906) (xy 424.067929 -366.503405)
			(xy 424.120713 -366.485398) (xy 424.175556 -366.475268) (xy 424.23129 -366.473231) (xy 424.286727 -366.479331)
			(xy 424.340684 -366.493437) (xy 424.392013 -366.515249) (xy 424.439619 -366.544303) (xy 424.482487 -366.579978)
			(xy 424.519704 -366.621515) (xy 424.550477 -366.668028) (xy 424.574149 -366.718525) (xy 424.590217 -366.771932)
			(xy 424.598337 -366.827108) (xy 424.598846 -366.854994) (xy 424.598337 -366.88288) (xy 424.590217 -366.938056)
			(xy 424.574149 -366.991463) (xy 424.550477 -367.04196) (xy 424.519704 -367.088473) (xy 424.482487 -367.13001)
			(xy 424.439619 -367.165685) (xy 424.392013 -367.194739) (xy 424.340684 -367.216551) (xy 424.286727 -367.230657)
			(xy 424.23129 -367.236757) (xy 424.175556 -367.23472) (xy 424.120713 -367.22459) (xy 424.067929 -367.206583)
			(xy 424.018329 -367.181082) (xy 423.972971 -367.148631) (xy 423.932822 -367.109922) (xy 423.898736 -367.065779)
			(xy 423.87144 -367.017144) (xy 423.851517 -366.965053) (xy 423.839391 -366.910616) (xy 423.83532 -366.854994)
			(xy 413.167256 -366.854994) (xy 413.166059 -366.863126) (xy 413.149991 -366.916533) (xy 413.126319 -366.96703)
			(xy 413.095546 -367.013543) (xy 413.058329 -367.05508) (xy 413.015461 -367.090755) (xy 412.967855 -367.119809)
			(xy 412.916526 -367.141621) (xy 412.862569 -367.155727) (xy 412.807132 -367.161827) (xy 412.751398 -367.15979)
			(xy 412.696555 -367.14966) (xy 412.643771 -367.131653) (xy 412.594171 -367.106152) (xy 412.548813 -367.073701)
			(xy 412.508664 -367.034992) (xy 412.474578 -366.990849) (xy 412.447282 -366.942214) (xy 412.427359 -366.890123)
			(xy 412.415233 -366.835686) (xy 412.411162 -366.780064) (xy 411.602936 -366.780064) (xy 412.26232 -367.439448)
			(xy 412.267365 -367.444098) (xy 412.279339 -367.450789) (xy 412.285942 -367.452656) (xy 412.926784 -367.613438)
			(xy 412.937251 -367.615509) (xy 412.958253 -367.611881) (xy 412.975971 -367.600037) (xy 412.982156 -367.59134)
			(xy 412.997234 -367.568483) (xy 413.032904 -367.526939) (xy 413.074151 -367.490927) (xy 413.120127 -367.461187)
			(xy 413.169885 -367.438333) (xy 413.222402 -367.422834) (xy 413.276596 -367.415009) (xy 413.303974 -367.414556)
			(xy 413.331227 -367.41504) (xy 413.38518 -367.422793) (xy 413.43748 -367.438146) (xy 413.487063 -367.460785)
			(xy 413.506826 -367.473484) (xy 415.2044 -367.473484) (xy 415.208471 -367.417862) (xy 415.220597 -367.363425)
			(xy 415.24052 -367.311334) (xy 415.267816 -367.262699) (xy 415.301902 -367.218556) (xy 415.342051 -367.179847)
			(xy 415.387409 -367.147396) (xy 415.437009 -367.121895) (xy 415.489793 -367.103888) (xy 415.544636 -367.093758)
			(xy 415.60037 -367.091721) (xy 415.655807 -367.097821) (xy 415.709764 -367.111927) (xy 415.761093 -367.133739)
			(xy 415.808699 -367.162793) (xy 415.851567 -367.198468) (xy 415.888784 -367.240005) (xy 415.919557 -367.286518)
			(xy 415.943229 -367.337015) (xy 415.959297 -367.390422) (xy 415.967417 -367.445598) (xy 415.967926 -367.473484)
			(xy 416.4744 -367.473484) (xy 416.478471 -367.417862) (xy 416.490597 -367.363425) (xy 416.51052 -367.311334)
			(xy 416.537816 -367.262699) (xy 416.571902 -367.218556) (xy 416.612051 -367.179847) (xy 416.657409 -367.147396)
			(xy 416.707009 -367.121895) (xy 416.759793 -367.103888) (xy 416.814636 -367.093758) (xy 416.87037 -367.091721)
			(xy 416.925807 -367.097821) (xy 416.979764 -367.111927) (xy 417.031093 -367.133739) (xy 417.078699 -367.162793)
			(xy 417.121567 -367.198468) (xy 417.158784 -367.240005) (xy 417.189557 -367.286518) (xy 417.213229 -367.337015)
			(xy 417.229297 -367.390422) (xy 417.237417 -367.445598) (xy 417.237773 -367.465102) (xy 418.560502 -367.465102)
			(xy 418.564573 -367.40948) (xy 418.576699 -367.355043) (xy 418.596622 -367.302952) (xy 418.623918 -367.254317)
			(xy 418.658004 -367.210174) (xy 418.698153 -367.171465) (xy 418.743511 -367.139014) (xy 418.793111 -367.113513)
			(xy 418.845895 -367.095506) (xy 418.900738 -367.085376) (xy 418.956472 -367.083339) (xy 419.011909 -367.089439)
			(xy 419.065866 -367.103545) (xy 419.117195 -367.125357) (xy 419.164801 -367.154411) (xy 419.207669 -367.190086)
			(xy 419.244886 -367.231623) (xy 419.275659 -367.278136) (xy 419.299331 -367.328633) (xy 419.315399 -367.38204)
			(xy 419.323519 -367.437216) (xy 419.324028 -367.465102) (xy 419.323519 -367.492988) (xy 419.315399 -367.548164)
			(xy 419.299331 -367.601571) (xy 419.275659 -367.652068) (xy 419.244886 -367.698581) (xy 419.207669 -367.740118)
			(xy 419.164801 -367.775793) (xy 419.117195 -367.804847) (xy 419.065866 -367.826659) (xy 419.011909 -367.840765)
			(xy 418.956472 -367.846865) (xy 418.900738 -367.844828) (xy 418.845895 -367.834698) (xy 418.793111 -367.816691)
			(xy 418.743511 -367.79119) (xy 418.698153 -367.758739) (xy 418.658004 -367.72003) (xy 418.623918 -367.675887)
			(xy 418.596622 -367.627252) (xy 418.576699 -367.575161) (xy 418.564573 -367.520724) (xy 418.560502 -367.465102)
			(xy 417.237773 -367.465102) (xy 417.237926 -367.473484) (xy 417.237417 -367.50137) (xy 417.229297 -367.556546)
			(xy 417.213229 -367.609953) (xy 417.189557 -367.66045) (xy 417.158784 -367.706963) (xy 417.121567 -367.7485)
			(xy 417.078699 -367.784175) (xy 417.031093 -367.813229) (xy 416.979764 -367.835041) (xy 416.925807 -367.849147)
			(xy 416.87037 -367.855247) (xy 416.814636 -367.85321) (xy 416.759793 -367.84308) (xy 416.707009 -367.825073)
			(xy 416.657409 -367.799572) (xy 416.612051 -367.767121) (xy 416.571902 -367.728412) (xy 416.537816 -367.684269)
			(xy 416.51052 -367.635634) (xy 416.490597 -367.583543) (xy 416.478471 -367.529106) (xy 416.4744 -367.473484)
			(xy 415.967926 -367.473484) (xy 415.967417 -367.50137) (xy 415.959297 -367.556546) (xy 415.943229 -367.609953)
			(xy 415.919557 -367.66045) (xy 415.888784 -367.706963) (xy 415.851567 -367.7485) (xy 415.808699 -367.784175)
			(xy 415.761093 -367.813229) (xy 415.709764 -367.835041) (xy 415.655807 -367.849147) (xy 415.60037 -367.855247)
			(xy 415.544636 -367.85321) (xy 415.489793 -367.84308) (xy 415.437009 -367.825073) (xy 415.387409 -367.799572)
			(xy 415.342051 -367.767121) (xy 415.301902 -367.728412) (xy 415.267816 -367.684269) (xy 415.24052 -367.635634)
			(xy 415.220597 -367.583543) (xy 415.208471 -367.529106) (xy 415.2044 -367.473484) (xy 413.506826 -367.473484)
			(xy 413.532919 -367.49025) (xy 413.574115 -367.525941) (xy 413.609813 -367.567131) (xy 413.639285 -367.612983)
			(xy 413.661933 -367.662562) (xy 413.677294 -367.714859) (xy 413.685056 -367.768811) (xy 413.685482 -367.796064)
			(xy 413.685482 -367.803684) (xy 416.12185 -368.414554) (xy 416.16757 -368.428016) (xy 420.975028 -370.065046)
			(xy 420.978975 -370.066311) (xy 420.987141 -370.067718) (xy 420.991284 -370.06784)
		)
		(stroke
			(width 0)
			(type solid)
		)
		(fill yes)
		(layer "In6.Cu")
		(net "GND")
	)
	(gr_poly
		(pts
			(xy 113.81994 -281.998928) (xy 113.830066 -281.998744) (xy 113.848929 -281.991413) (xy 113.856516 -281.984704)
			(xy 113.857024 -281.984196) (xy 113.92662 -281.9146) (xy 113.934748 -281.904186) (xy 113.944351 -281.887768)
			(xy 113.965449 -281.856117) (xy 113.976912 -281.84094) (xy 113.985294 -281.830272) (xy 113.98885 -281.803602)
			(xy 113.94567 -281.697176) (xy 113.924588 -281.680666) (xy 113.911126 -281.678634) (xy 113.887213 -281.674714)
			(xy 113.84095 -281.660303) (xy 113.797546 -281.638762) (xy 113.758091 -281.610633) (xy 113.723577 -281.576622)
			(xy 113.694872 -281.537584) (xy 113.672697 -281.494501) (xy 113.657608 -281.448454) (xy 113.649986 -281.400602)
			(xy 113.649506 -281.376374) (xy 113.649979 -281.352385) (xy 113.657488 -281.304997) (xy 113.672318 -281.259367)
			(xy 113.694103 -281.216619) (xy 113.722307 -281.177805) (xy 113.756236 -281.143881) (xy 113.795053 -281.115682)
			(xy 113.837804 -281.093903) (xy 113.883436 -281.079079) (xy 113.930824 -281.071575) (xy 113.954814 -281.071066)
			(xy 113.97864 -281.071525) (xy 114.025714 -281.07893) (xy 114.071066 -281.093558) (xy 114.113595 -281.115055)
			(xy 114.152268 -281.142897) (xy 114.186146 -281.176409) (xy 114.214407 -281.214778) (xy 114.236363 -281.257071)
			(xy 114.251483 -281.302261) (xy 114.259399 -281.349252) (xy 114.260122 -281.373072) (xy 114.260122 -281.376628)
			(xy 114.259737 -281.3982) (xy 114.253623 -281.440908) (xy 114.24793 -281.461718) (xy 114.244374 -281.473402)
			(xy 114.248692 -281.497024) (xy 114.304826 -281.5717) (xy 114.312428 -281.580808) (xy 114.333618 -281.591414)
			(xy 114.345466 -281.59202) (xy 114.503962 -281.59202) (xy 114.515813 -281.59141) (xy 114.53702 -281.580826)
			(xy 114.544602 -281.5717) (xy 114.600736 -281.497024) (xy 114.605054 -281.473402) (xy 114.601498 -281.461718)
			(xy 114.595851 -281.441028) (xy 114.589726 -281.398579) (xy 114.589306 -281.377136) (xy 114.589306 -281.373072)
			(xy 114.590085 -281.347996) (xy 114.59882 -281.298595) (xy 114.615514 -281.251288) (xy 114.639716 -281.207346)
			(xy 114.670776 -281.167951) (xy 114.707859 -281.134163) (xy 114.749966 -281.106892) (xy 114.795964 -281.086872)
			(xy 114.844616 -281.074639) (xy 114.894614 -281.070525) (xy 114.944612 -281.074639) (xy 114.993264 -281.086872)
			(xy 115.039262 -281.106892) (xy 115.081369 -281.134163) (xy 115.118452 -281.167951) (xy 115.149512 -281.207346)
			(xy 115.173714 -281.251288) (xy 115.190408 -281.298595) (xy 115.199143 -281.347996) (xy 115.199922 -281.373072)
			(xy 115.199922 -281.376628) (xy 115.199537 -281.3982) (xy 115.193423 -281.440908) (xy 115.18773 -281.461718)
			(xy 115.184174 -281.473402) (xy 115.188492 -281.497024) (xy 115.244626 -281.5717) (xy 115.252228 -281.580808)
			(xy 115.273418 -281.591414) (xy 115.285266 -281.59202) (xy 115.444016 -281.59202) (xy 115.455861 -281.591398)
			(xy 115.477049 -281.580802) (xy 115.484656 -281.5717) (xy 115.54079 -281.497024) (xy 115.545108 -281.473402)
			(xy 115.541552 -281.461718) (xy 115.535905 -281.441028) (xy 115.529782 -281.398579) (xy 115.52936 -281.377136)
			(xy 115.52936 -281.373072) (xy 115.530139 -281.347996) (xy 115.538874 -281.298595) (xy 115.555568 -281.251288)
			(xy 115.57977 -281.207346) (xy 115.61083 -281.167951) (xy 115.647913 -281.134163) (xy 115.69002 -281.106892)
			(xy 115.736018 -281.086872) (xy 115.78467 -281.074639) (xy 115.834668 -281.070525) (xy 115.884666 -281.074639)
			(xy 115.933318 -281.086872) (xy 115.979316 -281.106892) (xy 116.021423 -281.134163) (xy 116.058506 -281.167951)
			(xy 116.089566 -281.207346) (xy 116.113768 -281.251288) (xy 116.130462 -281.298595) (xy 116.139197 -281.347996)
			(xy 116.139976 -281.373072) (xy 116.139976 -281.376628) (xy 116.139591 -281.3982) (xy 116.133479 -281.440908)
			(xy 116.127784 -281.461718) (xy 116.124228 -281.473402) (xy 116.128546 -281.497024) (xy 116.18468 -281.5717)
			(xy 116.192286 -281.580799) (xy 116.213477 -281.591382) (xy 116.22532 -281.59202) (xy 118.264178 -281.59202)
			(xy 118.276027 -281.591406) (xy 118.297229 -281.580819) (xy 118.304818 -281.5717) (xy 118.360952 -281.497024)
			(xy 118.36527 -281.473402) (xy 118.361714 -281.461718) (xy 118.356066 -281.441028) (xy 118.349942 -281.398579)
			(xy 118.349522 -281.377136) (xy 118.349522 -281.373072) (xy 118.350301 -281.347996) (xy 118.359036 -281.298595)
			(xy 118.37573 -281.251288) (xy 118.399932 -281.207346) (xy 118.430992 -281.167951) (xy 118.468075 -281.134163)
			(xy 118.510182 -281.106892) (xy 118.55618 -281.086872) (xy 118.604832 -281.074639) (xy 118.65483 -281.070525)
			(xy 118.704828 -281.074639) (xy 118.75348 -281.086872) (xy 118.799478 -281.106892) (xy 118.841585 -281.134163)
			(xy 118.878668 -281.167951) (xy 118.909728 -281.207346) (xy 118.93393 -281.251288) (xy 118.950624 -281.298595)
			(xy 118.959359 -281.347996) (xy 118.960138 -281.373072) (xy 118.960138 -281.376628) (xy 118.959753 -281.3982)
			(xy 118.95364 -281.440908) (xy 118.947946 -281.461718) (xy 118.94439 -281.473402) (xy 118.948708 -281.497024)
			(xy 119.004842 -281.5717) (xy 119.012445 -281.580806) (xy 119.033636 -281.591404) (xy 119.045482 -281.59202)
			(xy 121.084086 -281.59202) (xy 121.095934 -281.591405) (xy 121.117133 -281.580815) (xy 121.124726 -281.5717)
			(xy 121.18086 -281.497024) (xy 121.185178 -281.473402) (xy 121.181622 -281.461718) (xy 121.175974 -281.441028)
			(xy 121.169849 -281.398579) (xy 121.16943 -281.377136) (xy 121.16943 -281.373072) (xy 121.170142 -281.349023)
			(xy 121.178203 -281.301594) (xy 121.193601 -281.256014) (xy 121.215954 -281.213413) (xy 121.244711 -281.174844)
			(xy 121.27916 -281.14126) (xy 121.318448 -281.113494) (xy 121.361604 -281.09223) (xy 121.40756 -281.077997)
			(xy 121.431304 -281.074114) (xy 121.443496 -281.072336) (xy 121.474738 -281.070812) (xy 121.49934 -281.07131)
			(xy 121.547907 -281.079208) (xy 121.594578 -281.094793) (xy 121.638145 -281.117663) (xy 121.658126 -281.132026)
			(xy 121.673366 -281.143456) (xy 121.710958 -281.140662) (xy 121.844562 -281.007058) (xy 121.847864 -281.003502)
			(xy 121.85453 -280.994604) (xy 121.860188 -280.97313) (xy 121.858786 -280.9621) (xy 121.842022 -280.86812)
			(xy 121.827036 -280.848562) (xy 121.815606 -280.843228) (xy 121.793373 -280.832314) (xy 121.752469 -280.804394)
			(xy 121.716603 -280.770241) (xy 121.686715 -280.730752) (xy 121.663588 -280.686958) (xy 121.647826 -280.640008)
			(xy 121.639844 -280.591131) (xy 121.63933 -280.566368) (xy 121.639779 -280.542378) (xy 121.64729 -280.494988)
			(xy 121.662121 -280.449357) (xy 121.683909 -280.406608) (xy 121.712116 -280.367794) (xy 121.746047 -280.33387)
			(xy 121.784868 -280.305672) (xy 121.827622 -280.283895) (xy 121.873256 -280.269073) (xy 121.920647 -280.261573)
			(xy 121.944638 -280.26106) (xy 121.970381 -280.261597) (xy 122.021136 -280.270241) (xy 122.069721 -280.287278)
			(xy 122.11476 -280.312224) (xy 122.154974 -280.344373) (xy 122.189225 -280.382814) (xy 122.216542 -280.426456)
			(xy 122.236149 -280.474062) (xy 122.242326 -280.499058) (xy 122.244104 -280.505916) (xy 122.247406 -280.512266)
			(xy 122.253689 -280.5224) (xy 122.27329 -280.535925) (xy 122.284998 -280.538174) (xy 122.296936 -280.539952)
			(xy 122.319288 -280.532332) (xy 122.341894 -280.509726) (xy 122.349291 -280.502876) (xy 122.367889 -280.495135)
			(xy 122.377962 -280.49474) (xy 122.56643 -280.49474) (xy 122.592338 -280.476706) (xy 122.597926 -280.461466)
			(xy 122.606923 -280.438294) (xy 122.631333 -280.394996) (xy 122.662435 -280.356224) (xy 122.699405 -280.323001)
			(xy 122.741268 -280.296204) (xy 122.786919 -280.276542) (xy 122.835151 -280.264533) (xy 122.884692 -280.260494)
			(xy 122.934233 -280.264533) (xy 122.982465 -280.276542) (xy 123.028116 -280.296204) (xy 123.069979 -280.323001)
			(xy 123.106949 -280.356224) (xy 123.138051 -280.394996) (xy 123.162461 -280.438294) (xy 123.171458 -280.461466)
			(xy 123.177046 -280.476706) (xy 123.202954 -280.49474) (xy 123.506484 -280.49474) (xy 123.532392 -280.476706)
			(xy 123.53798 -280.461466) (xy 123.546977 -280.438294) (xy 123.571387 -280.394996) (xy 123.602489 -280.356224)
			(xy 123.639459 -280.323001) (xy 123.681322 -280.296204) (xy 123.726973 -280.276542) (xy 123.775205 -280.264533)
			(xy 123.824746 -280.260494) (xy 123.874287 -280.264533) (xy 123.922519 -280.276542) (xy 123.96817 -280.296204)
			(xy 124.010033 -280.323001) (xy 124.047003 -280.356224) (xy 124.078105 -280.394996) (xy 124.102515 -280.438294)
			(xy 124.111512 -280.461466) (xy 124.1171 -280.476706) (xy 124.143008 -280.49474) (xy 124.446538 -280.49474)
			(xy 124.472446 -280.476706) (xy 124.478034 -280.461466) (xy 124.487031 -280.438294) (xy 124.511441 -280.394996)
			(xy 124.542543 -280.356224) (xy 124.579513 -280.323001) (xy 124.621376 -280.296204) (xy 124.667027 -280.276542)
			(xy 124.715259 -280.264533) (xy 124.7648 -280.260494) (xy 124.814341 -280.264533) (xy 124.862573 -280.276542)
			(xy 124.908224 -280.296204) (xy 124.950087 -280.323001) (xy 124.987057 -280.356224) (xy 125.018159 -280.394996)
			(xy 125.042569 -280.438294) (xy 125.051566 -280.461466) (xy 125.057154 -280.476706) (xy 125.083062 -280.49474)
			(xy 125.386592 -280.49474) (xy 125.4125 -280.476706) (xy 125.418088 -280.461466) (xy 125.427085 -280.438294)
			(xy 125.451495 -280.394996) (xy 125.482597 -280.356224) (xy 125.519567 -280.323001) (xy 125.56143 -280.296204)
			(xy 125.607081 -280.276542) (xy 125.655313 -280.264533) (xy 125.704854 -280.260494) (xy 125.754395 -280.264533)
			(xy 125.802627 -280.276542) (xy 125.848278 -280.296204) (xy 125.890141 -280.323001) (xy 125.927111 -280.356224)
			(xy 125.958213 -280.394996) (xy 125.982623 -280.438294) (xy 125.99162 -280.461466) (xy 125.997208 -280.476706)
			(xy 126.023116 -280.49474) (xy 126.326392 -280.49474) (xy 126.3523 -280.476706) (xy 126.357888 -280.461466)
			(xy 126.366302 -280.439737) (xy 126.388767 -280.398915) (xy 126.417174 -280.361982) (xy 126.450864 -280.329795)
			(xy 126.489054 -280.303101) (xy 126.530857 -280.28252) (xy 126.575302 -280.268531) (xy 126.621357 -280.261459)
			(xy 126.644654 -280.26106) (xy 126.672263 -280.261676) (xy 126.726576 -280.271642) (xy 126.752604 -280.280872)
			(xy 126.766574 -280.286206) (xy 126.795784 -280.279856) (xy 126.888494 -280.187146) (xy 126.889002 -280.186638)
			(xy 126.895588 -280.179259) (xy 126.903043 -280.160959) (xy 126.90348 -280.151078) (xy 126.90348 -280.00706)
			(xy 126.903387 -280.002306) (xy 126.901603 -279.992967) (xy 126.899924 -279.988518) (xy 126.890272 -279.963372)
			(xy 126.88443 -279.956768) (xy 126.867185 -279.936044) (xy 126.839519 -279.889775) (xy 126.820397 -279.83937)
			(xy 126.810413 -279.786393) (xy 126.809876 -279.732486) (xy 126.813818 -279.705816) (xy 126.813564 -279.705816)
			(xy 126.818843 -279.678312) (xy 126.838059 -279.625714) (xy 126.866527 -279.577493) (xy 126.88443 -279.555956)
			(xy 126.890018 -279.549352) (xy 126.899924 -279.524206) (xy 126.901548 -279.519742) (xy 126.903332 -279.510412)
			(xy 126.90348 -279.505664) (xy 126.90348 -278.387048) (xy 126.903385 -278.382294) (xy 126.901599 -278.372956)
			(xy 126.899924 -278.368506) (xy 126.890272 -278.34336) (xy 126.88443 -278.336756) (xy 126.867186 -278.316031)
			(xy 126.839522 -278.269762) (xy 126.820402 -278.219358) (xy 126.81042 -278.166381) (xy 126.809885 -278.112475)
			(xy 126.813818 -278.085804) (xy 126.813564 -278.085804) (xy 126.818844 -278.058301) (xy 126.838061 -278.005704)
			(xy 126.866531 -277.957484) (xy 126.88443 -277.935944) (xy 126.890018 -277.92934) (xy 126.899924 -277.904194)
			(xy 126.901546 -277.89973) (xy 126.903328 -277.8904) (xy 126.90348 -277.885652) (xy 126.90348 -277.701502)
			(xy 126.902838 -277.688946) (xy 126.890982 -277.666812) (xy 126.880874 -277.659338) (xy 126.810516 -277.612602)
			(xy 126.79971 -277.606109) (xy 126.774659 -277.603594) (xy 126.762764 -277.607776) (xy 126.76251 -277.60803)
			(xy 126.762256 -277.60803) (xy 126.734111 -277.619041) (xy 126.674868 -277.63094) (xy 126.644654 -277.631652)
			(xy 126.640082 -277.631652) (xy 126.616325 -277.630847) (xy 126.56948 -277.622786) (xy 126.524451 -277.607561)
			(xy 126.482325 -277.585542) (xy 126.444121 -277.557259) (xy 126.410763 -277.523397) (xy 126.383056 -277.484774)
			(xy 126.36167 -277.442323) (xy 126.347122 -277.397071) (xy 126.339763 -277.350111) (xy 126.339346 -277.326344)
			(xy 126.339813 -277.302349) (xy 126.347314 -277.254949) (xy 126.362137 -277.209307) (xy 126.383917 -277.166545)
			(xy 126.412119 -277.127716) (xy 126.446048 -277.093777) (xy 126.484868 -277.065564) (xy 126.527623 -277.043771)
			(xy 126.573262 -277.028935) (xy 126.620659 -277.02142) (xy 126.644654 -277.021036) (xy 126.674865 -277.02177)
			(xy 126.734106 -277.033668) (xy 126.762256 -277.044658) (xy 126.76251 -277.044658) (xy 126.762764 -277.044912)
			(xy 126.774656 -277.049077) (xy 126.799697 -277.046545) (xy 126.810516 -277.040086) (xy 126.880874 -276.99335)
			(xy 126.890923 -276.985828) (xy 126.90275 -276.96372) (xy 126.90348 -276.951186) (xy 126.90348 -276.767036)
			(xy 126.903384 -276.762282) (xy 126.901596 -276.752945) (xy 126.899924 -276.748494) (xy 126.890272 -276.723348)
			(xy 126.88443 -276.716744) (xy 126.867187 -276.696019) (xy 126.839524 -276.64975) (xy 126.820407 -276.599346)
			(xy 126.810427 -276.54637) (xy 126.809893 -276.492464) (xy 126.813818 -276.465792) (xy 126.813564 -276.465792)
			(xy 126.818845 -276.438289) (xy 126.838064 -276.385694) (xy 126.866535 -276.337475) (xy 126.88443 -276.315932)
			(xy 126.890018 -276.309328) (xy 126.899924 -276.284182) (xy 126.901545 -276.279717) (xy 126.903325 -276.270388)
			(xy 126.90348 -276.26564) (xy 126.90348 -275.479002) (xy 126.903057 -275.468932) (xy 126.895341 -275.450329)
			(xy 126.888494 -275.442934) (xy 126.546102 -275.100542) (xy 126.538487 -275.093559) (xy 126.519347 -275.085831)
			(xy 126.509018 -275.085556) (xy 126.435866 -275.086826) (xy 126.430618 -275.087033) (xy 126.420373 -275.08933)
			(xy 126.415546 -275.091398) (xy 126.406402 -275.095716) (xy 126.39929 -275.103336) (xy 126.381808 -275.121559)
			(xy 126.341963 -275.152579) (xy 126.297559 -275.176621) (xy 126.249805 -275.193032) (xy 126.200001 -275.201363)
			(xy 126.174754 -275.201888) (xy 125.2347 -275.201888) (xy 125.209422 -275.201366) (xy 125.159554 -275.193045)
			(xy 125.111736 -275.176629) (xy 125.067273 -275.152566) (xy 125.027376 -275.121514) (xy 124.993135 -275.084318)
			(xy 124.965483 -275.041993) (xy 124.945174 -274.995694) (xy 124.932763 -274.946684) (xy 124.928589 -274.8963)
			(xy 124.932763 -274.845916) (xy 124.945174 -274.796906) (xy 124.965483 -274.750607) (xy 124.993135 -274.708282)
			(xy 125.027376 -274.671086) (xy 125.067273 -274.640034) (xy 125.111736 -274.615971) (xy 125.159554 -274.599555)
			(xy 125.209422 -274.591234) (xy 125.2347 -274.590764) (xy 125.913642 -274.590764) (xy 125.923642 -274.590277)
			(xy 125.942133 -274.58265) (xy 125.95633 -274.568562) (xy 125.960632 -274.559522) (xy 125.966728 -274.545044)
			(xy 125.960632 -274.515072) (xy 125.838458 -274.392898) (xy 125.831807 -274.386718) (xy 125.815333 -274.379122)
			(xy 125.79724 -274.377786) (xy 125.78842 -274.379944) (xy 125.767959 -274.38539) (xy 125.726025 -274.391253)
			(xy 125.704854 -274.391628) (xy 125.701806 -274.391628) (xy 125.678125 -274.390941) (xy 125.631397 -274.383151)
			(xy 125.586433 -274.368238) (xy 125.544312 -274.346559) (xy 125.506044 -274.318635) (xy 125.472548 -274.285136)
			(xy 125.444627 -274.246866) (xy 125.422952 -274.204742) (xy 125.408043 -274.159777) (xy 125.400256 -274.113048)
			(xy 125.399546 -274.089368) (xy 125.399546 -274.086066) (xy 125.399917 -274.064958) (xy 125.405776 -274.023149)
			(xy 125.41123 -274.002754) (xy 125.413359 -273.993939) (xy 125.411967 -273.97587) (xy 125.404404 -273.959402)
			(xy 125.398276 -273.952716) (xy 125.338586 -273.893026) (xy 125.331474 -273.88566) (xy 125.312678 -273.87804)
			(xy 125.157484 -273.87804) (xy 125.145725 -273.878629) (xy 125.124661 -273.889084) (xy 125.117098 -273.898106)
			(xy 125.068076 -273.962114) (xy 125.064657 -273.966841) (xy 125.0599 -273.977492) (xy 125.058678 -273.983196)
			(xy 125.056392 -273.99488) (xy 125.05944 -274.00631) (xy 125.064428 -274.025935) (xy 125.06978 -274.066073)
			(xy 125.070108 -274.08632) (xy 125.069586 -274.111575) (xy 125.061273 -274.161397) (xy 125.044872 -274.209171)
			(xy 125.020831 -274.253594) (xy 124.989807 -274.293454) (xy 124.952645 -274.327664) (xy 124.910359 -274.35529)
			(xy 124.864103 -274.37558) (xy 124.815138 -274.38798) (xy 124.7648 -274.392151) (xy 124.714462 -274.38798)
			(xy 124.665497 -274.37558) (xy 124.619241 -274.35529) (xy 124.576955 -274.327664) (xy 124.539793 -274.293454)
			(xy 124.508769 -274.253594) (xy 124.484728 -274.209171) (xy 124.468327 -274.161397) (xy 124.460014 -274.111575)
			(xy 124.459492 -274.08632) (xy 124.459632 -274.073557) (xy 124.461798 -274.048124) (xy 124.46381 -274.03552)
			(xy 124.463556 -274.03552) (xy 124.47016 -274.00631) (xy 124.473208 -273.99488) (xy 124.470922 -273.983196)
			(xy 124.469649 -273.977508) (xy 124.464901 -273.966865) (xy 124.461524 -273.962114) (xy 124.412502 -273.898106)
			(xy 124.404908 -273.889123) (xy 124.383862 -273.878678) (xy 124.372116 -273.87804) (xy 124.21743 -273.87804)
			(xy 124.205677 -273.87864) (xy 124.184631 -273.889108) (xy 124.177044 -273.898106) (xy 124.128022 -273.962114)
			(xy 124.124617 -273.966849) (xy 124.119866 -273.977498) (xy 124.118624 -273.983196) (xy 124.116338 -273.99488)
			(xy 124.119386 -274.00631) (xy 124.124375 -274.025935) (xy 124.129728 -274.066073) (xy 124.130054 -274.08632)
			(xy 124.129532 -274.111575) (xy 124.121219 -274.161397) (xy 124.104818 -274.209171) (xy 124.080777 -274.253594)
			(xy 124.049753 -274.293454) (xy 124.012591 -274.327664) (xy 123.970305 -274.35529) (xy 123.924049 -274.37558)
			(xy 123.875084 -274.38798) (xy 123.824746 -274.392151) (xy 123.774408 -274.38798) (xy 123.725443 -274.37558)
			(xy 123.679187 -274.35529) (xy 123.636901 -274.327664) (xy 123.599739 -274.293454) (xy 123.568715 -274.253594)
			(xy 123.544674 -274.209171) (xy 123.528273 -274.161397) (xy 123.51996 -274.111575) (xy 123.519438 -274.08632)
			(xy 123.519578 -274.073557) (xy 123.521744 -274.048124) (xy 123.523756 -274.03552) (xy 123.523502 -274.03552)
			(xy 123.530106 -274.00631) (xy 123.533154 -273.99488) (xy 123.530868 -273.983196) (xy 123.529597 -273.977507)
			(xy 123.524852 -273.966862) (xy 123.52147 -273.962114) (xy 123.472448 -273.898106) (xy 123.464857 -273.889115)
			(xy 123.443812 -273.878651) (xy 123.432062 -273.87804) (xy 123.277376 -273.87804) (xy 123.265618 -273.878631)
			(xy 123.244556 -273.889087) (xy 123.23699 -273.898106) (xy 123.187968 -273.962114) (xy 123.184549 -273.966842)
			(xy 123.179793 -273.977492) (xy 123.17857 -273.983196) (xy 123.176284 -273.99488) (xy 123.179332 -274.00631)
			(xy 123.18432 -274.025935) (xy 123.189672 -274.066073) (xy 123.19 -274.08632) (xy 123.189478 -274.111575)
			(xy 123.181165 -274.161397) (xy 123.164764 -274.209171) (xy 123.140723 -274.253594) (xy 123.109699 -274.293454)
			(xy 123.072537 -274.327664) (xy 123.030251 -274.35529) (xy 122.983995 -274.37558) (xy 122.93503 -274.38798)
			(xy 122.884692 -274.392151) (xy 122.834354 -274.38798) (xy 122.785389 -274.37558) (xy 122.739133 -274.35529)
			(xy 122.696847 -274.327664) (xy 122.659685 -274.293454) (xy 122.628661 -274.253594) (xy 122.60462 -274.209171)
			(xy 122.588219 -274.161397) (xy 122.579906 -274.111575) (xy 122.579384 -274.08632) (xy 122.579524 -274.073557)
			(xy 122.58169 -274.048124) (xy 122.583702 -274.03552) (xy 122.583448 -274.03552) (xy 122.590052 -274.00631)
			(xy 122.5931 -273.99488) (xy 122.590814 -273.983196) (xy 122.589541 -273.977508) (xy 122.584792 -273.966866)
			(xy 122.581416 -273.962114) (xy 122.532394 -273.898106) (xy 122.524799 -273.889125) (xy 122.503754 -273.878682)
			(xy 122.492008 -273.87804) (xy 122.337322 -273.87804) (xy 122.32557 -273.878642) (xy 122.304527 -273.889112)
			(xy 122.296936 -273.898106) (xy 122.247914 -273.962114) (xy 122.244493 -273.96684) (xy 122.239732 -273.97749)
			(xy 122.238516 -273.983196) (xy 122.23623 -273.99488) (xy 122.239278 -274.00631) (xy 122.244267 -274.025935)
			(xy 122.24962 -274.066073) (xy 122.249946 -274.08632) (xy 122.249424 -274.111575) (xy 122.241111 -274.161397)
			(xy 122.22471 -274.209171) (xy 122.200669 -274.253594) (xy 122.169645 -274.293454) (xy 122.132483 -274.327664)
			(xy 122.090197 -274.35529) (xy 122.043941 -274.37558) (xy 121.994976 -274.38798) (xy 121.944638 -274.392151)
			(xy 121.8943 -274.38798) (xy 121.845335 -274.37558) (xy 121.799079 -274.35529) (xy 121.756793 -274.327664)
			(xy 121.719631 -274.293454) (xy 121.688607 -274.253594) (xy 121.664566 -274.209171) (xy 121.648165 -274.161397)
			(xy 121.639852 -274.111575) (xy 121.63933 -274.08632) (xy 121.63947 -274.073557) (xy 121.641636 -274.048124)
			(xy 121.643648 -274.03552) (xy 121.643394 -274.03552) (xy 121.649998 -274.00631) (xy 121.653046 -273.99488)
			(xy 121.65076 -273.983196) (xy 121.649489 -273.977507) (xy 121.644743 -273.966862) (xy 121.641362 -273.962114)
			(xy 121.59234 -273.898106) (xy 121.584748 -273.889117) (xy 121.563703 -273.878656) (xy 121.551954 -273.87804)
			(xy 121.397522 -273.87804) (xy 121.38577 -273.878642) (xy 121.364727 -273.889112) (xy 121.357136 -273.898106)
			(xy 121.308114 -273.962114) (xy 121.304693 -273.96684) (xy 121.299932 -273.97749) (xy 121.298716 -273.983196)
			(xy 121.29643 -273.99488) (xy 121.299478 -274.00631) (xy 121.304467 -274.025935) (xy 121.30982 -274.066073)
			(xy 121.310146 -274.08632) (xy 121.309624 -274.111575) (xy 121.301311 -274.161397) (xy 121.28491 -274.209171)
			(xy 121.260869 -274.253594) (xy 121.229845 -274.293454) (xy 121.192683 -274.327664) (xy 121.150397 -274.35529)
			(xy 121.104141 -274.37558) (xy 121.055176 -274.38798) (xy 121.004838 -274.392151) (xy 120.9545 -274.38798)
			(xy 120.905535 -274.37558) (xy 120.859279 -274.35529) (xy 120.816993 -274.327664) (xy 120.779831 -274.293454)
			(xy 120.748807 -274.253594) (xy 120.724766 -274.209171) (xy 120.708365 -274.161397) (xy 120.700052 -274.111575)
			(xy 120.69953 -274.08632) (xy 120.69967 -274.073557) (xy 120.701836 -274.048124) (xy 120.703848 -274.03552)
			(xy 120.703594 -274.03552) (xy 120.710198 -274.00631) (xy 120.713246 -273.99488) (xy 120.71096 -273.983196)
			(xy 120.709689 -273.977507) (xy 120.704943 -273.966862) (xy 120.701562 -273.962114) (xy 120.65254 -273.898106)
			(xy 120.644948 -273.889117) (xy 120.623903 -273.878656) (xy 120.612154 -273.87804) (xy 120.457468 -273.87804)
			(xy 120.445711 -273.878633) (xy 120.424652 -273.889091) (xy 120.417082 -273.898106) (xy 120.36806 -273.962114)
			(xy 120.364642 -273.966842) (xy 120.359886 -273.977492) (xy 120.358662 -273.983196) (xy 120.356376 -273.99488)
			(xy 120.359424 -274.00631) (xy 120.364412 -274.025935) (xy 120.369764 -274.066073) (xy 120.370092 -274.08632)
			(xy 120.36957 -274.111575) (xy 120.361257 -274.161397) (xy 120.344856 -274.209171) (xy 120.320815 -274.253594)
			(xy 120.289791 -274.293454) (xy 120.252629 -274.327664) (xy 120.210343 -274.35529) (xy 120.164087 -274.37558)
			(xy 120.115122 -274.38798) (xy 120.064784 -274.392151) (xy 120.014446 -274.38798) (xy 119.965481 -274.37558)
			(xy 119.919225 -274.35529) (xy 119.876939 -274.327664) (xy 119.839777 -274.293454) (xy 119.808753 -274.253594)
			(xy 119.784712 -274.209171) (xy 119.768311 -274.161397) (xy 119.759998 -274.111575) (xy 119.759476 -274.08632)
			(xy 119.759616 -274.073557) (xy 119.761782 -274.048124) (xy 119.763794 -274.03552) (xy 119.76354 -274.03552)
			(xy 119.770144 -274.00631) (xy 119.773192 -273.99488) (xy 119.770906 -273.983196) (xy 119.769633 -273.977508)
			(xy 119.764883 -273.966866) (xy 119.761508 -273.962114) (xy 119.712486 -273.898106) (xy 119.704897 -273.889109)
			(xy 119.683853 -273.878629) (xy 119.6721 -273.87804) (xy 119.517414 -273.87804) (xy 119.505663 -273.878644)
			(xy 119.484622 -273.889116) (xy 119.477028 -273.898106) (xy 119.428006 -273.962114) (xy 119.424585 -273.966841)
			(xy 119.419825 -273.97749) (xy 119.418608 -273.983196) (xy 119.416322 -273.99488) (xy 119.41937 -274.00631)
			(xy 119.424359 -274.025935) (xy 119.429712 -274.066073) (xy 119.430038 -274.08632) (xy 119.429516 -274.111575)
			(xy 119.421203 -274.161397) (xy 119.404802 -274.209171) (xy 119.380761 -274.253594) (xy 119.349737 -274.293454)
			(xy 119.312575 -274.327664) (xy 119.270289 -274.35529) (xy 119.224033 -274.37558) (xy 119.175068 -274.38798)
			(xy 119.12473 -274.392151) (xy 119.074392 -274.38798) (xy 119.025427 -274.37558) (xy 118.979171 -274.35529)
			(xy 118.936885 -274.327664) (xy 118.899723 -274.293454) (xy 118.868699 -274.253594) (xy 118.844658 -274.209171)
			(xy 118.828257 -274.161397) (xy 118.819944 -274.111575) (xy 118.819422 -274.08632) (xy 118.819562 -274.073557)
			(xy 118.821728 -274.048124) (xy 118.82374 -274.03552) (xy 118.823486 -274.03552) (xy 118.83009 -274.00631)
			(xy 118.833138 -273.99488) (xy 118.830852 -273.983196) (xy 118.829581 -273.977507) (xy 118.824835 -273.966863)
			(xy 118.821454 -273.962114) (xy 118.772432 -273.898106) (xy 118.76484 -273.889118) (xy 118.743795 -273.87866)
			(xy 118.732046 -273.87804) (xy 118.57736 -273.87804) (xy 118.565604 -273.878634) (xy 118.544548 -273.889095)
			(xy 118.536974 -273.898106) (xy 118.487952 -273.962114) (xy 118.484534 -273.966842) (xy 118.479779 -273.977493)
			(xy 118.478554 -273.983196) (xy 118.476268 -273.99488) (xy 118.479316 -274.00631) (xy 118.484304 -274.025935)
			(xy 118.489657 -274.066073) (xy 118.489984 -274.08632) (xy 118.489462 -274.111575) (xy 118.481149 -274.161397)
			(xy 118.464748 -274.209171) (xy 118.440707 -274.253594) (xy 118.409683 -274.293454) (xy 118.372521 -274.327664)
			(xy 118.330235 -274.35529) (xy 118.283979 -274.37558) (xy 118.235014 -274.38798) (xy 118.184676 -274.392151)
			(xy 118.134338 -274.38798) (xy 118.085373 -274.37558) (xy 118.039117 -274.35529) (xy 117.996831 -274.327664)
			(xy 117.959669 -274.293454) (xy 117.928645 -274.253594) (xy 117.904604 -274.209171) (xy 117.888203 -274.161397)
			(xy 117.87989 -274.111575) (xy 117.879368 -274.08632) (xy 117.879508 -274.073557) (xy 117.881674 -274.048124)
			(xy 117.883686 -274.03552) (xy 117.883432 -274.03552) (xy 117.890036 -274.00631) (xy 117.893084 -273.99488)
			(xy 117.890798 -273.983196) (xy 117.889525 -273.977508) (xy 117.884775 -273.966867) (xy 117.8814 -273.962114)
			(xy 117.832378 -273.898106) (xy 117.824789 -273.889111) (xy 117.803744 -273.878634) (xy 117.791992 -273.87804)
			(xy 117.637306 -273.87804) (xy 117.625556 -273.878645) (xy 117.604518 -273.889119) (xy 117.59692 -273.898106)
			(xy 117.547898 -273.962114) (xy 117.544478 -273.966841) (xy 117.539718 -273.977491) (xy 117.5385 -273.983196)
			(xy 117.536214 -273.99488) (xy 117.539262 -274.00631) (xy 117.544251 -274.025935) (xy 117.549604 -274.066073)
			(xy 117.54993 -274.08632) (xy 117.549408 -274.111575) (xy 117.541095 -274.161397) (xy 117.524694 -274.209171)
			(xy 117.500653 -274.253594) (xy 117.469629 -274.293454) (xy 117.432467 -274.327664) (xy 117.390181 -274.35529)
			(xy 117.343925 -274.37558) (xy 117.29496 -274.38798) (xy 117.244622 -274.392151) (xy 117.194284 -274.38798)
			(xy 117.145319 -274.37558) (xy 117.099063 -274.35529) (xy 117.056777 -274.327664) (xy 117.019615 -274.293454)
			(xy 116.988591 -274.253594) (xy 116.96455 -274.209171) (xy 116.948149 -274.161397) (xy 116.939836 -274.111575)
			(xy 116.939314 -274.08632) (xy 116.939454 -274.073557) (xy 116.94162 -274.048124) (xy 116.943632 -274.03552)
			(xy 116.943378 -274.03552) (xy 116.949982 -274.00631) (xy 116.95303 -273.99488) (xy 116.950744 -273.983196)
			(xy 116.949472 -273.977507) (xy 116.944726 -273.966863) (xy 116.941346 -273.962114) (xy 116.892324 -273.898106)
			(xy 116.884731 -273.88912) (xy 116.863686 -273.878665) (xy 116.851938 -273.87804) (xy 116.697506 -273.87804)
			(xy 116.685756 -273.878645) (xy 116.664718 -273.889119) (xy 116.65712 -273.898106) (xy 116.608098 -273.962114)
			(xy 116.604678 -273.966841) (xy 116.599918 -273.977491) (xy 116.5987 -273.983196) (xy 116.596414 -273.99488)
			(xy 116.599462 -274.00631) (xy 116.604451 -274.025935) (xy 116.609804 -274.066073) (xy 116.61013 -274.08632)
			(xy 116.609608 -274.111575) (xy 116.601295 -274.161397) (xy 116.584894 -274.209171) (xy 116.560853 -274.253594)
			(xy 116.529829 -274.293454) (xy 116.492667 -274.327664) (xy 116.450381 -274.35529) (xy 116.404125 -274.37558)
			(xy 116.35516 -274.38798) (xy 116.304822 -274.392151) (xy 116.254484 -274.38798) (xy 116.205519 -274.37558)
			(xy 116.159263 -274.35529) (xy 116.116977 -274.327664) (xy 116.079815 -274.293454) (xy 116.048791 -274.253594)
			(xy 116.02475 -274.209171) (xy 116.008349 -274.161397) (xy 116.000036 -274.111575) (xy 115.999514 -274.08632)
			(xy 115.999654 -274.073557) (xy 116.00182 -274.048124) (xy 116.003832 -274.03552) (xy 116.003578 -274.03552)
			(xy 116.010182 -274.00631) (xy 116.01323 -273.99488) (xy 116.010944 -273.983196) (xy 116.009672 -273.977507)
			(xy 116.004926 -273.966863) (xy 116.001546 -273.962114) (xy 115.952524 -273.898106) (xy 115.944931 -273.88912)
			(xy 115.923886 -273.878665) (xy 115.912138 -273.87804) (xy 115.757706 -273.87804) (xy 115.74604 -273.878611)
			(xy 115.725118 -273.888935) (xy 115.717574 -273.897852) (xy 115.668298 -273.962114) (xy 115.664853 -273.966849)
			(xy 115.659976 -273.977493) (xy 115.658646 -273.983196) (xy 115.65636 -273.99488) (xy 115.659408 -274.00631)
			(xy 115.664396 -274.025935) (xy 115.669749 -274.066073) (xy 115.670076 -274.08632) (xy 115.669628 -274.110311)
			(xy 115.662119 -274.157702) (xy 115.647288 -274.203335) (xy 115.625501 -274.246086) (xy 115.597295 -274.284903)
			(xy 115.563363 -274.318829) (xy 115.524542 -274.347028) (xy 115.481787 -274.368808) (xy 115.436152 -274.383631)
			(xy 115.388759 -274.391132) (xy 115.364768 -274.391628) (xy 114.424714 -274.391882) (xy 114.400702 -274.391412)
			(xy 114.353268 -274.383902) (xy 114.307592 -274.369063) (xy 114.264801 -274.347263) (xy 114.225946 -274.319037)
			(xy 114.191986 -274.28508) (xy 114.163755 -274.246228) (xy 114.14195 -274.203439) (xy 114.127106 -274.157766)
			(xy 114.119591 -274.110332) (xy 114.119152 -274.08632) (xy 114.119565 -274.06613) (xy 114.125045 -274.026122)
			(xy 114.130074 -274.006564) (xy 114.133122 -273.995134) (xy 114.130836 -273.983196) (xy 114.129544 -273.977481)
			(xy 114.124659 -273.966833) (xy 114.121184 -273.962114) (xy 114.071908 -273.897852) (xy 114.064324 -273.888989)
			(xy 114.043424 -273.878681) (xy 114.031776 -273.87804) (xy 113.877344 -273.87804) (xy 113.865589 -273.878638)
			(xy 113.844539 -273.889102) (xy 113.836958 -273.898106) (xy 113.787936 -273.962114) (xy 113.784519 -273.966842)
			(xy 113.779765 -273.977493) (xy 113.778538 -273.983196) (xy 113.776252 -273.99488) (xy 113.7793 -274.00631)
			(xy 113.784288 -274.025935) (xy 113.789641 -274.066073) (xy 113.789968 -274.08632) (xy 113.789446 -274.111575)
			(xy 113.781133 -274.161397) (xy 113.764732 -274.209171) (xy 113.740691 -274.253594) (xy 113.709667 -274.293454)
			(xy 113.672505 -274.327664) (xy 113.630219 -274.35529) (xy 113.583963 -274.37558) (xy 113.534998 -274.38798)
			(xy 113.48466 -274.392151) (xy 113.434322 -274.38798) (xy 113.385357 -274.37558) (xy 113.339101 -274.35529)
			(xy 113.296815 -274.327664) (xy 113.259653 -274.293454) (xy 113.228629 -274.253594) (xy 113.204588 -274.209171)
			(xy 113.188187 -274.161397) (xy 113.179874 -274.111575) (xy 113.179352 -274.08632) (xy 113.179492 -274.073557)
			(xy 113.181658 -274.048124) (xy 113.18367 -274.03552) (xy 113.183416 -274.03552) (xy 113.19002 -274.00631)
			(xy 113.193068 -273.99488) (xy 113.190782 -273.983196) (xy 113.189508 -273.977508) (xy 113.184757 -273.966868)
			(xy 113.181384 -273.962114) (xy 113.132362 -273.898106) (xy 113.124772 -273.889113) (xy 113.103727 -273.878643)
			(xy 113.091976 -273.87804) (xy 111.063786 -273.87804) (xy 111.052027 -273.878629) (xy 111.030962 -273.889083)
			(xy 111.0234 -273.898106) (xy 110.974378 -273.962114) (xy 110.970959 -273.966841) (xy 110.966201 -273.977491)
			(xy 110.96498 -273.983196) (xy 110.962694 -273.99488) (xy 110.965742 -274.00631) (xy 110.97073 -274.025935)
			(xy 110.976082 -274.066073) (xy 110.97641 -274.08632) (xy 110.975888 -274.111575) (xy 110.967575 -274.161397)
			(xy 110.951174 -274.209171) (xy 110.927133 -274.253594) (xy 110.896109 -274.293454) (xy 110.858947 -274.327664)
			(xy 110.816661 -274.35529) (xy 110.770405 -274.37558) (xy 110.72144 -274.38798) (xy 110.671102 -274.392151)
			(xy 110.620764 -274.38798) (xy 110.571799 -274.37558) (xy 110.525543 -274.35529) (xy 110.483257 -274.327664)
			(xy 110.446095 -274.293454) (xy 110.415071 -274.253594) (xy 110.39103 -274.209171) (xy 110.374629 -274.161397)
			(xy 110.366316 -274.111575) (xy 110.365794 -274.08632) (xy 110.365934 -274.073557) (xy 110.3681 -274.048124)
			(xy 110.370112 -274.03552) (xy 110.369858 -274.03552) (xy 110.376462 -274.00631) (xy 110.37951 -273.99488)
			(xy 110.377224 -273.983196) (xy 110.375951 -273.977508) (xy 110.371203 -273.966865) (xy 110.367826 -273.962114)
			(xy 110.318804 -273.898106) (xy 110.31121 -273.889123) (xy 110.290165 -273.878676) (xy 110.278418 -273.87804)
			(xy 110.123986 -273.87804) (xy 110.112322 -273.878615) (xy 110.091407 -273.888944) (xy 110.083854 -273.897852)
			(xy 110.034578 -273.962114) (xy 110.031134 -273.96685) (xy 110.026259 -273.977494) (xy 110.024926 -273.983196)
			(xy 110.02264 -273.99488) (xy 110.025688 -274.00631) (xy 110.030677 -274.025935) (xy 110.036029 -274.066073)
			(xy 110.036356 -274.08632) (xy 110.035884 -274.110312) (xy 110.028376 -274.157704) (xy 110.013547 -274.203338)
			(xy 109.991763 -274.246091) (xy 109.96356 -274.284911) (xy 109.929633 -274.318842) (xy 109.890815 -274.347049)
			(xy 109.848064 -274.368836) (xy 109.802431 -274.383669) (xy 109.75504 -274.391182) (xy 109.731048 -274.391628)
			(xy 108.790994 -274.391882) (xy 108.766983 -274.391411) (xy 108.719551 -274.383898) (xy 108.673878 -274.369058)
			(xy 108.63109 -274.347256) (xy 108.592238 -274.319029) (xy 108.55828 -274.285073) (xy 108.530051 -274.246222)
			(xy 108.508248 -274.203434) (xy 108.493406 -274.157763) (xy 108.48589 -274.110331) (xy 108.485432 -274.08632)
			(xy 108.485845 -274.066131) (xy 108.491327 -274.026122) (xy 108.496354 -274.006564) (xy 108.499402 -273.995134)
			(xy 108.497116 -273.983196) (xy 108.495826 -273.977479) (xy 108.490948 -273.966827) (xy 108.487464 -273.962114)
			(xy 108.438188 -273.897852) (xy 108.430609 -273.888976) (xy 108.40971 -273.878636) (xy 108.398056 -273.87804)
			(xy 108.243624 -273.87804) (xy 108.231872 -273.878642) (xy 108.210828 -273.889111) (xy 108.203238 -273.898106)
			(xy 108.154216 -273.962114) (xy 108.150812 -273.96685) (xy 108.146061 -273.977498) (xy 108.144818 -273.983196)
			(xy 108.142532 -273.99488) (xy 108.14558 -274.00631) (xy 108.150569 -274.025935) (xy 108.155922 -274.066073)
			(xy 108.156248 -274.08632) (xy 108.155726 -274.111575) (xy 108.147413 -274.161397) (xy 108.131012 -274.209171)
			(xy 108.106971 -274.253594) (xy 108.075947 -274.293454) (xy 108.038785 -274.327664) (xy 107.996499 -274.35529)
			(xy 107.950243 -274.37558) (xy 107.901278 -274.38798) (xy 107.85094 -274.392151) (xy 107.800602 -274.38798)
			(xy 107.751637 -274.37558) (xy 107.705381 -274.35529) (xy 107.663095 -274.327664) (xy 107.625933 -274.293454)
			(xy 107.594909 -274.253594) (xy 107.570868 -274.209171) (xy 107.554467 -274.161397) (xy 107.546154 -274.111575)
			(xy 107.545632 -274.08632) (xy 107.545772 -274.073557) (xy 107.547938 -274.048124) (xy 107.54995 -274.03552)
			(xy 107.549696 -274.03552) (xy 107.5563 -274.00631) (xy 107.559348 -273.99488) (xy 107.557062 -273.983196)
			(xy 107.555791 -273.977507) (xy 107.551046 -273.966862) (xy 107.547664 -273.962114) (xy 107.498642 -273.898106)
			(xy 107.49105 -273.889117) (xy 107.470005 -273.878655) (xy 107.458256 -273.87804) (xy 107.303824 -273.87804)
			(xy 107.292072 -273.878642) (xy 107.271028 -273.889111) (xy 107.263438 -273.898106) (xy 107.214416 -273.962114)
			(xy 107.211012 -273.96685) (xy 107.206261 -273.977498) (xy 107.205018 -273.983196) (xy 107.202732 -273.99488)
			(xy 107.20578 -274.00631) (xy 107.210769 -274.025935) (xy 107.216122 -274.066073) (xy 107.216448 -274.08632)
			(xy 107.215926 -274.111575) (xy 107.207613 -274.161397) (xy 107.191212 -274.209171) (xy 107.167171 -274.253594)
			(xy 107.136147 -274.293454) (xy 107.098985 -274.327664) (xy 107.056699 -274.35529) (xy 107.010443 -274.37558)
			(xy 106.961478 -274.38798) (xy 106.91114 -274.392151) (xy 106.860802 -274.38798) (xy 106.811837 -274.37558)
			(xy 106.765581 -274.35529) (xy 106.723295 -274.327664) (xy 106.686133 -274.293454) (xy 106.655109 -274.253594)
			(xy 106.631068 -274.209171) (xy 106.614667 -274.161397) (xy 106.606354 -274.111575) (xy 106.605832 -274.08632)
			(xy 106.605972 -274.073557) (xy 106.608138 -274.048124) (xy 106.61015 -274.03552) (xy 106.609896 -274.03552)
			(xy 106.6165 -274.00631) (xy 106.619548 -273.99488) (xy 106.617262 -273.983196) (xy 106.615991 -273.977507)
			(xy 106.611246 -273.966862) (xy 106.607864 -273.962114) (xy 106.558842 -273.898106) (xy 106.55125 -273.889117)
			(xy 106.530205 -273.878655) (xy 106.518456 -273.87804) (xy 106.36377 -273.87804) (xy 106.352013 -273.878632)
			(xy 106.330953 -273.88909) (xy 106.323384 -273.898106) (xy 106.274362 -273.962114) (xy 106.270944 -273.966842)
			(xy 106.266188 -273.977492) (xy 106.264964 -273.983196) (xy 106.262678 -273.99488) (xy 106.265726 -274.00631)
			(xy 106.270714 -274.025935) (xy 106.276066 -274.066073) (xy 106.276394 -274.08632) (xy 106.275872 -274.111575)
			(xy 106.267559 -274.161397) (xy 106.251158 -274.209171) (xy 106.227117 -274.253594) (xy 106.196093 -274.293454)
			(xy 106.158931 -274.327664) (xy 106.116645 -274.35529) (xy 106.070389 -274.37558) (xy 106.021424 -274.38798)
			(xy 105.971086 -274.392151) (xy 105.920748 -274.38798) (xy 105.871783 -274.37558) (xy 105.825527 -274.35529)
			(xy 105.783241 -274.327664) (xy 105.746079 -274.293454) (xy 105.715055 -274.253594) (xy 105.691014 -274.209171)
			(xy 105.674613 -274.161397) (xy 105.6663 -274.111575) (xy 105.665778 -274.08632) (xy 105.665918 -274.073557)
			(xy 105.668084 -274.048124) (xy 105.670096 -274.03552) (xy 105.669842 -274.03552) (xy 105.676446 -274.00631)
			(xy 105.679494 -273.99488) (xy 105.677208 -273.983196) (xy 105.675935 -273.977508) (xy 105.671186 -273.966866)
			(xy 105.66781 -273.962114) (xy 105.618788 -273.898106) (xy 105.6112 -273.889109) (xy 105.590155 -273.878628)
			(xy 105.578402 -273.87804) (xy 105.423716 -273.87804) (xy 105.411964 -273.878643) (xy 105.390923 -273.889115)
			(xy 105.38333 -273.898106) (xy 105.334308 -273.962114) (xy 105.330887 -273.966841) (xy 105.326127 -273.97749)
			(xy 105.32491 -273.983196) (xy 105.322624 -273.99488) (xy 105.325672 -274.00631) (xy 105.330661 -274.025935)
			(xy 105.336014 -274.066073) (xy 105.33634 -274.08632) (xy 105.335818 -274.111575) (xy 105.327505 -274.161397)
			(xy 105.311104 -274.209171) (xy 105.287063 -274.253594) (xy 105.256039 -274.293454) (xy 105.218877 -274.327664)
			(xy 105.176591 -274.35529) (xy 105.130335 -274.37558) (xy 105.08137 -274.38798) (xy 105.031032 -274.392151)
			(xy 104.980694 -274.38798) (xy 104.931729 -274.37558) (xy 104.885473 -274.35529) (xy 104.843187 -274.327664)
			(xy 104.806025 -274.293454) (xy 104.775001 -274.253594) (xy 104.75096 -274.209171) (xy 104.734559 -274.161397)
			(xy 104.726246 -274.111575) (xy 104.725724 -274.08632) (xy 104.725864 -274.073557) (xy 104.72803 -274.048124)
			(xy 104.730042 -274.03552) (xy 104.729788 -274.03552) (xy 104.736392 -274.00631) (xy 104.73944 -273.99488)
			(xy 104.737154 -273.983196) (xy 104.735883 -273.977507) (xy 104.731137 -273.966863) (xy 104.727756 -273.962114)
			(xy 104.678734 -273.898106) (xy 104.671142 -273.889118) (xy 104.650097 -273.878659) (xy 104.638348 -273.87804)
			(xy 104.483662 -273.87804) (xy 104.471905 -273.878634) (xy 104.450849 -273.889094) (xy 104.443276 -273.898106)
			(xy 104.394254 -273.962114) (xy 104.390836 -273.966842) (xy 104.386081 -273.977492) (xy 104.384856 -273.983196)
			(xy 104.38257 -273.99488) (xy 104.385618 -274.00631) (xy 104.390606 -274.025935) (xy 104.395958 -274.066073)
			(xy 104.396286 -274.08632) (xy 104.395764 -274.111575) (xy 104.387451 -274.161397) (xy 104.37105 -274.209171)
			(xy 104.347009 -274.253594) (xy 104.315985 -274.293454) (xy 104.278823 -274.327664) (xy 104.236537 -274.35529)
			(xy 104.190281 -274.37558) (xy 104.141316 -274.38798) (xy 104.090978 -274.392151) (xy 104.04064 -274.38798)
			(xy 103.991675 -274.37558) (xy 103.945419 -274.35529) (xy 103.903133 -274.327664) (xy 103.865971 -274.293454)
			(xy 103.834947 -274.253594) (xy 103.810906 -274.209171) (xy 103.794505 -274.161397) (xy 103.786192 -274.111575)
			(xy 103.78567 -274.08632) (xy 103.78581 -274.073557) (xy 103.787976 -274.048124) (xy 103.789988 -274.03552)
			(xy 103.789734 -274.03552) (xy 103.796338 -274.00631) (xy 103.799386 -273.99488) (xy 103.7971 -273.983196)
			(xy 103.795827 -273.977508) (xy 103.791077 -273.966867) (xy 103.787702 -273.962114) (xy 103.73868 -273.898106)
			(xy 103.731091 -273.88911) (xy 103.710046 -273.878633) (xy 103.698294 -273.87804) (xy 103.543862 -273.87804)
			(xy 103.532105 -273.878634) (xy 103.511049 -273.889094) (xy 103.503476 -273.898106) (xy 103.454454 -273.962114)
			(xy 103.451036 -273.966842) (xy 103.446281 -273.977492) (xy 103.445056 -273.983196) (xy 103.44277 -273.99488)
			(xy 103.445818 -274.00631) (xy 103.450806 -274.025935) (xy 103.456158 -274.066073) (xy 103.456486 -274.08632)
			(xy 103.455964 -274.111575) (xy 103.447651 -274.161397) (xy 103.43125 -274.209171) (xy 103.407209 -274.253594)
			(xy 103.376185 -274.293454) (xy 103.339023 -274.327664) (xy 103.296737 -274.35529) (xy 103.250481 -274.37558)
			(xy 103.201516 -274.38798) (xy 103.151178 -274.392151) (xy 103.10084 -274.38798) (xy 103.051875 -274.37558)
			(xy 103.005619 -274.35529) (xy 102.963333 -274.327664) (xy 102.926171 -274.293454) (xy 102.895147 -274.253594)
			(xy 102.871106 -274.209171) (xy 102.854705 -274.161397) (xy 102.846392 -274.111575) (xy 102.84587 -274.08632)
			(xy 102.84601 -274.073557) (xy 102.848176 -274.048124) (xy 102.850188 -274.03552) (xy 102.849934 -274.03552)
			(xy 102.856538 -274.00631) (xy 102.859586 -273.99488) (xy 102.8573 -273.983196) (xy 102.856027 -273.977508)
			(xy 102.851277 -273.966867) (xy 102.847902 -273.962114) (xy 102.79888 -273.898106) (xy 102.791291 -273.88911)
			(xy 102.770246 -273.878633) (xy 102.758494 -273.87804) (xy 102.603808 -273.87804) (xy 102.592057 -273.878645)
			(xy 102.571019 -273.889118) (xy 102.563422 -273.898106) (xy 102.5144 -273.962114) (xy 102.510979 -273.966841)
			(xy 102.50622 -273.977491) (xy 102.505002 -273.983196) (xy 102.502716 -273.99488) (xy 102.505764 -274.00631)
			(xy 102.510753 -274.025935) (xy 102.516106 -274.066073) (xy 102.516432 -274.08632) (xy 102.51591 -274.111575)
			(xy 102.507597 -274.161397) (xy 102.491196 -274.209171) (xy 102.467155 -274.253594) (xy 102.436131 -274.293454)
			(xy 102.398969 -274.327664) (xy 102.356683 -274.35529) (xy 102.310427 -274.37558) (xy 102.261462 -274.38798)
			(xy 102.211124 -274.392151) (xy 102.160786 -274.38798) (xy 102.111821 -274.37558) (xy 102.065565 -274.35529)
			(xy 102.023279 -274.327664) (xy 101.986117 -274.293454) (xy 101.955093 -274.253594) (xy 101.931052 -274.209171)
			(xy 101.914651 -274.161397) (xy 101.906338 -274.111575) (xy 101.905816 -274.08632) (xy 101.905956 -274.073557)
			(xy 101.908122 -274.048124) (xy 101.910134 -274.03552) (xy 101.90988 -274.03552) (xy 101.916484 -274.00631)
			(xy 101.919532 -273.99488) (xy 101.917246 -273.983196) (xy 101.915974 -273.977507) (xy 101.911228 -273.966863)
			(xy 101.907848 -273.962114) (xy 101.858826 -273.898106) (xy 101.851234 -273.889119) (xy 101.830188 -273.878664)
			(xy 101.81844 -273.87804) (xy 101.663754 -273.87804) (xy 101.651998 -273.878635) (xy 101.630944 -273.889097)
			(xy 101.623368 -273.898106) (xy 101.574346 -273.962114) (xy 101.570929 -273.966842) (xy 101.566174 -273.977493)
			(xy 101.564948 -273.983196) (xy 101.562662 -273.99488) (xy 101.56571 -274.00631) (xy 101.570698 -274.025935)
			(xy 101.576051 -274.066073) (xy 101.576378 -274.08632) (xy 101.575856 -274.111575) (xy 101.567543 -274.161397)
			(xy 101.551142 -274.209171) (xy 101.527101 -274.253594) (xy 101.496077 -274.293454) (xy 101.458915 -274.327664)
			(xy 101.416629 -274.35529) (xy 101.370373 -274.37558) (xy 101.321408 -274.38798) (xy 101.27107 -274.392151)
			(xy 101.220732 -274.38798) (xy 101.171767 -274.37558) (xy 101.125511 -274.35529) (xy 101.083225 -274.327664)
			(xy 101.046063 -274.293454) (xy 101.015039 -274.253594) (xy 100.990998 -274.209171) (xy 100.974597 -274.161397)
			(xy 100.966284 -274.111575) (xy 100.965762 -274.08632) (xy 100.965902 -274.073557) (xy 100.968068 -274.048124)
			(xy 100.97008 -274.03552) (xy 100.969826 -274.03552) (xy 100.97643 -274.00631) (xy 100.979478 -273.99488)
			(xy 100.977192 -273.983196) (xy 100.975919 -273.977508) (xy 100.971168 -273.966867) (xy 100.967794 -273.962114)
			(xy 100.918772 -273.898106) (xy 100.911183 -273.889112) (xy 100.890138 -273.878637) (xy 100.878386 -273.87804)
			(xy 100.7237 -273.87804) (xy 100.711939 -273.878626) (xy 100.69087 -273.889076) (xy 100.683314 -273.898106)
			(xy 100.634292 -273.962114) (xy 100.630872 -273.966841) (xy 100.626113 -273.977491) (xy 100.624894 -273.983196)
			(xy 100.622608 -273.99488) (xy 100.625656 -274.00631) (xy 100.630644 -274.025935) (xy 100.635995 -274.066073)
			(xy 100.636324 -274.08632) (xy 100.635802 -274.111575) (xy 100.627489 -274.161397) (xy 100.611088 -274.209171)
			(xy 100.587047 -274.253594) (xy 100.556023 -274.293454) (xy 100.518861 -274.327664) (xy 100.476575 -274.35529)
			(xy 100.430319 -274.37558) (xy 100.381354 -274.38798) (xy 100.331016 -274.392151) (xy 100.280678 -274.38798)
			(xy 100.231713 -274.37558) (xy 100.185457 -274.35529) (xy 100.143171 -274.327664) (xy 100.106009 -274.293454)
			(xy 100.074985 -274.253594) (xy 100.050944 -274.209171) (xy 100.034543 -274.161397) (xy 100.02623 -274.111575)
			(xy 100.025708 -274.08632) (xy 100.025848 -274.073557) (xy 100.028015 -274.048124) (xy 100.030026 -274.03552)
			(xy 100.029772 -274.03552) (xy 100.036376 -274.00631) (xy 100.039424 -273.99488) (xy 100.037138 -273.983196)
			(xy 100.035866 -273.977507) (xy 100.031119 -273.966864) (xy 100.02774 -273.962114) (xy 99.978718 -273.898106)
			(xy 99.971125 -273.889121) (xy 99.95008 -273.878668) (xy 99.938332 -273.87804) (xy 99.783646 -273.87804)
			(xy 99.771891 -273.878637) (xy 99.75084 -273.889101) (xy 99.74326 -273.898106) (xy 99.694238 -273.962114)
			(xy 99.690821 -273.966842) (xy 99.686067 -273.977493) (xy 99.68484 -273.983196) (xy 99.682554 -273.99488)
			(xy 99.685602 -274.00631) (xy 99.69059 -274.025935) (xy 99.695943 -274.066073) (xy 99.69627 -274.08632)
			(xy 99.695748 -274.111575) (xy 99.687435 -274.161397) (xy 99.671034 -274.209171) (xy 99.646993 -274.253594)
			(xy 99.615969 -274.293454) (xy 99.578807 -274.327664) (xy 99.536521 -274.35529) (xy 99.490265 -274.37558)
			(xy 99.4413 -274.38798) (xy 99.390962 -274.392151) (xy 99.340624 -274.38798) (xy 99.291659 -274.37558)
			(xy 99.245403 -274.35529) (xy 99.203117 -274.327664) (xy 99.165955 -274.293454) (xy 99.134931 -274.253594)
			(xy 99.11089 -274.209171) (xy 99.094489 -274.161397) (xy 99.086176 -274.111575) (xy 99.085654 -274.08632)
			(xy 99.085794 -274.073557) (xy 99.08796 -274.048124) (xy 99.089972 -274.03552) (xy 99.089718 -274.03552)
			(xy 99.096322 -274.00631) (xy 99.09937 -273.99488) (xy 99.097084 -273.983196) (xy 99.09581 -273.977508)
			(xy 99.091059 -273.966868) (xy 99.087686 -273.962114) (xy 99.038664 -273.898106) (xy 99.031074 -273.889113)
			(xy 99.010029 -273.878642) (xy 98.998278 -273.87804) (xy 98.843846 -273.87804) (xy 98.832091 -273.878637)
			(xy 98.81104 -273.889101) (xy 98.80346 -273.898106) (xy 98.754438 -273.962114) (xy 98.751021 -273.966842)
			(xy 98.746267 -273.977493) (xy 98.74504 -273.983196) (xy 98.742754 -273.99488) (xy 98.745802 -274.00631)
			(xy 98.75079 -274.025935) (xy 98.756143 -274.066073) (xy 98.75647 -274.08632) (xy 98.755948 -274.111575)
			(xy 98.747635 -274.161397) (xy 98.731234 -274.209171) (xy 98.707193 -274.253594) (xy 98.676169 -274.293454)
			(xy 98.639007 -274.327664) (xy 98.596721 -274.35529) (xy 98.550465 -274.37558) (xy 98.5015 -274.38798)
			(xy 98.451162 -274.392151) (xy 98.400824 -274.38798) (xy 98.351859 -274.37558) (xy 98.305603 -274.35529)
			(xy 98.263317 -274.327664) (xy 98.226155 -274.293454) (xy 98.195131 -274.253594) (xy 98.17109 -274.209171)
			(xy 98.154689 -274.161397) (xy 98.146376 -274.111575) (xy 98.145854 -274.08632) (xy 98.145994 -274.073557)
			(xy 98.14816 -274.048124) (xy 98.150172 -274.03552) (xy 98.149918 -274.03552) (xy 98.156522 -274.00631)
			(xy 98.15957 -273.99488) (xy 98.157284 -273.983196) (xy 98.15601 -273.977508) (xy 98.151259 -273.966868)
			(xy 98.147886 -273.962114) (xy 98.098864 -273.898106) (xy 98.091274 -273.889113) (xy 98.070229 -273.878642)
			(xy 98.058478 -273.87804) (xy 97.903792 -273.87804) (xy 97.892032 -273.878627) (xy 97.870965 -273.88908)
			(xy 97.863406 -273.898106) (xy 97.814384 -273.962114) (xy 97.810964 -273.966841) (xy 97.806206 -273.977491)
			(xy 97.804986 -273.983196) (xy 97.8027 -273.99488) (xy 97.805748 -274.00631) (xy 97.810736 -274.025935)
			(xy 97.816087 -274.066073) (xy 97.816416 -274.08632) (xy 97.815944 -274.11031) (xy 97.808435 -274.1577)
			(xy 97.793606 -274.203332) (xy 97.771822 -274.246083) (xy 97.743618 -274.284899) (xy 97.70969 -274.318826)
			(xy 97.670872 -274.347028) (xy 97.628121 -274.368811) (xy 97.582488 -274.383638) (xy 97.535098 -274.391145)
			(xy 97.511108 -274.391628) (xy 97.482207 -274.390956) (xy 97.425436 -274.380092) (xy 97.398332 -274.370038)
			(xy 97.386394 -274.365212) (xy 97.361502 -274.368006) (xy 97.281492 -274.422362) (xy 97.271473 -274.42989)
			(xy 97.259757 -274.452008) (xy 97.25914 -274.464526) (xy 97.25914 -274.653756) (xy 97.259263 -274.658304)
			(xy 97.260922 -274.667248) (xy 97.262442 -274.671536) (xy 97.271332 -274.695412) (xy 97.276666 -274.702016)
			(xy 97.292992 -274.722699) (xy 97.319037 -274.7685) (xy 97.336861 -274.818082) (xy 97.34594 -274.869982)
			(xy 97.346516 -274.896326) (xy 97.675204 -274.896326) (xy 97.679164 -274.847272) (xy 97.690941 -274.799488)
			(xy 97.710232 -274.754212) (xy 97.736535 -274.712616) (xy 97.76917 -274.675779) (xy 97.807291 -274.644654)
			(xy 97.849912 -274.620047) (xy 97.895928 -274.602595) (xy 97.944147 -274.592751) (xy 97.993322 -274.59077)
			(xy 98.042177 -274.596702) (xy 98.089448 -274.610394) (xy 98.13391 -274.631492) (xy 98.174413 -274.659448)
			(xy 98.209906 -274.69354) (xy 98.239471 -274.732884) (xy 98.262342 -274.776461) (xy 98.277926 -274.823142)
			(xy 98.285821 -274.871719) (xy 98.286316 -274.896326) (xy 98.615258 -274.896326) (xy 98.619218 -274.847272)
			(xy 98.630995 -274.799488) (xy 98.650286 -274.754212) (xy 98.676589 -274.712616) (xy 98.709224 -274.675779)
			(xy 98.747345 -274.644654) (xy 98.789966 -274.620047) (xy 98.835982 -274.602595) (xy 98.884201 -274.592751)
			(xy 98.933376 -274.59077) (xy 98.982231 -274.596702) (xy 99.029502 -274.610394) (xy 99.073964 -274.631492)
			(xy 99.114467 -274.659448) (xy 99.14996 -274.69354) (xy 99.179525 -274.732884) (xy 99.202396 -274.776461)
			(xy 99.21798 -274.823142) (xy 99.225875 -274.871719) (xy 99.22637 -274.896326) (xy 99.555312 -274.896326)
			(xy 99.559272 -274.847272) (xy 99.571049 -274.799488) (xy 99.59034 -274.754212) (xy 99.616643 -274.712616)
			(xy 99.649278 -274.675779) (xy 99.687399 -274.644654) (xy 99.73002 -274.620047) (xy 99.776036 -274.602595)
			(xy 99.824255 -274.592751) (xy 99.87343 -274.59077) (xy 99.922285 -274.596702) (xy 99.969556 -274.610394)
			(xy 100.014018 -274.631492) (xy 100.054521 -274.659448) (xy 100.090014 -274.69354) (xy 100.119579 -274.732884)
			(xy 100.14245 -274.776461) (xy 100.158034 -274.823142) (xy 100.165929 -274.871719) (xy 100.166424 -274.896326)
			(xy 100.495366 -274.896326) (xy 100.499326 -274.847272) (xy 100.511103 -274.799488) (xy 100.530394 -274.754212)
			(xy 100.556697 -274.712616) (xy 100.589332 -274.675779) (xy 100.627453 -274.644654) (xy 100.670074 -274.620047)
			(xy 100.71609 -274.602595) (xy 100.764309 -274.592751) (xy 100.813484 -274.59077) (xy 100.862339 -274.596702)
			(xy 100.90961 -274.610394) (xy 100.954072 -274.631492) (xy 100.994575 -274.659448) (xy 101.030068 -274.69354)
			(xy 101.059633 -274.732884) (xy 101.082504 -274.776461) (xy 101.098088 -274.823142) (xy 101.105983 -274.871719)
			(xy 101.106478 -274.896326) (xy 101.435166 -274.896326) (xy 101.439126 -274.847272) (xy 101.450903 -274.799488)
			(xy 101.470194 -274.754212) (xy 101.496497 -274.712616) (xy 101.529132 -274.675779) (xy 101.567253 -274.644654)
			(xy 101.609874 -274.620047) (xy 101.65589 -274.602595) (xy 101.704109 -274.592751) (xy 101.753284 -274.59077)
			(xy 101.802139 -274.596702) (xy 101.84941 -274.610394) (xy 101.893872 -274.631492) (xy 101.934375 -274.659448)
			(xy 101.969868 -274.69354) (xy 101.999433 -274.732884) (xy 102.022304 -274.776461) (xy 102.037888 -274.823142)
			(xy 102.045783 -274.871719) (xy 102.046278 -274.896326) (xy 102.37522 -274.896326) (xy 102.37918 -274.847272)
			(xy 102.390957 -274.799488) (xy 102.410248 -274.754212) (xy 102.436551 -274.712616) (xy 102.469186 -274.675779)
			(xy 102.507307 -274.644654) (xy 102.549928 -274.620047) (xy 102.595944 -274.602595) (xy 102.644163 -274.592751)
			(xy 102.693338 -274.59077) (xy 102.742193 -274.596702) (xy 102.789464 -274.610394) (xy 102.833926 -274.631492)
			(xy 102.874429 -274.659448) (xy 102.909922 -274.69354) (xy 102.939487 -274.732884) (xy 102.962358 -274.776461)
			(xy 102.977942 -274.823142) (xy 102.985837 -274.871719) (xy 102.986332 -274.896326) (xy 103.315274 -274.896326)
			(xy 103.319234 -274.847272) (xy 103.331011 -274.799488) (xy 103.350302 -274.754212) (xy 103.376605 -274.712616)
			(xy 103.40924 -274.675779) (xy 103.447361 -274.644654) (xy 103.489982 -274.620047) (xy 103.535998 -274.602595)
			(xy 103.584217 -274.592751) (xy 103.633392 -274.59077) (xy 103.682247 -274.596702) (xy 103.729518 -274.610394)
			(xy 103.77398 -274.631492) (xy 103.814483 -274.659448) (xy 103.849976 -274.69354) (xy 103.879541 -274.732884)
			(xy 103.902412 -274.776461) (xy 103.917996 -274.823142) (xy 103.925891 -274.871719) (xy 103.926386 -274.896326)
			(xy 104.255328 -274.896326) (xy 104.259288 -274.847272) (xy 104.271065 -274.799488) (xy 104.290356 -274.754212)
			(xy 104.316659 -274.712616) (xy 104.349294 -274.675779) (xy 104.387415 -274.644654) (xy 104.430036 -274.620047)
			(xy 104.476052 -274.602595) (xy 104.524271 -274.592751) (xy 104.573446 -274.59077) (xy 104.622301 -274.596702)
			(xy 104.669572 -274.610394) (xy 104.714034 -274.631492) (xy 104.754537 -274.659448) (xy 104.79003 -274.69354)
			(xy 104.819595 -274.732884) (xy 104.842466 -274.776461) (xy 104.85805 -274.823142) (xy 104.865945 -274.871719)
			(xy 104.86644 -274.896326) (xy 105.195128 -274.896326) (xy 105.199088 -274.847272) (xy 105.210865 -274.799488)
			(xy 105.230156 -274.754212) (xy 105.256459 -274.712616) (xy 105.289094 -274.675779) (xy 105.327215 -274.644654)
			(xy 105.369836 -274.620047) (xy 105.415852 -274.602595) (xy 105.464071 -274.592751) (xy 105.513246 -274.59077)
			(xy 105.562101 -274.596702) (xy 105.609372 -274.610394) (xy 105.653834 -274.631492) (xy 105.694337 -274.659448)
			(xy 105.72983 -274.69354) (xy 105.759395 -274.732884) (xy 105.782266 -274.776461) (xy 105.79785 -274.823142)
			(xy 105.805745 -274.871719) (xy 105.80624 -274.896326) (xy 106.135182 -274.896326) (xy 106.139142 -274.847272)
			(xy 106.150919 -274.799488) (xy 106.17021 -274.754212) (xy 106.196513 -274.712616) (xy 106.229148 -274.675779)
			(xy 106.267269 -274.644654) (xy 106.30989 -274.620047) (xy 106.355906 -274.602595) (xy 106.404125 -274.592751)
			(xy 106.4533 -274.59077) (xy 106.502155 -274.596702) (xy 106.549426 -274.610394) (xy 106.593888 -274.631492)
			(xy 106.634391 -274.659448) (xy 106.669884 -274.69354) (xy 106.699449 -274.732884) (xy 106.72232 -274.776461)
			(xy 106.737904 -274.823142) (xy 106.745799 -274.871719) (xy 106.746294 -274.896326) (xy 107.075236 -274.896326)
			(xy 107.079196 -274.847272) (xy 107.090973 -274.799488) (xy 107.110264 -274.754212) (xy 107.136567 -274.712616)
			(xy 107.169202 -274.675779) (xy 107.207323 -274.644654) (xy 107.249944 -274.620047) (xy 107.29596 -274.602595)
			(xy 107.344179 -274.592751) (xy 107.393354 -274.59077) (xy 107.442209 -274.596702) (xy 107.48948 -274.610394)
			(xy 107.533942 -274.631492) (xy 107.574445 -274.659448) (xy 107.609938 -274.69354) (xy 107.639503 -274.732884)
			(xy 107.662374 -274.776461) (xy 107.677958 -274.823142) (xy 107.685853 -274.871719) (xy 107.686348 -274.896326)
			(xy 108.01529 -274.896326) (xy 108.01925 -274.847272) (xy 108.031027 -274.799488) (xy 108.050318 -274.754212)
			(xy 108.076621 -274.712616) (xy 108.109256 -274.675779) (xy 108.147377 -274.644654) (xy 108.189998 -274.620047)
			(xy 108.236014 -274.602595) (xy 108.284233 -274.592751) (xy 108.333408 -274.59077) (xy 108.382263 -274.596702)
			(xy 108.429534 -274.610394) (xy 108.473996 -274.631492) (xy 108.514499 -274.659448) (xy 108.549992 -274.69354)
			(xy 108.579557 -274.732884) (xy 108.602428 -274.776461) (xy 108.618012 -274.823142) (xy 108.625907 -274.871719)
			(xy 108.626402 -274.896326) (xy 115.528864 -274.896326) (xy 115.532824 -274.847272) (xy 115.544601 -274.799488)
			(xy 115.563892 -274.754212) (xy 115.590195 -274.712616) (xy 115.62283 -274.675779) (xy 115.660951 -274.644654)
			(xy 115.703572 -274.620047) (xy 115.749588 -274.602595) (xy 115.797807 -274.592751) (xy 115.846982 -274.59077)
			(xy 115.895837 -274.596702) (xy 115.943108 -274.610394) (xy 115.98757 -274.631492) (xy 116.028073 -274.659448)
			(xy 116.063566 -274.69354) (xy 116.093131 -274.732884) (xy 116.116002 -274.776461) (xy 116.131586 -274.823142)
			(xy 116.139481 -274.871719) (xy 116.139976 -274.896326) (xy 116.468918 -274.896326) (xy 116.472878 -274.847272)
			(xy 116.484655 -274.799488) (xy 116.503946 -274.754212) (xy 116.530249 -274.712616) (xy 116.562884 -274.675779)
			(xy 116.601005 -274.644654) (xy 116.643626 -274.620047) (xy 116.689642 -274.602595) (xy 116.737861 -274.592751)
			(xy 116.787036 -274.59077) (xy 116.835891 -274.596702) (xy 116.883162 -274.610394) (xy 116.927624 -274.631492)
			(xy 116.968127 -274.659448) (xy 117.00362 -274.69354) (xy 117.033185 -274.732884) (xy 117.056056 -274.776461)
			(xy 117.07164 -274.823142) (xy 117.079535 -274.871719) (xy 117.08003 -274.896326) (xy 117.408972 -274.896326)
			(xy 117.412932 -274.847272) (xy 117.424709 -274.799488) (xy 117.444 -274.754212) (xy 117.470303 -274.712616)
			(xy 117.502938 -274.675779) (xy 117.541059 -274.644654) (xy 117.58368 -274.620047) (xy 117.629696 -274.602595)
			(xy 117.677915 -274.592751) (xy 117.72709 -274.59077) (xy 117.775945 -274.596702) (xy 117.823216 -274.610394)
			(xy 117.867678 -274.631492) (xy 117.908181 -274.659448) (xy 117.943674 -274.69354) (xy 117.973239 -274.732884)
			(xy 117.99611 -274.776461) (xy 118.011694 -274.823142) (xy 118.019589 -274.871719) (xy 118.020084 -274.896326)
			(xy 118.349026 -274.896326) (xy 118.352986 -274.847272) (xy 118.364763 -274.799488) (xy 118.384054 -274.754212)
			(xy 118.410357 -274.712616) (xy 118.442992 -274.675779) (xy 118.481113 -274.644654) (xy 118.523734 -274.620047)
			(xy 118.56975 -274.602595) (xy 118.617969 -274.592751) (xy 118.667144 -274.59077) (xy 118.715999 -274.596702)
			(xy 118.76327 -274.610394) (xy 118.807732 -274.631492) (xy 118.848235 -274.659448) (xy 118.883728 -274.69354)
			(xy 118.913293 -274.732884) (xy 118.936164 -274.776461) (xy 118.951748 -274.823142) (xy 118.959643 -274.871719)
			(xy 118.960138 -274.896326) (xy 119.288826 -274.896326) (xy 119.292786 -274.847272) (xy 119.304563 -274.799488)
			(xy 119.323854 -274.754212) (xy 119.350157 -274.712616) (xy 119.382792 -274.675779) (xy 119.420913 -274.644654)
			(xy 119.463534 -274.620047) (xy 119.50955 -274.602595) (xy 119.557769 -274.592751) (xy 119.606944 -274.59077)
			(xy 119.655799 -274.596702) (xy 119.70307 -274.610394) (xy 119.747532 -274.631492) (xy 119.788035 -274.659448)
			(xy 119.823528 -274.69354) (xy 119.853093 -274.732884) (xy 119.875964 -274.776461) (xy 119.891548 -274.823142)
			(xy 119.899443 -274.871719) (xy 119.899938 -274.896326) (xy 120.22888 -274.896326) (xy 120.23284 -274.847272)
			(xy 120.244617 -274.799488) (xy 120.263908 -274.754212) (xy 120.290211 -274.712616) (xy 120.322846 -274.675779)
			(xy 120.360967 -274.644654) (xy 120.403588 -274.620047) (xy 120.449604 -274.602595) (xy 120.497823 -274.592751)
			(xy 120.546998 -274.59077) (xy 120.595853 -274.596702) (xy 120.643124 -274.610394) (xy 120.687586 -274.631492)
			(xy 120.728089 -274.659448) (xy 120.763582 -274.69354) (xy 120.793147 -274.732884) (xy 120.816018 -274.776461)
			(xy 120.831602 -274.823142) (xy 120.839497 -274.871719) (xy 120.839992 -274.896326) (xy 121.168934 -274.896326)
			(xy 121.172894 -274.847272) (xy 121.184671 -274.799488) (xy 121.203962 -274.754212) (xy 121.230265 -274.712616)
			(xy 121.2629 -274.675779) (xy 121.301021 -274.644654) (xy 121.343642 -274.620047) (xy 121.389658 -274.602595)
			(xy 121.437877 -274.592751) (xy 121.487052 -274.59077) (xy 121.535907 -274.596702) (xy 121.583178 -274.610394)
			(xy 121.62764 -274.631492) (xy 121.668143 -274.659448) (xy 121.703636 -274.69354) (xy 121.733201 -274.732884)
			(xy 121.756072 -274.776461) (xy 121.771656 -274.823142) (xy 121.779551 -274.871719) (xy 121.780046 -274.896326)
			(xy 122.108988 -274.896326) (xy 122.112948 -274.847272) (xy 122.124725 -274.799488) (xy 122.144016 -274.754212)
			(xy 122.170319 -274.712616) (xy 122.202954 -274.675779) (xy 122.241075 -274.644654) (xy 122.283696 -274.620047)
			(xy 122.329712 -274.602595) (xy 122.377931 -274.592751) (xy 122.427106 -274.59077) (xy 122.475961 -274.596702)
			(xy 122.523232 -274.610394) (xy 122.567694 -274.631492) (xy 122.608197 -274.659448) (xy 122.64369 -274.69354)
			(xy 122.673255 -274.732884) (xy 122.696126 -274.776461) (xy 122.71171 -274.823142) (xy 122.719605 -274.871719)
			(xy 122.7201 -274.896326) (xy 123.049042 -274.896326) (xy 123.053002 -274.847272) (xy 123.064779 -274.799488)
			(xy 123.08407 -274.754212) (xy 123.110373 -274.712616) (xy 123.143008 -274.675779) (xy 123.181129 -274.644654)
			(xy 123.22375 -274.620047) (xy 123.269766 -274.602595) (xy 123.317985 -274.592751) (xy 123.36716 -274.59077)
			(xy 123.416015 -274.596702) (xy 123.463286 -274.610394) (xy 123.507748 -274.631492) (xy 123.548251 -274.659448)
			(xy 123.583744 -274.69354) (xy 123.613309 -274.732884) (xy 123.63618 -274.776461) (xy 123.651764 -274.823142)
			(xy 123.659659 -274.871719) (xy 123.660154 -274.896326) (xy 123.988842 -274.896326) (xy 123.992802 -274.847272)
			(xy 124.004579 -274.799488) (xy 124.02387 -274.754212) (xy 124.050173 -274.712616) (xy 124.082808 -274.675779)
			(xy 124.120929 -274.644654) (xy 124.16355 -274.620047) (xy 124.209566 -274.602595) (xy 124.257785 -274.592751)
			(xy 124.30696 -274.59077) (xy 124.355815 -274.596702) (xy 124.403086 -274.610394) (xy 124.447548 -274.631492)
			(xy 124.488051 -274.659448) (xy 124.523544 -274.69354) (xy 124.553109 -274.732884) (xy 124.57598 -274.776461)
			(xy 124.591564 -274.823142) (xy 124.599459 -274.871719) (xy 124.599954 -274.896326) (xy 124.599459 -274.920933)
			(xy 124.591564 -274.96951) (xy 124.57598 -275.016191) (xy 124.553109 -275.059768) (xy 124.523544 -275.099112)
			(xy 124.488051 -275.133204) (xy 124.447548 -275.16116) (xy 124.403086 -275.182258) (xy 124.355815 -275.19595)
			(xy 124.30696 -275.201882) (xy 124.257785 -275.199901) (xy 124.209566 -275.190057) (xy 124.16355 -275.172605)
			(xy 124.120929 -275.147998) (xy 124.082808 -275.116873) (xy 124.050173 -275.080036) (xy 124.02387 -275.03844)
			(xy 124.004579 -274.993164) (xy 123.992802 -274.94538) (xy 123.988842 -274.896326) (xy 123.660154 -274.896326)
			(xy 123.659659 -274.920933) (xy 123.651764 -274.96951) (xy 123.63618 -275.016191) (xy 123.613309 -275.059768)
			(xy 123.583744 -275.099112) (xy 123.548251 -275.133204) (xy 123.507748 -275.16116) (xy 123.463286 -275.182258)
			(xy 123.416015 -275.19595) (xy 123.36716 -275.201882) (xy 123.317985 -275.199901) (xy 123.269766 -275.190057)
			(xy 123.22375 -275.172605) (xy 123.181129 -275.147998) (xy 123.143008 -275.116873) (xy 123.110373 -275.080036)
			(xy 123.08407 -275.03844) (xy 123.064779 -274.993164) (xy 123.053002 -274.94538) (xy 123.049042 -274.896326)
			(xy 122.7201 -274.896326) (xy 122.719605 -274.920933) (xy 122.71171 -274.96951) (xy 122.696126 -275.016191)
			(xy 122.673255 -275.059768) (xy 122.64369 -275.099112) (xy 122.608197 -275.133204) (xy 122.567694 -275.16116)
			(xy 122.523232 -275.182258) (xy 122.475961 -275.19595) (xy 122.427106 -275.201882) (xy 122.377931 -275.199901)
			(xy 122.329712 -275.190057) (xy 122.283696 -275.172605) (xy 122.241075 -275.147998) (xy 122.202954 -275.116873)
			(xy 122.170319 -275.080036) (xy 122.144016 -275.03844) (xy 122.124725 -274.993164) (xy 122.112948 -274.94538)
			(xy 122.108988 -274.896326) (xy 121.780046 -274.896326) (xy 121.779551 -274.920933) (xy 121.771656 -274.96951)
			(xy 121.756072 -275.016191) (xy 121.733201 -275.059768) (xy 121.703636 -275.099112) (xy 121.668143 -275.133204)
			(xy 121.62764 -275.16116) (xy 121.583178 -275.182258) (xy 121.535907 -275.19595) (xy 121.487052 -275.201882)
			(xy 121.437877 -275.199901) (xy 121.389658 -275.190057) (xy 121.343642 -275.172605) (xy 121.301021 -275.147998)
			(xy 121.2629 -275.116873) (xy 121.230265 -275.080036) (xy 121.203962 -275.03844) (xy 121.184671 -274.993164)
			(xy 121.172894 -274.94538) (xy 121.168934 -274.896326) (xy 120.839992 -274.896326) (xy 120.839497 -274.920933)
			(xy 120.831602 -274.96951) (xy 120.816018 -275.016191) (xy 120.793147 -275.059768) (xy 120.763582 -275.099112)
			(xy 120.728089 -275.133204) (xy 120.687586 -275.16116) (xy 120.643124 -275.182258) (xy 120.595853 -275.19595)
			(xy 120.546998 -275.201882) (xy 120.497823 -275.199901) (xy 120.449604 -275.190057) (xy 120.403588 -275.172605)
			(xy 120.360967 -275.147998) (xy 120.322846 -275.116873) (xy 120.290211 -275.080036) (xy 120.263908 -275.03844)
			(xy 120.244617 -274.993164) (xy 120.23284 -274.94538) (xy 120.22888 -274.896326) (xy 119.899938 -274.896326)
			(xy 119.899443 -274.920933) (xy 119.891548 -274.96951) (xy 119.875964 -275.016191) (xy 119.853093 -275.059768)
			(xy 119.823528 -275.099112) (xy 119.788035 -275.133204) (xy 119.747532 -275.16116) (xy 119.70307 -275.182258)
			(xy 119.655799 -275.19595) (xy 119.606944 -275.201882) (xy 119.557769 -275.199901) (xy 119.50955 -275.190057)
			(xy 119.463534 -275.172605) (xy 119.420913 -275.147998) (xy 119.382792 -275.116873) (xy 119.350157 -275.080036)
			(xy 119.323854 -275.03844) (xy 119.304563 -274.993164) (xy 119.292786 -274.94538) (xy 119.288826 -274.896326)
			(xy 118.960138 -274.896326) (xy 118.959643 -274.920933) (xy 118.951748 -274.96951) (xy 118.936164 -275.016191)
			(xy 118.913293 -275.059768) (xy 118.883728 -275.099112) (xy 118.848235 -275.133204) (xy 118.807732 -275.16116)
			(xy 118.76327 -275.182258) (xy 118.715999 -275.19595) (xy 118.667144 -275.201882) (xy 118.617969 -275.199901)
			(xy 118.56975 -275.190057) (xy 118.523734 -275.172605) (xy 118.481113 -275.147998) (xy 118.442992 -275.116873)
			(xy 118.410357 -275.080036) (xy 118.384054 -275.03844) (xy 118.364763 -274.993164) (xy 118.352986 -274.94538)
			(xy 118.349026 -274.896326) (xy 118.020084 -274.896326) (xy 118.019589 -274.920933) (xy 118.011694 -274.96951)
			(xy 117.99611 -275.016191) (xy 117.973239 -275.059768) (xy 117.943674 -275.099112) (xy 117.908181 -275.133204)
			(xy 117.867678 -275.16116) (xy 117.823216 -275.182258) (xy 117.775945 -275.19595) (xy 117.72709 -275.201882)
			(xy 117.677915 -275.199901) (xy 117.629696 -275.190057) (xy 117.58368 -275.172605) (xy 117.541059 -275.147998)
			(xy 117.502938 -275.116873) (xy 117.470303 -275.080036) (xy 117.444 -275.03844) (xy 117.424709 -274.993164)
			(xy 117.412932 -274.94538) (xy 117.408972 -274.896326) (xy 117.08003 -274.896326) (xy 117.079535 -274.920933)
			(xy 117.07164 -274.96951) (xy 117.056056 -275.016191) (xy 117.033185 -275.059768) (xy 117.00362 -275.099112)
			(xy 116.968127 -275.133204) (xy 116.927624 -275.16116) (xy 116.883162 -275.182258) (xy 116.835891 -275.19595)
			(xy 116.787036 -275.201882) (xy 116.737861 -275.199901) (xy 116.689642 -275.190057) (xy 116.643626 -275.172605)
			(xy 116.601005 -275.147998) (xy 116.562884 -275.116873) (xy 116.530249 -275.080036) (xy 116.503946 -275.03844)
			(xy 116.484655 -274.993164) (xy 116.472878 -274.94538) (xy 116.468918 -274.896326) (xy 116.139976 -274.896326)
			(xy 116.139481 -274.920933) (xy 116.131586 -274.96951) (xy 116.116002 -275.016191) (xy 116.093131 -275.059768)
			(xy 116.063566 -275.099112) (xy 116.028073 -275.133204) (xy 115.98757 -275.16116) (xy 115.943108 -275.182258)
			(xy 115.895837 -275.19595) (xy 115.846982 -275.201882) (xy 115.797807 -275.199901) (xy 115.749588 -275.190057)
			(xy 115.703572 -275.172605) (xy 115.660951 -275.147998) (xy 115.62283 -275.116873) (xy 115.590195 -275.080036)
			(xy 115.563892 -275.03844) (xy 115.544601 -274.993164) (xy 115.532824 -274.94538) (xy 115.528864 -274.896326)
			(xy 108.626402 -274.896326) (xy 108.625907 -274.920933) (xy 108.618012 -274.96951) (xy 108.602428 -275.016191)
			(xy 108.579557 -275.059768) (xy 108.549992 -275.099112) (xy 108.514499 -275.133204) (xy 108.473996 -275.16116)
			(xy 108.429534 -275.182258) (xy 108.382263 -275.19595) (xy 108.333408 -275.201882) (xy 108.284233 -275.199901)
			(xy 108.236014 -275.190057) (xy 108.189998 -275.172605) (xy 108.147377 -275.147998) (xy 108.109256 -275.116873)
			(xy 108.076621 -275.080036) (xy 108.050318 -275.03844) (xy 108.031027 -274.993164) (xy 108.01925 -274.94538)
			(xy 108.01529 -274.896326) (xy 107.686348 -274.896326) (xy 107.685853 -274.920933) (xy 107.677958 -274.96951)
			(xy 107.662374 -275.016191) (xy 107.639503 -275.059768) (xy 107.609938 -275.099112) (xy 107.574445 -275.133204)
			(xy 107.533942 -275.16116) (xy 107.48948 -275.182258) (xy 107.442209 -275.19595) (xy 107.393354 -275.201882)
			(xy 107.344179 -275.199901) (xy 107.29596 -275.190057) (xy 107.249944 -275.172605) (xy 107.207323 -275.147998)
			(xy 107.169202 -275.116873) (xy 107.136567 -275.080036) (xy 107.110264 -275.03844) (xy 107.090973 -274.993164)
			(xy 107.079196 -274.94538) (xy 107.075236 -274.896326) (xy 106.746294 -274.896326) (xy 106.745799 -274.920933)
			(xy 106.737904 -274.96951) (xy 106.72232 -275.016191) (xy 106.699449 -275.059768) (xy 106.669884 -275.099112)
			(xy 106.634391 -275.133204) (xy 106.593888 -275.16116) (xy 106.549426 -275.182258) (xy 106.502155 -275.19595)
			(xy 106.4533 -275.201882) (xy 106.404125 -275.199901) (xy 106.355906 -275.190057) (xy 106.30989 -275.172605)
			(xy 106.267269 -275.147998) (xy 106.229148 -275.116873) (xy 106.196513 -275.080036) (xy 106.17021 -275.03844)
			(xy 106.150919 -274.993164) (xy 106.139142 -274.94538) (xy 106.135182 -274.896326) (xy 105.80624 -274.896326)
			(xy 105.805745 -274.920933) (xy 105.79785 -274.96951) (xy 105.782266 -275.016191) (xy 105.759395 -275.059768)
			(xy 105.72983 -275.099112) (xy 105.694337 -275.133204) (xy 105.653834 -275.16116) (xy 105.609372 -275.182258)
			(xy 105.562101 -275.19595) (xy 105.513246 -275.201882) (xy 105.464071 -275.199901) (xy 105.415852 -275.190057)
			(xy 105.369836 -275.172605) (xy 105.327215 -275.147998) (xy 105.289094 -275.116873) (xy 105.256459 -275.080036)
			(xy 105.230156 -275.03844) (xy 105.210865 -274.993164) (xy 105.199088 -274.94538) (xy 105.195128 -274.896326)
			(xy 104.86644 -274.896326) (xy 104.865945 -274.920933) (xy 104.85805 -274.96951) (xy 104.842466 -275.016191)
			(xy 104.819595 -275.059768) (xy 104.79003 -275.099112) (xy 104.754537 -275.133204) (xy 104.714034 -275.16116)
			(xy 104.669572 -275.182258) (xy 104.622301 -275.19595) (xy 104.573446 -275.201882) (xy 104.524271 -275.199901)
			(xy 104.476052 -275.190057) (xy 104.430036 -275.172605) (xy 104.387415 -275.147998) (xy 104.349294 -275.116873)
			(xy 104.316659 -275.080036) (xy 104.290356 -275.03844) (xy 104.271065 -274.993164) (xy 104.259288 -274.94538)
			(xy 104.255328 -274.896326) (xy 103.926386 -274.896326) (xy 103.925891 -274.920933) (xy 103.917996 -274.96951)
			(xy 103.902412 -275.016191) (xy 103.879541 -275.059768) (xy 103.849976 -275.099112) (xy 103.814483 -275.133204)
			(xy 103.77398 -275.16116) (xy 103.729518 -275.182258) (xy 103.682247 -275.19595) (xy 103.633392 -275.201882)
			(xy 103.584217 -275.199901) (xy 103.535998 -275.190057) (xy 103.489982 -275.172605) (xy 103.447361 -275.147998)
			(xy 103.40924 -275.116873) (xy 103.376605 -275.080036) (xy 103.350302 -275.03844) (xy 103.331011 -274.993164)
			(xy 103.319234 -274.94538) (xy 103.315274 -274.896326) (xy 102.986332 -274.896326) (xy 102.985837 -274.920933)
			(xy 102.977942 -274.96951) (xy 102.962358 -275.016191) (xy 102.939487 -275.059768) (xy 102.909922 -275.099112)
			(xy 102.874429 -275.133204) (xy 102.833926 -275.16116) (xy 102.789464 -275.182258) (xy 102.742193 -275.19595)
			(xy 102.693338 -275.201882) (xy 102.644163 -275.199901) (xy 102.595944 -275.190057) (xy 102.549928 -275.172605)
			(xy 102.507307 -275.147998) (xy 102.469186 -275.116873) (xy 102.436551 -275.080036) (xy 102.410248 -275.03844)
			(xy 102.390957 -274.993164) (xy 102.37918 -274.94538) (xy 102.37522 -274.896326) (xy 102.046278 -274.896326)
			(xy 102.045783 -274.920933) (xy 102.037888 -274.96951) (xy 102.022304 -275.016191) (xy 101.999433 -275.059768)
			(xy 101.969868 -275.099112) (xy 101.934375 -275.133204) (xy 101.893872 -275.16116) (xy 101.84941 -275.182258)
			(xy 101.802139 -275.19595) (xy 101.753284 -275.201882) (xy 101.704109 -275.199901) (xy 101.65589 -275.190057)
			(xy 101.609874 -275.172605) (xy 101.567253 -275.147998) (xy 101.529132 -275.116873) (xy 101.496497 -275.080036)
			(xy 101.470194 -275.03844) (xy 101.450903 -274.993164) (xy 101.439126 -274.94538) (xy 101.435166 -274.896326)
			(xy 101.106478 -274.896326) (xy 101.105983 -274.920933) (xy 101.098088 -274.96951) (xy 101.082504 -275.016191)
			(xy 101.059633 -275.059768) (xy 101.030068 -275.099112) (xy 100.994575 -275.133204) (xy 100.954072 -275.16116)
			(xy 100.90961 -275.182258) (xy 100.862339 -275.19595) (xy 100.813484 -275.201882) (xy 100.764309 -275.199901)
			(xy 100.71609 -275.190057) (xy 100.670074 -275.172605) (xy 100.627453 -275.147998) (xy 100.589332 -275.116873)
			(xy 100.556697 -275.080036) (xy 100.530394 -275.03844) (xy 100.511103 -274.993164) (xy 100.499326 -274.94538)
			(xy 100.495366 -274.896326) (xy 100.166424 -274.896326) (xy 100.165929 -274.920933) (xy 100.158034 -274.96951)
			(xy 100.14245 -275.016191) (xy 100.119579 -275.059768) (xy 100.090014 -275.099112) (xy 100.054521 -275.133204)
			(xy 100.014018 -275.16116) (xy 99.969556 -275.182258) (xy 99.922285 -275.19595) (xy 99.87343 -275.201882)
			(xy 99.824255 -275.199901) (xy 99.776036 -275.190057) (xy 99.73002 -275.172605) (xy 99.687399 -275.147998)
			(xy 99.649278 -275.116873) (xy 99.616643 -275.080036) (xy 99.59034 -275.03844) (xy 99.571049 -274.993164)
			(xy 99.559272 -274.94538) (xy 99.555312 -274.896326) (xy 99.22637 -274.896326) (xy 99.225875 -274.920933)
			(xy 99.21798 -274.96951) (xy 99.202396 -275.016191) (xy 99.179525 -275.059768) (xy 99.14996 -275.099112)
			(xy 99.114467 -275.133204) (xy 99.073964 -275.16116) (xy 99.029502 -275.182258) (xy 98.982231 -275.19595)
			(xy 98.933376 -275.201882) (xy 98.884201 -275.199901) (xy 98.835982 -275.190057) (xy 98.789966 -275.172605)
			(xy 98.747345 -275.147998) (xy 98.709224 -275.116873) (xy 98.676589 -275.080036) (xy 98.650286 -275.03844)
			(xy 98.630995 -274.993164) (xy 98.619218 -274.94538) (xy 98.615258 -274.896326) (xy 98.286316 -274.896326)
			(xy 98.285821 -274.920933) (xy 98.277926 -274.96951) (xy 98.262342 -275.016191) (xy 98.239471 -275.059768)
			(xy 98.209906 -275.099112) (xy 98.174413 -275.133204) (xy 98.13391 -275.16116) (xy 98.089448 -275.182258)
			(xy 98.042177 -275.19595) (xy 97.993322 -275.201882) (xy 97.944147 -275.199901) (xy 97.895928 -275.190057)
			(xy 97.849912 -275.172605) (xy 97.807291 -275.147998) (xy 97.76917 -275.116873) (xy 97.736535 -275.080036)
			(xy 97.710232 -275.03844) (xy 97.690941 -274.993164) (xy 97.679164 -274.94538) (xy 97.675204 -274.896326)
			(xy 97.346516 -274.896326) (xy 97.345974 -274.922676) (xy 97.336944 -274.974596) (xy 97.319122 -275.024191)
			(xy 97.293039 -275.069984) (xy 97.276666 -275.090636) (xy 97.271332 -275.09724) (xy 97.262442 -275.121116)
			(xy 97.260922 -275.125404) (xy 97.259263 -275.134348) (xy 97.25914 -275.138896) (xy 97.25914 -275.706332)
			(xy 99.085158 -275.706332) (xy 99.089118 -275.657278) (xy 99.100895 -275.609494) (xy 99.120186 -275.564218)
			(xy 99.146489 -275.522622) (xy 99.179124 -275.485785) (xy 99.217245 -275.45466) (xy 99.259866 -275.430053)
			(xy 99.305882 -275.412601) (xy 99.354101 -275.402757) (xy 99.403276 -275.400776) (xy 99.452131 -275.406708)
			(xy 99.499402 -275.4204) (xy 99.543864 -275.441498) (xy 99.584367 -275.469454) (xy 99.61986 -275.503546)
			(xy 99.649425 -275.54289) (xy 99.672296 -275.586467) (xy 99.68788 -275.633148) (xy 99.695775 -275.681725)
			(xy 99.69627 -275.706332) (xy 101.90532 -275.706332) (xy 101.90928 -275.657278) (xy 101.921057 -275.609494)
			(xy 101.940348 -275.564218) (xy 101.966651 -275.522622) (xy 101.999286 -275.485785) (xy 102.037407 -275.45466)
			(xy 102.080028 -275.430053) (xy 102.126044 -275.412601) (xy 102.174263 -275.402757) (xy 102.223438 -275.400776)
			(xy 102.272293 -275.406708) (xy 102.319564 -275.4204) (xy 102.364026 -275.441498) (xy 102.404529 -275.469454)
			(xy 102.440022 -275.503546) (xy 102.469587 -275.54289) (xy 102.492458 -275.586467) (xy 102.508042 -275.633148)
			(xy 102.515937 -275.681725) (xy 102.516432 -275.706332) (xy 104.725228 -275.706332) (xy 104.729188 -275.657278)
			(xy 104.740965 -275.609494) (xy 104.760256 -275.564218) (xy 104.786559 -275.522622) (xy 104.819194 -275.485785)
			(xy 104.857315 -275.45466) (xy 104.899936 -275.430053) (xy 104.945952 -275.412601) (xy 104.994171 -275.402757)
			(xy 105.043346 -275.400776) (xy 105.092201 -275.406708) (xy 105.139472 -275.4204) (xy 105.183934 -275.441498)
			(xy 105.224437 -275.469454) (xy 105.25993 -275.503546) (xy 105.289495 -275.54289) (xy 105.312366 -275.586467)
			(xy 105.32795 -275.633148) (xy 105.335845 -275.681725) (xy 105.33634 -275.706332) (xy 107.545136 -275.706332)
			(xy 107.549096 -275.657278) (xy 107.560873 -275.609494) (xy 107.580164 -275.564218) (xy 107.606467 -275.522622)
			(xy 107.639102 -275.485785) (xy 107.677223 -275.45466) (xy 107.719844 -275.430053) (xy 107.76586 -275.412601)
			(xy 107.814079 -275.402757) (xy 107.863254 -275.400776) (xy 107.912109 -275.406708) (xy 107.95938 -275.4204)
			(xy 108.003842 -275.441498) (xy 108.044345 -275.469454) (xy 108.079838 -275.503546) (xy 108.109403 -275.54289)
			(xy 108.132274 -275.586467) (xy 108.147858 -275.633148) (xy 108.155753 -275.681725) (xy 108.156248 -275.706332)
			(xy 108.48519 -275.706332) (xy 108.48915 -275.657278) (xy 108.500927 -275.609494) (xy 108.520218 -275.564218)
			(xy 108.546521 -275.522622) (xy 108.579156 -275.485785) (xy 108.617277 -275.45466) (xy 108.659898 -275.430053)
			(xy 108.705914 -275.412601) (xy 108.754133 -275.402757) (xy 108.803308 -275.400776) (xy 108.852163 -275.406708)
			(xy 108.899434 -275.4204) (xy 108.943896 -275.441498) (xy 108.984399 -275.469454) (xy 109.019892 -275.503546)
			(xy 109.049457 -275.54289) (xy 109.072328 -275.586467) (xy 109.087912 -275.633148) (xy 109.095807 -275.681725)
			(xy 109.096302 -275.706332) (xy 109.425244 -275.706332) (xy 109.429204 -275.657278) (xy 109.440981 -275.609494)
			(xy 109.460272 -275.564218) (xy 109.486575 -275.522622) (xy 109.51921 -275.485785) (xy 109.557331 -275.45466)
			(xy 109.599952 -275.430053) (xy 109.645968 -275.412601) (xy 109.694187 -275.402757) (xy 109.743362 -275.400776)
			(xy 109.792217 -275.406708) (xy 109.839488 -275.4204) (xy 109.88395 -275.441498) (xy 109.924453 -275.469454)
			(xy 109.959946 -275.503546) (xy 109.989511 -275.54289) (xy 110.012382 -275.586467) (xy 110.027966 -275.633148)
			(xy 110.035861 -275.681725) (xy 110.036356 -275.706332) (xy 110.365298 -275.706332) (xy 110.369258 -275.657278)
			(xy 110.381035 -275.609494) (xy 110.400326 -275.564218) (xy 110.426629 -275.522622) (xy 110.459264 -275.485785)
			(xy 110.497385 -275.45466) (xy 110.540006 -275.430053) (xy 110.586022 -275.412601) (xy 110.634241 -275.402757)
			(xy 110.683416 -275.400776) (xy 110.732271 -275.406708) (xy 110.779542 -275.4204) (xy 110.824004 -275.441498)
			(xy 110.864507 -275.469454) (xy 110.9 -275.503546) (xy 110.929565 -275.54289) (xy 110.952436 -275.586467)
			(xy 110.96802 -275.633148) (xy 110.975915 -275.681725) (xy 110.97641 -275.706332) (xy 113.178856 -275.706332)
			(xy 113.182816 -275.657278) (xy 113.194593 -275.609494) (xy 113.213884 -275.564218) (xy 113.240187 -275.522622)
			(xy 113.272822 -275.485785) (xy 113.310943 -275.45466) (xy 113.353564 -275.430053) (xy 113.39958 -275.412601)
			(xy 113.447799 -275.402757) (xy 113.496974 -275.400776) (xy 113.545829 -275.406708) (xy 113.5931 -275.4204)
			(xy 113.637562 -275.441498) (xy 113.678065 -275.469454) (xy 113.713558 -275.503546) (xy 113.743123 -275.54289)
			(xy 113.765994 -275.586467) (xy 113.781578 -275.633148) (xy 113.789473 -275.681725) (xy 113.789968 -275.706332)
			(xy 114.11891 -275.706332) (xy 114.12287 -275.657278) (xy 114.134647 -275.609494) (xy 114.153938 -275.564218)
			(xy 114.180241 -275.522622) (xy 114.212876 -275.485785) (xy 114.250997 -275.45466) (xy 114.293618 -275.430053)
			(xy 114.339634 -275.412601) (xy 114.387853 -275.402757) (xy 114.437028 -275.400776) (xy 114.485883 -275.406708)
			(xy 114.533154 -275.4204) (xy 114.577616 -275.441498) (xy 114.618119 -275.469454) (xy 114.653612 -275.503546)
			(xy 114.683177 -275.54289) (xy 114.706048 -275.586467) (xy 114.721632 -275.633148) (xy 114.729527 -275.681725)
			(xy 114.730022 -275.706332) (xy 115.058964 -275.706332) (xy 115.062924 -275.657278) (xy 115.074701 -275.609494)
			(xy 115.093992 -275.564218) (xy 115.120295 -275.522622) (xy 115.15293 -275.485785) (xy 115.191051 -275.45466)
			(xy 115.233672 -275.430053) (xy 115.279688 -275.412601) (xy 115.327907 -275.402757) (xy 115.377082 -275.400776)
			(xy 115.425937 -275.406708) (xy 115.473208 -275.4204) (xy 115.51767 -275.441498) (xy 115.558173 -275.469454)
			(xy 115.593666 -275.503546) (xy 115.623231 -275.54289) (xy 115.646102 -275.586467) (xy 115.661686 -275.633148)
			(xy 115.669581 -275.681725) (xy 115.670076 -275.706332) (xy 115.999018 -275.706332) (xy 116.002978 -275.657278)
			(xy 116.014755 -275.609494) (xy 116.034046 -275.564218) (xy 116.060349 -275.522622) (xy 116.092984 -275.485785)
			(xy 116.131105 -275.45466) (xy 116.173726 -275.430053) (xy 116.219742 -275.412601) (xy 116.267961 -275.402757)
			(xy 116.317136 -275.400776) (xy 116.365991 -275.406708) (xy 116.413262 -275.4204) (xy 116.457724 -275.441498)
			(xy 116.498227 -275.469454) (xy 116.53372 -275.503546) (xy 116.563285 -275.54289) (xy 116.586156 -275.586467)
			(xy 116.60174 -275.633148) (xy 116.609635 -275.681725) (xy 116.61013 -275.706332) (xy 118.818926 -275.706332)
			(xy 118.822886 -275.657278) (xy 118.834663 -275.609494) (xy 118.853954 -275.564218) (xy 118.880257 -275.522622)
			(xy 118.912892 -275.485785) (xy 118.951013 -275.45466) (xy 118.993634 -275.430053) (xy 119.03965 -275.412601)
			(xy 119.087869 -275.402757) (xy 119.137044 -275.400776) (xy 119.185899 -275.406708) (xy 119.23317 -275.4204)
			(xy 119.277632 -275.441498) (xy 119.318135 -275.469454) (xy 119.353628 -275.503546) (xy 119.383193 -275.54289)
			(xy 119.406064 -275.586467) (xy 119.421648 -275.633148) (xy 119.429543 -275.681725) (xy 119.430038 -275.706332)
			(xy 121.638834 -275.706332) (xy 121.642794 -275.657278) (xy 121.654571 -275.609494) (xy 121.673862 -275.564218)
			(xy 121.700165 -275.522622) (xy 121.7328 -275.485785) (xy 121.770921 -275.45466) (xy 121.813542 -275.430053)
			(xy 121.859558 -275.412601) (xy 121.907777 -275.402757) (xy 121.956952 -275.400776) (xy 122.005807 -275.406708)
			(xy 122.053078 -275.4204) (xy 122.09754 -275.441498) (xy 122.138043 -275.469454) (xy 122.173536 -275.503546)
			(xy 122.203101 -275.54289) (xy 122.225972 -275.586467) (xy 122.241556 -275.633148) (xy 122.249451 -275.681725)
			(xy 122.249946 -275.706332) (xy 124.458996 -275.706332) (xy 124.462956 -275.657278) (xy 124.474733 -275.609494)
			(xy 124.494024 -275.564218) (xy 124.520327 -275.522622) (xy 124.552962 -275.485785) (xy 124.591083 -275.45466)
			(xy 124.633704 -275.430053) (xy 124.67972 -275.412601) (xy 124.727939 -275.402757) (xy 124.777114 -275.400776)
			(xy 124.825969 -275.406708) (xy 124.87324 -275.4204) (xy 124.917702 -275.441498) (xy 124.958205 -275.469454)
			(xy 124.993698 -275.503546) (xy 125.023263 -275.54289) (xy 125.046134 -275.586467) (xy 125.061718 -275.633148)
			(xy 125.069613 -275.681725) (xy 125.070108 -275.706332) (xy 125.069613 -275.730939) (xy 125.061718 -275.779516)
			(xy 125.046134 -275.826197) (xy 125.023263 -275.869774) (xy 124.993698 -275.909118) (xy 124.958205 -275.94321)
			(xy 124.917702 -275.971166) (xy 124.87324 -275.992264) (xy 124.825969 -276.005956) (xy 124.777114 -276.011888)
			(xy 124.727939 -276.009907) (xy 124.67972 -276.000063) (xy 124.633704 -275.982611) (xy 124.591083 -275.958004)
			(xy 124.552962 -275.926879) (xy 124.520327 -275.890042) (xy 124.494024 -275.848446) (xy 124.474733 -275.80317)
			(xy 124.462956 -275.755386) (xy 124.458996 -275.706332) (xy 122.249946 -275.706332) (xy 122.249451 -275.730939)
			(xy 122.241556 -275.779516) (xy 122.225972 -275.826197) (xy 122.203101 -275.869774) (xy 122.173536 -275.909118)
			(xy 122.138043 -275.94321) (xy 122.09754 -275.971166) (xy 122.053078 -275.992264) (xy 122.005807 -276.005956)
			(xy 121.956952 -276.011888) (xy 121.907777 -276.009907) (xy 121.859558 -276.000063) (xy 121.813542 -275.982611)
			(xy 121.770921 -275.958004) (xy 121.7328 -275.926879) (xy 121.700165 -275.890042) (xy 121.673862 -275.848446)
			(xy 121.654571 -275.80317) (xy 121.642794 -275.755386) (xy 121.638834 -275.706332) (xy 119.430038 -275.706332)
			(xy 119.429543 -275.730939) (xy 119.421648 -275.779516) (xy 119.406064 -275.826197) (xy 119.383193 -275.869774)
			(xy 119.353628 -275.909118) (xy 119.318135 -275.94321) (xy 119.277632 -275.971166) (xy 119.23317 -275.992264)
			(xy 119.185899 -276.005956) (xy 119.137044 -276.011888) (xy 119.087869 -276.009907) (xy 119.03965 -276.000063)
			(xy 118.993634 -275.982611) (xy 118.951013 -275.958004) (xy 118.912892 -275.926879) (xy 118.880257 -275.890042)
			(xy 118.853954 -275.848446) (xy 118.834663 -275.80317) (xy 118.822886 -275.755386) (xy 118.818926 -275.706332)
			(xy 116.61013 -275.706332) (xy 116.609635 -275.730939) (xy 116.60174 -275.779516) (xy 116.586156 -275.826197)
			(xy 116.563285 -275.869774) (xy 116.53372 -275.909118) (xy 116.498227 -275.94321) (xy 116.457724 -275.971166)
			(xy 116.413262 -275.992264) (xy 116.365991 -276.005956) (xy 116.317136 -276.011888) (xy 116.267961 -276.009907)
			(xy 116.219742 -276.000063) (xy 116.173726 -275.982611) (xy 116.131105 -275.958004) (xy 116.092984 -275.926879)
			(xy 116.060349 -275.890042) (xy 116.034046 -275.848446) (xy 116.014755 -275.80317) (xy 116.002978 -275.755386)
			(xy 115.999018 -275.706332) (xy 115.670076 -275.706332) (xy 115.669581 -275.730939) (xy 115.661686 -275.779516)
			(xy 115.646102 -275.826197) (xy 115.623231 -275.869774) (xy 115.593666 -275.909118) (xy 115.558173 -275.94321)
			(xy 115.51767 -275.971166) (xy 115.473208 -275.992264) (xy 115.425937 -276.005956) (xy 115.377082 -276.011888)
			(xy 115.327907 -276.009907) (xy 115.279688 -276.000063) (xy 115.233672 -275.982611) (xy 115.191051 -275.958004)
			(xy 115.15293 -275.926879) (xy 115.120295 -275.890042) (xy 115.093992 -275.848446) (xy 115.074701 -275.80317)
			(xy 115.062924 -275.755386) (xy 115.058964 -275.706332) (xy 114.730022 -275.706332) (xy 114.729527 -275.730939)
			(xy 114.721632 -275.779516) (xy 114.706048 -275.826197) (xy 114.683177 -275.869774) (xy 114.653612 -275.909118)
			(xy 114.618119 -275.94321) (xy 114.577616 -275.971166) (xy 114.533154 -275.992264) (xy 114.485883 -276.005956)
			(xy 114.437028 -276.011888) (xy 114.387853 -276.009907) (xy 114.339634 -276.000063) (xy 114.293618 -275.982611)
			(xy 114.250997 -275.958004) (xy 114.212876 -275.926879) (xy 114.180241 -275.890042) (xy 114.153938 -275.848446)
			(xy 114.134647 -275.80317) (xy 114.12287 -275.755386) (xy 114.11891 -275.706332) (xy 113.789968 -275.706332)
			(xy 113.789473 -275.730939) (xy 113.781578 -275.779516) (xy 113.765994 -275.826197) (xy 113.743123 -275.869774)
			(xy 113.713558 -275.909118) (xy 113.678065 -275.94321) (xy 113.637562 -275.971166) (xy 113.5931 -275.992264)
			(xy 113.545829 -276.005956) (xy 113.496974 -276.011888) (xy 113.447799 -276.009907) (xy 113.39958 -276.000063)
			(xy 113.353564 -275.982611) (xy 113.310943 -275.958004) (xy 113.272822 -275.926879) (xy 113.240187 -275.890042)
			(xy 113.213884 -275.848446) (xy 113.194593 -275.80317) (xy 113.182816 -275.755386) (xy 113.178856 -275.706332)
			(xy 110.97641 -275.706332) (xy 110.975915 -275.730939) (xy 110.96802 -275.779516) (xy 110.952436 -275.826197)
			(xy 110.929565 -275.869774) (xy 110.9 -275.909118) (xy 110.864507 -275.94321) (xy 110.824004 -275.971166)
			(xy 110.779542 -275.992264) (xy 110.732271 -276.005956) (xy 110.683416 -276.011888) (xy 110.634241 -276.009907)
			(xy 110.586022 -276.000063) (xy 110.540006 -275.982611) (xy 110.497385 -275.958004) (xy 110.459264 -275.926879)
			(xy 110.426629 -275.890042) (xy 110.400326 -275.848446) (xy 110.381035 -275.80317) (xy 110.369258 -275.755386)
			(xy 110.365298 -275.706332) (xy 110.036356 -275.706332) (xy 110.035861 -275.730939) (xy 110.027966 -275.779516)
			(xy 110.012382 -275.826197) (xy 109.989511 -275.869774) (xy 109.959946 -275.909118) (xy 109.924453 -275.94321)
			(xy 109.88395 -275.971166) (xy 109.839488 -275.992264) (xy 109.792217 -276.005956) (xy 109.743362 -276.011888)
			(xy 109.694187 -276.009907) (xy 109.645968 -276.000063) (xy 109.599952 -275.982611) (xy 109.557331 -275.958004)
			(xy 109.51921 -275.926879) (xy 109.486575 -275.890042) (xy 109.460272 -275.848446) (xy 109.440981 -275.80317)
			(xy 109.429204 -275.755386) (xy 109.425244 -275.706332) (xy 109.096302 -275.706332) (xy 109.095807 -275.730939)
			(xy 109.087912 -275.779516) (xy 109.072328 -275.826197) (xy 109.049457 -275.869774) (xy 109.019892 -275.909118)
			(xy 108.984399 -275.94321) (xy 108.943896 -275.971166) (xy 108.899434 -275.992264) (xy 108.852163 -276.005956)
			(xy 108.803308 -276.011888) (xy 108.754133 -276.009907) (xy 108.705914 -276.000063) (xy 108.659898 -275.982611)
			(xy 108.617277 -275.958004) (xy 108.579156 -275.926879) (xy 108.546521 -275.890042) (xy 108.520218 -275.848446)
			(xy 108.500927 -275.80317) (xy 108.48915 -275.755386) (xy 108.48519 -275.706332) (xy 108.156248 -275.706332)
			(xy 108.155753 -275.730939) (xy 108.147858 -275.779516) (xy 108.132274 -275.826197) (xy 108.109403 -275.869774)
			(xy 108.079838 -275.909118) (xy 108.044345 -275.94321) (xy 108.003842 -275.971166) (xy 107.95938 -275.992264)
			(xy 107.912109 -276.005956) (xy 107.863254 -276.011888) (xy 107.814079 -276.009907) (xy 107.76586 -276.000063)
			(xy 107.719844 -275.982611) (xy 107.677223 -275.958004) (xy 107.639102 -275.926879) (xy 107.606467 -275.890042)
			(xy 107.580164 -275.848446) (xy 107.560873 -275.80317) (xy 107.549096 -275.755386) (xy 107.545136 -275.706332)
			(xy 105.33634 -275.706332) (xy 105.335845 -275.730939) (xy 105.32795 -275.779516) (xy 105.312366 -275.826197)
			(xy 105.289495 -275.869774) (xy 105.25993 -275.909118) (xy 105.224437 -275.94321) (xy 105.183934 -275.971166)
			(xy 105.139472 -275.992264) (xy 105.092201 -276.005956) (xy 105.043346 -276.011888) (xy 104.994171 -276.009907)
			(xy 104.945952 -276.000063) (xy 104.899936 -275.982611) (xy 104.857315 -275.958004) (xy 104.819194 -275.926879)
			(xy 104.786559 -275.890042) (xy 104.760256 -275.848446) (xy 104.740965 -275.80317) (xy 104.729188 -275.755386)
			(xy 104.725228 -275.706332) (xy 102.516432 -275.706332) (xy 102.515937 -275.730939) (xy 102.508042 -275.779516)
			(xy 102.492458 -275.826197) (xy 102.469587 -275.869774) (xy 102.440022 -275.909118) (xy 102.404529 -275.94321)
			(xy 102.364026 -275.971166) (xy 102.319564 -275.992264) (xy 102.272293 -276.005956) (xy 102.223438 -276.011888)
			(xy 102.174263 -276.009907) (xy 102.126044 -276.000063) (xy 102.080028 -275.982611) (xy 102.037407 -275.958004)
			(xy 101.999286 -275.926879) (xy 101.966651 -275.890042) (xy 101.940348 -275.848446) (xy 101.921057 -275.80317)
			(xy 101.90928 -275.755386) (xy 101.90532 -275.706332) (xy 99.69627 -275.706332) (xy 99.695775 -275.730939)
			(xy 99.68788 -275.779516) (xy 99.672296 -275.826197) (xy 99.649425 -275.869774) (xy 99.61986 -275.909118)
			(xy 99.584367 -275.94321) (xy 99.543864 -275.971166) (xy 99.499402 -275.992264) (xy 99.452131 -276.005956)
			(xy 99.403276 -276.011888) (xy 99.354101 -276.009907) (xy 99.305882 -276.000063) (xy 99.259866 -275.982611)
			(xy 99.217245 -275.958004) (xy 99.179124 -275.926879) (xy 99.146489 -275.890042) (xy 99.120186 -275.848446)
			(xy 99.100895 -275.80317) (xy 99.089118 -275.755386) (xy 99.085158 -275.706332) (xy 97.25914 -275.706332)
			(xy 97.25914 -276.273768) (xy 97.259264 -276.278316) (xy 97.260925 -276.287259) (xy 97.262442 -276.291548)
			(xy 97.271332 -276.315424) (xy 97.276666 -276.322028) (xy 97.292991 -276.342711) (xy 97.319034 -276.388513)
			(xy 97.336857 -276.438095) (xy 97.345933 -276.489995) (xy 97.346516 -276.516338) (xy 97.675204 -276.516338)
			(xy 97.679164 -276.467284) (xy 97.690941 -276.4195) (xy 97.710232 -276.374224) (xy 97.736535 -276.332628)
			(xy 97.76917 -276.295791) (xy 97.807291 -276.264666) (xy 97.849912 -276.240059) (xy 97.895928 -276.222607)
			(xy 97.944147 -276.212763) (xy 97.993322 -276.210782) (xy 98.042177 -276.216714) (xy 98.089448 -276.230406)
			(xy 98.13391 -276.251504) (xy 98.174413 -276.27946) (xy 98.209906 -276.313552) (xy 98.239471 -276.352896)
			(xy 98.262342 -276.396473) (xy 98.277926 -276.443154) (xy 98.285821 -276.491731) (xy 98.286316 -276.516338)
			(xy 98.615258 -276.516338) (xy 98.619218 -276.467284) (xy 98.630995 -276.4195) (xy 98.650286 -276.374224)
			(xy 98.676589 -276.332628) (xy 98.709224 -276.295791) (xy 98.747345 -276.264666) (xy 98.789966 -276.240059)
			(xy 98.835982 -276.222607) (xy 98.884201 -276.212763) (xy 98.933376 -276.210782) (xy 98.982231 -276.216714)
			(xy 99.029502 -276.230406) (xy 99.073964 -276.251504) (xy 99.114467 -276.27946) (xy 99.14996 -276.313552)
			(xy 99.179525 -276.352896) (xy 99.202396 -276.396473) (xy 99.21798 -276.443154) (xy 99.225875 -276.491731)
			(xy 99.22637 -276.516338) (xy 99.555312 -276.516338) (xy 99.559272 -276.467284) (xy 99.571049 -276.4195)
			(xy 99.59034 -276.374224) (xy 99.616643 -276.332628) (xy 99.649278 -276.295791) (xy 99.687399 -276.264666)
			(xy 99.73002 -276.240059) (xy 99.776036 -276.222607) (xy 99.824255 -276.212763) (xy 99.87343 -276.210782)
			(xy 99.922285 -276.216714) (xy 99.969556 -276.230406) (xy 100.014018 -276.251504) (xy 100.054521 -276.27946)
			(xy 100.090014 -276.313552) (xy 100.119579 -276.352896) (xy 100.14245 -276.396473) (xy 100.158034 -276.443154)
			(xy 100.165929 -276.491731) (xy 100.166424 -276.516338) (xy 100.495366 -276.516338) (xy 100.499326 -276.467284)
			(xy 100.511103 -276.4195) (xy 100.530394 -276.374224) (xy 100.556697 -276.332628) (xy 100.589332 -276.295791)
			(xy 100.627453 -276.264666) (xy 100.670074 -276.240059) (xy 100.71609 -276.222607) (xy 100.764309 -276.212763)
			(xy 100.813484 -276.210782) (xy 100.862339 -276.216714) (xy 100.90961 -276.230406) (xy 100.954072 -276.251504)
			(xy 100.994575 -276.27946) (xy 101.030068 -276.313552) (xy 101.059633 -276.352896) (xy 101.082504 -276.396473)
			(xy 101.098088 -276.443154) (xy 101.105983 -276.491731) (xy 101.106478 -276.516338) (xy 101.435166 -276.516338)
			(xy 101.439126 -276.467284) (xy 101.450903 -276.4195) (xy 101.470194 -276.374224) (xy 101.496497 -276.332628)
			(xy 101.529132 -276.295791) (xy 101.567253 -276.264666) (xy 101.609874 -276.240059) (xy 101.65589 -276.222607)
			(xy 101.704109 -276.212763) (xy 101.753284 -276.210782) (xy 101.802139 -276.216714) (xy 101.84941 -276.230406)
			(xy 101.893872 -276.251504) (xy 101.934375 -276.27946) (xy 101.969868 -276.313552) (xy 101.999433 -276.352896)
			(xy 102.022304 -276.396473) (xy 102.037888 -276.443154) (xy 102.045783 -276.491731) (xy 102.046278 -276.516338)
			(xy 102.37522 -276.516338) (xy 102.37918 -276.467284) (xy 102.390957 -276.4195) (xy 102.410248 -276.374224)
			(xy 102.436551 -276.332628) (xy 102.469186 -276.295791) (xy 102.507307 -276.264666) (xy 102.549928 -276.240059)
			(xy 102.595944 -276.222607) (xy 102.644163 -276.212763) (xy 102.693338 -276.210782) (xy 102.742193 -276.216714)
			(xy 102.789464 -276.230406) (xy 102.833926 -276.251504) (xy 102.874429 -276.27946) (xy 102.909922 -276.313552)
			(xy 102.939487 -276.352896) (xy 102.962358 -276.396473) (xy 102.977942 -276.443154) (xy 102.985837 -276.491731)
			(xy 102.986332 -276.516338) (xy 103.315274 -276.516338) (xy 103.319234 -276.467284) (xy 103.331011 -276.4195)
			(xy 103.350302 -276.374224) (xy 103.376605 -276.332628) (xy 103.40924 -276.295791) (xy 103.447361 -276.264666)
			(xy 103.489982 -276.240059) (xy 103.535998 -276.222607) (xy 103.584217 -276.212763) (xy 103.633392 -276.210782)
			(xy 103.682247 -276.216714) (xy 103.729518 -276.230406) (xy 103.77398 -276.251504) (xy 103.814483 -276.27946)
			(xy 103.849976 -276.313552) (xy 103.879541 -276.352896) (xy 103.902412 -276.396473) (xy 103.917996 -276.443154)
			(xy 103.925891 -276.491731) (xy 103.926386 -276.516338) (xy 104.255328 -276.516338) (xy 104.259288 -276.467284)
			(xy 104.271065 -276.4195) (xy 104.290356 -276.374224) (xy 104.316659 -276.332628) (xy 104.349294 -276.295791)
			(xy 104.387415 -276.264666) (xy 104.430036 -276.240059) (xy 104.476052 -276.222607) (xy 104.524271 -276.212763)
			(xy 104.573446 -276.210782) (xy 104.622301 -276.216714) (xy 104.669572 -276.230406) (xy 104.714034 -276.251504)
			(xy 104.754537 -276.27946) (xy 104.79003 -276.313552) (xy 104.819595 -276.352896) (xy 104.842466 -276.396473)
			(xy 104.85805 -276.443154) (xy 104.865945 -276.491731) (xy 104.86644 -276.516338) (xy 105.195128 -276.516338)
			(xy 105.199088 -276.467284) (xy 105.210865 -276.4195) (xy 105.230156 -276.374224) (xy 105.256459 -276.332628)
			(xy 105.289094 -276.295791) (xy 105.327215 -276.264666) (xy 105.369836 -276.240059) (xy 105.415852 -276.222607)
			(xy 105.464071 -276.212763) (xy 105.513246 -276.210782) (xy 105.562101 -276.216714) (xy 105.609372 -276.230406)
			(xy 105.653834 -276.251504) (xy 105.694337 -276.27946) (xy 105.72983 -276.313552) (xy 105.759395 -276.352896)
			(xy 105.782266 -276.396473) (xy 105.79785 -276.443154) (xy 105.805745 -276.491731) (xy 105.80624 -276.516338)
			(xy 106.135182 -276.516338) (xy 106.139142 -276.467284) (xy 106.150919 -276.4195) (xy 106.17021 -276.374224)
			(xy 106.196513 -276.332628) (xy 106.229148 -276.295791) (xy 106.267269 -276.264666) (xy 106.30989 -276.240059)
			(xy 106.355906 -276.222607) (xy 106.404125 -276.212763) (xy 106.4533 -276.210782) (xy 106.502155 -276.216714)
			(xy 106.549426 -276.230406) (xy 106.593888 -276.251504) (xy 106.634391 -276.27946) (xy 106.669884 -276.313552)
			(xy 106.699449 -276.352896) (xy 106.72232 -276.396473) (xy 106.737904 -276.443154) (xy 106.745799 -276.491731)
			(xy 106.746294 -276.516338) (xy 107.075236 -276.516338) (xy 107.079196 -276.467284) (xy 107.090973 -276.4195)
			(xy 107.110264 -276.374224) (xy 107.136567 -276.332628) (xy 107.169202 -276.295791) (xy 107.207323 -276.264666)
			(xy 107.249944 -276.240059) (xy 107.29596 -276.222607) (xy 107.344179 -276.212763) (xy 107.393354 -276.210782)
			(xy 107.442209 -276.216714) (xy 107.48948 -276.230406) (xy 107.533942 -276.251504) (xy 107.574445 -276.27946)
			(xy 107.609938 -276.313552) (xy 107.639503 -276.352896) (xy 107.662374 -276.396473) (xy 107.677958 -276.443154)
			(xy 107.685853 -276.491731) (xy 107.686348 -276.516338) (xy 108.01529 -276.516338) (xy 108.01925 -276.467284)
			(xy 108.031027 -276.4195) (xy 108.050318 -276.374224) (xy 108.076621 -276.332628) (xy 108.109256 -276.295791)
			(xy 108.147377 -276.264666) (xy 108.189998 -276.240059) (xy 108.236014 -276.222607) (xy 108.284233 -276.212763)
			(xy 108.333408 -276.210782) (xy 108.382263 -276.216714) (xy 108.429534 -276.230406) (xy 108.473996 -276.251504)
			(xy 108.514499 -276.27946) (xy 108.549992 -276.313552) (xy 108.579557 -276.352896) (xy 108.602428 -276.396473)
			(xy 108.618012 -276.443154) (xy 108.625907 -276.491731) (xy 108.626402 -276.516338) (xy 108.955344 -276.516338)
			(xy 108.959304 -276.467284) (xy 108.971081 -276.4195) (xy 108.990372 -276.374224) (xy 109.016675 -276.332628)
			(xy 109.04931 -276.295791) (xy 109.087431 -276.264666) (xy 109.130052 -276.240059) (xy 109.176068 -276.222607)
			(xy 109.224287 -276.212763) (xy 109.273462 -276.210782) (xy 109.322317 -276.216714) (xy 109.369588 -276.230406)
			(xy 109.41405 -276.251504) (xy 109.454553 -276.27946) (xy 109.490046 -276.313552) (xy 109.519611 -276.352896)
			(xy 109.542482 -276.396473) (xy 109.558066 -276.443154) (xy 109.565961 -276.491731) (xy 109.566456 -276.516338)
			(xy 109.895144 -276.516338) (xy 109.899104 -276.467284) (xy 109.910881 -276.4195) (xy 109.930172 -276.374224)
			(xy 109.956475 -276.332628) (xy 109.98911 -276.295791) (xy 110.027231 -276.264666) (xy 110.069852 -276.240059)
			(xy 110.115868 -276.222607) (xy 110.164087 -276.212763) (xy 110.213262 -276.210782) (xy 110.262117 -276.216714)
			(xy 110.309388 -276.230406) (xy 110.35385 -276.251504) (xy 110.394353 -276.27946) (xy 110.429846 -276.313552)
			(xy 110.459411 -276.352896) (xy 110.482282 -276.396473) (xy 110.497866 -276.443154) (xy 110.505761 -276.491731)
			(xy 110.506256 -276.516338) (xy 113.64901 -276.516338) (xy 113.65297 -276.467284) (xy 113.664747 -276.4195)
			(xy 113.684038 -276.374224) (xy 113.710341 -276.332628) (xy 113.742976 -276.295791) (xy 113.781097 -276.264666)
			(xy 113.823718 -276.240059) (xy 113.869734 -276.222607) (xy 113.917953 -276.212763) (xy 113.967128 -276.210782)
			(xy 114.015983 -276.216714) (xy 114.063254 -276.230406) (xy 114.107716 -276.251504) (xy 114.148219 -276.27946)
			(xy 114.183712 -276.313552) (xy 114.213277 -276.352896) (xy 114.236148 -276.396473) (xy 114.251732 -276.443154)
			(xy 114.259627 -276.491731) (xy 114.260122 -276.516338) (xy 114.58881 -276.516338) (xy 114.59277 -276.467284)
			(xy 114.604547 -276.4195) (xy 114.623838 -276.374224) (xy 114.650141 -276.332628) (xy 114.682776 -276.295791)
			(xy 114.720897 -276.264666) (xy 114.763518 -276.240059) (xy 114.809534 -276.222607) (xy 114.857753 -276.212763)
			(xy 114.906928 -276.210782) (xy 114.955783 -276.216714) (xy 115.003054 -276.230406) (xy 115.047516 -276.251504)
			(xy 115.088019 -276.27946) (xy 115.123512 -276.313552) (xy 115.153077 -276.352896) (xy 115.175948 -276.396473)
			(xy 115.191532 -276.443154) (xy 115.199427 -276.491731) (xy 115.199922 -276.516338) (xy 115.528864 -276.516338)
			(xy 115.532824 -276.467284) (xy 115.544601 -276.4195) (xy 115.563892 -276.374224) (xy 115.590195 -276.332628)
			(xy 115.62283 -276.295791) (xy 115.660951 -276.264666) (xy 115.703572 -276.240059) (xy 115.749588 -276.222607)
			(xy 115.797807 -276.212763) (xy 115.846982 -276.210782) (xy 115.895837 -276.216714) (xy 115.943108 -276.230406)
			(xy 115.98757 -276.251504) (xy 116.028073 -276.27946) (xy 116.063566 -276.313552) (xy 116.093131 -276.352896)
			(xy 116.116002 -276.396473) (xy 116.131586 -276.443154) (xy 116.139481 -276.491731) (xy 116.139976 -276.516338)
			(xy 116.468918 -276.516338) (xy 116.472878 -276.467284) (xy 116.484655 -276.4195) (xy 116.503946 -276.374224)
			(xy 116.530249 -276.332628) (xy 116.562884 -276.295791) (xy 116.601005 -276.264666) (xy 116.643626 -276.240059)
			(xy 116.689642 -276.222607) (xy 116.737861 -276.212763) (xy 116.787036 -276.210782) (xy 116.835891 -276.216714)
			(xy 116.883162 -276.230406) (xy 116.927624 -276.251504) (xy 116.968127 -276.27946) (xy 117.00362 -276.313552)
			(xy 117.033185 -276.352896) (xy 117.056056 -276.396473) (xy 117.07164 -276.443154) (xy 117.079535 -276.491731)
			(xy 117.08003 -276.516338) (xy 117.408972 -276.516338) (xy 117.412932 -276.467284) (xy 117.424709 -276.4195)
			(xy 117.444 -276.374224) (xy 117.470303 -276.332628) (xy 117.502938 -276.295791) (xy 117.541059 -276.264666)
			(xy 117.58368 -276.240059) (xy 117.629696 -276.222607) (xy 117.677915 -276.212763) (xy 117.72709 -276.210782)
			(xy 117.775945 -276.216714) (xy 117.823216 -276.230406) (xy 117.867678 -276.251504) (xy 117.908181 -276.27946)
			(xy 117.943674 -276.313552) (xy 117.973239 -276.352896) (xy 117.99611 -276.396473) (xy 118.011694 -276.443154)
			(xy 118.019589 -276.491731) (xy 118.020084 -276.516338) (xy 118.349026 -276.516338) (xy 118.352986 -276.467284)
			(xy 118.364763 -276.4195) (xy 118.384054 -276.374224) (xy 118.410357 -276.332628) (xy 118.442992 -276.295791)
			(xy 118.481113 -276.264666) (xy 118.523734 -276.240059) (xy 118.56975 -276.222607) (xy 118.617969 -276.212763)
			(xy 118.667144 -276.210782) (xy 118.715999 -276.216714) (xy 118.76327 -276.230406) (xy 118.807732 -276.251504)
			(xy 118.848235 -276.27946) (xy 118.883728 -276.313552) (xy 118.913293 -276.352896) (xy 118.936164 -276.396473)
			(xy 118.951748 -276.443154) (xy 118.959643 -276.491731) (xy 118.960138 -276.516338) (xy 119.288826 -276.516338)
			(xy 119.292786 -276.467284) (xy 119.304563 -276.4195) (xy 119.323854 -276.374224) (xy 119.350157 -276.332628)
			(xy 119.382792 -276.295791) (xy 119.420913 -276.264666) (xy 119.463534 -276.240059) (xy 119.50955 -276.222607)
			(xy 119.557769 -276.212763) (xy 119.606944 -276.210782) (xy 119.655799 -276.216714) (xy 119.70307 -276.230406)
			(xy 119.747532 -276.251504) (xy 119.788035 -276.27946) (xy 119.823528 -276.313552) (xy 119.853093 -276.352896)
			(xy 119.875964 -276.396473) (xy 119.891548 -276.443154) (xy 119.899443 -276.491731) (xy 119.899938 -276.516338)
			(xy 120.22888 -276.516338) (xy 120.23284 -276.467284) (xy 120.244617 -276.4195) (xy 120.263908 -276.374224)
			(xy 120.290211 -276.332628) (xy 120.322846 -276.295791) (xy 120.360967 -276.264666) (xy 120.403588 -276.240059)
			(xy 120.449604 -276.222607) (xy 120.497823 -276.212763) (xy 120.546998 -276.210782) (xy 120.595853 -276.216714)
			(xy 120.643124 -276.230406) (xy 120.687586 -276.251504) (xy 120.728089 -276.27946) (xy 120.763582 -276.313552)
			(xy 120.793147 -276.352896) (xy 120.816018 -276.396473) (xy 120.831602 -276.443154) (xy 120.839497 -276.491731)
			(xy 120.839992 -276.516338) (xy 121.168934 -276.516338) (xy 121.172894 -276.467284) (xy 121.184671 -276.4195)
			(xy 121.203962 -276.374224) (xy 121.230265 -276.332628) (xy 121.2629 -276.295791) (xy 121.301021 -276.264666)
			(xy 121.343642 -276.240059) (xy 121.389658 -276.222607) (xy 121.437877 -276.212763) (xy 121.487052 -276.210782)
			(xy 121.535907 -276.216714) (xy 121.583178 -276.230406) (xy 121.62764 -276.251504) (xy 121.668143 -276.27946)
			(xy 121.703636 -276.313552) (xy 121.733201 -276.352896) (xy 121.756072 -276.396473) (xy 121.771656 -276.443154)
			(xy 121.779551 -276.491731) (xy 121.780046 -276.516338) (xy 122.108988 -276.516338) (xy 122.112948 -276.467284)
			(xy 122.124725 -276.4195) (xy 122.144016 -276.374224) (xy 122.170319 -276.332628) (xy 122.202954 -276.295791)
			(xy 122.241075 -276.264666) (xy 122.283696 -276.240059) (xy 122.329712 -276.222607) (xy 122.377931 -276.212763)
			(xy 122.427106 -276.210782) (xy 122.475961 -276.216714) (xy 122.523232 -276.230406) (xy 122.567694 -276.251504)
			(xy 122.608197 -276.27946) (xy 122.64369 -276.313552) (xy 122.673255 -276.352896) (xy 122.696126 -276.396473)
			(xy 122.71171 -276.443154) (xy 122.719605 -276.491731) (xy 122.7201 -276.516338) (xy 123.049042 -276.516338)
			(xy 123.053002 -276.467284) (xy 123.064779 -276.4195) (xy 123.08407 -276.374224) (xy 123.110373 -276.332628)
			(xy 123.143008 -276.295791) (xy 123.181129 -276.264666) (xy 123.22375 -276.240059) (xy 123.269766 -276.222607)
			(xy 123.317985 -276.212763) (xy 123.36716 -276.210782) (xy 123.416015 -276.216714) (xy 123.463286 -276.230406)
			(xy 123.507748 -276.251504) (xy 123.548251 -276.27946) (xy 123.583744 -276.313552) (xy 123.613309 -276.352896)
			(xy 123.63618 -276.396473) (xy 123.651764 -276.443154) (xy 123.659659 -276.491731) (xy 123.660154 -276.516338)
			(xy 123.988842 -276.516338) (xy 123.992802 -276.467284) (xy 124.004579 -276.4195) (xy 124.02387 -276.374224)
			(xy 124.050173 -276.332628) (xy 124.082808 -276.295791) (xy 124.120929 -276.264666) (xy 124.16355 -276.240059)
			(xy 124.209566 -276.222607) (xy 124.257785 -276.212763) (xy 124.30696 -276.210782) (xy 124.355815 -276.216714)
			(xy 124.403086 -276.230406) (xy 124.447548 -276.251504) (xy 124.488051 -276.27946) (xy 124.523544 -276.313552)
			(xy 124.553109 -276.352896) (xy 124.57598 -276.396473) (xy 124.591564 -276.443154) (xy 124.599459 -276.491731)
			(xy 124.599954 -276.516338) (xy 124.928896 -276.516338) (xy 124.932856 -276.467284) (xy 124.944633 -276.4195)
			(xy 124.963924 -276.374224) (xy 124.990227 -276.332628) (xy 125.022862 -276.295791) (xy 125.060983 -276.264666)
			(xy 125.103604 -276.240059) (xy 125.14962 -276.222607) (xy 125.197839 -276.212763) (xy 125.247014 -276.210782)
			(xy 125.295869 -276.216714) (xy 125.34314 -276.230406) (xy 125.387602 -276.251504) (xy 125.428105 -276.27946)
			(xy 125.463598 -276.313552) (xy 125.493163 -276.352896) (xy 125.516034 -276.396473) (xy 125.531618 -276.443154)
			(xy 125.539513 -276.491731) (xy 125.540008 -276.516338) (xy 125.86895 -276.516338) (xy 125.87291 -276.467284)
			(xy 125.884687 -276.4195) (xy 125.903978 -276.374224) (xy 125.930281 -276.332628) (xy 125.962916 -276.295791)
			(xy 126.001037 -276.264666) (xy 126.043658 -276.240059) (xy 126.089674 -276.222607) (xy 126.137893 -276.212763)
			(xy 126.187068 -276.210782) (xy 126.235923 -276.216714) (xy 126.283194 -276.230406) (xy 126.327656 -276.251504)
			(xy 126.368159 -276.27946) (xy 126.403652 -276.313552) (xy 126.433217 -276.352896) (xy 126.456088 -276.396473)
			(xy 126.471672 -276.443154) (xy 126.479567 -276.491731) (xy 126.480062 -276.516338) (xy 126.479567 -276.540945)
			(xy 126.471672 -276.589522) (xy 126.456088 -276.636203) (xy 126.433217 -276.67978) (xy 126.403652 -276.719124)
			(xy 126.368159 -276.753216) (xy 126.327656 -276.781172) (xy 126.283194 -276.80227) (xy 126.235923 -276.815962)
			(xy 126.187068 -276.821894) (xy 126.137893 -276.819913) (xy 126.089674 -276.810069) (xy 126.043658 -276.792617)
			(xy 126.001037 -276.76801) (xy 125.962916 -276.736885) (xy 125.930281 -276.700048) (xy 125.903978 -276.658452)
			(xy 125.884687 -276.613176) (xy 125.87291 -276.565392) (xy 125.86895 -276.516338) (xy 125.540008 -276.516338)
			(xy 125.539513 -276.540945) (xy 125.531618 -276.589522) (xy 125.516034 -276.636203) (xy 125.493163 -276.67978)
			(xy 125.463598 -276.719124) (xy 125.428105 -276.753216) (xy 125.387602 -276.781172) (xy 125.34314 -276.80227)
			(xy 125.295869 -276.815962) (xy 125.247014 -276.821894) (xy 125.197839 -276.819913) (xy 125.14962 -276.810069)
			(xy 125.103604 -276.792617) (xy 125.060983 -276.76801) (xy 125.022862 -276.736885) (xy 124.990227 -276.700048)
			(xy 124.963924 -276.658452) (xy 124.944633 -276.613176) (xy 124.932856 -276.565392) (xy 124.928896 -276.516338)
			(xy 124.599954 -276.516338) (xy 124.599459 -276.540945) (xy 124.591564 -276.589522) (xy 124.57598 -276.636203)
			(xy 124.553109 -276.67978) (xy 124.523544 -276.719124) (xy 124.488051 -276.753216) (xy 124.447548 -276.781172)
			(xy 124.403086 -276.80227) (xy 124.355815 -276.815962) (xy 124.30696 -276.821894) (xy 124.257785 -276.819913)
			(xy 124.209566 -276.810069) (xy 124.16355 -276.792617) (xy 124.120929 -276.76801) (xy 124.082808 -276.736885)
			(xy 124.050173 -276.700048) (xy 124.02387 -276.658452) (xy 124.004579 -276.613176) (xy 123.992802 -276.565392)
			(xy 123.988842 -276.516338) (xy 123.660154 -276.516338) (xy 123.659659 -276.540945) (xy 123.651764 -276.589522)
			(xy 123.63618 -276.636203) (xy 123.613309 -276.67978) (xy 123.583744 -276.719124) (xy 123.548251 -276.753216)
			(xy 123.507748 -276.781172) (xy 123.463286 -276.80227) (xy 123.416015 -276.815962) (xy 123.36716 -276.821894)
			(xy 123.317985 -276.819913) (xy 123.269766 -276.810069) (xy 123.22375 -276.792617) (xy 123.181129 -276.76801)
			(xy 123.143008 -276.736885) (xy 123.110373 -276.700048) (xy 123.08407 -276.658452) (xy 123.064779 -276.613176)
			(xy 123.053002 -276.565392) (xy 123.049042 -276.516338) (xy 122.7201 -276.516338) (xy 122.719605 -276.540945)
			(xy 122.71171 -276.589522) (xy 122.696126 -276.636203) (xy 122.673255 -276.67978) (xy 122.64369 -276.719124)
			(xy 122.608197 -276.753216) (xy 122.567694 -276.781172) (xy 122.523232 -276.80227) (xy 122.475961 -276.815962)
			(xy 122.427106 -276.821894) (xy 122.377931 -276.819913) (xy 122.329712 -276.810069) (xy 122.283696 -276.792617)
			(xy 122.241075 -276.76801) (xy 122.202954 -276.736885) (xy 122.170319 -276.700048) (xy 122.144016 -276.658452)
			(xy 122.124725 -276.613176) (xy 122.112948 -276.565392) (xy 122.108988 -276.516338) (xy 121.780046 -276.516338)
			(xy 121.779551 -276.540945) (xy 121.771656 -276.589522) (xy 121.756072 -276.636203) (xy 121.733201 -276.67978)
			(xy 121.703636 -276.719124) (xy 121.668143 -276.753216) (xy 121.62764 -276.781172) (xy 121.583178 -276.80227)
			(xy 121.535907 -276.815962) (xy 121.487052 -276.821894) (xy 121.437877 -276.819913) (xy 121.389658 -276.810069)
			(xy 121.343642 -276.792617) (xy 121.301021 -276.76801) (xy 121.2629 -276.736885) (xy 121.230265 -276.700048)
			(xy 121.203962 -276.658452) (xy 121.184671 -276.613176) (xy 121.172894 -276.565392) (xy 121.168934 -276.516338)
			(xy 120.839992 -276.516338) (xy 120.839497 -276.540945) (xy 120.831602 -276.589522) (xy 120.816018 -276.636203)
			(xy 120.793147 -276.67978) (xy 120.763582 -276.719124) (xy 120.728089 -276.753216) (xy 120.687586 -276.781172)
			(xy 120.643124 -276.80227) (xy 120.595853 -276.815962) (xy 120.546998 -276.821894) (xy 120.497823 -276.819913)
			(xy 120.449604 -276.810069) (xy 120.403588 -276.792617) (xy 120.360967 -276.76801) (xy 120.322846 -276.736885)
			(xy 120.290211 -276.700048) (xy 120.263908 -276.658452) (xy 120.244617 -276.613176) (xy 120.23284 -276.565392)
			(xy 120.22888 -276.516338) (xy 119.899938 -276.516338) (xy 119.899443 -276.540945) (xy 119.891548 -276.589522)
			(xy 119.875964 -276.636203) (xy 119.853093 -276.67978) (xy 119.823528 -276.719124) (xy 119.788035 -276.753216)
			(xy 119.747532 -276.781172) (xy 119.70307 -276.80227) (xy 119.655799 -276.815962) (xy 119.606944 -276.821894)
			(xy 119.557769 -276.819913) (xy 119.50955 -276.810069) (xy 119.463534 -276.792617) (xy 119.420913 -276.76801)
			(xy 119.382792 -276.736885) (xy 119.350157 -276.700048) (xy 119.323854 -276.658452) (xy 119.304563 -276.613176)
			(xy 119.292786 -276.565392) (xy 119.288826 -276.516338) (xy 118.960138 -276.516338) (xy 118.959643 -276.540945)
			(xy 118.951748 -276.589522) (xy 118.936164 -276.636203) (xy 118.913293 -276.67978) (xy 118.883728 -276.719124)
			(xy 118.848235 -276.753216) (xy 118.807732 -276.781172) (xy 118.76327 -276.80227) (xy 118.715999 -276.815962)
			(xy 118.667144 -276.821894) (xy 118.617969 -276.819913) (xy 118.56975 -276.810069) (xy 118.523734 -276.792617)
			(xy 118.481113 -276.76801) (xy 118.442992 -276.736885) (xy 118.410357 -276.700048) (xy 118.384054 -276.658452)
			(xy 118.364763 -276.613176) (xy 118.352986 -276.565392) (xy 118.349026 -276.516338) (xy 118.020084 -276.516338)
			(xy 118.019589 -276.540945) (xy 118.011694 -276.589522) (xy 117.99611 -276.636203) (xy 117.973239 -276.67978)
			(xy 117.943674 -276.719124) (xy 117.908181 -276.753216) (xy 117.867678 -276.781172) (xy 117.823216 -276.80227)
			(xy 117.775945 -276.815962) (xy 117.72709 -276.821894) (xy 117.677915 -276.819913) (xy 117.629696 -276.810069)
			(xy 117.58368 -276.792617) (xy 117.541059 -276.76801) (xy 117.502938 -276.736885) (xy 117.470303 -276.700048)
			(xy 117.444 -276.658452) (xy 117.424709 -276.613176) (xy 117.412932 -276.565392) (xy 117.408972 -276.516338)
			(xy 117.08003 -276.516338) (xy 117.079535 -276.540945) (xy 117.07164 -276.589522) (xy 117.056056 -276.636203)
			(xy 117.033185 -276.67978) (xy 117.00362 -276.719124) (xy 116.968127 -276.753216) (xy 116.927624 -276.781172)
			(xy 116.883162 -276.80227) (xy 116.835891 -276.815962) (xy 116.787036 -276.821894) (xy 116.737861 -276.819913)
			(xy 116.689642 -276.810069) (xy 116.643626 -276.792617) (xy 116.601005 -276.76801) (xy 116.562884 -276.736885)
			(xy 116.530249 -276.700048) (xy 116.503946 -276.658452) (xy 116.484655 -276.613176) (xy 116.472878 -276.565392)
			(xy 116.468918 -276.516338) (xy 116.139976 -276.516338) (xy 116.139481 -276.540945) (xy 116.131586 -276.589522)
			(xy 116.116002 -276.636203) (xy 116.093131 -276.67978) (xy 116.063566 -276.719124) (xy 116.028073 -276.753216)
			(xy 115.98757 -276.781172) (xy 115.943108 -276.80227) (xy 115.895837 -276.815962) (xy 115.846982 -276.821894)
			(xy 115.797807 -276.819913) (xy 115.749588 -276.810069) (xy 115.703572 -276.792617) (xy 115.660951 -276.76801)
			(xy 115.62283 -276.736885) (xy 115.590195 -276.700048) (xy 115.563892 -276.658452) (xy 115.544601 -276.613176)
			(xy 115.532824 -276.565392) (xy 115.528864 -276.516338) (xy 115.199922 -276.516338) (xy 115.199427 -276.540945)
			(xy 115.191532 -276.589522) (xy 115.175948 -276.636203) (xy 115.153077 -276.67978) (xy 115.123512 -276.719124)
			(xy 115.088019 -276.753216) (xy 115.047516 -276.781172) (xy 115.003054 -276.80227) (xy 114.955783 -276.815962)
			(xy 114.906928 -276.821894) (xy 114.857753 -276.819913) (xy 114.809534 -276.810069) (xy 114.763518 -276.792617)
			(xy 114.720897 -276.76801) (xy 114.682776 -276.736885) (xy 114.650141 -276.700048) (xy 114.623838 -276.658452)
			(xy 114.604547 -276.613176) (xy 114.59277 -276.565392) (xy 114.58881 -276.516338) (xy 114.260122 -276.516338)
			(xy 114.259627 -276.540945) (xy 114.251732 -276.589522) (xy 114.236148 -276.636203) (xy 114.213277 -276.67978)
			(xy 114.183712 -276.719124) (xy 114.148219 -276.753216) (xy 114.107716 -276.781172) (xy 114.063254 -276.80227)
			(xy 114.015983 -276.815962) (xy 113.967128 -276.821894) (xy 113.917953 -276.819913) (xy 113.869734 -276.810069)
			(xy 113.823718 -276.792617) (xy 113.781097 -276.76801) (xy 113.742976 -276.736885) (xy 113.710341 -276.700048)
			(xy 113.684038 -276.658452) (xy 113.664747 -276.613176) (xy 113.65297 -276.565392) (xy 113.64901 -276.516338)
			(xy 110.506256 -276.516338) (xy 110.505761 -276.540945) (xy 110.497866 -276.589522) (xy 110.482282 -276.636203)
			(xy 110.459411 -276.67978) (xy 110.429846 -276.719124) (xy 110.394353 -276.753216) (xy 110.35385 -276.781172)
			(xy 110.309388 -276.80227) (xy 110.262117 -276.815962) (xy 110.213262 -276.821894) (xy 110.164087 -276.819913)
			(xy 110.115868 -276.810069) (xy 110.069852 -276.792617) (xy 110.027231 -276.76801) (xy 109.98911 -276.736885)
			(xy 109.956475 -276.700048) (xy 109.930172 -276.658452) (xy 109.910881 -276.613176) (xy 109.899104 -276.565392)
			(xy 109.895144 -276.516338) (xy 109.566456 -276.516338) (xy 109.565961 -276.540945) (xy 109.558066 -276.589522)
			(xy 109.542482 -276.636203) (xy 109.519611 -276.67978) (xy 109.490046 -276.719124) (xy 109.454553 -276.753216)
			(xy 109.41405 -276.781172) (xy 109.369588 -276.80227) (xy 109.322317 -276.815962) (xy 109.273462 -276.821894)
			(xy 109.224287 -276.819913) (xy 109.176068 -276.810069) (xy 109.130052 -276.792617) (xy 109.087431 -276.76801)
			(xy 109.04931 -276.736885) (xy 109.016675 -276.700048) (xy 108.990372 -276.658452) (xy 108.971081 -276.613176)
			(xy 108.959304 -276.565392) (xy 108.955344 -276.516338) (xy 108.626402 -276.516338) (xy 108.625907 -276.540945)
			(xy 108.618012 -276.589522) (xy 108.602428 -276.636203) (xy 108.579557 -276.67978) (xy 108.549992 -276.719124)
			(xy 108.514499 -276.753216) (xy 108.473996 -276.781172) (xy 108.429534 -276.80227) (xy 108.382263 -276.815962)
			(xy 108.333408 -276.821894) (xy 108.284233 -276.819913) (xy 108.236014 -276.810069) (xy 108.189998 -276.792617)
			(xy 108.147377 -276.76801) (xy 108.109256 -276.736885) (xy 108.076621 -276.700048) (xy 108.050318 -276.658452)
			(xy 108.031027 -276.613176) (xy 108.01925 -276.565392) (xy 108.01529 -276.516338) (xy 107.686348 -276.516338)
			(xy 107.685853 -276.540945) (xy 107.677958 -276.589522) (xy 107.662374 -276.636203) (xy 107.639503 -276.67978)
			(xy 107.609938 -276.719124) (xy 107.574445 -276.753216) (xy 107.533942 -276.781172) (xy 107.48948 -276.80227)
			(xy 107.442209 -276.815962) (xy 107.393354 -276.821894) (xy 107.344179 -276.819913) (xy 107.29596 -276.810069)
			(xy 107.249944 -276.792617) (xy 107.207323 -276.76801) (xy 107.169202 -276.736885) (xy 107.136567 -276.700048)
			(xy 107.110264 -276.658452) (xy 107.090973 -276.613176) (xy 107.079196 -276.565392) (xy 107.075236 -276.516338)
			(xy 106.746294 -276.516338) (xy 106.745799 -276.540945) (xy 106.737904 -276.589522) (xy 106.72232 -276.636203)
			(xy 106.699449 -276.67978) (xy 106.669884 -276.719124) (xy 106.634391 -276.753216) (xy 106.593888 -276.781172)
			(xy 106.549426 -276.80227) (xy 106.502155 -276.815962) (xy 106.4533 -276.821894) (xy 106.404125 -276.819913)
			(xy 106.355906 -276.810069) (xy 106.30989 -276.792617) (xy 106.267269 -276.76801) (xy 106.229148 -276.736885)
			(xy 106.196513 -276.700048) (xy 106.17021 -276.658452) (xy 106.150919 -276.613176) (xy 106.139142 -276.565392)
			(xy 106.135182 -276.516338) (xy 105.80624 -276.516338) (xy 105.805745 -276.540945) (xy 105.79785 -276.589522)
			(xy 105.782266 -276.636203) (xy 105.759395 -276.67978) (xy 105.72983 -276.719124) (xy 105.694337 -276.753216)
			(xy 105.653834 -276.781172) (xy 105.609372 -276.80227) (xy 105.562101 -276.815962) (xy 105.513246 -276.821894)
			(xy 105.464071 -276.819913) (xy 105.415852 -276.810069) (xy 105.369836 -276.792617) (xy 105.327215 -276.76801)
			(xy 105.289094 -276.736885) (xy 105.256459 -276.700048) (xy 105.230156 -276.658452) (xy 105.210865 -276.613176)
			(xy 105.199088 -276.565392) (xy 105.195128 -276.516338) (xy 104.86644 -276.516338) (xy 104.865945 -276.540945)
			(xy 104.85805 -276.589522) (xy 104.842466 -276.636203) (xy 104.819595 -276.67978) (xy 104.79003 -276.719124)
			(xy 104.754537 -276.753216) (xy 104.714034 -276.781172) (xy 104.669572 -276.80227) (xy 104.622301 -276.815962)
			(xy 104.573446 -276.821894) (xy 104.524271 -276.819913) (xy 104.476052 -276.810069) (xy 104.430036 -276.792617)
			(xy 104.387415 -276.76801) (xy 104.349294 -276.736885) (xy 104.316659 -276.700048) (xy 104.290356 -276.658452)
			(xy 104.271065 -276.613176) (xy 104.259288 -276.565392) (xy 104.255328 -276.516338) (xy 103.926386 -276.516338)
			(xy 103.925891 -276.540945) (xy 103.917996 -276.589522) (xy 103.902412 -276.636203) (xy 103.879541 -276.67978)
			(xy 103.849976 -276.719124) (xy 103.814483 -276.753216) (xy 103.77398 -276.781172) (xy 103.729518 -276.80227)
			(xy 103.682247 -276.815962) (xy 103.633392 -276.821894) (xy 103.584217 -276.819913) (xy 103.535998 -276.810069)
			(xy 103.489982 -276.792617) (xy 103.447361 -276.76801) (xy 103.40924 -276.736885) (xy 103.376605 -276.700048)
			(xy 103.350302 -276.658452) (xy 103.331011 -276.613176) (xy 103.319234 -276.565392) (xy 103.315274 -276.516338)
			(xy 102.986332 -276.516338) (xy 102.985837 -276.540945) (xy 102.977942 -276.589522) (xy 102.962358 -276.636203)
			(xy 102.939487 -276.67978) (xy 102.909922 -276.719124) (xy 102.874429 -276.753216) (xy 102.833926 -276.781172)
			(xy 102.789464 -276.80227) (xy 102.742193 -276.815962) (xy 102.693338 -276.821894) (xy 102.644163 -276.819913)
			(xy 102.595944 -276.810069) (xy 102.549928 -276.792617) (xy 102.507307 -276.76801) (xy 102.469186 -276.736885)
			(xy 102.436551 -276.700048) (xy 102.410248 -276.658452) (xy 102.390957 -276.613176) (xy 102.37918 -276.565392)
			(xy 102.37522 -276.516338) (xy 102.046278 -276.516338) (xy 102.045783 -276.540945) (xy 102.037888 -276.589522)
			(xy 102.022304 -276.636203) (xy 101.999433 -276.67978) (xy 101.969868 -276.719124) (xy 101.934375 -276.753216)
			(xy 101.893872 -276.781172) (xy 101.84941 -276.80227) (xy 101.802139 -276.815962) (xy 101.753284 -276.821894)
			(xy 101.704109 -276.819913) (xy 101.65589 -276.810069) (xy 101.609874 -276.792617) (xy 101.567253 -276.76801)
			(xy 101.529132 -276.736885) (xy 101.496497 -276.700048) (xy 101.470194 -276.658452) (xy 101.450903 -276.613176)
			(xy 101.439126 -276.565392) (xy 101.435166 -276.516338) (xy 101.106478 -276.516338) (xy 101.105983 -276.540945)
			(xy 101.098088 -276.589522) (xy 101.082504 -276.636203) (xy 101.059633 -276.67978) (xy 101.030068 -276.719124)
			(xy 100.994575 -276.753216) (xy 100.954072 -276.781172) (xy 100.90961 -276.80227) (xy 100.862339 -276.815962)
			(xy 100.813484 -276.821894) (xy 100.764309 -276.819913) (xy 100.71609 -276.810069) (xy 100.670074 -276.792617)
			(xy 100.627453 -276.76801) (xy 100.589332 -276.736885) (xy 100.556697 -276.700048) (xy 100.530394 -276.658452)
			(xy 100.511103 -276.613176) (xy 100.499326 -276.565392) (xy 100.495366 -276.516338) (xy 100.166424 -276.516338)
			(xy 100.165929 -276.540945) (xy 100.158034 -276.589522) (xy 100.14245 -276.636203) (xy 100.119579 -276.67978)
			(xy 100.090014 -276.719124) (xy 100.054521 -276.753216) (xy 100.014018 -276.781172) (xy 99.969556 -276.80227)
			(xy 99.922285 -276.815962) (xy 99.87343 -276.821894) (xy 99.824255 -276.819913) (xy 99.776036 -276.810069)
			(xy 99.73002 -276.792617) (xy 99.687399 -276.76801) (xy 99.649278 -276.736885) (xy 99.616643 -276.700048)
			(xy 99.59034 -276.658452) (xy 99.571049 -276.613176) (xy 99.559272 -276.565392) (xy 99.555312 -276.516338)
			(xy 99.22637 -276.516338) (xy 99.225875 -276.540945) (xy 99.21798 -276.589522) (xy 99.202396 -276.636203)
			(xy 99.179525 -276.67978) (xy 99.14996 -276.719124) (xy 99.114467 -276.753216) (xy 99.073964 -276.781172)
			(xy 99.029502 -276.80227) (xy 98.982231 -276.815962) (xy 98.933376 -276.821894) (xy 98.884201 -276.819913)
			(xy 98.835982 -276.810069) (xy 98.789966 -276.792617) (xy 98.747345 -276.76801) (xy 98.709224 -276.736885)
			(xy 98.676589 -276.700048) (xy 98.650286 -276.658452) (xy 98.630995 -276.613176) (xy 98.619218 -276.565392)
			(xy 98.615258 -276.516338) (xy 98.286316 -276.516338) (xy 98.285821 -276.540945) (xy 98.277926 -276.589522)
			(xy 98.262342 -276.636203) (xy 98.239471 -276.67978) (xy 98.209906 -276.719124) (xy 98.174413 -276.753216)
			(xy 98.13391 -276.781172) (xy 98.089448 -276.80227) (xy 98.042177 -276.815962) (xy 97.993322 -276.821894)
			(xy 97.944147 -276.819913) (xy 97.895928 -276.810069) (xy 97.849912 -276.792617) (xy 97.807291 -276.76801)
			(xy 97.76917 -276.736885) (xy 97.736535 -276.700048) (xy 97.710232 -276.658452) (xy 97.690941 -276.613176)
			(xy 97.679164 -276.565392) (xy 97.675204 -276.516338) (xy 97.346516 -276.516338) (xy 97.345973 -276.542688)
			(xy 97.336941 -276.594607) (xy 97.319118 -276.644201) (xy 97.293034 -276.689992) (xy 97.276666 -276.710648)
			(xy 97.271332 -276.717252) (xy 97.262442 -276.741128) (xy 97.260923 -276.745416) (xy 97.259266 -276.75436)
			(xy 97.25914 -276.758908) (xy 97.25914 -276.948138) (xy 97.259778 -276.960649) (xy 97.27149 -276.982761)
			(xy 97.281492 -276.990302) (xy 97.361502 -277.044658) (xy 97.386394 -277.047452) (xy 97.398332 -277.042626)
			(xy 97.425437 -277.032576) (xy 97.482207 -277.021706) (xy 97.511108 -277.021036) (xy 97.536359 -277.021558)
			(xy 97.586173 -277.029872) (xy 97.633939 -277.046271) (xy 97.678354 -277.070308) (xy 97.718207 -277.101328)
			(xy 97.752411 -277.138484) (xy 97.780033 -277.180764) (xy 97.800319 -277.227013) (xy 97.812717 -277.27597)
			(xy 97.816887 -277.3263) (xy 97.816883 -277.326344) (xy 98.145358 -277.326344) (xy 98.149318 -277.27729)
			(xy 98.161095 -277.229506) (xy 98.180386 -277.18423) (xy 98.206689 -277.142634) (xy 98.239324 -277.105797)
			(xy 98.277445 -277.074672) (xy 98.320066 -277.050065) (xy 98.366082 -277.032613) (xy 98.414301 -277.022769)
			(xy 98.463476 -277.020788) (xy 98.512331 -277.02672) (xy 98.559602 -277.040412) (xy 98.604064 -277.06151)
			(xy 98.644567 -277.089466) (xy 98.68006 -277.123558) (xy 98.709625 -277.162902) (xy 98.732496 -277.206479)
			(xy 98.74808 -277.25316) (xy 98.755975 -277.301737) (xy 98.75647 -277.326344) (xy 99.085158 -277.326344)
			(xy 99.089118 -277.27729) (xy 99.100895 -277.229506) (xy 99.120186 -277.18423) (xy 99.146489 -277.142634)
			(xy 99.179124 -277.105797) (xy 99.217245 -277.074672) (xy 99.259866 -277.050065) (xy 99.305882 -277.032613)
			(xy 99.354101 -277.022769) (xy 99.403276 -277.020788) (xy 99.452131 -277.02672) (xy 99.499402 -277.040412)
			(xy 99.543864 -277.06151) (xy 99.584367 -277.089466) (xy 99.61986 -277.123558) (xy 99.649425 -277.162902)
			(xy 99.672296 -277.206479) (xy 99.68788 -277.25316) (xy 99.695775 -277.301737) (xy 99.69627 -277.326344)
			(xy 100.025212 -277.326344) (xy 100.029172 -277.27729) (xy 100.040949 -277.229506) (xy 100.06024 -277.18423)
			(xy 100.086543 -277.142634) (xy 100.119178 -277.105797) (xy 100.157299 -277.074672) (xy 100.19992 -277.050065)
			(xy 100.245936 -277.032613) (xy 100.294155 -277.022769) (xy 100.34333 -277.020788) (xy 100.392185 -277.02672)
			(xy 100.439456 -277.040412) (xy 100.483918 -277.06151) (xy 100.524421 -277.089466) (xy 100.559914 -277.123558)
			(xy 100.589479 -277.162902) (xy 100.61235 -277.206479) (xy 100.627934 -277.25316) (xy 100.635829 -277.301737)
			(xy 100.636324 -277.326344) (xy 100.965266 -277.326344) (xy 100.969226 -277.27729) (xy 100.981003 -277.229506)
			(xy 101.000294 -277.18423) (xy 101.026597 -277.142634) (xy 101.059232 -277.105797) (xy 101.097353 -277.074672)
			(xy 101.139974 -277.050065) (xy 101.18599 -277.032613) (xy 101.234209 -277.022769) (xy 101.283384 -277.020788)
			(xy 101.332239 -277.02672) (xy 101.37951 -277.040412) (xy 101.423972 -277.06151) (xy 101.464475 -277.089466)
			(xy 101.499968 -277.123558) (xy 101.529533 -277.162902) (xy 101.552404 -277.206479) (xy 101.567988 -277.25316)
			(xy 101.575883 -277.301737) (xy 101.576378 -277.326344) (xy 101.90532 -277.326344) (xy 101.90928 -277.27729)
			(xy 101.921057 -277.229506) (xy 101.940348 -277.18423) (xy 101.966651 -277.142634) (xy 101.999286 -277.105797)
			(xy 102.037407 -277.074672) (xy 102.080028 -277.050065) (xy 102.126044 -277.032613) (xy 102.174263 -277.022769)
			(xy 102.223438 -277.020788) (xy 102.272293 -277.02672) (xy 102.319564 -277.040412) (xy 102.364026 -277.06151)
			(xy 102.404529 -277.089466) (xy 102.440022 -277.123558) (xy 102.469587 -277.162902) (xy 102.492458 -277.206479)
			(xy 102.508042 -277.25316) (xy 102.515937 -277.301737) (xy 102.516432 -277.326344) (xy 102.845374 -277.326344)
			(xy 102.849334 -277.27729) (xy 102.861111 -277.229506) (xy 102.880402 -277.18423) (xy 102.906705 -277.142634)
			(xy 102.93934 -277.105797) (xy 102.977461 -277.074672) (xy 103.020082 -277.050065) (xy 103.066098 -277.032613)
			(xy 103.114317 -277.022769) (xy 103.163492 -277.020788) (xy 103.212347 -277.02672) (xy 103.259618 -277.040412)
			(xy 103.30408 -277.06151) (xy 103.344583 -277.089466) (xy 103.380076 -277.123558) (xy 103.409641 -277.162902)
			(xy 103.432512 -277.206479) (xy 103.448096 -277.25316) (xy 103.455991 -277.301737) (xy 103.456486 -277.326344)
			(xy 103.785174 -277.326344) (xy 103.789134 -277.27729) (xy 103.800911 -277.229506) (xy 103.820202 -277.18423)
			(xy 103.846505 -277.142634) (xy 103.87914 -277.105797) (xy 103.917261 -277.074672) (xy 103.959882 -277.050065)
			(xy 104.005898 -277.032613) (xy 104.054117 -277.022769) (xy 104.103292 -277.020788) (xy 104.152147 -277.02672)
			(xy 104.199418 -277.040412) (xy 104.24388 -277.06151) (xy 104.284383 -277.089466) (xy 104.319876 -277.123558)
			(xy 104.349441 -277.162902) (xy 104.372312 -277.206479) (xy 104.387896 -277.25316) (xy 104.395791 -277.301737)
			(xy 104.396286 -277.326344) (xy 104.725228 -277.326344) (xy 104.729188 -277.27729) (xy 104.740965 -277.229506)
			(xy 104.760256 -277.18423) (xy 104.786559 -277.142634) (xy 104.819194 -277.105797) (xy 104.857315 -277.074672)
			(xy 104.899936 -277.050065) (xy 104.945952 -277.032613) (xy 104.994171 -277.022769) (xy 105.043346 -277.020788)
			(xy 105.092201 -277.02672) (xy 105.139472 -277.040412) (xy 105.183934 -277.06151) (xy 105.224437 -277.089466)
			(xy 105.25993 -277.123558) (xy 105.289495 -277.162902) (xy 105.312366 -277.206479) (xy 105.32795 -277.25316)
			(xy 105.335845 -277.301737) (xy 105.33634 -277.326344) (xy 105.665282 -277.326344) (xy 105.669242 -277.27729)
			(xy 105.681019 -277.229506) (xy 105.70031 -277.18423) (xy 105.726613 -277.142634) (xy 105.759248 -277.105797)
			(xy 105.797369 -277.074672) (xy 105.83999 -277.050065) (xy 105.886006 -277.032613) (xy 105.934225 -277.022769)
			(xy 105.9834 -277.020788) (xy 106.032255 -277.02672) (xy 106.079526 -277.040412) (xy 106.123988 -277.06151)
			(xy 106.164491 -277.089466) (xy 106.199984 -277.123558) (xy 106.229549 -277.162902) (xy 106.25242 -277.206479)
			(xy 106.268004 -277.25316) (xy 106.275899 -277.301737) (xy 106.276394 -277.326344) (xy 106.605336 -277.326344)
			(xy 106.609296 -277.27729) (xy 106.621073 -277.229506) (xy 106.640364 -277.18423) (xy 106.666667 -277.142634)
			(xy 106.699302 -277.105797) (xy 106.737423 -277.074672) (xy 106.780044 -277.050065) (xy 106.82606 -277.032613)
			(xy 106.874279 -277.022769) (xy 106.923454 -277.020788) (xy 106.972309 -277.02672) (xy 107.01958 -277.040412)
			(xy 107.064042 -277.06151) (xy 107.104545 -277.089466) (xy 107.140038 -277.123558) (xy 107.169603 -277.162902)
			(xy 107.192474 -277.206479) (xy 107.208058 -277.25316) (xy 107.215953 -277.301737) (xy 107.216448 -277.326344)
			(xy 107.545136 -277.326344) (xy 107.549096 -277.27729) (xy 107.560873 -277.229506) (xy 107.580164 -277.18423)
			(xy 107.606467 -277.142634) (xy 107.639102 -277.105797) (xy 107.677223 -277.074672) (xy 107.719844 -277.050065)
			(xy 107.76586 -277.032613) (xy 107.814079 -277.022769) (xy 107.863254 -277.020788) (xy 107.912109 -277.02672)
			(xy 107.95938 -277.040412) (xy 108.003842 -277.06151) (xy 108.044345 -277.089466) (xy 108.079838 -277.123558)
			(xy 108.109403 -277.162902) (xy 108.132274 -277.206479) (xy 108.147858 -277.25316) (xy 108.155753 -277.301737)
			(xy 108.156248 -277.326344) (xy 108.48519 -277.326344) (xy 108.48915 -277.27729) (xy 108.500927 -277.229506)
			(xy 108.520218 -277.18423) (xy 108.546521 -277.142634) (xy 108.579156 -277.105797) (xy 108.617277 -277.074672)
			(xy 108.659898 -277.050065) (xy 108.705914 -277.032613) (xy 108.754133 -277.022769) (xy 108.803308 -277.020788)
			(xy 108.852163 -277.02672) (xy 108.899434 -277.040412) (xy 108.943896 -277.06151) (xy 108.984399 -277.089466)
			(xy 109.019892 -277.123558) (xy 109.049457 -277.162902) (xy 109.072328 -277.206479) (xy 109.087912 -277.25316)
			(xy 109.095807 -277.301737) (xy 109.096302 -277.326344) (xy 109.425244 -277.326344) (xy 109.429204 -277.27729)
			(xy 109.440981 -277.229506) (xy 109.460272 -277.18423) (xy 109.486575 -277.142634) (xy 109.51921 -277.105797)
			(xy 109.557331 -277.074672) (xy 109.599952 -277.050065) (xy 109.645968 -277.032613) (xy 109.694187 -277.022769)
			(xy 109.743362 -277.020788) (xy 109.792217 -277.02672) (xy 109.839488 -277.040412) (xy 109.88395 -277.06151)
			(xy 109.924453 -277.089466) (xy 109.959946 -277.123558) (xy 109.989511 -277.162902) (xy 110.012382 -277.206479)
			(xy 110.027966 -277.25316) (xy 110.035861 -277.301737) (xy 110.036356 -277.326344) (xy 110.365298 -277.326344)
			(xy 110.369258 -277.27729) (xy 110.381035 -277.229506) (xy 110.400326 -277.18423) (xy 110.426629 -277.142634)
			(xy 110.459264 -277.105797) (xy 110.497385 -277.074672) (xy 110.540006 -277.050065) (xy 110.586022 -277.032613)
			(xy 110.634241 -277.022769) (xy 110.683416 -277.020788) (xy 110.732271 -277.02672) (xy 110.779542 -277.040412)
			(xy 110.824004 -277.06151) (xy 110.864507 -277.089466) (xy 110.9 -277.123558) (xy 110.929565 -277.162902)
			(xy 110.952436 -277.206479) (xy 110.96802 -277.25316) (xy 110.975915 -277.301737) (xy 110.97641 -277.326344)
			(xy 113.178856 -277.326344) (xy 113.182816 -277.27729) (xy 113.194593 -277.229506) (xy 113.213884 -277.18423)
			(xy 113.240187 -277.142634) (xy 113.272822 -277.105797) (xy 113.310943 -277.074672) (xy 113.353564 -277.050065)
			(xy 113.39958 -277.032613) (xy 113.447799 -277.022769) (xy 113.496974 -277.020788) (xy 113.545829 -277.02672)
			(xy 113.5931 -277.040412) (xy 113.637562 -277.06151) (xy 113.678065 -277.089466) (xy 113.713558 -277.123558)
			(xy 113.743123 -277.162902) (xy 113.765994 -277.206479) (xy 113.781578 -277.25316) (xy 113.789473 -277.301737)
			(xy 113.789968 -277.326344) (xy 114.11891 -277.326344) (xy 114.12287 -277.27729) (xy 114.134647 -277.229506)
			(xy 114.153938 -277.18423) (xy 114.180241 -277.142634) (xy 114.212876 -277.105797) (xy 114.250997 -277.074672)
			(xy 114.293618 -277.050065) (xy 114.339634 -277.032613) (xy 114.387853 -277.022769) (xy 114.437028 -277.020788)
			(xy 114.485883 -277.02672) (xy 114.533154 -277.040412) (xy 114.577616 -277.06151) (xy 114.618119 -277.089466)
			(xy 114.653612 -277.123558) (xy 114.683177 -277.162902) (xy 114.706048 -277.206479) (xy 114.721632 -277.25316)
			(xy 114.729527 -277.301737) (xy 114.730022 -277.326344) (xy 115.058964 -277.326344) (xy 115.062924 -277.27729)
			(xy 115.074701 -277.229506) (xy 115.093992 -277.18423) (xy 115.120295 -277.142634) (xy 115.15293 -277.105797)
			(xy 115.191051 -277.074672) (xy 115.233672 -277.050065) (xy 115.279688 -277.032613) (xy 115.327907 -277.022769)
			(xy 115.377082 -277.020788) (xy 115.425937 -277.02672) (xy 115.473208 -277.040412) (xy 115.51767 -277.06151)
			(xy 115.558173 -277.089466) (xy 115.593666 -277.123558) (xy 115.623231 -277.162902) (xy 115.646102 -277.206479)
			(xy 115.661686 -277.25316) (xy 115.669581 -277.301737) (xy 115.670076 -277.326344) (xy 115.999018 -277.326344)
			(xy 116.002978 -277.27729) (xy 116.014755 -277.229506) (xy 116.034046 -277.18423) (xy 116.060349 -277.142634)
			(xy 116.092984 -277.105797) (xy 116.131105 -277.074672) (xy 116.173726 -277.050065) (xy 116.219742 -277.032613)
			(xy 116.267961 -277.022769) (xy 116.317136 -277.020788) (xy 116.365991 -277.02672) (xy 116.413262 -277.040412)
			(xy 116.457724 -277.06151) (xy 116.498227 -277.089466) (xy 116.53372 -277.123558) (xy 116.563285 -277.162902)
			(xy 116.586156 -277.206479) (xy 116.60174 -277.25316) (xy 116.609635 -277.301737) (xy 116.61013 -277.326344)
			(xy 116.938818 -277.326344) (xy 116.942778 -277.27729) (xy 116.954555 -277.229506) (xy 116.973846 -277.18423)
			(xy 117.000149 -277.142634) (xy 117.032784 -277.105797) (xy 117.070905 -277.074672) (xy 117.113526 -277.050065)
			(xy 117.159542 -277.032613) (xy 117.207761 -277.022769) (xy 117.256936 -277.020788) (xy 117.305791 -277.02672)
			(xy 117.353062 -277.040412) (xy 117.397524 -277.06151) (xy 117.438027 -277.089466) (xy 117.47352 -277.123558)
			(xy 117.503085 -277.162902) (xy 117.525956 -277.206479) (xy 117.54154 -277.25316) (xy 117.549435 -277.301737)
			(xy 117.54993 -277.326344) (xy 117.878872 -277.326344) (xy 117.882832 -277.27729) (xy 117.894609 -277.229506)
			(xy 117.9139 -277.18423) (xy 117.940203 -277.142634) (xy 117.972838 -277.105797) (xy 118.010959 -277.074672)
			(xy 118.05358 -277.050065) (xy 118.099596 -277.032613) (xy 118.147815 -277.022769) (xy 118.19699 -277.020788)
			(xy 118.245845 -277.02672) (xy 118.293116 -277.040412) (xy 118.337578 -277.06151) (xy 118.378081 -277.089466)
			(xy 118.413574 -277.123558) (xy 118.443139 -277.162902) (xy 118.46601 -277.206479) (xy 118.481594 -277.25316)
			(xy 118.489489 -277.301737) (xy 118.489984 -277.326344) (xy 118.818926 -277.326344) (xy 118.822886 -277.27729)
			(xy 118.834663 -277.229506) (xy 118.853954 -277.18423) (xy 118.880257 -277.142634) (xy 118.912892 -277.105797)
			(xy 118.951013 -277.074672) (xy 118.993634 -277.050065) (xy 119.03965 -277.032613) (xy 119.087869 -277.022769)
			(xy 119.137044 -277.020788) (xy 119.185899 -277.02672) (xy 119.23317 -277.040412) (xy 119.277632 -277.06151)
			(xy 119.318135 -277.089466) (xy 119.353628 -277.123558) (xy 119.383193 -277.162902) (xy 119.406064 -277.206479)
			(xy 119.421648 -277.25316) (xy 119.429543 -277.301737) (xy 119.430038 -277.326344) (xy 119.75898 -277.326344)
			(xy 119.76294 -277.27729) (xy 119.774717 -277.229506) (xy 119.794008 -277.18423) (xy 119.820311 -277.142634)
			(xy 119.852946 -277.105797) (xy 119.891067 -277.074672) (xy 119.933688 -277.050065) (xy 119.979704 -277.032613)
			(xy 120.027923 -277.022769) (xy 120.077098 -277.020788) (xy 120.125953 -277.02672) (xy 120.173224 -277.040412)
			(xy 120.217686 -277.06151) (xy 120.258189 -277.089466) (xy 120.293682 -277.123558) (xy 120.323247 -277.162902)
			(xy 120.346118 -277.206479) (xy 120.361702 -277.25316) (xy 120.369597 -277.301737) (xy 120.370092 -277.326344)
			(xy 120.699034 -277.326344) (xy 120.702994 -277.27729) (xy 120.714771 -277.229506) (xy 120.734062 -277.18423)
			(xy 120.760365 -277.142634) (xy 120.793 -277.105797) (xy 120.831121 -277.074672) (xy 120.873742 -277.050065)
			(xy 120.919758 -277.032613) (xy 120.967977 -277.022769) (xy 121.017152 -277.020788) (xy 121.066007 -277.02672)
			(xy 121.113278 -277.040412) (xy 121.15774 -277.06151) (xy 121.198243 -277.089466) (xy 121.233736 -277.123558)
			(xy 121.263301 -277.162902) (xy 121.286172 -277.206479) (xy 121.301756 -277.25316) (xy 121.309651 -277.301737)
			(xy 121.310146 -277.326344) (xy 121.638834 -277.326344) (xy 121.642794 -277.27729) (xy 121.654571 -277.229506)
			(xy 121.673862 -277.18423) (xy 121.700165 -277.142634) (xy 121.7328 -277.105797) (xy 121.770921 -277.074672)
			(xy 121.813542 -277.050065) (xy 121.859558 -277.032613) (xy 121.907777 -277.022769) (xy 121.956952 -277.020788)
			(xy 122.005807 -277.02672) (xy 122.053078 -277.040412) (xy 122.09754 -277.06151) (xy 122.138043 -277.089466)
			(xy 122.173536 -277.123558) (xy 122.203101 -277.162902) (xy 122.225972 -277.206479) (xy 122.241556 -277.25316)
			(xy 122.249451 -277.301737) (xy 122.249946 -277.326344) (xy 122.578888 -277.326344) (xy 122.582848 -277.27729)
			(xy 122.594625 -277.229506) (xy 122.613916 -277.18423) (xy 122.640219 -277.142634) (xy 122.672854 -277.105797)
			(xy 122.710975 -277.074672) (xy 122.753596 -277.050065) (xy 122.799612 -277.032613) (xy 122.847831 -277.022769)
			(xy 122.897006 -277.020788) (xy 122.945861 -277.02672) (xy 122.993132 -277.040412) (xy 123.037594 -277.06151)
			(xy 123.078097 -277.089466) (xy 123.11359 -277.123558) (xy 123.143155 -277.162902) (xy 123.166026 -277.206479)
			(xy 123.18161 -277.25316) (xy 123.189505 -277.301737) (xy 123.19 -277.326344) (xy 123.518942 -277.326344)
			(xy 123.522902 -277.27729) (xy 123.534679 -277.229506) (xy 123.55397 -277.18423) (xy 123.580273 -277.142634)
			(xy 123.612908 -277.105797) (xy 123.651029 -277.074672) (xy 123.69365 -277.050065) (xy 123.739666 -277.032613)
			(xy 123.787885 -277.022769) (xy 123.83706 -277.020788) (xy 123.885915 -277.02672) (xy 123.933186 -277.040412)
			(xy 123.977648 -277.06151) (xy 124.018151 -277.089466) (xy 124.053644 -277.123558) (xy 124.083209 -277.162902)
			(xy 124.10608 -277.206479) (xy 124.121664 -277.25316) (xy 124.129559 -277.301737) (xy 124.130054 -277.326344)
			(xy 124.458996 -277.326344) (xy 124.462956 -277.27729) (xy 124.474733 -277.229506) (xy 124.494024 -277.18423)
			(xy 124.520327 -277.142634) (xy 124.552962 -277.105797) (xy 124.591083 -277.074672) (xy 124.633704 -277.050065)
			(xy 124.67972 -277.032613) (xy 124.727939 -277.022769) (xy 124.777114 -277.020788) (xy 124.825969 -277.02672)
			(xy 124.87324 -277.040412) (xy 124.917702 -277.06151) (xy 124.958205 -277.089466) (xy 124.993698 -277.123558)
			(xy 125.023263 -277.162902) (xy 125.046134 -277.206479) (xy 125.061718 -277.25316) (xy 125.069613 -277.301737)
			(xy 125.070108 -277.326344) (xy 125.39905 -277.326344) (xy 125.40301 -277.27729) (xy 125.414787 -277.229506)
			(xy 125.434078 -277.18423) (xy 125.460381 -277.142634) (xy 125.493016 -277.105797) (xy 125.531137 -277.074672)
			(xy 125.573758 -277.050065) (xy 125.619774 -277.032613) (xy 125.667993 -277.022769) (xy 125.717168 -277.020788)
			(xy 125.766023 -277.02672) (xy 125.813294 -277.040412) (xy 125.857756 -277.06151) (xy 125.898259 -277.089466)
			(xy 125.933752 -277.123558) (xy 125.963317 -277.162902) (xy 125.986188 -277.206479) (xy 126.001772 -277.25316)
			(xy 126.009667 -277.301737) (xy 126.010162 -277.326344) (xy 126.009667 -277.350951) (xy 126.001772 -277.399528)
			(xy 125.986188 -277.446209) (xy 125.963317 -277.489786) (xy 125.933752 -277.52913) (xy 125.898259 -277.563222)
			(xy 125.857756 -277.591178) (xy 125.813294 -277.612276) (xy 125.766023 -277.625968) (xy 125.717168 -277.6319)
			(xy 125.667993 -277.629919) (xy 125.619774 -277.620075) (xy 125.573758 -277.602623) (xy 125.531137 -277.578016)
			(xy 125.493016 -277.546891) (xy 125.460381 -277.510054) (xy 125.434078 -277.468458) (xy 125.414787 -277.423182)
			(xy 125.40301 -277.375398) (xy 125.39905 -277.326344) (xy 125.070108 -277.326344) (xy 125.069613 -277.350951)
			(xy 125.061718 -277.399528) (xy 125.046134 -277.446209) (xy 125.023263 -277.489786) (xy 124.993698 -277.52913)
			(xy 124.958205 -277.563222) (xy 124.917702 -277.591178) (xy 124.87324 -277.612276) (xy 124.825969 -277.625968)
			(xy 124.777114 -277.6319) (xy 124.727939 -277.629919) (xy 124.67972 -277.620075) (xy 124.633704 -277.602623)
			(xy 124.591083 -277.578016) (xy 124.552962 -277.546891) (xy 124.520327 -277.510054) (xy 124.494024 -277.468458)
			(xy 124.474733 -277.423182) (xy 124.462956 -277.375398) (xy 124.458996 -277.326344) (xy 124.130054 -277.326344)
			(xy 124.129559 -277.350951) (xy 124.121664 -277.399528) (xy 124.10608 -277.446209) (xy 124.083209 -277.489786)
			(xy 124.053644 -277.52913) (xy 124.018151 -277.563222) (xy 123.977648 -277.591178) (xy 123.933186 -277.612276)
			(xy 123.885915 -277.625968) (xy 123.83706 -277.6319) (xy 123.787885 -277.629919) (xy 123.739666 -277.620075)
			(xy 123.69365 -277.602623) (xy 123.651029 -277.578016) (xy 123.612908 -277.546891) (xy 123.580273 -277.510054)
			(xy 123.55397 -277.468458) (xy 123.534679 -277.423182) (xy 123.522902 -277.375398) (xy 123.518942 -277.326344)
			(xy 123.19 -277.326344) (xy 123.189505 -277.350951) (xy 123.18161 -277.399528) (xy 123.166026 -277.446209)
			(xy 123.143155 -277.489786) (xy 123.11359 -277.52913) (xy 123.078097 -277.563222) (xy 123.037594 -277.591178)
			(xy 122.993132 -277.612276) (xy 122.945861 -277.625968) (xy 122.897006 -277.6319) (xy 122.847831 -277.629919)
			(xy 122.799612 -277.620075) (xy 122.753596 -277.602623) (xy 122.710975 -277.578016) (xy 122.672854 -277.546891)
			(xy 122.640219 -277.510054) (xy 122.613916 -277.468458) (xy 122.594625 -277.423182) (xy 122.582848 -277.375398)
			(xy 122.578888 -277.326344) (xy 122.249946 -277.326344) (xy 122.249451 -277.350951) (xy 122.241556 -277.399528)
			(xy 122.225972 -277.446209) (xy 122.203101 -277.489786) (xy 122.173536 -277.52913) (xy 122.138043 -277.563222)
			(xy 122.09754 -277.591178) (xy 122.053078 -277.612276) (xy 122.005807 -277.625968) (xy 121.956952 -277.6319)
			(xy 121.907777 -277.629919) (xy 121.859558 -277.620075) (xy 121.813542 -277.602623) (xy 121.770921 -277.578016)
			(xy 121.7328 -277.546891) (xy 121.700165 -277.510054) (xy 121.673862 -277.468458) (xy 121.654571 -277.423182)
			(xy 121.642794 -277.375398) (xy 121.638834 -277.326344) (xy 121.310146 -277.326344) (xy 121.309651 -277.350951)
			(xy 121.301756 -277.399528) (xy 121.286172 -277.446209) (xy 121.263301 -277.489786) (xy 121.233736 -277.52913)
			(xy 121.198243 -277.563222) (xy 121.15774 -277.591178) (xy 121.113278 -277.612276) (xy 121.066007 -277.625968)
			(xy 121.017152 -277.6319) (xy 120.967977 -277.629919) (xy 120.919758 -277.620075) (xy 120.873742 -277.602623)
			(xy 120.831121 -277.578016) (xy 120.793 -277.546891) (xy 120.760365 -277.510054) (xy 120.734062 -277.468458)
			(xy 120.714771 -277.423182) (xy 120.702994 -277.375398) (xy 120.699034 -277.326344) (xy 120.370092 -277.326344)
			(xy 120.369597 -277.350951) (xy 120.361702 -277.399528) (xy 120.346118 -277.446209) (xy 120.323247 -277.489786)
			(xy 120.293682 -277.52913) (xy 120.258189 -277.563222) (xy 120.217686 -277.591178) (xy 120.173224 -277.612276)
			(xy 120.125953 -277.625968) (xy 120.077098 -277.6319) (xy 120.027923 -277.629919) (xy 119.979704 -277.620075)
			(xy 119.933688 -277.602623) (xy 119.891067 -277.578016) (xy 119.852946 -277.546891) (xy 119.820311 -277.510054)
			(xy 119.794008 -277.468458) (xy 119.774717 -277.423182) (xy 119.76294 -277.375398) (xy 119.75898 -277.326344)
			(xy 119.430038 -277.326344) (xy 119.429543 -277.350951) (xy 119.421648 -277.399528) (xy 119.406064 -277.446209)
			(xy 119.383193 -277.489786) (xy 119.353628 -277.52913) (xy 119.318135 -277.563222) (xy 119.277632 -277.591178)
			(xy 119.23317 -277.612276) (xy 119.185899 -277.625968) (xy 119.137044 -277.6319) (xy 119.087869 -277.629919)
			(xy 119.03965 -277.620075) (xy 118.993634 -277.602623) (xy 118.951013 -277.578016) (xy 118.912892 -277.546891)
			(xy 118.880257 -277.510054) (xy 118.853954 -277.468458) (xy 118.834663 -277.423182) (xy 118.822886 -277.375398)
			(xy 118.818926 -277.326344) (xy 118.489984 -277.326344) (xy 118.489489 -277.350951) (xy 118.481594 -277.399528)
			(xy 118.46601 -277.446209) (xy 118.443139 -277.489786) (xy 118.413574 -277.52913) (xy 118.378081 -277.563222)
			(xy 118.337578 -277.591178) (xy 118.293116 -277.612276) (xy 118.245845 -277.625968) (xy 118.19699 -277.6319)
			(xy 118.147815 -277.629919) (xy 118.099596 -277.620075) (xy 118.05358 -277.602623) (xy 118.010959 -277.578016)
			(xy 117.972838 -277.546891) (xy 117.940203 -277.510054) (xy 117.9139 -277.468458) (xy 117.894609 -277.423182)
			(xy 117.882832 -277.375398) (xy 117.878872 -277.326344) (xy 117.54993 -277.326344) (xy 117.549435 -277.350951)
			(xy 117.54154 -277.399528) (xy 117.525956 -277.446209) (xy 117.503085 -277.489786) (xy 117.47352 -277.52913)
			(xy 117.438027 -277.563222) (xy 117.397524 -277.591178) (xy 117.353062 -277.612276) (xy 117.305791 -277.625968)
			(xy 117.256936 -277.6319) (xy 117.207761 -277.629919) (xy 117.159542 -277.620075) (xy 117.113526 -277.602623)
			(xy 117.070905 -277.578016) (xy 117.032784 -277.546891) (xy 117.000149 -277.510054) (xy 116.973846 -277.468458)
			(xy 116.954555 -277.423182) (xy 116.942778 -277.375398) (xy 116.938818 -277.326344) (xy 116.61013 -277.326344)
			(xy 116.609635 -277.350951) (xy 116.60174 -277.399528) (xy 116.586156 -277.446209) (xy 116.563285 -277.489786)
			(xy 116.53372 -277.52913) (xy 116.498227 -277.563222) (xy 116.457724 -277.591178) (xy 116.413262 -277.612276)
			(xy 116.365991 -277.625968) (xy 116.317136 -277.6319) (xy 116.267961 -277.629919) (xy 116.219742 -277.620075)
			(xy 116.173726 -277.602623) (xy 116.131105 -277.578016) (xy 116.092984 -277.546891) (xy 116.060349 -277.510054)
			(xy 116.034046 -277.468458) (xy 116.014755 -277.423182) (xy 116.002978 -277.375398) (xy 115.999018 -277.326344)
			(xy 115.670076 -277.326344) (xy 115.669581 -277.350951) (xy 115.661686 -277.399528) (xy 115.646102 -277.446209)
			(xy 115.623231 -277.489786) (xy 115.593666 -277.52913) (xy 115.558173 -277.563222) (xy 115.51767 -277.591178)
			(xy 115.473208 -277.612276) (xy 115.425937 -277.625968) (xy 115.377082 -277.6319) (xy 115.327907 -277.629919)
			(xy 115.279688 -277.620075) (xy 115.233672 -277.602623) (xy 115.191051 -277.578016) (xy 115.15293 -277.546891)
			(xy 115.120295 -277.510054) (xy 115.093992 -277.468458) (xy 115.074701 -277.423182) (xy 115.062924 -277.375398)
			(xy 115.058964 -277.326344) (xy 114.730022 -277.326344) (xy 114.729527 -277.350951) (xy 114.721632 -277.399528)
			(xy 114.706048 -277.446209) (xy 114.683177 -277.489786) (xy 114.653612 -277.52913) (xy 114.618119 -277.563222)
			(xy 114.577616 -277.591178) (xy 114.533154 -277.612276) (xy 114.485883 -277.625968) (xy 114.437028 -277.6319)
			(xy 114.387853 -277.629919) (xy 114.339634 -277.620075) (xy 114.293618 -277.602623) (xy 114.250997 -277.578016)
			(xy 114.212876 -277.546891) (xy 114.180241 -277.510054) (xy 114.153938 -277.468458) (xy 114.134647 -277.423182)
			(xy 114.12287 -277.375398) (xy 114.11891 -277.326344) (xy 113.789968 -277.326344) (xy 113.789473 -277.350951)
			(xy 113.781578 -277.399528) (xy 113.765994 -277.446209) (xy 113.743123 -277.489786) (xy 113.713558 -277.52913)
			(xy 113.678065 -277.563222) (xy 113.637562 -277.591178) (xy 113.5931 -277.612276) (xy 113.545829 -277.625968)
			(xy 113.496974 -277.6319) (xy 113.447799 -277.629919) (xy 113.39958 -277.620075) (xy 113.353564 -277.602623)
			(xy 113.310943 -277.578016) (xy 113.272822 -277.546891) (xy 113.240187 -277.510054) (xy 113.213884 -277.468458)
			(xy 113.194593 -277.423182) (xy 113.182816 -277.375398) (xy 113.178856 -277.326344) (xy 110.97641 -277.326344)
			(xy 110.975915 -277.350951) (xy 110.96802 -277.399528) (xy 110.952436 -277.446209) (xy 110.929565 -277.489786)
			(xy 110.9 -277.52913) (xy 110.864507 -277.563222) (xy 110.824004 -277.591178) (xy 110.779542 -277.612276)
			(xy 110.732271 -277.625968) (xy 110.683416 -277.6319) (xy 110.634241 -277.629919) (xy 110.586022 -277.620075)
			(xy 110.540006 -277.602623) (xy 110.497385 -277.578016) (xy 110.459264 -277.546891) (xy 110.426629 -277.510054)
			(xy 110.400326 -277.468458) (xy 110.381035 -277.423182) (xy 110.369258 -277.375398) (xy 110.365298 -277.326344)
			(xy 110.036356 -277.326344) (xy 110.035861 -277.350951) (xy 110.027966 -277.399528) (xy 110.012382 -277.446209)
			(xy 109.989511 -277.489786) (xy 109.959946 -277.52913) (xy 109.924453 -277.563222) (xy 109.88395 -277.591178)
			(xy 109.839488 -277.612276) (xy 109.792217 -277.625968) (xy 109.743362 -277.6319) (xy 109.694187 -277.629919)
			(xy 109.645968 -277.620075) (xy 109.599952 -277.602623) (xy 109.557331 -277.578016) (xy 109.51921 -277.546891)
			(xy 109.486575 -277.510054) (xy 109.460272 -277.468458) (xy 109.440981 -277.423182) (xy 109.429204 -277.375398)
			(xy 109.425244 -277.326344) (xy 109.096302 -277.326344) (xy 109.095807 -277.350951) (xy 109.087912 -277.399528)
			(xy 109.072328 -277.446209) (xy 109.049457 -277.489786) (xy 109.019892 -277.52913) (xy 108.984399 -277.563222)
			(xy 108.943896 -277.591178) (xy 108.899434 -277.612276) (xy 108.852163 -277.625968) (xy 108.803308 -277.6319)
			(xy 108.754133 -277.629919) (xy 108.705914 -277.620075) (xy 108.659898 -277.602623) (xy 108.617277 -277.578016)
			(xy 108.579156 -277.546891) (xy 108.546521 -277.510054) (xy 108.520218 -277.468458) (xy 108.500927 -277.423182)
			(xy 108.48915 -277.375398) (xy 108.48519 -277.326344) (xy 108.156248 -277.326344) (xy 108.155753 -277.350951)
			(xy 108.147858 -277.399528) (xy 108.132274 -277.446209) (xy 108.109403 -277.489786) (xy 108.079838 -277.52913)
			(xy 108.044345 -277.563222) (xy 108.003842 -277.591178) (xy 107.95938 -277.612276) (xy 107.912109 -277.625968)
			(xy 107.863254 -277.6319) (xy 107.814079 -277.629919) (xy 107.76586 -277.620075) (xy 107.719844 -277.602623)
			(xy 107.677223 -277.578016) (xy 107.639102 -277.546891) (xy 107.606467 -277.510054) (xy 107.580164 -277.468458)
			(xy 107.560873 -277.423182) (xy 107.549096 -277.375398) (xy 107.545136 -277.326344) (xy 107.216448 -277.326344)
			(xy 107.215953 -277.350951) (xy 107.208058 -277.399528) (xy 107.192474 -277.446209) (xy 107.169603 -277.489786)
			(xy 107.140038 -277.52913) (xy 107.104545 -277.563222) (xy 107.064042 -277.591178) (xy 107.01958 -277.612276)
			(xy 106.972309 -277.625968) (xy 106.923454 -277.6319) (xy 106.874279 -277.629919) (xy 106.82606 -277.620075)
			(xy 106.780044 -277.602623) (xy 106.737423 -277.578016) (xy 106.699302 -277.546891) (xy 106.666667 -277.510054)
			(xy 106.640364 -277.468458) (xy 106.621073 -277.423182) (xy 106.609296 -277.375398) (xy 106.605336 -277.326344)
			(xy 106.276394 -277.326344) (xy 106.275899 -277.350951) (xy 106.268004 -277.399528) (xy 106.25242 -277.446209)
			(xy 106.229549 -277.489786) (xy 106.199984 -277.52913) (xy 106.164491 -277.563222) (xy 106.123988 -277.591178)
			(xy 106.079526 -277.612276) (xy 106.032255 -277.625968) (xy 105.9834 -277.6319) (xy 105.934225 -277.629919)
			(xy 105.886006 -277.620075) (xy 105.83999 -277.602623) (xy 105.797369 -277.578016) (xy 105.759248 -277.546891)
			(xy 105.726613 -277.510054) (xy 105.70031 -277.468458) (xy 105.681019 -277.423182) (xy 105.669242 -277.375398)
			(xy 105.665282 -277.326344) (xy 105.33634 -277.326344) (xy 105.335845 -277.350951) (xy 105.32795 -277.399528)
			(xy 105.312366 -277.446209) (xy 105.289495 -277.489786) (xy 105.25993 -277.52913) (xy 105.224437 -277.563222)
			(xy 105.183934 -277.591178) (xy 105.139472 -277.612276) (xy 105.092201 -277.625968) (xy 105.043346 -277.6319)
			(xy 104.994171 -277.629919) (xy 104.945952 -277.620075) (xy 104.899936 -277.602623) (xy 104.857315 -277.578016)
			(xy 104.819194 -277.546891) (xy 104.786559 -277.510054) (xy 104.760256 -277.468458) (xy 104.740965 -277.423182)
			(xy 104.729188 -277.375398) (xy 104.725228 -277.326344) (xy 104.396286 -277.326344) (xy 104.395791 -277.350951)
			(xy 104.387896 -277.399528) (xy 104.372312 -277.446209) (xy 104.349441 -277.489786) (xy 104.319876 -277.52913)
			(xy 104.284383 -277.563222) (xy 104.24388 -277.591178) (xy 104.199418 -277.612276) (xy 104.152147 -277.625968)
			(xy 104.103292 -277.6319) (xy 104.054117 -277.629919) (xy 104.005898 -277.620075) (xy 103.959882 -277.602623)
			(xy 103.917261 -277.578016) (xy 103.87914 -277.546891) (xy 103.846505 -277.510054) (xy 103.820202 -277.468458)
			(xy 103.800911 -277.423182) (xy 103.789134 -277.375398) (xy 103.785174 -277.326344) (xy 103.456486 -277.326344)
			(xy 103.455991 -277.350951) (xy 103.448096 -277.399528) (xy 103.432512 -277.446209) (xy 103.409641 -277.489786)
			(xy 103.380076 -277.52913) (xy 103.344583 -277.563222) (xy 103.30408 -277.591178) (xy 103.259618 -277.612276)
			(xy 103.212347 -277.625968) (xy 103.163492 -277.6319) (xy 103.114317 -277.629919) (xy 103.066098 -277.620075)
			(xy 103.020082 -277.602623) (xy 102.977461 -277.578016) (xy 102.93934 -277.546891) (xy 102.906705 -277.510054)
			(xy 102.880402 -277.468458) (xy 102.861111 -277.423182) (xy 102.849334 -277.375398) (xy 102.845374 -277.326344)
			(xy 102.516432 -277.326344) (xy 102.515937 -277.350951) (xy 102.508042 -277.399528) (xy 102.492458 -277.446209)
			(xy 102.469587 -277.489786) (xy 102.440022 -277.52913) (xy 102.404529 -277.563222) (xy 102.364026 -277.591178)
			(xy 102.319564 -277.612276) (xy 102.272293 -277.625968) (xy 102.223438 -277.6319) (xy 102.174263 -277.629919)
			(xy 102.126044 -277.620075) (xy 102.080028 -277.602623) (xy 102.037407 -277.578016) (xy 101.999286 -277.546891)
			(xy 101.966651 -277.510054) (xy 101.940348 -277.468458) (xy 101.921057 -277.423182) (xy 101.90928 -277.375398)
			(xy 101.90532 -277.326344) (xy 101.576378 -277.326344) (xy 101.575883 -277.350951) (xy 101.567988 -277.399528)
			(xy 101.552404 -277.446209) (xy 101.529533 -277.489786) (xy 101.499968 -277.52913) (xy 101.464475 -277.563222)
			(xy 101.423972 -277.591178) (xy 101.37951 -277.612276) (xy 101.332239 -277.625968) (xy 101.283384 -277.6319)
			(xy 101.234209 -277.629919) (xy 101.18599 -277.620075) (xy 101.139974 -277.602623) (xy 101.097353 -277.578016)
			(xy 101.059232 -277.546891) (xy 101.026597 -277.510054) (xy 101.000294 -277.468458) (xy 100.981003 -277.423182)
			(xy 100.969226 -277.375398) (xy 100.965266 -277.326344) (xy 100.636324 -277.326344) (xy 100.635829 -277.350951)
			(xy 100.627934 -277.399528) (xy 100.61235 -277.446209) (xy 100.589479 -277.489786) (xy 100.559914 -277.52913)
			(xy 100.524421 -277.563222) (xy 100.483918 -277.591178) (xy 100.439456 -277.612276) (xy 100.392185 -277.625968)
			(xy 100.34333 -277.6319) (xy 100.294155 -277.629919) (xy 100.245936 -277.620075) (xy 100.19992 -277.602623)
			(xy 100.157299 -277.578016) (xy 100.119178 -277.546891) (xy 100.086543 -277.510054) (xy 100.06024 -277.468458)
			(xy 100.040949 -277.423182) (xy 100.029172 -277.375398) (xy 100.025212 -277.326344) (xy 99.69627 -277.326344)
			(xy 99.695775 -277.350951) (xy 99.68788 -277.399528) (xy 99.672296 -277.446209) (xy 99.649425 -277.489786)
			(xy 99.61986 -277.52913) (xy 99.584367 -277.563222) (xy 99.543864 -277.591178) (xy 99.499402 -277.612276)
			(xy 99.452131 -277.625968) (xy 99.403276 -277.6319) (xy 99.354101 -277.629919) (xy 99.305882 -277.620075)
			(xy 99.259866 -277.602623) (xy 99.217245 -277.578016) (xy 99.179124 -277.546891) (xy 99.146489 -277.510054)
			(xy 99.120186 -277.468458) (xy 99.100895 -277.423182) (xy 99.089118 -277.375398) (xy 99.085158 -277.326344)
			(xy 98.75647 -277.326344) (xy 98.755975 -277.350951) (xy 98.74808 -277.399528) (xy 98.732496 -277.446209)
			(xy 98.709625 -277.489786) (xy 98.68006 -277.52913) (xy 98.644567 -277.563222) (xy 98.604064 -277.591178)
			(xy 98.559602 -277.612276) (xy 98.512331 -277.625968) (xy 98.463476 -277.6319) (xy 98.414301 -277.629919)
			(xy 98.366082 -277.620075) (xy 98.320066 -277.602623) (xy 98.277445 -277.578016) (xy 98.239324 -277.546891)
			(xy 98.206689 -277.510054) (xy 98.180386 -277.468458) (xy 98.161095 -277.423182) (xy 98.149318 -277.375398)
			(xy 98.145358 -277.326344) (xy 97.816883 -277.326344) (xy 97.812717 -277.37663) (xy 97.800319 -277.425587)
			(xy 97.780033 -277.471836) (xy 97.752411 -277.514116) (xy 97.718207 -277.551272) (xy 97.678354 -277.582292)
			(xy 97.633939 -277.606329) (xy 97.586173 -277.622728) (xy 97.536359 -277.631042) (xy 97.511108 -277.631652)
			(xy 97.482207 -277.63098) (xy 97.425437 -277.620113) (xy 97.398332 -277.610062) (xy 97.386394 -277.605236)
			(xy 97.361502 -277.60803) (xy 97.281492 -277.662386) (xy 97.27146 -277.669908) (xy 97.259711 -277.692026)
			(xy 97.25914 -277.70455) (xy 97.25914 -277.89378) (xy 97.259265 -277.898327) (xy 97.260928 -277.90727)
			(xy 97.262442 -277.91156) (xy 97.271332 -277.935436) (xy 97.276666 -277.94204) (xy 97.29299 -277.962724)
			(xy 97.319031 -278.008525) (xy 97.336852 -278.058107) (xy 97.345926 -278.110007) (xy 97.346516 -278.13635)
			(xy 97.675204 -278.13635) (xy 97.679164 -278.087296) (xy 97.690941 -278.039512) (xy 97.710232 -277.994236)
			(xy 97.736535 -277.95264) (xy 97.76917 -277.915803) (xy 97.807291 -277.884678) (xy 97.849912 -277.860071)
			(xy 97.895928 -277.842619) (xy 97.944147 -277.832775) (xy 97.993322 -277.830794) (xy 98.042177 -277.836726)
			(xy 98.089448 -277.850418) (xy 98.13391 -277.871516) (xy 98.174413 -277.899472) (xy 98.209906 -277.933564)
			(xy 98.239471 -277.972908) (xy 98.262342 -278.016485) (xy 98.277926 -278.063166) (xy 98.285821 -278.111743)
			(xy 98.286316 -278.13635) (xy 98.615258 -278.13635) (xy 98.619218 -278.087296) (xy 98.630995 -278.039512)
			(xy 98.650286 -277.994236) (xy 98.676589 -277.95264) (xy 98.709224 -277.915803) (xy 98.747345 -277.884678)
			(xy 98.789966 -277.860071) (xy 98.835982 -277.842619) (xy 98.884201 -277.832775) (xy 98.933376 -277.830794)
			(xy 98.982231 -277.836726) (xy 99.029502 -277.850418) (xy 99.073964 -277.871516) (xy 99.114467 -277.899472)
			(xy 99.14996 -277.933564) (xy 99.179525 -277.972908) (xy 99.202396 -278.016485) (xy 99.21798 -278.063166)
			(xy 99.225875 -278.111743) (xy 99.22637 -278.13635) (xy 99.555312 -278.13635) (xy 99.559272 -278.087296)
			(xy 99.571049 -278.039512) (xy 99.59034 -277.994236) (xy 99.616643 -277.95264) (xy 99.649278 -277.915803)
			(xy 99.687399 -277.884678) (xy 99.73002 -277.860071) (xy 99.776036 -277.842619) (xy 99.824255 -277.832775)
			(xy 99.87343 -277.830794) (xy 99.922285 -277.836726) (xy 99.969556 -277.850418) (xy 100.014018 -277.871516)
			(xy 100.054521 -277.899472) (xy 100.090014 -277.933564) (xy 100.119579 -277.972908) (xy 100.14245 -278.016485)
			(xy 100.158034 -278.063166) (xy 100.165929 -278.111743) (xy 100.166424 -278.13635) (xy 100.495366 -278.13635)
			(xy 100.499326 -278.087296) (xy 100.511103 -278.039512) (xy 100.530394 -277.994236) (xy 100.556697 -277.95264)
			(xy 100.589332 -277.915803) (xy 100.627453 -277.884678) (xy 100.670074 -277.860071) (xy 100.71609 -277.842619)
			(xy 100.764309 -277.832775) (xy 100.813484 -277.830794) (xy 100.862339 -277.836726) (xy 100.90961 -277.850418)
			(xy 100.954072 -277.871516) (xy 100.994575 -277.899472) (xy 101.030068 -277.933564) (xy 101.059633 -277.972908)
			(xy 101.082504 -278.016485) (xy 101.098088 -278.063166) (xy 101.105983 -278.111743) (xy 101.106478 -278.13635)
			(xy 101.435166 -278.13635) (xy 101.439126 -278.087296) (xy 101.450903 -278.039512) (xy 101.470194 -277.994236)
			(xy 101.496497 -277.95264) (xy 101.529132 -277.915803) (xy 101.567253 -277.884678) (xy 101.609874 -277.860071)
			(xy 101.65589 -277.842619) (xy 101.704109 -277.832775) (xy 101.753284 -277.830794) (xy 101.802139 -277.836726)
			(xy 101.84941 -277.850418) (xy 101.893872 -277.871516) (xy 101.934375 -277.899472) (xy 101.969868 -277.933564)
			(xy 101.999433 -277.972908) (xy 102.022304 -278.016485) (xy 102.037888 -278.063166) (xy 102.045783 -278.111743)
			(xy 102.046278 -278.13635) (xy 102.37522 -278.13635) (xy 102.37918 -278.087296) (xy 102.390957 -278.039512)
			(xy 102.410248 -277.994236) (xy 102.436551 -277.95264) (xy 102.469186 -277.915803) (xy 102.507307 -277.884678)
			(xy 102.549928 -277.860071) (xy 102.595944 -277.842619) (xy 102.644163 -277.832775) (xy 102.693338 -277.830794)
			(xy 102.742193 -277.836726) (xy 102.789464 -277.850418) (xy 102.833926 -277.871516) (xy 102.874429 -277.899472)
			(xy 102.909922 -277.933564) (xy 102.939487 -277.972908) (xy 102.962358 -278.016485) (xy 102.977942 -278.063166)
			(xy 102.985837 -278.111743) (xy 102.986332 -278.13635) (xy 103.315274 -278.13635) (xy 103.319234 -278.087296)
			(xy 103.331011 -278.039512) (xy 103.350302 -277.994236) (xy 103.376605 -277.95264) (xy 103.40924 -277.915803)
			(xy 103.447361 -277.884678) (xy 103.489982 -277.860071) (xy 103.535998 -277.842619) (xy 103.584217 -277.832775)
			(xy 103.633392 -277.830794) (xy 103.682247 -277.836726) (xy 103.729518 -277.850418) (xy 103.77398 -277.871516)
			(xy 103.814483 -277.899472) (xy 103.849976 -277.933564) (xy 103.879541 -277.972908) (xy 103.902412 -278.016485)
			(xy 103.917996 -278.063166) (xy 103.925891 -278.111743) (xy 103.926386 -278.13635) (xy 104.255328 -278.13635)
			(xy 104.259288 -278.087296) (xy 104.271065 -278.039512) (xy 104.290356 -277.994236) (xy 104.316659 -277.95264)
			(xy 104.349294 -277.915803) (xy 104.387415 -277.884678) (xy 104.430036 -277.860071) (xy 104.476052 -277.842619)
			(xy 104.524271 -277.832775) (xy 104.573446 -277.830794) (xy 104.622301 -277.836726) (xy 104.669572 -277.850418)
			(xy 104.714034 -277.871516) (xy 104.754537 -277.899472) (xy 104.79003 -277.933564) (xy 104.819595 -277.972908)
			(xy 104.842466 -278.016485) (xy 104.85805 -278.063166) (xy 104.865945 -278.111743) (xy 104.86644 -278.13635)
			(xy 105.195128 -278.13635) (xy 105.199088 -278.087296) (xy 105.210865 -278.039512) (xy 105.230156 -277.994236)
			(xy 105.256459 -277.95264) (xy 105.289094 -277.915803) (xy 105.327215 -277.884678) (xy 105.369836 -277.860071)
			(xy 105.415852 -277.842619) (xy 105.464071 -277.832775) (xy 105.513246 -277.830794) (xy 105.562101 -277.836726)
			(xy 105.609372 -277.850418) (xy 105.653834 -277.871516) (xy 105.694337 -277.899472) (xy 105.72983 -277.933564)
			(xy 105.759395 -277.972908) (xy 105.782266 -278.016485) (xy 105.79785 -278.063166) (xy 105.805745 -278.111743)
			(xy 105.80624 -278.13635) (xy 106.135182 -278.13635) (xy 106.139142 -278.087296) (xy 106.150919 -278.039512)
			(xy 106.17021 -277.994236) (xy 106.196513 -277.95264) (xy 106.229148 -277.915803) (xy 106.267269 -277.884678)
			(xy 106.30989 -277.860071) (xy 106.355906 -277.842619) (xy 106.404125 -277.832775) (xy 106.4533 -277.830794)
			(xy 106.502155 -277.836726) (xy 106.549426 -277.850418) (xy 106.593888 -277.871516) (xy 106.634391 -277.899472)
			(xy 106.669884 -277.933564) (xy 106.699449 -277.972908) (xy 106.72232 -278.016485) (xy 106.737904 -278.063166)
			(xy 106.745799 -278.111743) (xy 106.746294 -278.13635) (xy 107.075236 -278.13635) (xy 107.079196 -278.087296)
			(xy 107.090973 -278.039512) (xy 107.110264 -277.994236) (xy 107.136567 -277.95264) (xy 107.169202 -277.915803)
			(xy 107.207323 -277.884678) (xy 107.249944 -277.860071) (xy 107.29596 -277.842619) (xy 107.344179 -277.832775)
			(xy 107.393354 -277.830794) (xy 107.442209 -277.836726) (xy 107.48948 -277.850418) (xy 107.533942 -277.871516)
			(xy 107.574445 -277.899472) (xy 107.609938 -277.933564) (xy 107.639503 -277.972908) (xy 107.662374 -278.016485)
			(xy 107.677958 -278.063166) (xy 107.685853 -278.111743) (xy 107.686348 -278.13635) (xy 108.01529 -278.13635)
			(xy 108.01925 -278.087296) (xy 108.031027 -278.039512) (xy 108.050318 -277.994236) (xy 108.076621 -277.95264)
			(xy 108.109256 -277.915803) (xy 108.147377 -277.884678) (xy 108.189998 -277.860071) (xy 108.236014 -277.842619)
			(xy 108.284233 -277.832775) (xy 108.333408 -277.830794) (xy 108.382263 -277.836726) (xy 108.429534 -277.850418)
			(xy 108.473996 -277.871516) (xy 108.514499 -277.899472) (xy 108.549992 -277.933564) (xy 108.579557 -277.972908)
			(xy 108.602428 -278.016485) (xy 108.618012 -278.063166) (xy 108.625907 -278.111743) (xy 108.626402 -278.13635)
			(xy 115.528864 -278.13635) (xy 115.532824 -278.087296) (xy 115.544601 -278.039512) (xy 115.563892 -277.994236)
			(xy 115.590195 -277.95264) (xy 115.62283 -277.915803) (xy 115.660951 -277.884678) (xy 115.703572 -277.860071)
			(xy 115.749588 -277.842619) (xy 115.797807 -277.832775) (xy 115.846982 -277.830794) (xy 115.895837 -277.836726)
			(xy 115.943108 -277.850418) (xy 115.98757 -277.871516) (xy 116.028073 -277.899472) (xy 116.063566 -277.933564)
			(xy 116.093131 -277.972908) (xy 116.116002 -278.016485) (xy 116.131586 -278.063166) (xy 116.139481 -278.111743)
			(xy 116.139976 -278.13635) (xy 116.468918 -278.13635) (xy 116.472878 -278.087296) (xy 116.484655 -278.039512)
			(xy 116.503946 -277.994236) (xy 116.530249 -277.95264) (xy 116.562884 -277.915803) (xy 116.601005 -277.884678)
			(xy 116.643626 -277.860071) (xy 116.689642 -277.842619) (xy 116.737861 -277.832775) (xy 116.787036 -277.830794)
			(xy 116.835891 -277.836726) (xy 116.883162 -277.850418) (xy 116.927624 -277.871516) (xy 116.968127 -277.899472)
			(xy 117.00362 -277.933564) (xy 117.033185 -277.972908) (xy 117.056056 -278.016485) (xy 117.07164 -278.063166)
			(xy 117.079535 -278.111743) (xy 117.08003 -278.13635) (xy 117.408972 -278.13635) (xy 117.412932 -278.087296)
			(xy 117.424709 -278.039512) (xy 117.444 -277.994236) (xy 117.470303 -277.95264) (xy 117.502938 -277.915803)
			(xy 117.541059 -277.884678) (xy 117.58368 -277.860071) (xy 117.629696 -277.842619) (xy 117.677915 -277.832775)
			(xy 117.72709 -277.830794) (xy 117.775945 -277.836726) (xy 117.823216 -277.850418) (xy 117.867678 -277.871516)
			(xy 117.908181 -277.899472) (xy 117.943674 -277.933564) (xy 117.973239 -277.972908) (xy 117.99611 -278.016485)
			(xy 118.011694 -278.063166) (xy 118.019589 -278.111743) (xy 118.020084 -278.13635) (xy 118.349026 -278.13635)
			(xy 118.352986 -278.087296) (xy 118.364763 -278.039512) (xy 118.384054 -277.994236) (xy 118.410357 -277.95264)
			(xy 118.442992 -277.915803) (xy 118.481113 -277.884678) (xy 118.523734 -277.860071) (xy 118.56975 -277.842619)
			(xy 118.617969 -277.832775) (xy 118.667144 -277.830794) (xy 118.715999 -277.836726) (xy 118.76327 -277.850418)
			(xy 118.807732 -277.871516) (xy 118.848235 -277.899472) (xy 118.883728 -277.933564) (xy 118.913293 -277.972908)
			(xy 118.936164 -278.016485) (xy 118.951748 -278.063166) (xy 118.959643 -278.111743) (xy 118.960138 -278.13635)
			(xy 119.288826 -278.13635) (xy 119.292786 -278.087296) (xy 119.304563 -278.039512) (xy 119.323854 -277.994236)
			(xy 119.350157 -277.95264) (xy 119.382792 -277.915803) (xy 119.420913 -277.884678) (xy 119.463534 -277.860071)
			(xy 119.50955 -277.842619) (xy 119.557769 -277.832775) (xy 119.606944 -277.830794) (xy 119.655799 -277.836726)
			(xy 119.70307 -277.850418) (xy 119.747532 -277.871516) (xy 119.788035 -277.899472) (xy 119.823528 -277.933564)
			(xy 119.853093 -277.972908) (xy 119.875964 -278.016485) (xy 119.891548 -278.063166) (xy 119.899443 -278.111743)
			(xy 119.899938 -278.13635) (xy 120.22888 -278.13635) (xy 120.23284 -278.087296) (xy 120.244617 -278.039512)
			(xy 120.263908 -277.994236) (xy 120.290211 -277.95264) (xy 120.322846 -277.915803) (xy 120.360967 -277.884678)
			(xy 120.403588 -277.860071) (xy 120.449604 -277.842619) (xy 120.497823 -277.832775) (xy 120.546998 -277.830794)
			(xy 120.595853 -277.836726) (xy 120.643124 -277.850418) (xy 120.687586 -277.871516) (xy 120.728089 -277.899472)
			(xy 120.763582 -277.933564) (xy 120.793147 -277.972908) (xy 120.816018 -278.016485) (xy 120.831602 -278.063166)
			(xy 120.839497 -278.111743) (xy 120.839992 -278.13635) (xy 121.168934 -278.13635) (xy 121.172894 -278.087296)
			(xy 121.184671 -278.039512) (xy 121.203962 -277.994236) (xy 121.230265 -277.95264) (xy 121.2629 -277.915803)
			(xy 121.301021 -277.884678) (xy 121.343642 -277.860071) (xy 121.389658 -277.842619) (xy 121.437877 -277.832775)
			(xy 121.487052 -277.830794) (xy 121.535907 -277.836726) (xy 121.583178 -277.850418) (xy 121.62764 -277.871516)
			(xy 121.668143 -277.899472) (xy 121.703636 -277.933564) (xy 121.733201 -277.972908) (xy 121.756072 -278.016485)
			(xy 121.771656 -278.063166) (xy 121.779551 -278.111743) (xy 121.780046 -278.13635) (xy 122.108988 -278.13635)
			(xy 122.112948 -278.087296) (xy 122.124725 -278.039512) (xy 122.144016 -277.994236) (xy 122.170319 -277.95264)
			(xy 122.202954 -277.915803) (xy 122.241075 -277.884678) (xy 122.283696 -277.860071) (xy 122.329712 -277.842619)
			(xy 122.377931 -277.832775) (xy 122.427106 -277.830794) (xy 122.475961 -277.836726) (xy 122.523232 -277.850418)
			(xy 122.567694 -277.871516) (xy 122.608197 -277.899472) (xy 122.64369 -277.933564) (xy 122.673255 -277.972908)
			(xy 122.696126 -278.016485) (xy 122.71171 -278.063166) (xy 122.719605 -278.111743) (xy 122.7201 -278.13635)
			(xy 123.049042 -278.13635) (xy 123.053002 -278.087296) (xy 123.064779 -278.039512) (xy 123.08407 -277.994236)
			(xy 123.110373 -277.95264) (xy 123.143008 -277.915803) (xy 123.181129 -277.884678) (xy 123.22375 -277.860071)
			(xy 123.269766 -277.842619) (xy 123.317985 -277.832775) (xy 123.36716 -277.830794) (xy 123.416015 -277.836726)
			(xy 123.463286 -277.850418) (xy 123.507748 -277.871516) (xy 123.548251 -277.899472) (xy 123.583744 -277.933564)
			(xy 123.613309 -277.972908) (xy 123.63618 -278.016485) (xy 123.651764 -278.063166) (xy 123.659659 -278.111743)
			(xy 123.660154 -278.13635) (xy 123.988842 -278.13635) (xy 123.992802 -278.087296) (xy 124.004579 -278.039512)
			(xy 124.02387 -277.994236) (xy 124.050173 -277.95264) (xy 124.082808 -277.915803) (xy 124.120929 -277.884678)
			(xy 124.16355 -277.860071) (xy 124.209566 -277.842619) (xy 124.257785 -277.832775) (xy 124.30696 -277.830794)
			(xy 124.355815 -277.836726) (xy 124.403086 -277.850418) (xy 124.447548 -277.871516) (xy 124.488051 -277.899472)
			(xy 124.523544 -277.933564) (xy 124.553109 -277.972908) (xy 124.57598 -278.016485) (xy 124.591564 -278.063166)
			(xy 124.599459 -278.111743) (xy 124.599954 -278.13635) (xy 124.928896 -278.13635) (xy 124.932856 -278.087296)
			(xy 124.944633 -278.039512) (xy 124.963924 -277.994236) (xy 124.990227 -277.95264) (xy 125.022862 -277.915803)
			(xy 125.060983 -277.884678) (xy 125.103604 -277.860071) (xy 125.14962 -277.842619) (xy 125.197839 -277.832775)
			(xy 125.247014 -277.830794) (xy 125.295869 -277.836726) (xy 125.34314 -277.850418) (xy 125.387602 -277.871516)
			(xy 125.428105 -277.899472) (xy 125.463598 -277.933564) (xy 125.493163 -277.972908) (xy 125.516034 -278.016485)
			(xy 125.531618 -278.063166) (xy 125.539513 -278.111743) (xy 125.540008 -278.13635) (xy 125.86895 -278.13635)
			(xy 125.87291 -278.087296) (xy 125.884687 -278.039512) (xy 125.903978 -277.994236) (xy 125.930281 -277.95264)
			(xy 125.962916 -277.915803) (xy 126.001037 -277.884678) (xy 126.043658 -277.860071) (xy 126.089674 -277.842619)
			(xy 126.137893 -277.832775) (xy 126.187068 -277.830794) (xy 126.235923 -277.836726) (xy 126.283194 -277.850418)
			(xy 126.327656 -277.871516) (xy 126.368159 -277.899472) (xy 126.403652 -277.933564) (xy 126.433217 -277.972908)
			(xy 126.456088 -278.016485) (xy 126.471672 -278.063166) (xy 126.479567 -278.111743) (xy 126.480062 -278.13635)
			(xy 126.479567 -278.160957) (xy 126.471672 -278.209534) (xy 126.456088 -278.256215) (xy 126.433217 -278.299792)
			(xy 126.403652 -278.339136) (xy 126.368159 -278.373228) (xy 126.327656 -278.401184) (xy 126.283194 -278.422282)
			(xy 126.235923 -278.435974) (xy 126.187068 -278.441906) (xy 126.137893 -278.439925) (xy 126.089674 -278.430081)
			(xy 126.043658 -278.412629) (xy 126.001037 -278.388022) (xy 125.962916 -278.356897) (xy 125.930281 -278.32006)
			(xy 125.903978 -278.278464) (xy 125.884687 -278.233188) (xy 125.87291 -278.185404) (xy 125.86895 -278.13635)
			(xy 125.540008 -278.13635) (xy 125.539513 -278.160957) (xy 125.531618 -278.209534) (xy 125.516034 -278.256215)
			(xy 125.493163 -278.299792) (xy 125.463598 -278.339136) (xy 125.428105 -278.373228) (xy 125.387602 -278.401184)
			(xy 125.34314 -278.422282) (xy 125.295869 -278.435974) (xy 125.247014 -278.441906) (xy 125.197839 -278.439925)
			(xy 125.14962 -278.430081) (xy 125.103604 -278.412629) (xy 125.060983 -278.388022) (xy 125.022862 -278.356897)
			(xy 124.990227 -278.32006) (xy 124.963924 -278.278464) (xy 124.944633 -278.233188) (xy 124.932856 -278.185404)
			(xy 124.928896 -278.13635) (xy 124.599954 -278.13635) (xy 124.599459 -278.160957) (xy 124.591564 -278.209534)
			(xy 124.57598 -278.256215) (xy 124.553109 -278.299792) (xy 124.523544 -278.339136) (xy 124.488051 -278.373228)
			(xy 124.447548 -278.401184) (xy 124.403086 -278.422282) (xy 124.355815 -278.435974) (xy 124.30696 -278.441906)
			(xy 124.257785 -278.439925) (xy 124.209566 -278.430081) (xy 124.16355 -278.412629) (xy 124.120929 -278.388022)
			(xy 124.082808 -278.356897) (xy 124.050173 -278.32006) (xy 124.02387 -278.278464) (xy 124.004579 -278.233188)
			(xy 123.992802 -278.185404) (xy 123.988842 -278.13635) (xy 123.660154 -278.13635) (xy 123.659659 -278.160957)
			(xy 123.651764 -278.209534) (xy 123.63618 -278.256215) (xy 123.613309 -278.299792) (xy 123.583744 -278.339136)
			(xy 123.548251 -278.373228) (xy 123.507748 -278.401184) (xy 123.463286 -278.422282) (xy 123.416015 -278.435974)
			(xy 123.36716 -278.441906) (xy 123.317985 -278.439925) (xy 123.269766 -278.430081) (xy 123.22375 -278.412629)
			(xy 123.181129 -278.388022) (xy 123.143008 -278.356897) (xy 123.110373 -278.32006) (xy 123.08407 -278.278464)
			(xy 123.064779 -278.233188) (xy 123.053002 -278.185404) (xy 123.049042 -278.13635) (xy 122.7201 -278.13635)
			(xy 122.719605 -278.160957) (xy 122.71171 -278.209534) (xy 122.696126 -278.256215) (xy 122.673255 -278.299792)
			(xy 122.64369 -278.339136) (xy 122.608197 -278.373228) (xy 122.567694 -278.401184) (xy 122.523232 -278.422282)
			(xy 122.475961 -278.435974) (xy 122.427106 -278.441906) (xy 122.377931 -278.439925) (xy 122.329712 -278.430081)
			(xy 122.283696 -278.412629) (xy 122.241075 -278.388022) (xy 122.202954 -278.356897) (xy 122.170319 -278.32006)
			(xy 122.144016 -278.278464) (xy 122.124725 -278.233188) (xy 122.112948 -278.185404) (xy 122.108988 -278.13635)
			(xy 121.780046 -278.13635) (xy 121.779551 -278.160957) (xy 121.771656 -278.209534) (xy 121.756072 -278.256215)
			(xy 121.733201 -278.299792) (xy 121.703636 -278.339136) (xy 121.668143 -278.373228) (xy 121.62764 -278.401184)
			(xy 121.583178 -278.422282) (xy 121.535907 -278.435974) (xy 121.487052 -278.441906) (xy 121.437877 -278.439925)
			(xy 121.389658 -278.430081) (xy 121.343642 -278.412629) (xy 121.301021 -278.388022) (xy 121.2629 -278.356897)
			(xy 121.230265 -278.32006) (xy 121.203962 -278.278464) (xy 121.184671 -278.233188) (xy 121.172894 -278.185404)
			(xy 121.168934 -278.13635) (xy 120.839992 -278.13635) (xy 120.839497 -278.160957) (xy 120.831602 -278.209534)
			(xy 120.816018 -278.256215) (xy 120.793147 -278.299792) (xy 120.763582 -278.339136) (xy 120.728089 -278.373228)
			(xy 120.687586 -278.401184) (xy 120.643124 -278.422282) (xy 120.595853 -278.435974) (xy 120.546998 -278.441906)
			(xy 120.497823 -278.439925) (xy 120.449604 -278.430081) (xy 120.403588 -278.412629) (xy 120.360967 -278.388022)
			(xy 120.322846 -278.356897) (xy 120.290211 -278.32006) (xy 120.263908 -278.278464) (xy 120.244617 -278.233188)
			(xy 120.23284 -278.185404) (xy 120.22888 -278.13635) (xy 119.899938 -278.13635) (xy 119.899443 -278.160957)
			(xy 119.891548 -278.209534) (xy 119.875964 -278.256215) (xy 119.853093 -278.299792) (xy 119.823528 -278.339136)
			(xy 119.788035 -278.373228) (xy 119.747532 -278.401184) (xy 119.70307 -278.422282) (xy 119.655799 -278.435974)
			(xy 119.606944 -278.441906) (xy 119.557769 -278.439925) (xy 119.50955 -278.430081) (xy 119.463534 -278.412629)
			(xy 119.420913 -278.388022) (xy 119.382792 -278.356897) (xy 119.350157 -278.32006) (xy 119.323854 -278.278464)
			(xy 119.304563 -278.233188) (xy 119.292786 -278.185404) (xy 119.288826 -278.13635) (xy 118.960138 -278.13635)
			(xy 118.959643 -278.160957) (xy 118.951748 -278.209534) (xy 118.936164 -278.256215) (xy 118.913293 -278.299792)
			(xy 118.883728 -278.339136) (xy 118.848235 -278.373228) (xy 118.807732 -278.401184) (xy 118.76327 -278.422282)
			(xy 118.715999 -278.435974) (xy 118.667144 -278.441906) (xy 118.617969 -278.439925) (xy 118.56975 -278.430081)
			(xy 118.523734 -278.412629) (xy 118.481113 -278.388022) (xy 118.442992 -278.356897) (xy 118.410357 -278.32006)
			(xy 118.384054 -278.278464) (xy 118.364763 -278.233188) (xy 118.352986 -278.185404) (xy 118.349026 -278.13635)
			(xy 118.020084 -278.13635) (xy 118.019589 -278.160957) (xy 118.011694 -278.209534) (xy 117.99611 -278.256215)
			(xy 117.973239 -278.299792) (xy 117.943674 -278.339136) (xy 117.908181 -278.373228) (xy 117.867678 -278.401184)
			(xy 117.823216 -278.422282) (xy 117.775945 -278.435974) (xy 117.72709 -278.441906) (xy 117.677915 -278.439925)
			(xy 117.629696 -278.430081) (xy 117.58368 -278.412629) (xy 117.541059 -278.388022) (xy 117.502938 -278.356897)
			(xy 117.470303 -278.32006) (xy 117.444 -278.278464) (xy 117.424709 -278.233188) (xy 117.412932 -278.185404)
			(xy 117.408972 -278.13635) (xy 117.08003 -278.13635) (xy 117.079535 -278.160957) (xy 117.07164 -278.209534)
			(xy 117.056056 -278.256215) (xy 117.033185 -278.299792) (xy 117.00362 -278.339136) (xy 116.968127 -278.373228)
			(xy 116.927624 -278.401184) (xy 116.883162 -278.422282) (xy 116.835891 -278.435974) (xy 116.787036 -278.441906)
			(xy 116.737861 -278.439925) (xy 116.689642 -278.430081) (xy 116.643626 -278.412629) (xy 116.601005 -278.388022)
			(xy 116.562884 -278.356897) (xy 116.530249 -278.32006) (xy 116.503946 -278.278464) (xy 116.484655 -278.233188)
			(xy 116.472878 -278.185404) (xy 116.468918 -278.13635) (xy 116.139976 -278.13635) (xy 116.139481 -278.160957)
			(xy 116.131586 -278.209534) (xy 116.116002 -278.256215) (xy 116.093131 -278.299792) (xy 116.063566 -278.339136)
			(xy 116.028073 -278.373228) (xy 115.98757 -278.401184) (xy 115.943108 -278.422282) (xy 115.895837 -278.435974)
			(xy 115.846982 -278.441906) (xy 115.797807 -278.439925) (xy 115.749588 -278.430081) (xy 115.703572 -278.412629)
			(xy 115.660951 -278.388022) (xy 115.62283 -278.356897) (xy 115.590195 -278.32006) (xy 115.563892 -278.278464)
			(xy 115.544601 -278.233188) (xy 115.532824 -278.185404) (xy 115.528864 -278.13635) (xy 108.626402 -278.13635)
			(xy 108.625907 -278.160957) (xy 108.618012 -278.209534) (xy 108.602428 -278.256215) (xy 108.579557 -278.299792)
			(xy 108.549992 -278.339136) (xy 108.514499 -278.373228) (xy 108.473996 -278.401184) (xy 108.429534 -278.422282)
			(xy 108.382263 -278.435974) (xy 108.333408 -278.441906) (xy 108.284233 -278.439925) (xy 108.236014 -278.430081)
			(xy 108.189998 -278.412629) (xy 108.147377 -278.388022) (xy 108.109256 -278.356897) (xy 108.076621 -278.32006)
			(xy 108.050318 -278.278464) (xy 108.031027 -278.233188) (xy 108.01925 -278.185404) (xy 108.01529 -278.13635)
			(xy 107.686348 -278.13635) (xy 107.685853 -278.160957) (xy 107.677958 -278.209534) (xy 107.662374 -278.256215)
			(xy 107.639503 -278.299792) (xy 107.609938 -278.339136) (xy 107.574445 -278.373228) (xy 107.533942 -278.401184)
			(xy 107.48948 -278.422282) (xy 107.442209 -278.435974) (xy 107.393354 -278.441906) (xy 107.344179 -278.439925)
			(xy 107.29596 -278.430081) (xy 107.249944 -278.412629) (xy 107.207323 -278.388022) (xy 107.169202 -278.356897)
			(xy 107.136567 -278.32006) (xy 107.110264 -278.278464) (xy 107.090973 -278.233188) (xy 107.079196 -278.185404)
			(xy 107.075236 -278.13635) (xy 106.746294 -278.13635) (xy 106.745799 -278.160957) (xy 106.737904 -278.209534)
			(xy 106.72232 -278.256215) (xy 106.699449 -278.299792) (xy 106.669884 -278.339136) (xy 106.634391 -278.373228)
			(xy 106.593888 -278.401184) (xy 106.549426 -278.422282) (xy 106.502155 -278.435974) (xy 106.4533 -278.441906)
			(xy 106.404125 -278.439925) (xy 106.355906 -278.430081) (xy 106.30989 -278.412629) (xy 106.267269 -278.388022)
			(xy 106.229148 -278.356897) (xy 106.196513 -278.32006) (xy 106.17021 -278.278464) (xy 106.150919 -278.233188)
			(xy 106.139142 -278.185404) (xy 106.135182 -278.13635) (xy 105.80624 -278.13635) (xy 105.805745 -278.160957)
			(xy 105.79785 -278.209534) (xy 105.782266 -278.256215) (xy 105.759395 -278.299792) (xy 105.72983 -278.339136)
			(xy 105.694337 -278.373228) (xy 105.653834 -278.401184) (xy 105.609372 -278.422282) (xy 105.562101 -278.435974)
			(xy 105.513246 -278.441906) (xy 105.464071 -278.439925) (xy 105.415852 -278.430081) (xy 105.369836 -278.412629)
			(xy 105.327215 -278.388022) (xy 105.289094 -278.356897) (xy 105.256459 -278.32006) (xy 105.230156 -278.278464)
			(xy 105.210865 -278.233188) (xy 105.199088 -278.185404) (xy 105.195128 -278.13635) (xy 104.86644 -278.13635)
			(xy 104.865945 -278.160957) (xy 104.85805 -278.209534) (xy 104.842466 -278.256215) (xy 104.819595 -278.299792)
			(xy 104.79003 -278.339136) (xy 104.754537 -278.373228) (xy 104.714034 -278.401184) (xy 104.669572 -278.422282)
			(xy 104.622301 -278.435974) (xy 104.573446 -278.441906) (xy 104.524271 -278.439925) (xy 104.476052 -278.430081)
			(xy 104.430036 -278.412629) (xy 104.387415 -278.388022) (xy 104.349294 -278.356897) (xy 104.316659 -278.32006)
			(xy 104.290356 -278.278464) (xy 104.271065 -278.233188) (xy 104.259288 -278.185404) (xy 104.255328 -278.13635)
			(xy 103.926386 -278.13635) (xy 103.925891 -278.160957) (xy 103.917996 -278.209534) (xy 103.902412 -278.256215)
			(xy 103.879541 -278.299792) (xy 103.849976 -278.339136) (xy 103.814483 -278.373228) (xy 103.77398 -278.401184)
			(xy 103.729518 -278.422282) (xy 103.682247 -278.435974) (xy 103.633392 -278.441906) (xy 103.584217 -278.439925)
			(xy 103.535998 -278.430081) (xy 103.489982 -278.412629) (xy 103.447361 -278.388022) (xy 103.40924 -278.356897)
			(xy 103.376605 -278.32006) (xy 103.350302 -278.278464) (xy 103.331011 -278.233188) (xy 103.319234 -278.185404)
			(xy 103.315274 -278.13635) (xy 102.986332 -278.13635) (xy 102.985837 -278.160957) (xy 102.977942 -278.209534)
			(xy 102.962358 -278.256215) (xy 102.939487 -278.299792) (xy 102.909922 -278.339136) (xy 102.874429 -278.373228)
			(xy 102.833926 -278.401184) (xy 102.789464 -278.422282) (xy 102.742193 -278.435974) (xy 102.693338 -278.441906)
			(xy 102.644163 -278.439925) (xy 102.595944 -278.430081) (xy 102.549928 -278.412629) (xy 102.507307 -278.388022)
			(xy 102.469186 -278.356897) (xy 102.436551 -278.32006) (xy 102.410248 -278.278464) (xy 102.390957 -278.233188)
			(xy 102.37918 -278.185404) (xy 102.37522 -278.13635) (xy 102.046278 -278.13635) (xy 102.045783 -278.160957)
			(xy 102.037888 -278.209534) (xy 102.022304 -278.256215) (xy 101.999433 -278.299792) (xy 101.969868 -278.339136)
			(xy 101.934375 -278.373228) (xy 101.893872 -278.401184) (xy 101.84941 -278.422282) (xy 101.802139 -278.435974)
			(xy 101.753284 -278.441906) (xy 101.704109 -278.439925) (xy 101.65589 -278.430081) (xy 101.609874 -278.412629)
			(xy 101.567253 -278.388022) (xy 101.529132 -278.356897) (xy 101.496497 -278.32006) (xy 101.470194 -278.278464)
			(xy 101.450903 -278.233188) (xy 101.439126 -278.185404) (xy 101.435166 -278.13635) (xy 101.106478 -278.13635)
			(xy 101.105983 -278.160957) (xy 101.098088 -278.209534) (xy 101.082504 -278.256215) (xy 101.059633 -278.299792)
			(xy 101.030068 -278.339136) (xy 100.994575 -278.373228) (xy 100.954072 -278.401184) (xy 100.90961 -278.422282)
			(xy 100.862339 -278.435974) (xy 100.813484 -278.441906) (xy 100.764309 -278.439925) (xy 100.71609 -278.430081)
			(xy 100.670074 -278.412629) (xy 100.627453 -278.388022) (xy 100.589332 -278.356897) (xy 100.556697 -278.32006)
			(xy 100.530394 -278.278464) (xy 100.511103 -278.233188) (xy 100.499326 -278.185404) (xy 100.495366 -278.13635)
			(xy 100.166424 -278.13635) (xy 100.165929 -278.160957) (xy 100.158034 -278.209534) (xy 100.14245 -278.256215)
			(xy 100.119579 -278.299792) (xy 100.090014 -278.339136) (xy 100.054521 -278.373228) (xy 100.014018 -278.401184)
			(xy 99.969556 -278.422282) (xy 99.922285 -278.435974) (xy 99.87343 -278.441906) (xy 99.824255 -278.439925)
			(xy 99.776036 -278.430081) (xy 99.73002 -278.412629) (xy 99.687399 -278.388022) (xy 99.649278 -278.356897)
			(xy 99.616643 -278.32006) (xy 99.59034 -278.278464) (xy 99.571049 -278.233188) (xy 99.559272 -278.185404)
			(xy 99.555312 -278.13635) (xy 99.22637 -278.13635) (xy 99.225875 -278.160957) (xy 99.21798 -278.209534)
			(xy 99.202396 -278.256215) (xy 99.179525 -278.299792) (xy 99.14996 -278.339136) (xy 99.114467 -278.373228)
			(xy 99.073964 -278.401184) (xy 99.029502 -278.422282) (xy 98.982231 -278.435974) (xy 98.933376 -278.441906)
			(xy 98.884201 -278.439925) (xy 98.835982 -278.430081) (xy 98.789966 -278.412629) (xy 98.747345 -278.388022)
			(xy 98.709224 -278.356897) (xy 98.676589 -278.32006) (xy 98.650286 -278.278464) (xy 98.630995 -278.233188)
			(xy 98.619218 -278.185404) (xy 98.615258 -278.13635) (xy 98.286316 -278.13635) (xy 98.285821 -278.160957)
			(xy 98.277926 -278.209534) (xy 98.262342 -278.256215) (xy 98.239471 -278.299792) (xy 98.209906 -278.339136)
			(xy 98.174413 -278.373228) (xy 98.13391 -278.401184) (xy 98.089448 -278.422282) (xy 98.042177 -278.435974)
			(xy 97.993322 -278.441906) (xy 97.944147 -278.439925) (xy 97.895928 -278.430081) (xy 97.849912 -278.412629)
			(xy 97.807291 -278.388022) (xy 97.76917 -278.356897) (xy 97.736535 -278.32006) (xy 97.710232 -278.278464)
			(xy 97.690941 -278.233188) (xy 97.679164 -278.185404) (xy 97.675204 -278.13635) (xy 97.346516 -278.13635)
			(xy 97.345972 -278.162699) (xy 97.336938 -278.214618) (xy 97.319113 -278.26421) (xy 97.293028 -278.31)
			(xy 97.276666 -278.33066) (xy 97.271332 -278.337264) (xy 97.262442 -278.36114) (xy 97.260924 -278.365428)
			(xy 97.259269 -278.374372) (xy 97.25914 -278.37892) (xy 97.25914 -278.946356) (xy 99.085158 -278.946356)
			(xy 99.089118 -278.897302) (xy 99.100895 -278.849518) (xy 99.120186 -278.804242) (xy 99.146489 -278.762646)
			(xy 99.179124 -278.725809) (xy 99.217245 -278.694684) (xy 99.259866 -278.670077) (xy 99.305882 -278.652625)
			(xy 99.354101 -278.642781) (xy 99.403276 -278.6408) (xy 99.452131 -278.646732) (xy 99.499402 -278.660424)
			(xy 99.543864 -278.681522) (xy 99.584367 -278.709478) (xy 99.61986 -278.74357) (xy 99.649425 -278.782914)
			(xy 99.672296 -278.826491) (xy 99.68788 -278.873172) (xy 99.695775 -278.921749) (xy 99.69627 -278.946356)
			(xy 101.90532 -278.946356) (xy 101.90928 -278.897302) (xy 101.921057 -278.849518) (xy 101.940348 -278.804242)
			(xy 101.966651 -278.762646) (xy 101.999286 -278.725809) (xy 102.037407 -278.694684) (xy 102.080028 -278.670077)
			(xy 102.126044 -278.652625) (xy 102.174263 -278.642781) (xy 102.223438 -278.6408) (xy 102.272293 -278.646732)
			(xy 102.319564 -278.660424) (xy 102.364026 -278.681522) (xy 102.404529 -278.709478) (xy 102.440022 -278.74357)
			(xy 102.469587 -278.782914) (xy 102.492458 -278.826491) (xy 102.508042 -278.873172) (xy 102.515937 -278.921749)
			(xy 102.516432 -278.946356) (xy 104.725228 -278.946356) (xy 104.729188 -278.897302) (xy 104.740965 -278.849518)
			(xy 104.760256 -278.804242) (xy 104.786559 -278.762646) (xy 104.819194 -278.725809) (xy 104.857315 -278.694684)
			(xy 104.899936 -278.670077) (xy 104.945952 -278.652625) (xy 104.994171 -278.642781) (xy 105.043346 -278.6408)
			(xy 105.092201 -278.646732) (xy 105.139472 -278.660424) (xy 105.183934 -278.681522) (xy 105.224437 -278.709478)
			(xy 105.25993 -278.74357) (xy 105.289495 -278.782914) (xy 105.312366 -278.826491) (xy 105.32795 -278.873172)
			(xy 105.335845 -278.921749) (xy 105.33634 -278.946356) (xy 107.545136 -278.946356) (xy 107.549096 -278.897302)
			(xy 107.560873 -278.849518) (xy 107.580164 -278.804242) (xy 107.606467 -278.762646) (xy 107.639102 -278.725809)
			(xy 107.677223 -278.694684) (xy 107.719844 -278.670077) (xy 107.76586 -278.652625) (xy 107.814079 -278.642781)
			(xy 107.863254 -278.6408) (xy 107.912109 -278.646732) (xy 107.95938 -278.660424) (xy 108.003842 -278.681522)
			(xy 108.044345 -278.709478) (xy 108.079838 -278.74357) (xy 108.109403 -278.782914) (xy 108.132274 -278.826491)
			(xy 108.147858 -278.873172) (xy 108.155753 -278.921749) (xy 108.156248 -278.946356) (xy 108.48519 -278.946356)
			(xy 108.48915 -278.897302) (xy 108.500927 -278.849518) (xy 108.520218 -278.804242) (xy 108.546521 -278.762646)
			(xy 108.579156 -278.725809) (xy 108.617277 -278.694684) (xy 108.659898 -278.670077) (xy 108.705914 -278.652625)
			(xy 108.754133 -278.642781) (xy 108.803308 -278.6408) (xy 108.852163 -278.646732) (xy 108.899434 -278.660424)
			(xy 108.943896 -278.681522) (xy 108.984399 -278.709478) (xy 109.019892 -278.74357) (xy 109.049457 -278.782914)
			(xy 109.072328 -278.826491) (xy 109.087912 -278.873172) (xy 109.095807 -278.921749) (xy 109.096302 -278.946356)
			(xy 109.425244 -278.946356) (xy 109.429204 -278.897302) (xy 109.440981 -278.849518) (xy 109.460272 -278.804242)
			(xy 109.486575 -278.762646) (xy 109.51921 -278.725809) (xy 109.557331 -278.694684) (xy 109.599952 -278.670077)
			(xy 109.645968 -278.652625) (xy 109.694187 -278.642781) (xy 109.743362 -278.6408) (xy 109.792217 -278.646732)
			(xy 109.839488 -278.660424) (xy 109.88395 -278.681522) (xy 109.924453 -278.709478) (xy 109.959946 -278.74357)
			(xy 109.989511 -278.782914) (xy 110.012382 -278.826491) (xy 110.027966 -278.873172) (xy 110.035861 -278.921749)
			(xy 110.036356 -278.946356) (xy 110.365298 -278.946356) (xy 110.369258 -278.897302) (xy 110.381035 -278.849518)
			(xy 110.400326 -278.804242) (xy 110.426629 -278.762646) (xy 110.459264 -278.725809) (xy 110.497385 -278.694684)
			(xy 110.540006 -278.670077) (xy 110.586022 -278.652625) (xy 110.634241 -278.642781) (xy 110.683416 -278.6408)
			(xy 110.732271 -278.646732) (xy 110.779542 -278.660424) (xy 110.824004 -278.681522) (xy 110.864507 -278.709478)
			(xy 110.9 -278.74357) (xy 110.929565 -278.782914) (xy 110.952436 -278.826491) (xy 110.96802 -278.873172)
			(xy 110.975915 -278.921749) (xy 110.97641 -278.946356) (xy 113.178856 -278.946356) (xy 113.182816 -278.897302)
			(xy 113.194593 -278.849518) (xy 113.213884 -278.804242) (xy 113.240187 -278.762646) (xy 113.272822 -278.725809)
			(xy 113.310943 -278.694684) (xy 113.353564 -278.670077) (xy 113.39958 -278.652625) (xy 113.447799 -278.642781)
			(xy 113.496974 -278.6408) (xy 113.545829 -278.646732) (xy 113.5931 -278.660424) (xy 113.637562 -278.681522)
			(xy 113.678065 -278.709478) (xy 113.713558 -278.74357) (xy 113.743123 -278.782914) (xy 113.765994 -278.826491)
			(xy 113.781578 -278.873172) (xy 113.789473 -278.921749) (xy 113.789968 -278.946356) (xy 114.11891 -278.946356)
			(xy 114.12287 -278.897302) (xy 114.134647 -278.849518) (xy 114.153938 -278.804242) (xy 114.180241 -278.762646)
			(xy 114.212876 -278.725809) (xy 114.250997 -278.694684) (xy 114.293618 -278.670077) (xy 114.339634 -278.652625)
			(xy 114.387853 -278.642781) (xy 114.437028 -278.6408) (xy 114.485883 -278.646732) (xy 114.533154 -278.660424)
			(xy 114.577616 -278.681522) (xy 114.618119 -278.709478) (xy 114.653612 -278.74357) (xy 114.683177 -278.782914)
			(xy 114.706048 -278.826491) (xy 114.721632 -278.873172) (xy 114.729527 -278.921749) (xy 114.730022 -278.946356)
			(xy 115.058964 -278.946356) (xy 115.062924 -278.897302) (xy 115.074701 -278.849518) (xy 115.093992 -278.804242)
			(xy 115.120295 -278.762646) (xy 115.15293 -278.725809) (xy 115.191051 -278.694684) (xy 115.233672 -278.670077)
			(xy 115.279688 -278.652625) (xy 115.327907 -278.642781) (xy 115.377082 -278.6408) (xy 115.425937 -278.646732)
			(xy 115.473208 -278.660424) (xy 115.51767 -278.681522) (xy 115.558173 -278.709478) (xy 115.593666 -278.74357)
			(xy 115.623231 -278.782914) (xy 115.646102 -278.826491) (xy 115.661686 -278.873172) (xy 115.669581 -278.921749)
			(xy 115.670076 -278.946356) (xy 115.999018 -278.946356) (xy 116.002978 -278.897302) (xy 116.014755 -278.849518)
			(xy 116.034046 -278.804242) (xy 116.060349 -278.762646) (xy 116.092984 -278.725809) (xy 116.131105 -278.694684)
			(xy 116.173726 -278.670077) (xy 116.219742 -278.652625) (xy 116.267961 -278.642781) (xy 116.317136 -278.6408)
			(xy 116.365991 -278.646732) (xy 116.413262 -278.660424) (xy 116.457724 -278.681522) (xy 116.498227 -278.709478)
			(xy 116.53372 -278.74357) (xy 116.563285 -278.782914) (xy 116.586156 -278.826491) (xy 116.60174 -278.873172)
			(xy 116.609635 -278.921749) (xy 116.61013 -278.946356) (xy 118.818926 -278.946356) (xy 118.822886 -278.897302)
			(xy 118.834663 -278.849518) (xy 118.853954 -278.804242) (xy 118.880257 -278.762646) (xy 118.912892 -278.725809)
			(xy 118.951013 -278.694684) (xy 118.993634 -278.670077) (xy 119.03965 -278.652625) (xy 119.087869 -278.642781)
			(xy 119.137044 -278.6408) (xy 119.185899 -278.646732) (xy 119.23317 -278.660424) (xy 119.277632 -278.681522)
			(xy 119.318135 -278.709478) (xy 119.353628 -278.74357) (xy 119.383193 -278.782914) (xy 119.406064 -278.826491)
			(xy 119.421648 -278.873172) (xy 119.429543 -278.921749) (xy 119.430038 -278.946356) (xy 121.638834 -278.946356)
			(xy 121.642794 -278.897302) (xy 121.654571 -278.849518) (xy 121.673862 -278.804242) (xy 121.700165 -278.762646)
			(xy 121.7328 -278.725809) (xy 121.770921 -278.694684) (xy 121.813542 -278.670077) (xy 121.859558 -278.652625)
			(xy 121.907777 -278.642781) (xy 121.956952 -278.6408) (xy 122.005807 -278.646732) (xy 122.053078 -278.660424)
			(xy 122.09754 -278.681522) (xy 122.138043 -278.709478) (xy 122.173536 -278.74357) (xy 122.203101 -278.782914)
			(xy 122.225972 -278.826491) (xy 122.241556 -278.873172) (xy 122.249451 -278.921749) (xy 122.249946 -278.946356)
			(xy 124.458996 -278.946356) (xy 124.462956 -278.897302) (xy 124.474733 -278.849518) (xy 124.494024 -278.804242)
			(xy 124.520327 -278.762646) (xy 124.552962 -278.725809) (xy 124.591083 -278.694684) (xy 124.633704 -278.670077)
			(xy 124.67972 -278.652625) (xy 124.727939 -278.642781) (xy 124.777114 -278.6408) (xy 124.825969 -278.646732)
			(xy 124.87324 -278.660424) (xy 124.917702 -278.681522) (xy 124.958205 -278.709478) (xy 124.993698 -278.74357)
			(xy 125.023263 -278.782914) (xy 125.046134 -278.826491) (xy 125.061718 -278.873172) (xy 125.069613 -278.921749)
			(xy 125.070108 -278.946356) (xy 125.069613 -278.970963) (xy 125.061718 -279.01954) (xy 125.046134 -279.066221)
			(xy 125.023263 -279.109798) (xy 124.993698 -279.149142) (xy 124.958205 -279.183234) (xy 124.917702 -279.21119)
			(xy 124.87324 -279.232288) (xy 124.825969 -279.24598) (xy 124.777114 -279.251912) (xy 124.727939 -279.249931)
			(xy 124.67972 -279.240087) (xy 124.633704 -279.222635) (xy 124.591083 -279.198028) (xy 124.552962 -279.166903)
			(xy 124.520327 -279.130066) (xy 124.494024 -279.08847) (xy 124.474733 -279.043194) (xy 124.462956 -278.99541)
			(xy 124.458996 -278.946356) (xy 122.249946 -278.946356) (xy 122.249451 -278.970963) (xy 122.241556 -279.01954)
			(xy 122.225972 -279.066221) (xy 122.203101 -279.109798) (xy 122.173536 -279.149142) (xy 122.138043 -279.183234)
			(xy 122.09754 -279.21119) (xy 122.053078 -279.232288) (xy 122.005807 -279.24598) (xy 121.956952 -279.251912)
			(xy 121.907777 -279.249931) (xy 121.859558 -279.240087) (xy 121.813542 -279.222635) (xy 121.770921 -279.198028)
			(xy 121.7328 -279.166903) (xy 121.700165 -279.130066) (xy 121.673862 -279.08847) (xy 121.654571 -279.043194)
			(xy 121.642794 -278.99541) (xy 121.638834 -278.946356) (xy 119.430038 -278.946356) (xy 119.429543 -278.970963)
			(xy 119.421648 -279.01954) (xy 119.406064 -279.066221) (xy 119.383193 -279.109798) (xy 119.353628 -279.149142)
			(xy 119.318135 -279.183234) (xy 119.277632 -279.21119) (xy 119.23317 -279.232288) (xy 119.185899 -279.24598)
			(xy 119.137044 -279.251912) (xy 119.087869 -279.249931) (xy 119.03965 -279.240087) (xy 118.993634 -279.222635)
			(xy 118.951013 -279.198028) (xy 118.912892 -279.166903) (xy 118.880257 -279.130066) (xy 118.853954 -279.08847)
			(xy 118.834663 -279.043194) (xy 118.822886 -278.99541) (xy 118.818926 -278.946356) (xy 116.61013 -278.946356)
			(xy 116.609635 -278.970963) (xy 116.60174 -279.01954) (xy 116.586156 -279.066221) (xy 116.563285 -279.109798)
			(xy 116.53372 -279.149142) (xy 116.498227 -279.183234) (xy 116.457724 -279.21119) (xy 116.413262 -279.232288)
			(xy 116.365991 -279.24598) (xy 116.317136 -279.251912) (xy 116.267961 -279.249931) (xy 116.219742 -279.240087)
			(xy 116.173726 -279.222635) (xy 116.131105 -279.198028) (xy 116.092984 -279.166903) (xy 116.060349 -279.130066)
			(xy 116.034046 -279.08847) (xy 116.014755 -279.043194) (xy 116.002978 -278.99541) (xy 115.999018 -278.946356)
			(xy 115.670076 -278.946356) (xy 115.669581 -278.970963) (xy 115.661686 -279.01954) (xy 115.646102 -279.066221)
			(xy 115.623231 -279.109798) (xy 115.593666 -279.149142) (xy 115.558173 -279.183234) (xy 115.51767 -279.21119)
			(xy 115.473208 -279.232288) (xy 115.425937 -279.24598) (xy 115.377082 -279.251912) (xy 115.327907 -279.249931)
			(xy 115.279688 -279.240087) (xy 115.233672 -279.222635) (xy 115.191051 -279.198028) (xy 115.15293 -279.166903)
			(xy 115.120295 -279.130066) (xy 115.093992 -279.08847) (xy 115.074701 -279.043194) (xy 115.062924 -278.99541)
			(xy 115.058964 -278.946356) (xy 114.730022 -278.946356) (xy 114.729527 -278.970963) (xy 114.721632 -279.01954)
			(xy 114.706048 -279.066221) (xy 114.683177 -279.109798) (xy 114.653612 -279.149142) (xy 114.618119 -279.183234)
			(xy 114.577616 -279.21119) (xy 114.533154 -279.232288) (xy 114.485883 -279.24598) (xy 114.437028 -279.251912)
			(xy 114.387853 -279.249931) (xy 114.339634 -279.240087) (xy 114.293618 -279.222635) (xy 114.250997 -279.198028)
			(xy 114.212876 -279.166903) (xy 114.180241 -279.130066) (xy 114.153938 -279.08847) (xy 114.134647 -279.043194)
			(xy 114.12287 -278.99541) (xy 114.11891 -278.946356) (xy 113.789968 -278.946356) (xy 113.789473 -278.970963)
			(xy 113.781578 -279.01954) (xy 113.765994 -279.066221) (xy 113.743123 -279.109798) (xy 113.713558 -279.149142)
			(xy 113.678065 -279.183234) (xy 113.637562 -279.21119) (xy 113.5931 -279.232288) (xy 113.545829 -279.24598)
			(xy 113.496974 -279.251912) (xy 113.447799 -279.249931) (xy 113.39958 -279.240087) (xy 113.353564 -279.222635)
			(xy 113.310943 -279.198028) (xy 113.272822 -279.166903) (xy 113.240187 -279.130066) (xy 113.213884 -279.08847)
			(xy 113.194593 -279.043194) (xy 113.182816 -278.99541) (xy 113.178856 -278.946356) (xy 110.97641 -278.946356)
			(xy 110.975915 -278.970963) (xy 110.96802 -279.01954) (xy 110.952436 -279.066221) (xy 110.929565 -279.109798)
			(xy 110.9 -279.149142) (xy 110.864507 -279.183234) (xy 110.824004 -279.21119) (xy 110.779542 -279.232288)
			(xy 110.732271 -279.24598) (xy 110.683416 -279.251912) (xy 110.634241 -279.249931) (xy 110.586022 -279.240087)
			(xy 110.540006 -279.222635) (xy 110.497385 -279.198028) (xy 110.459264 -279.166903) (xy 110.426629 -279.130066)
			(xy 110.400326 -279.08847) (xy 110.381035 -279.043194) (xy 110.369258 -278.99541) (xy 110.365298 -278.946356)
			(xy 110.036356 -278.946356) (xy 110.035861 -278.970963) (xy 110.027966 -279.01954) (xy 110.012382 -279.066221)
			(xy 109.989511 -279.109798) (xy 109.959946 -279.149142) (xy 109.924453 -279.183234) (xy 109.88395 -279.21119)
			(xy 109.839488 -279.232288) (xy 109.792217 -279.24598) (xy 109.743362 -279.251912) (xy 109.694187 -279.249931)
			(xy 109.645968 -279.240087) (xy 109.599952 -279.222635) (xy 109.557331 -279.198028) (xy 109.51921 -279.166903)
			(xy 109.486575 -279.130066) (xy 109.460272 -279.08847) (xy 109.440981 -279.043194) (xy 109.429204 -278.99541)
			(xy 109.425244 -278.946356) (xy 109.096302 -278.946356) (xy 109.095807 -278.970963) (xy 109.087912 -279.01954)
			(xy 109.072328 -279.066221) (xy 109.049457 -279.109798) (xy 109.019892 -279.149142) (xy 108.984399 -279.183234)
			(xy 108.943896 -279.21119) (xy 108.899434 -279.232288) (xy 108.852163 -279.24598) (xy 108.803308 -279.251912)
			(xy 108.754133 -279.249931) (xy 108.705914 -279.240087) (xy 108.659898 -279.222635) (xy 108.617277 -279.198028)
			(xy 108.579156 -279.166903) (xy 108.546521 -279.130066) (xy 108.520218 -279.08847) (xy 108.500927 -279.043194)
			(xy 108.48915 -278.99541) (xy 108.48519 -278.946356) (xy 108.156248 -278.946356) (xy 108.155753 -278.970963)
			(xy 108.147858 -279.01954) (xy 108.132274 -279.066221) (xy 108.109403 -279.109798) (xy 108.079838 -279.149142)
			(xy 108.044345 -279.183234) (xy 108.003842 -279.21119) (xy 107.95938 -279.232288) (xy 107.912109 -279.24598)
			(xy 107.863254 -279.251912) (xy 107.814079 -279.249931) (xy 107.76586 -279.240087) (xy 107.719844 -279.222635)
			(xy 107.677223 -279.198028) (xy 107.639102 -279.166903) (xy 107.606467 -279.130066) (xy 107.580164 -279.08847)
			(xy 107.560873 -279.043194) (xy 107.549096 -278.99541) (xy 107.545136 -278.946356) (xy 105.33634 -278.946356)
			(xy 105.335845 -278.970963) (xy 105.32795 -279.01954) (xy 105.312366 -279.066221) (xy 105.289495 -279.109798)
			(xy 105.25993 -279.149142) (xy 105.224437 -279.183234) (xy 105.183934 -279.21119) (xy 105.139472 -279.232288)
			(xy 105.092201 -279.24598) (xy 105.043346 -279.251912) (xy 104.994171 -279.249931) (xy 104.945952 -279.240087)
			(xy 104.899936 -279.222635) (xy 104.857315 -279.198028) (xy 104.819194 -279.166903) (xy 104.786559 -279.130066)
			(xy 104.760256 -279.08847) (xy 104.740965 -279.043194) (xy 104.729188 -278.99541) (xy 104.725228 -278.946356)
			(xy 102.516432 -278.946356) (xy 102.515937 -278.970963) (xy 102.508042 -279.01954) (xy 102.492458 -279.066221)
			(xy 102.469587 -279.109798) (xy 102.440022 -279.149142) (xy 102.404529 -279.183234) (xy 102.364026 -279.21119)
			(xy 102.319564 -279.232288) (xy 102.272293 -279.24598) (xy 102.223438 -279.251912) (xy 102.174263 -279.249931)
			(xy 102.126044 -279.240087) (xy 102.080028 -279.222635) (xy 102.037407 -279.198028) (xy 101.999286 -279.166903)
			(xy 101.966651 -279.130066) (xy 101.940348 -279.08847) (xy 101.921057 -279.043194) (xy 101.90928 -278.99541)
			(xy 101.90532 -278.946356) (xy 99.69627 -278.946356) (xy 99.695775 -278.970963) (xy 99.68788 -279.01954)
			(xy 99.672296 -279.066221) (xy 99.649425 -279.109798) (xy 99.61986 -279.149142) (xy 99.584367 -279.183234)
			(xy 99.543864 -279.21119) (xy 99.499402 -279.232288) (xy 99.452131 -279.24598) (xy 99.403276 -279.251912)
			(xy 99.354101 -279.249931) (xy 99.305882 -279.240087) (xy 99.259866 -279.222635) (xy 99.217245 -279.198028)
			(xy 99.179124 -279.166903) (xy 99.146489 -279.130066) (xy 99.120186 -279.08847) (xy 99.100895 -279.043194)
			(xy 99.089118 -278.99541) (xy 99.085158 -278.946356) (xy 97.25914 -278.946356) (xy 97.25914 -279.513792)
			(xy 97.259266 -279.518339) (xy 97.260931 -279.527281) (xy 97.262442 -279.531572) (xy 97.271332 -279.555448)
			(xy 97.276666 -279.562052) (xy 97.292989 -279.582736) (xy 97.319029 -279.628538) (xy 97.336848 -279.67812)
			(xy 97.34592 -279.730019) (xy 97.346516 -279.756362) (xy 97.675204 -279.756362) (xy 97.679164 -279.707308)
			(xy 97.690941 -279.659524) (xy 97.710232 -279.614248) (xy 97.736535 -279.572652) (xy 97.76917 -279.535815)
			(xy 97.807291 -279.50469) (xy 97.849912 -279.480083) (xy 97.895928 -279.462631) (xy 97.944147 -279.452787)
			(xy 97.993322 -279.450806) (xy 98.042177 -279.456738) (xy 98.089448 -279.47043) (xy 98.13391 -279.491528)
			(xy 98.174413 -279.519484) (xy 98.209906 -279.553576) (xy 98.239471 -279.59292) (xy 98.262342 -279.636497)
			(xy 98.277926 -279.683178) (xy 98.285821 -279.731755) (xy 98.286316 -279.756362) (xy 98.615258 -279.756362)
			(xy 98.619218 -279.707308) (xy 98.630995 -279.659524) (xy 98.650286 -279.614248) (xy 98.676589 -279.572652)
			(xy 98.709224 -279.535815) (xy 98.747345 -279.50469) (xy 98.789966 -279.480083) (xy 98.835982 -279.462631)
			(xy 98.884201 -279.452787) (xy 98.933376 -279.450806) (xy 98.982231 -279.456738) (xy 99.029502 -279.47043)
			(xy 99.073964 -279.491528) (xy 99.114467 -279.519484) (xy 99.14996 -279.553576) (xy 99.179525 -279.59292)
			(xy 99.202396 -279.636497) (xy 99.21798 -279.683178) (xy 99.225875 -279.731755) (xy 99.22637 -279.756362)
			(xy 99.555312 -279.756362) (xy 99.559272 -279.707308) (xy 99.571049 -279.659524) (xy 99.59034 -279.614248)
			(xy 99.616643 -279.572652) (xy 99.649278 -279.535815) (xy 99.687399 -279.50469) (xy 99.73002 -279.480083)
			(xy 99.776036 -279.462631) (xy 99.824255 -279.452787) (xy 99.87343 -279.450806) (xy 99.922285 -279.456738)
			(xy 99.969556 -279.47043) (xy 100.014018 -279.491528) (xy 100.054521 -279.519484) (xy 100.090014 -279.553576)
			(xy 100.119579 -279.59292) (xy 100.14245 -279.636497) (xy 100.158034 -279.683178) (xy 100.165929 -279.731755)
			(xy 100.166424 -279.756362) (xy 100.495366 -279.756362) (xy 100.499326 -279.707308) (xy 100.511103 -279.659524)
			(xy 100.530394 -279.614248) (xy 100.556697 -279.572652) (xy 100.589332 -279.535815) (xy 100.627453 -279.50469)
			(xy 100.670074 -279.480083) (xy 100.71609 -279.462631) (xy 100.764309 -279.452787) (xy 100.813484 -279.450806)
			(xy 100.862339 -279.456738) (xy 100.90961 -279.47043) (xy 100.954072 -279.491528) (xy 100.994575 -279.519484)
			(xy 101.030068 -279.553576) (xy 101.059633 -279.59292) (xy 101.082504 -279.636497) (xy 101.098088 -279.683178)
			(xy 101.105983 -279.731755) (xy 101.106478 -279.756362) (xy 101.435166 -279.756362) (xy 101.439126 -279.707308)
			(xy 101.450903 -279.659524) (xy 101.470194 -279.614248) (xy 101.496497 -279.572652) (xy 101.529132 -279.535815)
			(xy 101.567253 -279.50469) (xy 101.609874 -279.480083) (xy 101.65589 -279.462631) (xy 101.704109 -279.452787)
			(xy 101.753284 -279.450806) (xy 101.802139 -279.456738) (xy 101.84941 -279.47043) (xy 101.893872 -279.491528)
			(xy 101.934375 -279.519484) (xy 101.969868 -279.553576) (xy 101.999433 -279.59292) (xy 102.022304 -279.636497)
			(xy 102.037888 -279.683178) (xy 102.045783 -279.731755) (xy 102.046278 -279.756362) (xy 102.37522 -279.756362)
			(xy 102.37918 -279.707308) (xy 102.390957 -279.659524) (xy 102.410248 -279.614248) (xy 102.436551 -279.572652)
			(xy 102.469186 -279.535815) (xy 102.507307 -279.50469) (xy 102.549928 -279.480083) (xy 102.595944 -279.462631)
			(xy 102.644163 -279.452787) (xy 102.693338 -279.450806) (xy 102.742193 -279.456738) (xy 102.789464 -279.47043)
			(xy 102.833926 -279.491528) (xy 102.874429 -279.519484) (xy 102.909922 -279.553576) (xy 102.939487 -279.59292)
			(xy 102.962358 -279.636497) (xy 102.977942 -279.683178) (xy 102.985837 -279.731755) (xy 102.986332 -279.756362)
			(xy 103.315274 -279.756362) (xy 103.319234 -279.707308) (xy 103.331011 -279.659524) (xy 103.350302 -279.614248)
			(xy 103.376605 -279.572652) (xy 103.40924 -279.535815) (xy 103.447361 -279.50469) (xy 103.489982 -279.480083)
			(xy 103.535998 -279.462631) (xy 103.584217 -279.452787) (xy 103.633392 -279.450806) (xy 103.682247 -279.456738)
			(xy 103.729518 -279.47043) (xy 103.77398 -279.491528) (xy 103.814483 -279.519484) (xy 103.849976 -279.553576)
			(xy 103.879541 -279.59292) (xy 103.902412 -279.636497) (xy 103.917996 -279.683178) (xy 103.925891 -279.731755)
			(xy 103.926386 -279.756362) (xy 104.255328 -279.756362) (xy 104.259288 -279.707308) (xy 104.271065 -279.659524)
			(xy 104.290356 -279.614248) (xy 104.316659 -279.572652) (xy 104.349294 -279.535815) (xy 104.387415 -279.50469)
			(xy 104.430036 -279.480083) (xy 104.476052 -279.462631) (xy 104.524271 -279.452787) (xy 104.573446 -279.450806)
			(xy 104.622301 -279.456738) (xy 104.669572 -279.47043) (xy 104.714034 -279.491528) (xy 104.754537 -279.519484)
			(xy 104.79003 -279.553576) (xy 104.819595 -279.59292) (xy 104.842466 -279.636497) (xy 104.85805 -279.683178)
			(xy 104.865945 -279.731755) (xy 104.86644 -279.756362) (xy 105.195128 -279.756362) (xy 105.199088 -279.707308)
			(xy 105.210865 -279.659524) (xy 105.230156 -279.614248) (xy 105.256459 -279.572652) (xy 105.289094 -279.535815)
			(xy 105.327215 -279.50469) (xy 105.369836 -279.480083) (xy 105.415852 -279.462631) (xy 105.464071 -279.452787)
			(xy 105.513246 -279.450806) (xy 105.562101 -279.456738) (xy 105.609372 -279.47043) (xy 105.653834 -279.491528)
			(xy 105.694337 -279.519484) (xy 105.72983 -279.553576) (xy 105.759395 -279.59292) (xy 105.782266 -279.636497)
			(xy 105.79785 -279.683178) (xy 105.805745 -279.731755) (xy 105.80624 -279.756362) (xy 106.135182 -279.756362)
			(xy 106.139142 -279.707308) (xy 106.150919 -279.659524) (xy 106.17021 -279.614248) (xy 106.196513 -279.572652)
			(xy 106.229148 -279.535815) (xy 106.267269 -279.50469) (xy 106.30989 -279.480083) (xy 106.355906 -279.462631)
			(xy 106.404125 -279.452787) (xy 106.4533 -279.450806) (xy 106.502155 -279.456738) (xy 106.549426 -279.47043)
			(xy 106.593888 -279.491528) (xy 106.634391 -279.519484) (xy 106.669884 -279.553576) (xy 106.699449 -279.59292)
			(xy 106.72232 -279.636497) (xy 106.737904 -279.683178) (xy 106.745799 -279.731755) (xy 106.746294 -279.756362)
			(xy 107.075236 -279.756362) (xy 107.079196 -279.707308) (xy 107.090973 -279.659524) (xy 107.110264 -279.614248)
			(xy 107.136567 -279.572652) (xy 107.169202 -279.535815) (xy 107.207323 -279.50469) (xy 107.249944 -279.480083)
			(xy 107.29596 -279.462631) (xy 107.344179 -279.452787) (xy 107.393354 -279.450806) (xy 107.442209 -279.456738)
			(xy 107.48948 -279.47043) (xy 107.533942 -279.491528) (xy 107.574445 -279.519484) (xy 107.609938 -279.553576)
			(xy 107.639503 -279.59292) (xy 107.662374 -279.636497) (xy 107.677958 -279.683178) (xy 107.685853 -279.731755)
			(xy 107.686348 -279.756362) (xy 108.01529 -279.756362) (xy 108.01925 -279.707308) (xy 108.031027 -279.659524)
			(xy 108.050318 -279.614248) (xy 108.076621 -279.572652) (xy 108.109256 -279.535815) (xy 108.147377 -279.50469)
			(xy 108.189998 -279.480083) (xy 108.236014 -279.462631) (xy 108.284233 -279.452787) (xy 108.333408 -279.450806)
			(xy 108.382263 -279.456738) (xy 108.429534 -279.47043) (xy 108.473996 -279.491528) (xy 108.514499 -279.519484)
			(xy 108.549992 -279.553576) (xy 108.579557 -279.59292) (xy 108.602428 -279.636497) (xy 108.618012 -279.683178)
			(xy 108.625907 -279.731755) (xy 108.626402 -279.756362) (xy 108.955344 -279.756362) (xy 108.959304 -279.707308)
			(xy 108.971081 -279.659524) (xy 108.990372 -279.614248) (xy 109.016675 -279.572652) (xy 109.04931 -279.535815)
			(xy 109.087431 -279.50469) (xy 109.130052 -279.480083) (xy 109.176068 -279.462631) (xy 109.224287 -279.452787)
			(xy 109.273462 -279.450806) (xy 109.322317 -279.456738) (xy 109.369588 -279.47043) (xy 109.41405 -279.491528)
			(xy 109.454553 -279.519484) (xy 109.490046 -279.553576) (xy 109.519611 -279.59292) (xy 109.542482 -279.636497)
			(xy 109.558066 -279.683178) (xy 109.565961 -279.731755) (xy 109.566456 -279.756362) (xy 109.895144 -279.756362)
			(xy 109.899104 -279.707308) (xy 109.910881 -279.659524) (xy 109.930172 -279.614248) (xy 109.956475 -279.572652)
			(xy 109.98911 -279.535815) (xy 110.027231 -279.50469) (xy 110.069852 -279.480083) (xy 110.115868 -279.462631)
			(xy 110.164087 -279.452787) (xy 110.213262 -279.450806) (xy 110.262117 -279.456738) (xy 110.309388 -279.47043)
			(xy 110.35385 -279.491528) (xy 110.394353 -279.519484) (xy 110.429846 -279.553576) (xy 110.459411 -279.59292)
			(xy 110.482282 -279.636497) (xy 110.497866 -279.683178) (xy 110.505761 -279.731755) (xy 110.506256 -279.756362)
			(xy 113.64901 -279.756362) (xy 113.65297 -279.707308) (xy 113.664747 -279.659524) (xy 113.684038 -279.614248)
			(xy 113.710341 -279.572652) (xy 113.742976 -279.535815) (xy 113.781097 -279.50469) (xy 113.823718 -279.480083)
			(xy 113.869734 -279.462631) (xy 113.917953 -279.452787) (xy 113.967128 -279.450806) (xy 114.015983 -279.456738)
			(xy 114.063254 -279.47043) (xy 114.107716 -279.491528) (xy 114.148219 -279.519484) (xy 114.183712 -279.553576)
			(xy 114.213277 -279.59292) (xy 114.236148 -279.636497) (xy 114.251732 -279.683178) (xy 114.259627 -279.731755)
			(xy 114.260122 -279.756362) (xy 114.58881 -279.756362) (xy 114.59277 -279.707308) (xy 114.604547 -279.659524)
			(xy 114.623838 -279.614248) (xy 114.650141 -279.572652) (xy 114.682776 -279.535815) (xy 114.720897 -279.50469)
			(xy 114.763518 -279.480083) (xy 114.809534 -279.462631) (xy 114.857753 -279.452787) (xy 114.906928 -279.450806)
			(xy 114.955783 -279.456738) (xy 115.003054 -279.47043) (xy 115.047516 -279.491528) (xy 115.088019 -279.519484)
			(xy 115.123512 -279.553576) (xy 115.153077 -279.59292) (xy 115.175948 -279.636497) (xy 115.191532 -279.683178)
			(xy 115.199427 -279.731755) (xy 115.199922 -279.756362) (xy 115.528864 -279.756362) (xy 115.532824 -279.707308)
			(xy 115.544601 -279.659524) (xy 115.563892 -279.614248) (xy 115.590195 -279.572652) (xy 115.62283 -279.535815)
			(xy 115.660951 -279.50469) (xy 115.703572 -279.480083) (xy 115.749588 -279.462631) (xy 115.797807 -279.452787)
			(xy 115.846982 -279.450806) (xy 115.895837 -279.456738) (xy 115.943108 -279.47043) (xy 115.98757 -279.491528)
			(xy 116.028073 -279.519484) (xy 116.063566 -279.553576) (xy 116.093131 -279.59292) (xy 116.116002 -279.636497)
			(xy 116.131586 -279.683178) (xy 116.139481 -279.731755) (xy 116.139976 -279.756362) (xy 116.468918 -279.756362)
			(xy 116.472878 -279.707308) (xy 116.484655 -279.659524) (xy 116.503946 -279.614248) (xy 116.530249 -279.572652)
			(xy 116.562884 -279.535815) (xy 116.601005 -279.50469) (xy 116.643626 -279.480083) (xy 116.689642 -279.462631)
			(xy 116.737861 -279.452787) (xy 116.787036 -279.450806) (xy 116.835891 -279.456738) (xy 116.883162 -279.47043)
			(xy 116.927624 -279.491528) (xy 116.968127 -279.519484) (xy 117.00362 -279.553576) (xy 117.033185 -279.59292)
			(xy 117.056056 -279.636497) (xy 117.07164 -279.683178) (xy 117.079535 -279.731755) (xy 117.08003 -279.756362)
			(xy 117.408972 -279.756362) (xy 117.412932 -279.707308) (xy 117.424709 -279.659524) (xy 117.444 -279.614248)
			(xy 117.470303 -279.572652) (xy 117.502938 -279.535815) (xy 117.541059 -279.50469) (xy 117.58368 -279.480083)
			(xy 117.629696 -279.462631) (xy 117.677915 -279.452787) (xy 117.72709 -279.450806) (xy 117.775945 -279.456738)
			(xy 117.823216 -279.47043) (xy 117.867678 -279.491528) (xy 117.908181 -279.519484) (xy 117.943674 -279.553576)
			(xy 117.973239 -279.59292) (xy 117.99611 -279.636497) (xy 118.011694 -279.683178) (xy 118.019589 -279.731755)
			(xy 118.020084 -279.756362) (xy 118.349026 -279.756362) (xy 118.352986 -279.707308) (xy 118.364763 -279.659524)
			(xy 118.384054 -279.614248) (xy 118.410357 -279.572652) (xy 118.442992 -279.535815) (xy 118.481113 -279.50469)
			(xy 118.523734 -279.480083) (xy 118.56975 -279.462631) (xy 118.617969 -279.452787) (xy 118.667144 -279.450806)
			(xy 118.715999 -279.456738) (xy 118.76327 -279.47043) (xy 118.807732 -279.491528) (xy 118.848235 -279.519484)
			(xy 118.883728 -279.553576) (xy 118.913293 -279.59292) (xy 118.936164 -279.636497) (xy 118.951748 -279.683178)
			(xy 118.959643 -279.731755) (xy 118.960138 -279.756362) (xy 119.288826 -279.756362) (xy 119.292786 -279.707308)
			(xy 119.304563 -279.659524) (xy 119.323854 -279.614248) (xy 119.350157 -279.572652) (xy 119.382792 -279.535815)
			(xy 119.420913 -279.50469) (xy 119.463534 -279.480083) (xy 119.50955 -279.462631) (xy 119.557769 -279.452787)
			(xy 119.606944 -279.450806) (xy 119.655799 -279.456738) (xy 119.70307 -279.47043) (xy 119.747532 -279.491528)
			(xy 119.788035 -279.519484) (xy 119.823528 -279.553576) (xy 119.853093 -279.59292) (xy 119.875964 -279.636497)
			(xy 119.891548 -279.683178) (xy 119.899443 -279.731755) (xy 119.899938 -279.756362) (xy 120.22888 -279.756362)
			(xy 120.23284 -279.707308) (xy 120.244617 -279.659524) (xy 120.263908 -279.614248) (xy 120.290211 -279.572652)
			(xy 120.322846 -279.535815) (xy 120.360967 -279.50469) (xy 120.403588 -279.480083) (xy 120.449604 -279.462631)
			(xy 120.497823 -279.452787) (xy 120.546998 -279.450806) (xy 120.595853 -279.456738) (xy 120.643124 -279.47043)
			(xy 120.687586 -279.491528) (xy 120.728089 -279.519484) (xy 120.763582 -279.553576) (xy 120.793147 -279.59292)
			(xy 120.816018 -279.636497) (xy 120.831602 -279.683178) (xy 120.839497 -279.731755) (xy 120.839992 -279.756362)
			(xy 121.168934 -279.756362) (xy 121.172894 -279.707308) (xy 121.184671 -279.659524) (xy 121.203962 -279.614248)
			(xy 121.230265 -279.572652) (xy 121.2629 -279.535815) (xy 121.301021 -279.50469) (xy 121.343642 -279.480083)
			(xy 121.389658 -279.462631) (xy 121.437877 -279.452787) (xy 121.487052 -279.450806) (xy 121.535907 -279.456738)
			(xy 121.583178 -279.47043) (xy 121.62764 -279.491528) (xy 121.668143 -279.519484) (xy 121.703636 -279.553576)
			(xy 121.733201 -279.59292) (xy 121.756072 -279.636497) (xy 121.771656 -279.683178) (xy 121.779551 -279.731755)
			(xy 121.780046 -279.756362) (xy 122.108988 -279.756362) (xy 122.112948 -279.707308) (xy 122.124725 -279.659524)
			(xy 122.144016 -279.614248) (xy 122.170319 -279.572652) (xy 122.202954 -279.535815) (xy 122.241075 -279.50469)
			(xy 122.283696 -279.480083) (xy 122.329712 -279.462631) (xy 122.377931 -279.452787) (xy 122.427106 -279.450806)
			(xy 122.475961 -279.456738) (xy 122.523232 -279.47043) (xy 122.567694 -279.491528) (xy 122.608197 -279.519484)
			(xy 122.64369 -279.553576) (xy 122.673255 -279.59292) (xy 122.696126 -279.636497) (xy 122.71171 -279.683178)
			(xy 122.719605 -279.731755) (xy 122.7201 -279.756362) (xy 123.049042 -279.756362) (xy 123.053002 -279.707308)
			(xy 123.064779 -279.659524) (xy 123.08407 -279.614248) (xy 123.110373 -279.572652) (xy 123.143008 -279.535815)
			(xy 123.181129 -279.50469) (xy 123.22375 -279.480083) (xy 123.269766 -279.462631) (xy 123.317985 -279.452787)
			(xy 123.36716 -279.450806) (xy 123.416015 -279.456738) (xy 123.463286 -279.47043) (xy 123.507748 -279.491528)
			(xy 123.548251 -279.519484) (xy 123.583744 -279.553576) (xy 123.613309 -279.59292) (xy 123.63618 -279.636497)
			(xy 123.651764 -279.683178) (xy 123.659659 -279.731755) (xy 123.660154 -279.756362) (xy 123.988842 -279.756362)
			(xy 123.992802 -279.707308) (xy 124.004579 -279.659524) (xy 124.02387 -279.614248) (xy 124.050173 -279.572652)
			(xy 124.082808 -279.535815) (xy 124.120929 -279.50469) (xy 124.16355 -279.480083) (xy 124.209566 -279.462631)
			(xy 124.257785 -279.452787) (xy 124.30696 -279.450806) (xy 124.355815 -279.456738) (xy 124.403086 -279.47043)
			(xy 124.447548 -279.491528) (xy 124.488051 -279.519484) (xy 124.523544 -279.553576) (xy 124.553109 -279.59292)
			(xy 124.57598 -279.636497) (xy 124.591564 -279.683178) (xy 124.599459 -279.731755) (xy 124.599954 -279.756362)
			(xy 124.928896 -279.756362) (xy 124.932856 -279.707308) (xy 124.944633 -279.659524) (xy 124.963924 -279.614248)
			(xy 124.990227 -279.572652) (xy 125.022862 -279.535815) (xy 125.060983 -279.50469) (xy 125.103604 -279.480083)
			(xy 125.14962 -279.462631) (xy 125.197839 -279.452787) (xy 125.247014 -279.450806) (xy 125.295869 -279.456738)
			(xy 125.34314 -279.47043) (xy 125.387602 -279.491528) (xy 125.428105 -279.519484) (xy 125.463598 -279.553576)
			(xy 125.493163 -279.59292) (xy 125.516034 -279.636497) (xy 125.531618 -279.683178) (xy 125.539513 -279.731755)
			(xy 125.540008 -279.756362) (xy 125.86895 -279.756362) (xy 125.87291 -279.707308) (xy 125.884687 -279.659524)
			(xy 125.903978 -279.614248) (xy 125.930281 -279.572652) (xy 125.962916 -279.535815) (xy 126.001037 -279.50469)
			(xy 126.043658 -279.480083) (xy 126.089674 -279.462631) (xy 126.137893 -279.452787) (xy 126.187068 -279.450806)
			(xy 126.235923 -279.456738) (xy 126.283194 -279.47043) (xy 126.327656 -279.491528) (xy 126.368159 -279.519484)
			(xy 126.403652 -279.553576) (xy 126.433217 -279.59292) (xy 126.456088 -279.636497) (xy 126.471672 -279.683178)
			(xy 126.479567 -279.731755) (xy 126.480062 -279.756362) (xy 126.479567 -279.780969) (xy 126.471672 -279.829546)
			(xy 126.456088 -279.876227) (xy 126.433217 -279.919804) (xy 126.403652 -279.959148) (xy 126.368159 -279.99324)
			(xy 126.327656 -280.021196) (xy 126.283194 -280.042294) (xy 126.235923 -280.055986) (xy 126.187068 -280.061918)
			(xy 126.137893 -280.059937) (xy 126.089674 -280.050093) (xy 126.043658 -280.032641) (xy 126.001037 -280.008034)
			(xy 125.962916 -279.976909) (xy 125.930281 -279.940072) (xy 125.903978 -279.898476) (xy 125.884687 -279.8532)
			(xy 125.87291 -279.805416) (xy 125.86895 -279.756362) (xy 125.540008 -279.756362) (xy 125.539513 -279.780969)
			(xy 125.531618 -279.829546) (xy 125.516034 -279.876227) (xy 125.493163 -279.919804) (xy 125.463598 -279.959148)
			(xy 125.428105 -279.99324) (xy 125.387602 -280.021196) (xy 125.34314 -280.042294) (xy 125.295869 -280.055986)
			(xy 125.247014 -280.061918) (xy 125.197839 -280.059937) (xy 125.14962 -280.050093) (xy 125.103604 -280.032641)
			(xy 125.060983 -280.008034) (xy 125.022862 -279.976909) (xy 124.990227 -279.940072) (xy 124.963924 -279.898476)
			(xy 124.944633 -279.8532) (xy 124.932856 -279.805416) (xy 124.928896 -279.756362) (xy 124.599954 -279.756362)
			(xy 124.599459 -279.780969) (xy 124.591564 -279.829546) (xy 124.57598 -279.876227) (xy 124.553109 -279.919804)
			(xy 124.523544 -279.959148) (xy 124.488051 -279.99324) (xy 124.447548 -280.021196) (xy 124.403086 -280.042294)
			(xy 124.355815 -280.055986) (xy 124.30696 -280.061918) (xy 124.257785 -280.059937) (xy 124.209566 -280.050093)
			(xy 124.16355 -280.032641) (xy 124.120929 -280.008034) (xy 124.082808 -279.976909) (xy 124.050173 -279.940072)
			(xy 124.02387 -279.898476) (xy 124.004579 -279.8532) (xy 123.992802 -279.805416) (xy 123.988842 -279.756362)
			(xy 123.660154 -279.756362) (xy 123.659659 -279.780969) (xy 123.651764 -279.829546) (xy 123.63618 -279.876227)
			(xy 123.613309 -279.919804) (xy 123.583744 -279.959148) (xy 123.548251 -279.99324) (xy 123.507748 -280.021196)
			(xy 123.463286 -280.042294) (xy 123.416015 -280.055986) (xy 123.36716 -280.061918) (xy 123.317985 -280.059937)
			(xy 123.269766 -280.050093) (xy 123.22375 -280.032641) (xy 123.181129 -280.008034) (xy 123.143008 -279.976909)
			(xy 123.110373 -279.940072) (xy 123.08407 -279.898476) (xy 123.064779 -279.8532) (xy 123.053002 -279.805416)
			(xy 123.049042 -279.756362) (xy 122.7201 -279.756362) (xy 122.719605 -279.780969) (xy 122.71171 -279.829546)
			(xy 122.696126 -279.876227) (xy 122.673255 -279.919804) (xy 122.64369 -279.959148) (xy 122.608197 -279.99324)
			(xy 122.567694 -280.021196) (xy 122.523232 -280.042294) (xy 122.475961 -280.055986) (xy 122.427106 -280.061918)
			(xy 122.377931 -280.059937) (xy 122.329712 -280.050093) (xy 122.283696 -280.032641) (xy 122.241075 -280.008034)
			(xy 122.202954 -279.976909) (xy 122.170319 -279.940072) (xy 122.144016 -279.898476) (xy 122.124725 -279.8532)
			(xy 122.112948 -279.805416) (xy 122.108988 -279.756362) (xy 121.780046 -279.756362) (xy 121.779551 -279.780969)
			(xy 121.771656 -279.829546) (xy 121.756072 -279.876227) (xy 121.733201 -279.919804) (xy 121.703636 -279.959148)
			(xy 121.668143 -279.99324) (xy 121.62764 -280.021196) (xy 121.583178 -280.042294) (xy 121.535907 -280.055986)
			(xy 121.487052 -280.061918) (xy 121.437877 -280.059937) (xy 121.389658 -280.050093) (xy 121.343642 -280.032641)
			(xy 121.301021 -280.008034) (xy 121.2629 -279.976909) (xy 121.230265 -279.940072) (xy 121.203962 -279.898476)
			(xy 121.184671 -279.8532) (xy 121.172894 -279.805416) (xy 121.168934 -279.756362) (xy 120.839992 -279.756362)
			(xy 120.839497 -279.780969) (xy 120.831602 -279.829546) (xy 120.816018 -279.876227) (xy 120.793147 -279.919804)
			(xy 120.763582 -279.959148) (xy 120.728089 -279.99324) (xy 120.687586 -280.021196) (xy 120.643124 -280.042294)
			(xy 120.595853 -280.055986) (xy 120.546998 -280.061918) (xy 120.497823 -280.059937) (xy 120.449604 -280.050093)
			(xy 120.403588 -280.032641) (xy 120.360967 -280.008034) (xy 120.322846 -279.976909) (xy 120.290211 -279.940072)
			(xy 120.263908 -279.898476) (xy 120.244617 -279.8532) (xy 120.23284 -279.805416) (xy 120.22888 -279.756362)
			(xy 119.899938 -279.756362) (xy 119.899443 -279.780969) (xy 119.891548 -279.829546) (xy 119.875964 -279.876227)
			(xy 119.853093 -279.919804) (xy 119.823528 -279.959148) (xy 119.788035 -279.99324) (xy 119.747532 -280.021196)
			(xy 119.70307 -280.042294) (xy 119.655799 -280.055986) (xy 119.606944 -280.061918) (xy 119.557769 -280.059937)
			(xy 119.50955 -280.050093) (xy 119.463534 -280.032641) (xy 119.420913 -280.008034) (xy 119.382792 -279.976909)
			(xy 119.350157 -279.940072) (xy 119.323854 -279.898476) (xy 119.304563 -279.8532) (xy 119.292786 -279.805416)
			(xy 119.288826 -279.756362) (xy 118.960138 -279.756362) (xy 118.959643 -279.780969) (xy 118.951748 -279.829546)
			(xy 118.936164 -279.876227) (xy 118.913293 -279.919804) (xy 118.883728 -279.959148) (xy 118.848235 -279.99324)
			(xy 118.807732 -280.021196) (xy 118.76327 -280.042294) (xy 118.715999 -280.055986) (xy 118.667144 -280.061918)
			(xy 118.617969 -280.059937) (xy 118.56975 -280.050093) (xy 118.523734 -280.032641) (xy 118.481113 -280.008034)
			(xy 118.442992 -279.976909) (xy 118.410357 -279.940072) (xy 118.384054 -279.898476) (xy 118.364763 -279.8532)
			(xy 118.352986 -279.805416) (xy 118.349026 -279.756362) (xy 118.020084 -279.756362) (xy 118.019589 -279.780969)
			(xy 118.011694 -279.829546) (xy 117.99611 -279.876227) (xy 117.973239 -279.919804) (xy 117.943674 -279.959148)
			(xy 117.908181 -279.99324) (xy 117.867678 -280.021196) (xy 117.823216 -280.042294) (xy 117.775945 -280.055986)
			(xy 117.72709 -280.061918) (xy 117.677915 -280.059937) (xy 117.629696 -280.050093) (xy 117.58368 -280.032641)
			(xy 117.541059 -280.008034) (xy 117.502938 -279.976909) (xy 117.470303 -279.940072) (xy 117.444 -279.898476)
			(xy 117.424709 -279.8532) (xy 117.412932 -279.805416) (xy 117.408972 -279.756362) (xy 117.08003 -279.756362)
			(xy 117.079535 -279.780969) (xy 117.07164 -279.829546) (xy 117.056056 -279.876227) (xy 117.033185 -279.919804)
			(xy 117.00362 -279.959148) (xy 116.968127 -279.99324) (xy 116.927624 -280.021196) (xy 116.883162 -280.042294)
			(xy 116.835891 -280.055986) (xy 116.787036 -280.061918) (xy 116.737861 -280.059937) (xy 116.689642 -280.050093)
			(xy 116.643626 -280.032641) (xy 116.601005 -280.008034) (xy 116.562884 -279.976909) (xy 116.530249 -279.940072)
			(xy 116.503946 -279.898476) (xy 116.484655 -279.8532) (xy 116.472878 -279.805416) (xy 116.468918 -279.756362)
			(xy 116.139976 -279.756362) (xy 116.139481 -279.780969) (xy 116.131586 -279.829546) (xy 116.116002 -279.876227)
			(xy 116.093131 -279.919804) (xy 116.063566 -279.959148) (xy 116.028073 -279.99324) (xy 115.98757 -280.021196)
			(xy 115.943108 -280.042294) (xy 115.895837 -280.055986) (xy 115.846982 -280.061918) (xy 115.797807 -280.059937)
			(xy 115.749588 -280.050093) (xy 115.703572 -280.032641) (xy 115.660951 -280.008034) (xy 115.62283 -279.976909)
			(xy 115.590195 -279.940072) (xy 115.563892 -279.898476) (xy 115.544601 -279.8532) (xy 115.532824 -279.805416)
			(xy 115.528864 -279.756362) (xy 115.199922 -279.756362) (xy 115.199427 -279.780969) (xy 115.191532 -279.829546)
			(xy 115.175948 -279.876227) (xy 115.153077 -279.919804) (xy 115.123512 -279.959148) (xy 115.088019 -279.99324)
			(xy 115.047516 -280.021196) (xy 115.003054 -280.042294) (xy 114.955783 -280.055986) (xy 114.906928 -280.061918)
			(xy 114.857753 -280.059937) (xy 114.809534 -280.050093) (xy 114.763518 -280.032641) (xy 114.720897 -280.008034)
			(xy 114.682776 -279.976909) (xy 114.650141 -279.940072) (xy 114.623838 -279.898476) (xy 114.604547 -279.8532)
			(xy 114.59277 -279.805416) (xy 114.58881 -279.756362) (xy 114.260122 -279.756362) (xy 114.259627 -279.780969)
			(xy 114.251732 -279.829546) (xy 114.236148 -279.876227) (xy 114.213277 -279.919804) (xy 114.183712 -279.959148)
			(xy 114.148219 -279.99324) (xy 114.107716 -280.021196) (xy 114.063254 -280.042294) (xy 114.015983 -280.055986)
			(xy 113.967128 -280.061918) (xy 113.917953 -280.059937) (xy 113.869734 -280.050093) (xy 113.823718 -280.032641)
			(xy 113.781097 -280.008034) (xy 113.742976 -279.976909) (xy 113.710341 -279.940072) (xy 113.684038 -279.898476)
			(xy 113.664747 -279.8532) (xy 113.65297 -279.805416) (xy 113.64901 -279.756362) (xy 110.506256 -279.756362)
			(xy 110.505761 -279.780969) (xy 110.497866 -279.829546) (xy 110.482282 -279.876227) (xy 110.459411 -279.919804)
			(xy 110.429846 -279.959148) (xy 110.394353 -279.99324) (xy 110.35385 -280.021196) (xy 110.309388 -280.042294)
			(xy 110.262117 -280.055986) (xy 110.213262 -280.061918) (xy 110.164087 -280.059937) (xy 110.115868 -280.050093)
			(xy 110.069852 -280.032641) (xy 110.027231 -280.008034) (xy 109.98911 -279.976909) (xy 109.956475 -279.940072)
			(xy 109.930172 -279.898476) (xy 109.910881 -279.8532) (xy 109.899104 -279.805416) (xy 109.895144 -279.756362)
			(xy 109.566456 -279.756362) (xy 109.565961 -279.780969) (xy 109.558066 -279.829546) (xy 109.542482 -279.876227)
			(xy 109.519611 -279.919804) (xy 109.490046 -279.959148) (xy 109.454553 -279.99324) (xy 109.41405 -280.021196)
			(xy 109.369588 -280.042294) (xy 109.322317 -280.055986) (xy 109.273462 -280.061918) (xy 109.224287 -280.059937)
			(xy 109.176068 -280.050093) (xy 109.130052 -280.032641) (xy 109.087431 -280.008034) (xy 109.04931 -279.976909)
			(xy 109.016675 -279.940072) (xy 108.990372 -279.898476) (xy 108.971081 -279.8532) (xy 108.959304 -279.805416)
			(xy 108.955344 -279.756362) (xy 108.626402 -279.756362) (xy 108.625907 -279.780969) (xy 108.618012 -279.829546)
			(xy 108.602428 -279.876227) (xy 108.579557 -279.919804) (xy 108.549992 -279.959148) (xy 108.514499 -279.99324)
			(xy 108.473996 -280.021196) (xy 108.429534 -280.042294) (xy 108.382263 -280.055986) (xy 108.333408 -280.061918)
			(xy 108.284233 -280.059937) (xy 108.236014 -280.050093) (xy 108.189998 -280.032641) (xy 108.147377 -280.008034)
			(xy 108.109256 -279.976909) (xy 108.076621 -279.940072) (xy 108.050318 -279.898476) (xy 108.031027 -279.8532)
			(xy 108.01925 -279.805416) (xy 108.01529 -279.756362) (xy 107.686348 -279.756362) (xy 107.685853 -279.780969)
			(xy 107.677958 -279.829546) (xy 107.662374 -279.876227) (xy 107.639503 -279.919804) (xy 107.609938 -279.959148)
			(xy 107.574445 -279.99324) (xy 107.533942 -280.021196) (xy 107.48948 -280.042294) (xy 107.442209 -280.055986)
			(xy 107.393354 -280.061918) (xy 107.344179 -280.059937) (xy 107.29596 -280.050093) (xy 107.249944 -280.032641)
			(xy 107.207323 -280.008034) (xy 107.169202 -279.976909) (xy 107.136567 -279.940072) (xy 107.110264 -279.898476)
			(xy 107.090973 -279.8532) (xy 107.079196 -279.805416) (xy 107.075236 -279.756362) (xy 106.746294 -279.756362)
			(xy 106.745799 -279.780969) (xy 106.737904 -279.829546) (xy 106.72232 -279.876227) (xy 106.699449 -279.919804)
			(xy 106.669884 -279.959148) (xy 106.634391 -279.99324) (xy 106.593888 -280.021196) (xy 106.549426 -280.042294)
			(xy 106.502155 -280.055986) (xy 106.4533 -280.061918) (xy 106.404125 -280.059937) (xy 106.355906 -280.050093)
			(xy 106.30989 -280.032641) (xy 106.267269 -280.008034) (xy 106.229148 -279.976909) (xy 106.196513 -279.940072)
			(xy 106.17021 -279.898476) (xy 106.150919 -279.8532) (xy 106.139142 -279.805416) (xy 106.135182 -279.756362)
			(xy 105.80624 -279.756362) (xy 105.805745 -279.780969) (xy 105.79785 -279.829546) (xy 105.782266 -279.876227)
			(xy 105.759395 -279.919804) (xy 105.72983 -279.959148) (xy 105.694337 -279.99324) (xy 105.653834 -280.021196)
			(xy 105.609372 -280.042294) (xy 105.562101 -280.055986) (xy 105.513246 -280.061918) (xy 105.464071 -280.059937)
			(xy 105.415852 -280.050093) (xy 105.369836 -280.032641) (xy 105.327215 -280.008034) (xy 105.289094 -279.976909)
			(xy 105.256459 -279.940072) (xy 105.230156 -279.898476) (xy 105.210865 -279.8532) (xy 105.199088 -279.805416)
			(xy 105.195128 -279.756362) (xy 104.86644 -279.756362) (xy 104.865945 -279.780969) (xy 104.85805 -279.829546)
			(xy 104.842466 -279.876227) (xy 104.819595 -279.919804) (xy 104.79003 -279.959148) (xy 104.754537 -279.99324)
			(xy 104.714034 -280.021196) (xy 104.669572 -280.042294) (xy 104.622301 -280.055986) (xy 104.573446 -280.061918)
			(xy 104.524271 -280.059937) (xy 104.476052 -280.050093) (xy 104.430036 -280.032641) (xy 104.387415 -280.008034)
			(xy 104.349294 -279.976909) (xy 104.316659 -279.940072) (xy 104.290356 -279.898476) (xy 104.271065 -279.8532)
			(xy 104.259288 -279.805416) (xy 104.255328 -279.756362) (xy 103.926386 -279.756362) (xy 103.925891 -279.780969)
			(xy 103.917996 -279.829546) (xy 103.902412 -279.876227) (xy 103.879541 -279.919804) (xy 103.849976 -279.959148)
			(xy 103.814483 -279.99324) (xy 103.77398 -280.021196) (xy 103.729518 -280.042294) (xy 103.682247 -280.055986)
			(xy 103.633392 -280.061918) (xy 103.584217 -280.059937) (xy 103.535998 -280.050093) (xy 103.489982 -280.032641)
			(xy 103.447361 -280.008034) (xy 103.40924 -279.976909) (xy 103.376605 -279.940072) (xy 103.350302 -279.898476)
			(xy 103.331011 -279.8532) (xy 103.319234 -279.805416) (xy 103.315274 -279.756362) (xy 102.986332 -279.756362)
			(xy 102.985837 -279.780969) (xy 102.977942 -279.829546) (xy 102.962358 -279.876227) (xy 102.939487 -279.919804)
			(xy 102.909922 -279.959148) (xy 102.874429 -279.99324) (xy 102.833926 -280.021196) (xy 102.789464 -280.042294)
			(xy 102.742193 -280.055986) (xy 102.693338 -280.061918) (xy 102.644163 -280.059937) (xy 102.595944 -280.050093)
			(xy 102.549928 -280.032641) (xy 102.507307 -280.008034) (xy 102.469186 -279.976909) (xy 102.436551 -279.940072)
			(xy 102.410248 -279.898476) (xy 102.390957 -279.8532) (xy 102.37918 -279.805416) (xy 102.37522 -279.756362)
			(xy 102.046278 -279.756362) (xy 102.045783 -279.780969) (xy 102.037888 -279.829546) (xy 102.022304 -279.876227)
			(xy 101.999433 -279.919804) (xy 101.969868 -279.959148) (xy 101.934375 -279.99324) (xy 101.893872 -280.021196)
			(xy 101.84941 -280.042294) (xy 101.802139 -280.055986) (xy 101.753284 -280.061918) (xy 101.704109 -280.059937)
			(xy 101.65589 -280.050093) (xy 101.609874 -280.032641) (xy 101.567253 -280.008034) (xy 101.529132 -279.976909)
			(xy 101.496497 -279.940072) (xy 101.470194 -279.898476) (xy 101.450903 -279.8532) (xy 101.439126 -279.805416)
			(xy 101.435166 -279.756362) (xy 101.106478 -279.756362) (xy 101.105983 -279.780969) (xy 101.098088 -279.829546)
			(xy 101.082504 -279.876227) (xy 101.059633 -279.919804) (xy 101.030068 -279.959148) (xy 100.994575 -279.99324)
			(xy 100.954072 -280.021196) (xy 100.90961 -280.042294) (xy 100.862339 -280.055986) (xy 100.813484 -280.061918)
			(xy 100.764309 -280.059937) (xy 100.71609 -280.050093) (xy 100.670074 -280.032641) (xy 100.627453 -280.008034)
			(xy 100.589332 -279.976909) (xy 100.556697 -279.940072) (xy 100.530394 -279.898476) (xy 100.511103 -279.8532)
			(xy 100.499326 -279.805416) (xy 100.495366 -279.756362) (xy 100.166424 -279.756362) (xy 100.165929 -279.780969)
			(xy 100.158034 -279.829546) (xy 100.14245 -279.876227) (xy 100.119579 -279.919804) (xy 100.090014 -279.959148)
			(xy 100.054521 -279.99324) (xy 100.014018 -280.021196) (xy 99.969556 -280.042294) (xy 99.922285 -280.055986)
			(xy 99.87343 -280.061918) (xy 99.824255 -280.059937) (xy 99.776036 -280.050093) (xy 99.73002 -280.032641)
			(xy 99.687399 -280.008034) (xy 99.649278 -279.976909) (xy 99.616643 -279.940072) (xy 99.59034 -279.898476)
			(xy 99.571049 -279.8532) (xy 99.559272 -279.805416) (xy 99.555312 -279.756362) (xy 99.22637 -279.756362)
			(xy 99.225875 -279.780969) (xy 99.21798 -279.829546) (xy 99.202396 -279.876227) (xy 99.179525 -279.919804)
			(xy 99.14996 -279.959148) (xy 99.114467 -279.99324) (xy 99.073964 -280.021196) (xy 99.029502 -280.042294)
			(xy 98.982231 -280.055986) (xy 98.933376 -280.061918) (xy 98.884201 -280.059937) (xy 98.835982 -280.050093)
			(xy 98.789966 -280.032641) (xy 98.747345 -280.008034) (xy 98.709224 -279.976909) (xy 98.676589 -279.940072)
			(xy 98.650286 -279.898476) (xy 98.630995 -279.8532) (xy 98.619218 -279.805416) (xy 98.615258 -279.756362)
			(xy 98.286316 -279.756362) (xy 98.285821 -279.780969) (xy 98.277926 -279.829546) (xy 98.262342 -279.876227)
			(xy 98.239471 -279.919804) (xy 98.209906 -279.959148) (xy 98.174413 -279.99324) (xy 98.13391 -280.021196)
			(xy 98.089448 -280.042294) (xy 98.042177 -280.055986) (xy 97.993322 -280.061918) (xy 97.944147 -280.059937)
			(xy 97.895928 -280.050093) (xy 97.849912 -280.032641) (xy 97.807291 -280.008034) (xy 97.76917 -279.976909)
			(xy 97.736535 -279.940072) (xy 97.710232 -279.898476) (xy 97.690941 -279.8532) (xy 97.679164 -279.805416)
			(xy 97.675204 -279.756362) (xy 97.346516 -279.756362) (xy 97.345971 -279.782711) (xy 97.336935 -279.834628)
			(xy 97.319109 -279.884219) (xy 97.293023 -279.930007) (xy 97.276666 -279.950672) (xy 97.271332 -279.957276)
			(xy 97.262442 -279.981152) (xy 97.260925 -279.985441) (xy 97.259272 -279.994385) (xy 97.25914 -279.998932)
			(xy 97.25914 -280.188162) (xy 97.259783 -280.20067) (xy 97.271501 -280.222774) (xy 97.281492 -280.230326)
			(xy 97.361502 -280.284682) (xy 97.386394 -280.287476) (xy 97.398332 -280.28265) (xy 97.425437 -280.272599)
			(xy 97.482207 -280.261729) (xy 97.511108 -280.26106) (xy 97.5351 -280.261531) (xy 97.582492 -280.269038)
			(xy 97.628127 -280.283866) (xy 97.670881 -280.305649) (xy 97.709701 -280.333852) (xy 97.743632 -280.36778)
			(xy 97.771838 -280.406598) (xy 97.793625 -280.44935) (xy 97.808456 -280.494984) (xy 97.815967 -280.542376)
			(xy 97.816416 -280.566368) (xy 97.815766 -280.595068) (xy 97.805029 -280.651454) (xy 97.79508 -280.678382)
			(xy 97.790254 -280.691082) (xy 97.794064 -280.717498) (xy 97.865184 -280.807922) (xy 97.890076 -280.818082)
			(xy 97.903538 -280.81605) (xy 97.922808 -280.813552) (xy 97.961577 -280.810882) (xy 97.981008 -280.810716)
			(xy 98.070162 -280.810716) (xy 98.082485 -280.810117) (xy 98.104308 -280.798662) (xy 98.111818 -280.788872)
			(xy 98.166682 -280.709878) (xy 98.16973 -280.685494) (xy 98.165412 -280.673556) (xy 98.156344 -280.647689)
			(xy 98.146509 -280.593771) (xy 98.145854 -280.566368) (xy 98.146376 -280.541113) (xy 98.154689 -280.491291)
			(xy 98.17109 -280.443517) (xy 98.195131 -280.399094) (xy 98.226155 -280.359234) (xy 98.263317 -280.325024)
			(xy 98.305603 -280.297398) (xy 98.351859 -280.277108) (xy 98.400824 -280.264708) (xy 98.451162 -280.260537)
			(xy 98.5015 -280.264708) (xy 98.550465 -280.277108) (xy 98.596721 -280.297398) (xy 98.639007 -280.325024)
			(xy 98.676169 -280.359234) (xy 98.707193 -280.399094) (xy 98.731234 -280.443517) (xy 98.747635 -280.491291)
			(xy 98.755948 -280.541113) (xy 98.75647 -280.566368) (xy 98.755873 -280.593776) (xy 98.746035 -280.647704)
			(xy 98.736912 -280.673556) (xy 98.732594 -280.685494) (xy 98.735642 -280.709878) (xy 98.790506 -280.788872)
			(xy 98.798115 -280.798549) (xy 98.819876 -280.809978) (xy 98.832162 -280.810716) (xy 98.921062 -280.810716)
			(xy 98.940493 -280.81088) (xy 98.979262 -280.813549) (xy 98.998532 -280.81605) (xy 99.011994 -280.818082)
			(xy 99.036886 -280.807922) (xy 99.108006 -280.717498) (xy 99.111816 -280.691082) (xy 99.10699 -280.678382)
			(xy 99.097068 -280.651446) (xy 99.086322 -280.595065) (xy 99.085654 -280.566368) (xy 99.086143 -280.541544)
			(xy 99.09418 -280.492551) (xy 99.110038 -280.445503) (xy 99.133298 -280.401641) (xy 99.163348 -280.36212)
			(xy 99.199396 -280.327981) (xy 99.240492 -280.300123) (xy 99.285554 -280.279282) (xy 99.333394 -280.266005)
			(xy 99.382751 -280.260642) (xy 99.432326 -280.263336) (xy 99.480812 -280.274014) (xy 99.526932 -280.292396)
			(xy 99.569471 -280.317997) (xy 99.607307 -280.350143) (xy 99.639444 -280.387986) (xy 99.665035 -280.430531)
			(xy 99.683407 -280.476655) (xy 99.694074 -280.525143) (xy 99.696756 -280.574719) (xy 99.691382 -280.624075)
			(xy 99.678094 -280.671912) (xy 99.657242 -280.716969) (xy 99.629375 -280.758059) (xy 99.595228 -280.794099)
			(xy 99.5557 -280.82414) (xy 99.511832 -280.84739) (xy 99.464781 -280.863237) (xy 99.415786 -280.871263)
			(xy 99.390962 -280.871676) (xy 99.378395 -280.871575) (xy 99.353342 -280.869544) (xy 99.340924 -280.867612)
			(xy 99.330063 -280.866399) (xy 99.309014 -280.872198) (xy 99.292261 -280.8862) (xy 99.282819 -280.905886)
			(xy 99.282385 -280.927715) (xy 99.291038 -280.94776) (xy 99.29876 -280.955496) (xy 99.31019 -280.96591)
			(xy 99.317458 -280.972257) (xy 99.335349 -280.979443) (xy 99.344988 -280.97988) (xy 100.377244 -280.97988)
			(xy 100.386874 -280.979408) (xy 100.404749 -280.972218) (xy 100.412042 -280.96591) (xy 100.423472 -280.955496)
			(xy 100.431308 -280.947802) (xy 100.44011 -280.927707) (xy 100.439734 -280.905773) (xy 100.430249 -280.885991)
			(xy 100.413381 -280.871965) (xy 100.392201 -280.866248) (xy 100.381308 -280.867612) (xy 100.368826 -280.869547)
			(xy 100.343647 -280.871582) (xy 100.331016 -280.871676) (xy 100.306198 -280.871192) (xy 100.257215 -280.863164)
			(xy 100.210177 -280.847318) (xy 100.166322 -280.82407) (xy 100.126805 -280.794034) (xy 100.092668 -280.758001)
			(xy 100.06481 -280.71692) (xy 100.043966 -280.671873) (xy 100.030684 -280.624047) (xy 100.025314 -280.574702)
			(xy 100.027997 -280.525139) (xy 100.038664 -280.476662) (xy 100.057033 -280.43055) (xy 100.08262 -280.388018)
			(xy 100.11475 -280.350184) (xy 100.152579 -280.318048) (xy 100.195107 -280.292454) (xy 100.241217 -280.274078)
			(xy 100.289691 -280.263404) (xy 100.339254 -280.260712) (xy 100.3886 -280.266075) (xy 100.436427 -280.279349)
			(xy 100.481478 -280.300187) (xy 100.522564 -280.328038) (xy 100.558602 -280.362169) (xy 100.588645 -280.401681)
			(xy 100.611899 -280.445533) (xy 100.627752 -280.492569) (xy 100.635788 -280.54155) (xy 100.636324 -280.566368)
			(xy 100.635674 -280.595068) (xy 100.624938 -280.651454) (xy 100.614988 -280.678382) (xy 100.610162 -280.691082)
			(xy 100.613972 -280.717498) (xy 100.685092 -280.807922) (xy 100.709984 -280.818082) (xy 100.723446 -280.816304)
			(xy 100.742776 -280.813737) (xy 100.781672 -280.810938) (xy 100.80117 -280.810716) (xy 100.89007 -280.810716)
			(xy 100.902393 -280.810116) (xy 100.924212 -280.798659) (xy 100.931726 -280.788872) (xy 100.98659 -280.709878)
			(xy 100.989638 -280.685494) (xy 100.98532 -280.673556) (xy 100.976252 -280.647689) (xy 100.966416 -280.593771)
			(xy 100.965762 -280.566368) (xy 100.966284 -280.541113) (xy 100.974597 -280.491291) (xy 100.990998 -280.443517)
			(xy 101.015039 -280.399094) (xy 101.046063 -280.359234) (xy 101.083225 -280.325024) (xy 101.125511 -280.297398)
			(xy 101.171767 -280.277108) (xy 101.220732 -280.264708) (xy 101.27107 -280.260537) (xy 101.321408 -280.264708)
			(xy 101.370373 -280.277108) (xy 101.416629 -280.297398) (xy 101.458915 -280.325024) (xy 101.496077 -280.359234)
			(xy 101.527101 -280.399094) (xy 101.551142 -280.443517) (xy 101.567543 -280.491291) (xy 101.575856 -280.541113)
			(xy 101.576378 -280.566368) (xy 101.575781 -280.593776) (xy 101.565943 -280.647704) (xy 101.55682 -280.673556)
			(xy 101.552502 -280.685494) (xy 101.55555 -280.709878) (xy 101.610414 -280.788872) (xy 101.618024 -280.798548)
			(xy 101.639784 -280.809973) (xy 101.65207 -280.810716) (xy 101.74097 -280.810716) (xy 101.760468 -280.810933)
			(xy 101.799365 -280.813733) (xy 101.818694 -280.816304) (xy 101.832156 -280.818082) (xy 101.857048 -280.807922)
			(xy 101.928168 -280.717498) (xy 101.931978 -280.691082) (xy 101.927152 -280.678382) (xy 101.917231 -280.651446)
			(xy 101.906486 -280.595065) (xy 101.905816 -280.566368) (xy 101.906338 -280.541113) (xy 101.914651 -280.491291)
			(xy 101.931052 -280.443517) (xy 101.955093 -280.399094) (xy 101.986117 -280.359234) (xy 102.023279 -280.325024)
			(xy 102.065565 -280.297398) (xy 102.111821 -280.277108) (xy 102.160786 -280.264708) (xy 102.211124 -280.260537)
			(xy 102.261462 -280.264708) (xy 102.310427 -280.277108) (xy 102.356683 -280.297398) (xy 102.398969 -280.325024)
			(xy 102.436131 -280.359234) (xy 102.467155 -280.399094) (xy 102.491196 -280.443517) (xy 102.507597 -280.491291)
			(xy 102.51591 -280.541113) (xy 102.516432 -280.566368) (xy 102.845374 -280.566368) (xy 102.849334 -280.517314)
			(xy 102.861111 -280.46953) (xy 102.880402 -280.424254) (xy 102.906705 -280.382658) (xy 102.93934 -280.345821)
			(xy 102.977461 -280.314696) (xy 103.020082 -280.290089) (xy 103.066098 -280.272637) (xy 103.114317 -280.262793)
			(xy 103.163492 -280.260812) (xy 103.212347 -280.266744) (xy 103.259618 -280.280436) (xy 103.30408 -280.301534)
			(xy 103.344583 -280.32949) (xy 103.380076 -280.363582) (xy 103.409641 -280.402926) (xy 103.432512 -280.446503)
			(xy 103.448096 -280.493184) (xy 103.455991 -280.541761) (xy 103.456486 -280.566368) (xy 103.785174 -280.566368)
			(xy 103.789134 -280.517314) (xy 103.800911 -280.46953) (xy 103.820202 -280.424254) (xy 103.846505 -280.382658)
			(xy 103.87914 -280.345821) (xy 103.917261 -280.314696) (xy 103.959882 -280.290089) (xy 104.005898 -280.272637)
			(xy 104.054117 -280.262793) (xy 104.103292 -280.260812) (xy 104.152147 -280.266744) (xy 104.199418 -280.280436)
			(xy 104.24388 -280.301534) (xy 104.284383 -280.32949) (xy 104.319876 -280.363582) (xy 104.349441 -280.402926)
			(xy 104.372312 -280.446503) (xy 104.387896 -280.493184) (xy 104.395791 -280.541761) (xy 104.396286 -280.566368)
			(xy 104.725228 -280.566368) (xy 104.729188 -280.517314) (xy 104.740965 -280.46953) (xy 104.760256 -280.424254)
			(xy 104.786559 -280.382658) (xy 104.819194 -280.345821) (xy 104.857315 -280.314696) (xy 104.899936 -280.290089)
			(xy 104.945952 -280.272637) (xy 104.994171 -280.262793) (xy 105.043346 -280.260812) (xy 105.092201 -280.266744)
			(xy 105.139472 -280.280436) (xy 105.183934 -280.301534) (xy 105.224437 -280.32949) (xy 105.25993 -280.363582)
			(xy 105.289495 -280.402926) (xy 105.312366 -280.446503) (xy 105.32795 -280.493184) (xy 105.335845 -280.541761)
			(xy 105.33634 -280.566368) (xy 105.665282 -280.566368) (xy 105.669242 -280.517314) (xy 105.681019 -280.46953)
			(xy 105.70031 -280.424254) (xy 105.726613 -280.382658) (xy 105.759248 -280.345821) (xy 105.797369 -280.314696)
			(xy 105.83999 -280.290089) (xy 105.886006 -280.272637) (xy 105.934225 -280.262793) (xy 105.9834 -280.260812)
			(xy 106.032255 -280.266744) (xy 106.079526 -280.280436) (xy 106.123988 -280.301534) (xy 106.164491 -280.32949)
			(xy 106.199984 -280.363582) (xy 106.229549 -280.402926) (xy 106.25242 -280.446503) (xy 106.268004 -280.493184)
			(xy 106.275899 -280.541761) (xy 106.276394 -280.566368) (xy 106.605336 -280.566368) (xy 106.609296 -280.517314)
			(xy 106.621073 -280.46953) (xy 106.640364 -280.424254) (xy 106.666667 -280.382658) (xy 106.699302 -280.345821)
			(xy 106.737423 -280.314696) (xy 106.780044 -280.290089) (xy 106.82606 -280.272637) (xy 106.874279 -280.262793)
			(xy 106.923454 -280.260812) (xy 106.972309 -280.266744) (xy 107.01958 -280.280436) (xy 107.064042 -280.301534)
			(xy 107.104545 -280.32949) (xy 107.140038 -280.363582) (xy 107.169603 -280.402926) (xy 107.192474 -280.446503)
			(xy 107.208058 -280.493184) (xy 107.215953 -280.541761) (xy 107.216448 -280.566368) (xy 107.545136 -280.566368)
			(xy 107.549096 -280.517314) (xy 107.560873 -280.46953) (xy 107.580164 -280.424254) (xy 107.606467 -280.382658)
			(xy 107.639102 -280.345821) (xy 107.677223 -280.314696) (xy 107.719844 -280.290089) (xy 107.76586 -280.272637)
			(xy 107.814079 -280.262793) (xy 107.863254 -280.260812) (xy 107.912109 -280.266744) (xy 107.95938 -280.280436)
			(xy 108.003842 -280.301534) (xy 108.044345 -280.32949) (xy 108.079838 -280.363582) (xy 108.109403 -280.402926)
			(xy 108.132274 -280.446503) (xy 108.147858 -280.493184) (xy 108.155753 -280.541761) (xy 108.156248 -280.566368)
			(xy 110.365298 -280.566368) (xy 110.369258 -280.517314) (xy 110.381035 -280.46953) (xy 110.400326 -280.424254)
			(xy 110.426629 -280.382658) (xy 110.459264 -280.345821) (xy 110.497385 -280.314696) (xy 110.540006 -280.290089)
			(xy 110.586022 -280.272637) (xy 110.634241 -280.262793) (xy 110.683416 -280.260812) (xy 110.732271 -280.266744)
			(xy 110.779542 -280.280436) (xy 110.824004 -280.301534) (xy 110.864507 -280.32949) (xy 110.9 -280.363582)
			(xy 110.929565 -280.402926) (xy 110.952436 -280.446503) (xy 110.96802 -280.493184) (xy 110.975915 -280.541761)
			(xy 110.97641 -280.566368) (xy 113.178856 -280.566368) (xy 113.182816 -280.517314) (xy 113.194593 -280.46953)
			(xy 113.213884 -280.424254) (xy 113.240187 -280.382658) (xy 113.272822 -280.345821) (xy 113.310943 -280.314696)
			(xy 113.353564 -280.290089) (xy 113.39958 -280.272637) (xy 113.447799 -280.262793) (xy 113.496974 -280.260812)
			(xy 113.545829 -280.266744) (xy 113.5931 -280.280436) (xy 113.637562 -280.301534) (xy 113.678065 -280.32949)
			(xy 113.713558 -280.363582) (xy 113.743123 -280.402926) (xy 113.765994 -280.446503) (xy 113.781578 -280.493184)
			(xy 113.789473 -280.541761) (xy 113.789968 -280.566368) (xy 115.999018 -280.566368) (xy 116.002978 -280.517314)
			(xy 116.014755 -280.46953) (xy 116.034046 -280.424254) (xy 116.060349 -280.382658) (xy 116.092984 -280.345821)
			(xy 116.131105 -280.314696) (xy 116.173726 -280.290089) (xy 116.219742 -280.272637) (xy 116.267961 -280.262793)
			(xy 116.317136 -280.260812) (xy 116.365991 -280.266744) (xy 116.413262 -280.280436) (xy 116.457724 -280.301534)
			(xy 116.498227 -280.32949) (xy 116.53372 -280.363582) (xy 116.563285 -280.402926) (xy 116.586156 -280.446503)
			(xy 116.60174 -280.493184) (xy 116.609635 -280.541761) (xy 116.61013 -280.566368) (xy 116.938818 -280.566368)
			(xy 116.942778 -280.517314) (xy 116.954555 -280.46953) (xy 116.973846 -280.424254) (xy 117.000149 -280.382658)
			(xy 117.032784 -280.345821) (xy 117.070905 -280.314696) (xy 117.113526 -280.290089) (xy 117.159542 -280.272637)
			(xy 117.207761 -280.262793) (xy 117.256936 -280.260812) (xy 117.305791 -280.266744) (xy 117.353062 -280.280436)
			(xy 117.397524 -280.301534) (xy 117.438027 -280.32949) (xy 117.47352 -280.363582) (xy 117.503085 -280.402926)
			(xy 117.525956 -280.446503) (xy 117.54154 -280.493184) (xy 117.549435 -280.541761) (xy 117.54993 -280.566368)
			(xy 117.878872 -280.566368) (xy 117.882832 -280.517314) (xy 117.894609 -280.46953) (xy 117.9139 -280.424254)
			(xy 117.940203 -280.382658) (xy 117.972838 -280.345821) (xy 118.010959 -280.314696) (xy 118.05358 -280.290089)
			(xy 118.099596 -280.272637) (xy 118.147815 -280.262793) (xy 118.19699 -280.260812) (xy 118.245845 -280.266744)
			(xy 118.293116 -280.280436) (xy 118.337578 -280.301534) (xy 118.378081 -280.32949) (xy 118.413574 -280.363582)
			(xy 118.443139 -280.402926) (xy 118.46601 -280.446503) (xy 118.481594 -280.493184) (xy 118.489489 -280.541761)
			(xy 118.489984 -280.566368) (xy 118.818926 -280.566368) (xy 118.822886 -280.517314) (xy 118.834663 -280.46953)
			(xy 118.853954 -280.424254) (xy 118.880257 -280.382658) (xy 118.912892 -280.345821) (xy 118.951013 -280.314696)
			(xy 118.993634 -280.290089) (xy 119.03965 -280.272637) (xy 119.087869 -280.262793) (xy 119.137044 -280.260812)
			(xy 119.185899 -280.266744) (xy 119.23317 -280.280436) (xy 119.277632 -280.301534) (xy 119.318135 -280.32949)
			(xy 119.353628 -280.363582) (xy 119.383193 -280.402926) (xy 119.406064 -280.446503) (xy 119.421648 -280.493184)
			(xy 119.429543 -280.541761) (xy 119.430038 -280.566368) (xy 119.75898 -280.566368) (xy 119.76294 -280.517314)
			(xy 119.774717 -280.46953) (xy 119.794008 -280.424254) (xy 119.820311 -280.382658) (xy 119.852946 -280.345821)
			(xy 119.891067 -280.314696) (xy 119.933688 -280.290089) (xy 119.979704 -280.272637) (xy 120.027923 -280.262793)
			(xy 120.077098 -280.260812) (xy 120.125953 -280.266744) (xy 120.173224 -280.280436) (xy 120.217686 -280.301534)
			(xy 120.258189 -280.32949) (xy 120.293682 -280.363582) (xy 120.323247 -280.402926) (xy 120.346118 -280.446503)
			(xy 120.361702 -280.493184) (xy 120.369597 -280.541761) (xy 120.370092 -280.566368) (xy 120.699034 -280.566368)
			(xy 120.702994 -280.517314) (xy 120.714771 -280.46953) (xy 120.734062 -280.424254) (xy 120.760365 -280.382658)
			(xy 120.793 -280.345821) (xy 120.831121 -280.314696) (xy 120.873742 -280.290089) (xy 120.919758 -280.272637)
			(xy 120.967977 -280.262793) (xy 121.017152 -280.260812) (xy 121.066007 -280.266744) (xy 121.113278 -280.280436)
			(xy 121.15774 -280.301534) (xy 121.198243 -280.32949) (xy 121.233736 -280.363582) (xy 121.263301 -280.402926)
			(xy 121.286172 -280.446503) (xy 121.301756 -280.493184) (xy 121.309651 -280.541761) (xy 121.310146 -280.566368)
			(xy 121.309651 -280.590975) (xy 121.301756 -280.639552) (xy 121.286172 -280.686233) (xy 121.263301 -280.72981)
			(xy 121.233736 -280.769154) (xy 121.198243 -280.803246) (xy 121.15774 -280.831202) (xy 121.113278 -280.8523)
			(xy 121.066007 -280.865992) (xy 121.017152 -280.871924) (xy 120.967977 -280.869943) (xy 120.919758 -280.860099)
			(xy 120.873742 -280.842647) (xy 120.831121 -280.81804) (xy 120.793 -280.786915) (xy 120.760365 -280.750078)
			(xy 120.734062 -280.708482) (xy 120.714771 -280.663206) (xy 120.702994 -280.615422) (xy 120.699034 -280.566368)
			(xy 120.370092 -280.566368) (xy 120.369597 -280.590975) (xy 120.361702 -280.639552) (xy 120.346118 -280.686233)
			(xy 120.323247 -280.72981) (xy 120.293682 -280.769154) (xy 120.258189 -280.803246) (xy 120.217686 -280.831202)
			(xy 120.173224 -280.8523) (xy 120.125953 -280.865992) (xy 120.077098 -280.871924) (xy 120.027923 -280.869943)
			(xy 119.979704 -280.860099) (xy 119.933688 -280.842647) (xy 119.891067 -280.81804) (xy 119.852946 -280.786915)
			(xy 119.820311 -280.750078) (xy 119.794008 -280.708482) (xy 119.774717 -280.663206) (xy 119.76294 -280.615422)
			(xy 119.75898 -280.566368) (xy 119.430038 -280.566368) (xy 119.429543 -280.590975) (xy 119.421648 -280.639552)
			(xy 119.406064 -280.686233) (xy 119.383193 -280.72981) (xy 119.353628 -280.769154) (xy 119.318135 -280.803246)
			(xy 119.277632 -280.831202) (xy 119.23317 -280.8523) (xy 119.185899 -280.865992) (xy 119.137044 -280.871924)
			(xy 119.087869 -280.869943) (xy 119.03965 -280.860099) (xy 118.993634 -280.842647) (xy 118.951013 -280.81804)
			(xy 118.912892 -280.786915) (xy 118.880257 -280.750078) (xy 118.853954 -280.708482) (xy 118.834663 -280.663206)
			(xy 118.822886 -280.615422) (xy 118.818926 -280.566368) (xy 118.489984 -280.566368) (xy 118.489489 -280.590975)
			(xy 118.481594 -280.639552) (xy 118.46601 -280.686233) (xy 118.443139 -280.72981) (xy 118.413574 -280.769154)
			(xy 118.378081 -280.803246) (xy 118.337578 -280.831202) (xy 118.293116 -280.8523) (xy 118.245845 -280.865992)
			(xy 118.19699 -280.871924) (xy 118.147815 -280.869943) (xy 118.099596 -280.860099) (xy 118.05358 -280.842647)
			(xy 118.010959 -280.81804) (xy 117.972838 -280.786915) (xy 117.940203 -280.750078) (xy 117.9139 -280.708482)
			(xy 117.894609 -280.663206) (xy 117.882832 -280.615422) (xy 117.878872 -280.566368) (xy 117.54993 -280.566368)
			(xy 117.549435 -280.590975) (xy 117.54154 -280.639552) (xy 117.525956 -280.686233) (xy 117.503085 -280.72981)
			(xy 117.47352 -280.769154) (xy 117.438027 -280.803246) (xy 117.397524 -280.831202) (xy 117.353062 -280.8523)
			(xy 117.305791 -280.865992) (xy 117.256936 -280.871924) (xy 117.207761 -280.869943) (xy 117.159542 -280.860099)
			(xy 117.113526 -280.842647) (xy 117.070905 -280.81804) (xy 117.032784 -280.786915) (xy 117.000149 -280.750078)
			(xy 116.973846 -280.708482) (xy 116.954555 -280.663206) (xy 116.942778 -280.615422) (xy 116.938818 -280.566368)
			(xy 116.61013 -280.566368) (xy 116.609635 -280.590975) (xy 116.60174 -280.639552) (xy 116.586156 -280.686233)
			(xy 116.563285 -280.72981) (xy 116.53372 -280.769154) (xy 116.498227 -280.803246) (xy 116.457724 -280.831202)
			(xy 116.413262 -280.8523) (xy 116.365991 -280.865992) (xy 116.317136 -280.871924) (xy 116.267961 -280.869943)
			(xy 116.219742 -280.860099) (xy 116.173726 -280.842647) (xy 116.131105 -280.81804) (xy 116.092984 -280.786915)
			(xy 116.060349 -280.750078) (xy 116.034046 -280.708482) (xy 116.014755 -280.663206) (xy 116.002978 -280.615422)
			(xy 115.999018 -280.566368) (xy 113.789968 -280.566368) (xy 113.789473 -280.590975) (xy 113.781578 -280.639552)
			(xy 113.765994 -280.686233) (xy 113.743123 -280.72981) (xy 113.713558 -280.769154) (xy 113.678065 -280.803246)
			(xy 113.637562 -280.831202) (xy 113.5931 -280.8523) (xy 113.545829 -280.865992) (xy 113.496974 -280.871924)
			(xy 113.447799 -280.869943) (xy 113.39958 -280.860099) (xy 113.353564 -280.842647) (xy 113.310943 -280.81804)
			(xy 113.272822 -280.786915) (xy 113.240187 -280.750078) (xy 113.213884 -280.708482) (xy 113.194593 -280.663206)
			(xy 113.182816 -280.615422) (xy 113.178856 -280.566368) (xy 110.97641 -280.566368) (xy 110.975915 -280.590975)
			(xy 110.96802 -280.639552) (xy 110.952436 -280.686233) (xy 110.929565 -280.72981) (xy 110.9 -280.769154)
			(xy 110.864507 -280.803246) (xy 110.824004 -280.831202) (xy 110.779542 -280.8523) (xy 110.732271 -280.865992)
			(xy 110.683416 -280.871924) (xy 110.634241 -280.869943) (xy 110.586022 -280.860099) (xy 110.540006 -280.842647)
			(xy 110.497385 -280.81804) (xy 110.459264 -280.786915) (xy 110.426629 -280.750078) (xy 110.400326 -280.708482)
			(xy 110.381035 -280.663206) (xy 110.369258 -280.615422) (xy 110.365298 -280.566368) (xy 108.156248 -280.566368)
			(xy 108.155753 -280.590975) (xy 108.147858 -280.639552) (xy 108.132274 -280.686233) (xy 108.109403 -280.72981)
			(xy 108.079838 -280.769154) (xy 108.044345 -280.803246) (xy 108.003842 -280.831202) (xy 107.95938 -280.8523)
			(xy 107.912109 -280.865992) (xy 107.863254 -280.871924) (xy 107.814079 -280.869943) (xy 107.76586 -280.860099)
			(xy 107.719844 -280.842647) (xy 107.677223 -280.81804) (xy 107.639102 -280.786915) (xy 107.606467 -280.750078)
			(xy 107.580164 -280.708482) (xy 107.560873 -280.663206) (xy 107.549096 -280.615422) (xy 107.545136 -280.566368)
			(xy 107.216448 -280.566368) (xy 107.215953 -280.590975) (xy 107.208058 -280.639552) (xy 107.192474 -280.686233)
			(xy 107.169603 -280.72981) (xy 107.140038 -280.769154) (xy 107.104545 -280.803246) (xy 107.064042 -280.831202)
			(xy 107.01958 -280.8523) (xy 106.972309 -280.865992) (xy 106.923454 -280.871924) (xy 106.874279 -280.869943)
			(xy 106.82606 -280.860099) (xy 106.780044 -280.842647) (xy 106.737423 -280.81804) (xy 106.699302 -280.786915)
			(xy 106.666667 -280.750078) (xy 106.640364 -280.708482) (xy 106.621073 -280.663206) (xy 106.609296 -280.615422)
			(xy 106.605336 -280.566368) (xy 106.276394 -280.566368) (xy 106.275899 -280.590975) (xy 106.268004 -280.639552)
			(xy 106.25242 -280.686233) (xy 106.229549 -280.72981) (xy 106.199984 -280.769154) (xy 106.164491 -280.803246)
			(xy 106.123988 -280.831202) (xy 106.079526 -280.8523) (xy 106.032255 -280.865992) (xy 105.9834 -280.871924)
			(xy 105.934225 -280.869943) (xy 105.886006 -280.860099) (xy 105.83999 -280.842647) (xy 105.797369 -280.81804)
			(xy 105.759248 -280.786915) (xy 105.726613 -280.750078) (xy 105.70031 -280.708482) (xy 105.681019 -280.663206)
			(xy 105.669242 -280.615422) (xy 105.665282 -280.566368) (xy 105.33634 -280.566368) (xy 105.335845 -280.590975)
			(xy 105.32795 -280.639552) (xy 105.312366 -280.686233) (xy 105.289495 -280.72981) (xy 105.25993 -280.769154)
			(xy 105.224437 -280.803246) (xy 105.183934 -280.831202) (xy 105.139472 -280.8523) (xy 105.092201 -280.865992)
			(xy 105.043346 -280.871924) (xy 104.994171 -280.869943) (xy 104.945952 -280.860099) (xy 104.899936 -280.842647)
			(xy 104.857315 -280.81804) (xy 104.819194 -280.786915) (xy 104.786559 -280.750078) (xy 104.760256 -280.708482)
			(xy 104.740965 -280.663206) (xy 104.729188 -280.615422) (xy 104.725228 -280.566368) (xy 104.396286 -280.566368)
			(xy 104.395791 -280.590975) (xy 104.387896 -280.639552) (xy 104.372312 -280.686233) (xy 104.349441 -280.72981)
			(xy 104.319876 -280.769154) (xy 104.284383 -280.803246) (xy 104.24388 -280.831202) (xy 104.199418 -280.8523)
			(xy 104.152147 -280.865992) (xy 104.103292 -280.871924) (xy 104.054117 -280.869943) (xy 104.005898 -280.860099)
			(xy 103.959882 -280.842647) (xy 103.917261 -280.81804) (xy 103.87914 -280.786915) (xy 103.846505 -280.750078)
			(xy 103.820202 -280.708482) (xy 103.800911 -280.663206) (xy 103.789134 -280.615422) (xy 103.785174 -280.566368)
			(xy 103.456486 -280.566368) (xy 103.455991 -280.590975) (xy 103.448096 -280.639552) (xy 103.432512 -280.686233)
			(xy 103.409641 -280.72981) (xy 103.380076 -280.769154) (xy 103.344583 -280.803246) (xy 103.30408 -280.831202)
			(xy 103.259618 -280.8523) (xy 103.212347 -280.865992) (xy 103.163492 -280.871924) (xy 103.114317 -280.869943)
			(xy 103.066098 -280.860099) (xy 103.020082 -280.842647) (xy 102.977461 -280.81804) (xy 102.93934 -280.786915)
			(xy 102.906705 -280.750078) (xy 102.880402 -280.708482) (xy 102.861111 -280.663206) (xy 102.849334 -280.615422)
			(xy 102.845374 -280.566368) (xy 102.516432 -280.566368) (xy 102.515963 -280.590593) (xy 102.508306 -280.638433)
			(xy 102.493195 -280.684465) (xy 102.471009 -280.727536) (xy 102.442303 -280.766566) (xy 102.407797 -280.800576)
			(xy 102.368357 -280.828714) (xy 102.324969 -280.850275) (xy 102.278723 -280.864719) (xy 102.254812 -280.868628)
			(xy 102.24135 -280.870406) (xy 102.220014 -280.88717) (xy 102.176834 -280.993596) (xy 102.180644 -281.020266)
			(xy 102.188772 -281.031188) (xy 102.211875 -281.06218) (xy 102.250363 -281.129215) (xy 102.26548 -281.164792)
			(xy 102.27056 -281.177492) (xy 102.29215 -281.194256) (xy 102.406196 -281.210258) (xy 102.431596 -281.199844)
			(xy 102.439978 -281.189176) (xy 102.454521 -281.171129) (xy 102.488139 -281.139223) (xy 102.526194 -281.112768)
			(xy 102.567813 -281.092372) (xy 102.612037 -281.078505) (xy 102.65785 -281.071485) (xy 102.681024 -281.071066)
			(xy 102.705015 -281.071538) (xy 102.752405 -281.079047) (xy 102.798038 -281.093877) (xy 102.840789 -281.115661)
			(xy 102.879606 -281.143864) (xy 102.913534 -281.177792) (xy 102.941738 -281.21661) (xy 102.963523 -281.259361)
			(xy 102.978352 -281.304993) (xy 102.985861 -281.352383) (xy 102.986332 -281.376374) (xy 102.985799 -281.402037)
			(xy 102.977202 -281.452639) (xy 102.960262 -281.501089) (xy 102.935457 -281.546024) (xy 102.903486 -281.586177)
			(xy 102.884732 -281.603704) (xy 102.873048 -281.614372) (xy 102.865428 -281.644852) (xy 102.905052 -281.74823)
			(xy 102.90914 -281.757662) (xy 102.923379 -281.772464) (xy 102.94228 -281.780497) (xy 102.95255 -281.780996)
			(xy 105.229406 -281.780996) (xy 105.239677 -281.780525) (xy 105.258575 -281.772473) (xy 105.272807 -281.757661)
			(xy 105.276904 -281.74823) (xy 105.316528 -281.644852) (xy 105.308908 -281.614372) (xy 105.297224 -281.603704)
			(xy 105.278455 -281.586193) (xy 105.246482 -281.54604) (xy 105.221684 -281.501101) (xy 105.204759 -281.452644)
			(xy 105.196186 -281.402038) (xy 105.195624 -281.376374) (xy 105.196146 -281.351119) (xy 105.204459 -281.301297)
			(xy 105.22086 -281.253523) (xy 105.244901 -281.2091) (xy 105.275925 -281.16924) (xy 105.313087 -281.13503)
			(xy 105.355373 -281.107404) (xy 105.401629 -281.087114) (xy 105.450594 -281.074714) (xy 105.500932 -281.070543)
			(xy 105.55127 -281.074714) (xy 105.600235 -281.087114) (xy 105.646491 -281.107404) (xy 105.688777 -281.13503)
			(xy 105.725939 -281.16924) (xy 105.756963 -281.2091) (xy 105.781004 -281.253523) (xy 105.797405 -281.301297)
			(xy 105.805718 -281.351119) (xy 105.80624 -281.376374) (xy 105.805706 -281.402036) (xy 105.797107 -281.452636)
			(xy 105.780164 -281.501083) (xy 105.755354 -281.546013) (xy 105.723376 -281.586158) (xy 105.70464 -281.603704)
			(xy 105.692956 -281.614372) (xy 105.685336 -281.644852) (xy 105.72496 -281.74823) (xy 105.729048 -281.757661)
			(xy 105.743287 -281.772461) (xy 105.762189 -281.780492) (xy 105.772458 -281.780996) (xy 108.049568 -281.780996)
			(xy 108.059843 -281.780532) (xy 108.078753 -281.772488) (xy 108.092997 -281.757676) (xy 108.097066 -281.74823)
			(xy 108.13669 -281.644852) (xy 108.12907 -281.614372) (xy 108.117386 -281.603704) (xy 108.098613 -281.586195)
			(xy 108.066635 -281.546044) (xy 108.041831 -281.501105) (xy 108.024903 -281.452648) (xy 108.016328 -281.402039)
			(xy 108.015786 -281.376374) (xy 108.016308 -281.351119) (xy 108.024621 -281.301297) (xy 108.041022 -281.253523)
			(xy 108.065063 -281.2091) (xy 108.096087 -281.16924) (xy 108.133249 -281.13503) (xy 108.175535 -281.107404)
			(xy 108.221791 -281.087114) (xy 108.270756 -281.074714) (xy 108.321094 -281.070543) (xy 108.371432 -281.074714)
			(xy 108.420397 -281.087114) (xy 108.466653 -281.107404) (xy 108.508939 -281.13503) (xy 108.546101 -281.16924)
			(xy 108.577125 -281.2091) (xy 108.601166 -281.253523) (xy 108.617567 -281.301297) (xy 108.62588 -281.351119)
			(xy 108.626402 -281.376374) (xy 108.625751 -281.405074) (xy 108.615013 -281.461459) (xy 108.605066 -281.488388)
			(xy 108.60024 -281.501088) (xy 108.60405 -281.527504) (xy 108.67517 -281.617928) (xy 108.700062 -281.628088)
			(xy 108.713524 -281.626056) (xy 108.732798 -281.623617) (xy 108.771567 -281.621073) (xy 108.790994 -281.620976)
			(xy 108.880148 -281.620976) (xy 108.892467 -281.620181) (xy 108.914237 -281.608631) (xy 108.921804 -281.598878)
			(xy 108.976668 -281.519884) (xy 108.979716 -281.4955) (xy 108.975398 -281.483562) (xy 108.96633 -281.457695)
			(xy 108.956494 -281.403777) (xy 108.95584 -281.376374) (xy 108.956362 -281.351119) (xy 108.964675 -281.301297)
			(xy 108.981076 -281.253523) (xy 109.005117 -281.2091) (xy 109.036141 -281.16924) (xy 109.073303 -281.13503)
			(xy 109.115589 -281.107404) (xy 109.161845 -281.087114) (xy 109.21081 -281.074714) (xy 109.261148 -281.070543)
			(xy 109.311486 -281.074714) (xy 109.360451 -281.087114) (xy 109.406707 -281.107404) (xy 109.448993 -281.13503)
			(xy 109.486155 -281.16924) (xy 109.517179 -281.2091) (xy 109.54122 -281.253523) (xy 109.557621 -281.301297)
			(xy 109.565934 -281.351119) (xy 109.566456 -281.376374) (xy 109.56586 -281.403782) (xy 109.556023 -281.45771)
			(xy 109.546898 -281.483562) (xy 109.54258 -281.4955) (xy 109.545628 -281.519884) (xy 109.600492 -281.598878)
			(xy 109.608058 -281.608633) (xy 109.629829 -281.620184) (xy 109.642148 -281.620976) (xy 109.731048 -281.620976)
			(xy 109.750475 -281.62108) (xy 109.789244 -281.623621) (xy 109.808518 -281.626056) (xy 109.82198 -281.628088)
			(xy 109.846872 -281.617928) (xy 109.917992 -281.527504) (xy 109.921802 -281.501088) (xy 109.916976 -281.488388)
			(xy 109.907054 -281.461452) (xy 109.896307 -281.405071) (xy 109.89564 -281.376374) (xy 109.896162 -281.351119)
			(xy 109.904475 -281.301297) (xy 109.920876 -281.253523) (xy 109.944917 -281.2091) (xy 109.975941 -281.16924)
			(xy 110.013103 -281.13503) (xy 110.055389 -281.107404) (xy 110.101645 -281.087114) (xy 110.15061 -281.074714)
			(xy 110.200948 -281.070543) (xy 110.251286 -281.074714) (xy 110.300251 -281.087114) (xy 110.346507 -281.107404)
			(xy 110.388793 -281.13503) (xy 110.425955 -281.16924) (xy 110.456979 -281.2091) (xy 110.48102 -281.253523)
			(xy 110.497421 -281.301297) (xy 110.505734 -281.351119) (xy 110.506256 -281.376374) (xy 110.505722 -281.402036)
			(xy 110.497123 -281.452636) (xy 110.480181 -281.501084) (xy 110.455372 -281.546015) (xy 110.423395 -281.586162)
			(xy 110.404656 -281.603704) (xy 110.392972 -281.614372) (xy 110.385352 -281.644852) (xy 110.424976 -281.74823)
			(xy 110.42906 -281.757671) (xy 110.443295 -281.772493) (xy 110.462199 -281.780554) (xy 110.472474 -281.780996)
			(xy 110.968028 -281.780996) (xy 110.978096 -281.781424) (xy 110.996693 -281.789145) (xy 111.004096 -281.795982)
			(xy 111.0742 -281.866086) (xy 111.081598 -281.872934) (xy 111.100196 -281.88067) (xy 111.110268 -281.881072)
			(xy 113.47958 -281.881072) (xy 113.48466 -281.881072) (xy 113.510058 -281.881573) (xy 113.560153 -281.889975)
			(xy 113.608166 -281.906554) (xy 113.652772 -281.930853) (xy 113.69274 -281.962201) (xy 113.710212 -281.98064)
			(xy 113.717324 -281.98826) (xy 113.735866 -281.996896)
		)
		(stroke
			(width 0)
			(type solid)
		)
		(fill yes)
		(layer "In6.Cu")
		(net "PVDDCR_CPU1_P1")
	)
	(gr_poly
		(pts
			(xy 40.464232 -366.76203) (xy 40.4743 -366.761602) (xy 40.492899 -366.753883) (xy 40.5003 -366.747044)
			(xy 40.5511 -366.696244) (xy 40.557885 -366.688822) (xy 40.565494 -366.670225) (xy 40.565832 -366.660176)
			(xy 40.566206 -366.63495) (xy 40.572785 -366.58493) (xy 40.585892 -366.536212) (xy 40.605299 -366.489643)
			(xy 40.617648 -366.467644) (xy 40.622474 -366.459516) (xy 40.625522 -366.440974) (xy 40.60952 -366.365028)
			(xy 40.60716 -366.356002) (xy 40.596993 -366.340378) (xy 40.589708 -366.334548) (xy 40.589454 -366.334294)
			(xy 40.56904 -366.31896) (xy 40.532107 -366.283705) (xy 40.500215 -366.243833) (xy 40.473936 -366.200059)
			(xy 40.453739 -366.153166) (xy 40.439988 -366.103995) (xy 40.436038 -366.07877) (xy 40.43434 -366.069479)
			(xy 40.425064 -366.053042) (xy 40.418004 -366.046766) (xy 40.365172 -366.003078) (xy 40.357624 -365.997315)
			(xy 40.339617 -365.991328) (xy 40.33012 -365.991394) (xy 40.310816 -365.991902) (xy 40.283563 -365.99144)
			(xy 40.229611 -365.983685) (xy 40.177312 -365.96833) (xy 40.127731 -365.945689) (xy 40.081876 -365.916222)
			(xy 40.040682 -365.880529) (xy 40.004988 -365.839337) (xy 39.975519 -365.793483) (xy 39.952875 -365.743903)
			(xy 39.937519 -365.691605) (xy 39.929761 -365.637653) (xy 39.929761 -365.583147) (xy 39.937519 -365.529195)
			(xy 39.952875 -365.476897) (xy 39.975519 -365.427317) (xy 40.004988 -365.381463) (xy 40.040682 -365.340271)
			(xy 40.081876 -365.304578) (xy 40.127731 -365.275111) (xy 40.177312 -365.25247) (xy 40.229611 -365.237115)
			(xy 40.283563 -365.22936) (xy 40.310816 -365.228886) (xy 40.338129 -365.229348) (xy 40.392196 -365.237131)
			(xy 40.4446 -365.252549) (xy 40.494267 -365.275288) (xy 40.540181 -365.304881) (xy 40.581403 -365.340723)
			(xy 40.617088 -365.382081) (xy 40.646507 -365.428107) (xy 40.669056 -365.477861) (xy 40.684275 -365.530323)
			(xy 40.688514 -365.557308) (xy 40.690206 -365.566603) (xy 40.699472 -365.583052) (xy 40.706548 -365.589312)
			(xy 40.75938 -365.633) (xy 40.766925 -365.638772) (xy 40.784933 -365.64478) (xy 40.794432 -365.644684)
			(xy 40.813736 -365.644176) (xy 40.840313 -365.644632) (xy 40.892954 -365.652004) (xy 40.944062 -365.666613)
			(xy 40.992646 -365.688178) (xy 41.037765 -365.716279) (xy 41.078545 -365.750373) (xy 41.114196 -365.7898)
			(xy 41.129458 -365.811562) (xy 41.135046 -365.81969) (xy 41.151302 -365.830866) (xy 41.239948 -365.849154)
			(xy 41.259252 -365.845852) (xy 41.267634 -365.840518) (xy 41.290553 -365.826618) (xy 41.339461 -365.80468)
			(xy 41.39096 -365.789808) (xy 41.444033 -365.782292) (xy 41.470834 -365.781844) (xy 41.500778 -365.782425)
			(xy 41.559931 -365.791776) (xy 41.616896 -365.810259) (xy 41.670271 -365.837418) (xy 41.718744 -365.872587)
			(xy 41.740328 -365.89335) (xy 41.740582 -365.893604) (xy 41.747994 -365.900288) (xy 41.766427 -365.907885)
			(xy 41.786365 -365.907885) (xy 41.804798 -365.900288) (xy 41.81221 -365.893604) (xy 42.533062 -365.172752)
			(xy 42.548334 -365.157748) (xy 42.58075 -365.129777) (xy 42.597832 -365.116872) (xy 42.874438 -364.911894)
			(xy 42.874946 -364.911386) (xy 42.976478 -364.837025) (xy 43.184075 -364.694701) (xy 43.396601 -364.55985)
			(xy 43.61379 -364.432642) (xy 43.835364 -364.313239) (xy 44.061045 -364.201791) (xy 44.290546 -364.09844)
			(xy 44.523578 -364.003316) (xy 44.641516 -363.959394) (xy 46.367446 -363.324648) (xy 46.372543 -363.322641)
			(xy 46.381775 -363.31675) (xy 46.385734 -363.312964) (xy 46.397926 -363.300772) (xy 46.404606 -363.293363)
			(xy 46.412195 -363.274935) (xy 46.412183 -363.255006) (xy 46.404573 -363.236587) (xy 46.397926 -363.229144)
			(xy 46.393608 -363.224826) (xy 46.383448 -363.21873) (xy 46.377606 -363.216698) (xy 46.352503 -363.207964)
			(xy 46.304803 -363.184522) (xy 46.260819 -363.154685) (xy 46.221403 -363.119031) (xy 46.187318 -363.078251)
			(xy 46.159225 -363.033134) (xy 46.137666 -362.984553) (xy 46.123061 -362.93345) (xy 46.115691 -362.880815)
			(xy 46.115224 -362.85424) (xy 46.1157 -362.826872) (xy 46.123532 -362.772698) (xy 46.139026 -362.7202)
			(xy 46.161865 -362.670455) (xy 46.191579 -362.624486) (xy 46.209204 -362.603542) (xy 46.209204 -362.603288)
			(xy 46.209458 -362.603288) (xy 46.215045 -362.596202) (xy 46.221288 -362.579285) (xy 46.22165 -362.570268)
			(xy 46.22165 -362.503212) (xy 46.221294 -362.494194) (xy 46.215054 -362.477272) (xy 46.209458 -362.470192)
			(xy 46.209204 -362.469938) (xy 46.191561 -362.449005) (xy 46.161833 -362.403036) (xy 46.138983 -362.353288)
			(xy 46.123483 -362.300784) (xy 46.11565 -362.246602) (xy 46.115645 -362.191858) (xy 46.12347 -362.137675)
			(xy 46.138962 -362.085169) (xy 46.161804 -362.035417) (xy 46.191525 -361.989443) (xy 46.209204 -361.968542)
			(xy 46.209204 -361.968288) (xy 46.209458 -361.968288) (xy 46.215045 -361.961202) (xy 46.221288 -361.944285)
			(xy 46.22165 -361.935268) (xy 46.22165 -361.868212) (xy 46.221294 -361.859194) (xy 46.215054 -361.842272)
			(xy 46.209458 -361.835192) (xy 46.209204 -361.834938) (xy 46.191561 -361.814005) (xy 46.161833 -361.768036)
			(xy 46.138983 -361.718288) (xy 46.123483 -361.665784) (xy 46.11565 -361.611602) (xy 46.115645 -361.556858)
			(xy 46.12347 -361.502675) (xy 46.138962 -361.450169) (xy 46.161804 -361.400417) (xy 46.191525 -361.354443)
			(xy 46.209204 -361.333542) (xy 46.209204 -361.333288) (xy 46.209458 -361.333288) (xy 46.215045 -361.326202)
			(xy 46.221288 -361.309285) (xy 46.22165 -361.300268) (xy 46.22165 -361.233212) (xy 46.221294 -361.224194)
			(xy 46.215054 -361.207272) (xy 46.209458 -361.200192) (xy 46.209204 -361.199938) (xy 46.191561 -361.179005)
			(xy 46.161833 -361.133036) (xy 46.138983 -361.083288) (xy 46.123483 -361.030784) (xy 46.11565 -360.976602)
			(xy 46.115645 -360.921858) (xy 46.12347 -360.867675) (xy 46.138962 -360.815169) (xy 46.161804 -360.765417)
			(xy 46.191525 -360.719443) (xy 46.209204 -360.698542) (xy 46.209204 -360.698288) (xy 46.209458 -360.698288)
			(xy 46.215045 -360.691202) (xy 46.221288 -360.674285) (xy 46.22165 -360.665268) (xy 46.22165 -360.598212)
			(xy 46.221294 -360.589194) (xy 46.215054 -360.572272) (xy 46.209458 -360.565192) (xy 46.209204 -360.564938)
			(xy 46.191561 -360.544005) (xy 46.161833 -360.498036) (xy 46.138983 -360.448288) (xy 46.123483 -360.395784)
			(xy 46.11565 -360.341602) (xy 46.115645 -360.286858) (xy 46.12347 -360.232675) (xy 46.138962 -360.180169)
			(xy 46.161804 -360.130417) (xy 46.191525 -360.084443) (xy 46.209204 -360.063542) (xy 46.209204 -360.063288)
			(xy 46.209458 -360.063288) (xy 46.215045 -360.056202) (xy 46.221288 -360.039285) (xy 46.22165 -360.030268)
			(xy 46.22165 -359.963212) (xy 46.221294 -359.954194) (xy 46.215054 -359.937272) (xy 46.209458 -359.930192)
			(xy 46.209204 -359.929938) (xy 46.191565 -359.909006) (xy 46.161847 -359.863038) (xy 46.139011 -359.81329)
			(xy 46.123529 -359.760787) (xy 46.115719 -359.706609) (xy 46.115224 -359.67924) (xy 46.115685 -359.651986)
			(xy 46.123437 -359.598033) (xy 46.13879 -359.545732) (xy 46.161431 -359.496149) (xy 46.190898 -359.450293)
			(xy 46.226592 -359.409098) (xy 46.267786 -359.373403) (xy 46.313642 -359.343935) (xy 46.363224 -359.321293)
			(xy 46.415525 -359.305939) (xy 46.469478 -359.298185) (xy 46.496732 -359.297732) (xy 46.524101 -359.298206)
			(xy 46.578277 -359.306035) (xy 46.630777 -359.321526) (xy 46.680524 -359.344363) (xy 46.726496 -359.374075)
			(xy 46.74743 -359.391712) (xy 46.747684 -359.391712) (xy 46.747684 -359.391966) (xy 46.754769 -359.397556)
			(xy 46.771686 -359.403808) (xy 46.780704 -359.404158) (xy 46.84776 -359.404158) (xy 46.85678 -359.403806)
			(xy 46.873709 -359.397575) (xy 46.88078 -359.391966) (xy 46.881034 -359.391712) (xy 46.901967 -359.374071)
			(xy 46.947935 -359.344347) (xy 46.997681 -359.321501) (xy 47.050183 -359.306005) (xy 47.104361 -359.298176)
			(xy 47.159103 -359.298176) (xy 47.213281 -359.306005) (xy 47.265783 -359.321501) (xy 47.315529 -359.344347)
			(xy 47.361497 -359.374071) (xy 47.38243 -359.391712) (xy 47.382684 -359.391712) (xy 47.382684 -359.391966)
			(xy 47.389769 -359.397556) (xy 47.406686 -359.403808) (xy 47.415704 -359.404158) (xy 47.48276 -359.404158)
			(xy 47.49178 -359.403806) (xy 47.508709 -359.397575) (xy 47.51578 -359.391966) (xy 47.516034 -359.391712)
			(xy 47.536966 -359.374071) (xy 47.582933 -359.344349) (xy 47.63268 -359.321509) (xy 47.685183 -359.306023)
			(xy 47.739362 -359.298209) (xy 47.766732 -359.297732) (xy 47.793562 -359.298183) (xy 47.846693 -359.305691)
			(xy 47.898248 -359.320569) (xy 47.94721 -359.342523) (xy 47.992614 -359.371121) (xy 48.033563 -359.405797)
			(xy 48.06925 -359.445869) (xy 48.098972 -359.490545) (xy 48.12214 -359.538944) (xy 48.1383 -359.590113)
			(xy 48.14316 -359.616502) (xy 48.144938 -359.627424) (xy 48.156876 -359.645458) (xy 48.240442 -359.697274)
			(xy 48.262032 -359.700068) (xy 48.272446 -359.69702) (xy 48.299366 -359.689407) (xy 48.35471 -359.681247)
			(xy 48.382682 -359.680764) (xy 48.41005 -359.681242) (xy 48.464221 -359.689077) (xy 48.516717 -359.704575)
			(xy 48.566458 -359.727418) (xy 48.612423 -359.757136) (xy 48.63338 -359.774744) (xy 48.633634 -359.774744)
			(xy 48.633634 -359.774998) (xy 48.640722 -359.780578) (xy 48.65764 -359.786809) (xy 48.666654 -359.78719)
			(xy 48.73371 -359.78719) (xy 48.742726 -359.786829) (xy 48.759639 -359.780578) (xy 48.76673 -359.774998)
			(xy 48.766984 -359.774744) (xy 48.787917 -359.757103) (xy 48.833885 -359.727379) (xy 48.883631 -359.704533)
			(xy 48.936133 -359.689037) (xy 48.990311 -359.681208) (xy 49.045053 -359.681208) (xy 49.099231 -359.689037)
			(xy 49.151733 -359.704533) (xy 49.201479 -359.727379) (xy 49.247447 -359.757103) (xy 49.26838 -359.774744)
			(xy 49.268634 -359.774744) (xy 49.268634 -359.774998) (xy 49.275722 -359.780578) (xy 49.29264 -359.786809)
			(xy 49.301654 -359.78719) (xy 49.36871 -359.78719) (xy 49.377726 -359.786829) (xy 49.394639 -359.780578)
			(xy 49.40173 -359.774998) (xy 49.401984 -359.774744) (xy 49.422917 -359.757103) (xy 49.468885 -359.727379)
			(xy 49.518631 -359.704533) (xy 49.571133 -359.689037) (xy 49.625311 -359.681208) (xy 49.680053 -359.681208)
			(xy 49.734231 -359.689037) (xy 49.786733 -359.704533) (xy 49.836479 -359.727379) (xy 49.882447 -359.757103)
			(xy 49.90338 -359.774744) (xy 49.903634 -359.774744) (xy 49.903634 -359.774998) (xy 49.910722 -359.780578)
			(xy 49.92764 -359.786809) (xy 49.936654 -359.78719) (xy 50.00371 -359.78719) (xy 50.012726 -359.786829)
			(xy 50.029639 -359.780578) (xy 50.03673 -359.774998) (xy 50.036984 -359.774744) (xy 50.057914 -359.757099)
			(xy 50.103879 -359.727368) (xy 50.153626 -359.70452) (xy 50.20613 -359.689026) (xy 50.260311 -359.681204)
			(xy 50.287682 -359.680764) (xy 50.288444 -359.680764) (xy 50.318217 -359.681379) (xy 50.377031 -359.690696)
			(xy 50.405538 -359.699306) (xy 50.415444 -359.702608) (xy 50.436526 -359.700576) (xy 50.519584 -359.655364)
			(xy 50.532284 -359.639108) (xy 50.535078 -359.628948) (xy 50.542721 -359.602236) (xy 50.564673 -359.551199)
			(xy 50.593793 -359.503884) (xy 50.629467 -359.461292) (xy 50.670939 -359.424323) (xy 50.717335 -359.393759)
			(xy 50.767672 -359.370245) (xy 50.820886 -359.35428) (xy 50.875853 -359.346199) (xy 50.903632 -359.345738)
			(xy 50.932525 -359.346272) (xy 50.98965 -359.354986) (xy 51.044809 -359.37221) (xy 51.096742 -359.39755)
			(xy 51.120802 -359.413556) (xy 51.128422 -359.41889) (xy 51.146964 -359.423462) (xy 51.22418 -359.413048)
			(xy 51.233387 -359.411355) (xy 51.249789 -359.402361) (xy 51.256184 -359.395522) (xy 51.274397 -359.374635)
			(xy 51.315827 -359.337831) (xy 51.36215 -359.307416) (xy 51.41239 -359.284029) (xy 51.465487 -359.268166)
			(xy 51.520322 -359.260159) (xy 51.54803 -359.259632) (xy 51.573984 -359.260065) (xy 51.625413 -359.267096)
			(xy 51.675413 -359.281038) (xy 51.723061 -359.301632) (xy 51.767474 -359.3285) (xy 51.807833 -359.361142)
			(xy 51.825906 -359.379774) (xy 51.825906 -359.380028) (xy 51.832849 -359.386727) (xy 51.850341 -359.394832)
			(xy 51.859942 -359.395776) (xy 51.930046 -359.399586) (xy 51.939676 -359.399754) (xy 51.957963 -359.39376)
			(xy 51.965606 -359.387902) (xy 51.986336 -359.370957) (xy 52.031649 -359.342436) (xy 52.080506 -359.320536)
			(xy 52.131948 -359.305689) (xy 52.184961 -359.298187) (xy 52.211732 -359.297732) (xy 52.239101 -359.298206)
			(xy 52.293277 -359.306035) (xy 52.345777 -359.321526) (xy 52.395524 -359.344363) (xy 52.441496 -359.374075)
			(xy 52.46243 -359.391712) (xy 52.462684 -359.391712) (xy 52.462684 -359.391966) (xy 52.469769 -359.397556)
			(xy 52.486686 -359.403808) (xy 52.495704 -359.404158) (xy 52.56276 -359.404158) (xy 52.57178 -359.403806)
			(xy 52.588709 -359.397575) (xy 52.59578 -359.391966) (xy 52.596034 -359.391712) (xy 52.616966 -359.374071)
			(xy 52.662933 -359.344349) (xy 52.71268 -359.321509) (xy 52.765183 -359.306023) (xy 52.819362 -359.298209)
			(xy 52.846732 -359.297732) (xy 52.873982 -359.298198) (xy 52.927928 -359.305958) (xy 52.980219 -359.321318)
			(xy 53.029793 -359.343963) (xy 53.075639 -359.373432) (xy 53.116825 -359.409126) (xy 53.152511 -359.450319)
			(xy 53.181972 -359.49617) (xy 53.204608 -359.545748) (xy 53.219957 -359.598043) (xy 53.227708 -359.65199)
			(xy 53.22824 -359.67924) (xy 53.22824 -359.679748) (xy 53.227738 -359.707633) (xy 53.21958 -359.762805)
			(xy 53.203476 -359.816201) (xy 53.179768 -359.866682) (xy 53.148962 -359.913173) (xy 53.130704 -359.934256)
			(xy 53.124354 -359.941114) (xy 53.117496 -359.958894) (xy 53.11775 -360.036364) (xy 53.118147 -360.045647)
			(xy 53.124785 -360.062985) (xy 53.130704 -360.070146) (xy 53.149118 -360.09127) (xy 53.18019 -360.137904)
			(xy 53.2041 -360.188584) (xy 53.220333 -360.242218) (xy 53.228541 -360.297651) (xy 53.229002 -360.32567)
			(xy 53.227986 -360.35488) (xy 53.22697 -360.368088) (xy 53.238146 -360.392218) (xy 53.318918 -360.450638)
			(xy 53.326103 -360.455402) (xy 53.342627 -360.460282) (xy 53.359835 -360.45942) (xy 53.36794 -360.45648)
			(xy 53.65115 -360.339386) (xy 53.655714 -360.33738) (xy 53.664031 -360.331883) (xy 53.66766 -360.328464)
			(xy 53.962554 -360.03357) (xy 53.968863 -360.026773) (xy 53.976535 -360.009905) (xy 53.977666 -359.991409)
			(xy 53.972106 -359.973733) (xy 53.966618 -359.96626) (xy 53.951241 -359.946015) (xy 53.925414 -359.902227)
			(xy 53.905631 -359.855396) (xy 53.892242 -359.806353) (xy 53.885484 -359.755967) (xy 53.885084 -359.730548)
			(xy 53.885544 -359.703293) (xy 53.893295 -359.649336) (xy 53.908647 -359.597032) (xy 53.931287 -359.547445)
			(xy 53.960753 -359.501586) (xy 53.996447 -359.460387) (xy 54.037641 -359.424687) (xy 54.083496 -359.395214)
			(xy 54.13308 -359.372567) (xy 54.185381 -359.357207) (xy 54.239337 -359.349448) (xy 54.266592 -359.34904)
			(xy 54.292242 -359.349463) (xy 54.343077 -359.356355) (xy 54.392528 -359.37) (xy 54.439704 -359.390154)
			(xy 54.483751 -359.416451) (xy 54.523874 -359.448417) (xy 54.541928 -359.466642) (xy 54.54982 -359.474131)
			(xy 54.569995 -359.48222) (xy 54.591711 -359.481293) (xy 54.601618 -359.476802) (xy 54.622056 -359.46658)
			(xy 54.663596 -359.447524) (xy 54.684676 -359.438702) (xy 54.694074 -359.434892) (xy 54.694582 -359.434892)
			(xy 63.586868 -355.750876) (xy 63.587376 -355.750622) (xy 63.63232 -355.732681) (xy 63.724943 -355.704635)
			(xy 63.819866 -355.685782) (xy 63.916178 -355.676304) (xy 63.964566 -355.675692) (xy 71.5899 -355.675692)
			(xy 71.664842 -355.676226) (xy 71.81449 -355.684646) (xy 71.96343 -355.701444) (xy 72.111194 -355.726566)
			(xy 72.257318 -355.759933) (xy 72.40134 -355.801441) (xy 72.542809 -355.850958) (xy 72.61225 -355.879146)
			(xy 73.65746 -356.312216) (xy 73.696539 -356.327958) (xy 73.776667 -356.354006) (xy 73.85859 -356.373699)
			(xy 73.941803 -356.386916) (xy 74.025796 -356.393575) (xy 74.067924 -356.394004) (xy 97.980754 -356.394004)
			(xy 97.99082 -356.393571) (xy 98.00941 -356.385843) (xy 98.016822 -356.379018) (xy 105.026714 -349.369126)
			(xy 105.034112 -349.362279) (xy 105.05271 -349.354546) (xy 105.062782 -349.35414) (xy 107.619038 -349.35414)
			(xy 107.628436 -349.353124) (xy 107.628944 -349.353124) (xy 107.6361 -349.351413) (xy 107.649117 -349.344572)
			(xy 107.654598 -349.339662) (xy 108.07192 -348.92234) (xy 108.07192 -348.91091) (xy 112.14608 -344.83675)
			(xy 112.146588 -344.836242) (xy 113.016792 -343.98712) (xy 113.0173 -343.986612) (xy 115.361212 -341.6427)
			(xy 115.366197 -341.637272) (xy 115.373054 -341.624235) (xy 115.374674 -341.617046) (xy 115.374674 -341.616538)
			(xy 115.37569 -341.60714) (xy 115.37569 -337.357974) (xy 115.375336 -337.349246) (xy 115.36945 -337.332815)
			(xy 115.358347 -337.319347) (xy 115.351052 -337.31454) (xy 115.327168 -337.29967) (xy 115.28365 -337.264014)
			(xy 115.245839 -337.222354) (xy 115.214556 -337.175593) (xy 115.190479 -337.124746) (xy 115.17413 -337.070913)
			(xy 115.165864 -337.015264) (xy 115.165378 -336.987134) (xy 115.165378 -336.981292) (xy 115.165028 -336.971093)
			(xy 115.157304 -336.952223) (xy 115.150392 -336.944716) (xy 106.571288 -328.365612) (xy 106.567506 -328.362066)
			(xy 106.558798 -328.35644) (xy 106.554016 -328.354436) (xy 106.544618 -328.350626) (xy 106.533696 -328.35088)
			(xy 106.517694 -328.351134) (xy 106.49036 -328.350664) (xy 106.436253 -328.342859) (xy 106.383814 -328.327409)
			(xy 106.334118 -328.304631) (xy 106.288183 -328.274992) (xy 106.26725 -328.257408) (xy 106.263186 -328.25436)
			(xy 106.257697 -328.250664) (xy 106.245351 -328.245911) (xy 106.238802 -328.244962) (xy 106.233976 -328.244708)
			(xy 106.166412 -328.244708) (xy 106.161586 -328.244962) (xy 106.15464 -328.245877) (xy 106.141617 -328.251028)
			(xy 106.135932 -328.255122) (xy 106.133392 -328.257154) (xy 106.112472 -328.27478) (xy 106.066535 -328.304483)
			(xy 106.016826 -328.327317) (xy 105.964364 -328.342813) (xy 105.910226 -328.350655) (xy 105.855523 -328.35068)
			(xy 105.801378 -328.342888) (xy 105.748901 -328.327439) (xy 105.699171 -328.304651) (xy 105.653207 -328.27499)
			(xy 105.63225 -328.257408) (xy 105.628186 -328.25436) (xy 105.622697 -328.250664) (xy 105.610351 -328.245911)
			(xy 105.603802 -328.244962) (xy 105.598976 -328.244708) (xy 105.531412 -328.244708) (xy 105.526586 -328.244962)
			(xy 105.520021 -328.245847) (xy 105.507667 -328.250615) (xy 105.502202 -328.25436) (xy 105.498138 -328.257408)
			(xy 105.47721 -328.274997) (xy 105.431271 -328.304628) (xy 105.381573 -328.327399) (xy 105.329134 -328.342843)
			(xy 105.275027 -328.350645) (xy 105.247694 -328.351134) (xy 105.220442 -328.350648) (xy 105.166494 -328.342891)
			(xy 105.114198 -328.327535) (xy 105.06462 -328.304894) (xy 105.018769 -328.275428) (xy 104.977577 -328.239737)
			(xy 104.941884 -328.198547) (xy 104.912415 -328.152697) (xy 104.889772 -328.10312) (xy 104.874413 -328.050826)
			(xy 104.866654 -327.996878) (xy 104.866186 -327.969626) (xy 104.866186 -327.96861) (xy 104.86644 -327.956672)
			(xy 104.86644 -327.952862) (xy 104.866075 -327.943847) (xy 104.859822 -327.926937) (xy 104.854248 -327.919842)
			(xy 104.819958 -327.884536) (xy 104.801416 -327.865486) (xy 104.800908 -327.864978) (xy 104.797385 -327.861606)
			(xy 104.789327 -327.856115) (xy 104.784906 -327.854056) (xy 104.775254 -327.849992) (xy 102.96017 -327.849992)
			(xy 102.94963 -327.850569) (xy 102.93034 -327.859085) (xy 102.922832 -327.866502) (xy 102.872032 -327.921874)
			(xy 102.868998 -327.925396) (xy 102.864135 -327.933318) (xy 102.86238 -327.937622) (xy 102.861618 -327.939908)
			(xy 102.858062 -327.950068) (xy 102.859078 -327.95972) (xy 102.859078 -327.960736) (xy 102.859332 -327.962768)
			(xy 102.860602 -327.987914) (xy 102.860602 -327.995788) (xy 102.860063 -328.023002) (xy 102.852215 -328.076864)
			(xy 102.836792 -328.129064) (xy 102.814106 -328.178542) (xy 102.784618 -328.224293) (xy 102.748927 -328.265389)
			(xy 102.707757 -328.300994) (xy 102.661944 -328.330387) (xy 102.61242 -328.35297) (xy 102.560188 -328.368285)
			(xy 102.506309 -328.37602) (xy 102.479094 -328.376534) (xy 102.45176 -328.376064) (xy 102.397653 -328.368259)
			(xy 102.345214 -328.352809) (xy 102.295518 -328.330031) (xy 102.249583 -328.300392) (xy 102.22865 -328.282808)
			(xy 102.224586 -328.27976) (xy 102.219097 -328.276064) (xy 102.206751 -328.271311) (xy 102.200202 -328.270362)
			(xy 102.195376 -328.270108) (xy 102.127812 -328.270108) (xy 102.122986 -328.270362) (xy 102.11604 -328.271277)
			(xy 102.103017 -328.276428) (xy 102.097332 -328.280522) (xy 102.094792 -328.282554) (xy 102.073872 -328.30018)
			(xy 102.027935 -328.329883) (xy 101.978226 -328.352717) (xy 101.925764 -328.368213) (xy 101.871626 -328.376055)
			(xy 101.816923 -328.37608) (xy 101.762778 -328.368288) (xy 101.710301 -328.352839) (xy 101.660571 -328.330051)
			(xy 101.614607 -328.30039) (xy 101.59365 -328.282808) (xy 101.589586 -328.27976) (xy 101.584097 -328.276064)
			(xy 101.571751 -328.271311) (xy 101.565202 -328.270362) (xy 101.560376 -328.270108) (xy 101.492812 -328.270108)
			(xy 101.487986 -328.270362) (xy 101.481421 -328.271247) (xy 101.469067 -328.276015) (xy 101.463602 -328.27976)
			(xy 101.459538 -328.282808) (xy 101.43861 -328.300397) (xy 101.392671 -328.330028) (xy 101.342973 -328.352799)
			(xy 101.290534 -328.368243) (xy 101.236427 -328.376045) (xy 101.209094 -328.376534) (xy 101.181888 -328.376051)
			(xy 101.128029 -328.36832) (xy 101.075815 -328.353016) (xy 101.026304 -328.330449) (xy 100.980502 -328.301077)
			(xy 100.939337 -328.265497) (xy 100.903644 -328.224428) (xy 100.874148 -328.178706) (xy 100.851447 -328.129257)
			(xy 100.836001 -328.077084) (xy 100.828124 -328.023246) (xy 100.827586 -327.996042) (xy 100.827586 -327.994518)
			(xy 100.82911 -327.960736) (xy 100.830126 -327.950068) (xy 100.826824 -327.939908) (xy 100.825231 -327.935705)
			(xy 100.820757 -327.927911) (xy 100.817934 -327.924414) (xy 100.776024 -327.878186) (xy 100.775516 -327.877678)
			(xy 100.763324 -327.86447) (xy 100.755996 -327.857924) (xy 100.737832 -327.85048) (xy 100.728018 -327.849992)
			(xy 67.92849 -327.849992) (xy 67.920297 -327.850302) (xy 67.904752 -327.855486) (xy 67.89801 -327.860152)
			(xy 67.894708 -327.8632) (xy 67.893438 -327.864216) (xy 67.89166 -327.86574) (xy 64.622934 -331.134466)
			(xy 64.619407 -331.138193) (xy 64.613765 -331.146762) (xy 64.611758 -331.151484) (xy 64.608202 -331.16012)
			(xy 64.608202 -334.948784) (xy 64.607763 -334.958847) (xy 64.600028 -334.97743) (xy 64.593216 -334.984852)
			(xy 61.90234 -337.675728) (xy 61.894942 -337.682573) (xy 61.876343 -337.690297) (xy 61.866272 -337.690714)
			(xy 23.181564 -337.690714) (xy 23.173373 -337.691029) (xy 23.157834 -337.696221) (xy 23.151084 -337.700874)
			(xy 23.147782 -337.703922) (xy 23.146512 -337.704938) (xy 23.144734 -337.706462) (xy 22.191218 -338.659978)
			(xy 22.187692 -338.663706) (xy 22.182054 -338.672276) (xy 22.180042 -338.676996) (xy 22.176486 -338.685632)
			(xy 22.176486 -342.530684) (xy 22.177248 -342.539066) (xy 22.179788 -342.549988) (xy 22.181058 -342.554306)
			(xy 22.281896 -342.864186) (xy 22.287992 -342.876632) (xy 24.376634 -346.002356) (xy 24.3952 -346.031034)
			(xy 24.426222 -346.091905) (xy 24.44988 -346.155998) (xy 24.465847 -346.222425) (xy 24.473903 -346.290268)
			(xy 24.474424 -346.324428) (xy 24.474424 -347.388942) (xy 24.474911 -347.398943) (xy 24.482536 -347.417435)
			(xy 24.496624 -347.431635) (xy 24.505666 -347.435932) (xy 24.606758 -347.477842) (xy 24.63673 -347.471746)
			(xy 24.647652 -347.460824) (xy 24.669266 -347.440043) (xy 24.71777 -347.404802) (xy 24.771189 -347.377579)
			(xy 24.828207 -347.359044) (xy 24.887422 -347.349653) (xy 24.9174 -347.349064) (xy 24.917654 -347.349064)
			(xy 24.94491 -347.349524) (xy 24.998867 -347.357275) (xy 25.051172 -347.372627) (xy 25.10076 -347.395266)
			(xy 25.146621 -347.424733) (xy 25.187821 -347.460426) (xy 25.223523 -347.50162) (xy 25.252998 -347.547475)
			(xy 25.275647 -347.597058) (xy 25.291009 -347.64936) (xy 25.298771 -347.703316) (xy 25.299162 -347.730572)
			(xy 25.298678 -347.758484) (xy 25.290546 -347.813712) (xy 25.274452 -347.867165) (xy 25.250739 -347.917701)
			(xy 25.219913 -347.964242) (xy 25.201626 -347.985334) (xy 25.195276 -347.992446) (xy 25.188672 -348.009718)
			(xy 25.188672 -348.087442) (xy 25.189083 -348.096719) (xy 25.195743 -348.114037) (xy 25.201626 -348.121224)
			(xy 25.219901 -348.142325) (xy 25.250723 -348.188865) (xy 25.274434 -348.2394) (xy 25.290529 -348.29285)
			(xy 25.298665 -348.348075) (xy 25.299162 -348.375986) (xy 25.2987 -348.403238) (xy 25.290944 -348.457188)
			(xy 25.275589 -348.509485) (xy 25.252946 -348.559064) (xy 25.223478 -348.604916) (xy 25.187784 -348.646106)
			(xy 25.14659 -348.681797) (xy 25.103478 -348.7095) (xy 28.918321 -348.7095) (xy 28.92249 -348.653877)
			(xy 28.934903 -348.599498) (xy 28.955282 -348.547575) (xy 28.983173 -348.49927) (xy 29.017952 -348.455662)
			(xy 29.058842 -348.417725) (xy 29.10493 -348.386307) (xy 29.155187 -348.362108) (xy 29.208488 -348.345671)
			(xy 29.263645 -348.337363) (xy 29.291534 -348.33687) (xy 29.317956 -348.337315) (xy 29.370272 -348.344769)
			(xy 29.42101 -348.359538) (xy 29.469154 -348.381324) (xy 29.513739 -348.409692) (xy 29.534104 -348.426532)
			(xy 29.540962 -348.432374) (xy 29.55798 -348.438724) (xy 29.642308 -348.438724) (xy 29.659326 -348.432374)
			(xy 29.666184 -348.426532) (xy 29.68655 -348.409693) (xy 29.731136 -348.381328) (xy 29.77928 -348.359541)
			(xy 29.830017 -348.34477) (xy 29.882332 -348.33731) (xy 29.935176 -348.33731) (xy 29.987491 -348.34477)
			(xy 30.038228 -348.359541) (xy 30.086372 -348.381328) (xy 30.130958 -348.409693) (xy 30.151324 -348.426532)
			(xy 30.158182 -348.432374) (xy 30.1752 -348.438724) (xy 30.259528 -348.438724) (xy 30.276546 -348.432374)
			(xy 30.283404 -348.426532) (xy 30.304989 -348.408734) (xy 30.35245 -348.379119) (xy 30.403805 -348.356931)
			(xy 30.430724 -348.349316) (xy 30.44317 -348.346014) (xy 30.461204 -348.32925) (xy 30.49778 -348.22638)
			(xy 30.494224 -348.201488) (xy 30.486858 -348.191328) (xy 30.469611 -348.166737) (xy 30.442275 -348.113255)
			(xy 30.423672 -348.056145) (xy 30.414262 -347.996824) (xy 30.413706 -347.966792) (xy 30.413706 -347.966538)
			(xy 30.414196 -347.938964) (xy 30.422143 -347.884392) (xy 30.437863 -347.831533) (xy 30.461029 -347.781487)
			(xy 30.491157 -347.735297) (xy 30.527621 -347.693924) (xy 30.548326 -347.675708) (xy 30.556402 -347.668154)
			(xy 30.565755 -347.648142) (xy 30.56636 -347.6371) (xy 30.56636 -347.559376) (xy 30.565762 -347.54833)
			(xy 30.556419 -347.528308) (xy 30.548326 -347.520768) (xy 30.527601 -347.502571) (xy 30.491131 -347.4612)
			(xy 30.461 -347.415008) (xy 30.437836 -347.364957) (xy 30.422123 -347.312091) (xy 30.414188 -347.257514)
			(xy 30.413706 -347.229938) (xy 30.414192 -347.202687) (xy 30.421948 -347.148739) (xy 30.437303 -347.096444)
			(xy 30.459945 -347.046867) (xy 30.489411 -347.001017) (xy 30.525102 -346.959826) (xy 30.566293 -346.924135)
			(xy 30.612143 -346.894669) (xy 30.66172 -346.872027) (xy 30.714015 -346.856672) (xy 30.767963 -346.848916)
			(xy 30.822465 -346.848916) (xy 30.876413 -346.856672) (xy 30.928708 -346.872027) (xy 30.978285 -346.894669)
			(xy 31.024135 -346.924135) (xy 31.065326 -346.959826) (xy 31.101017 -347.001017) (xy 31.130483 -347.046867)
			(xy 31.153125 -347.096444) (xy 31.16848 -347.148739) (xy 31.176236 -347.202687) (xy 31.176722 -347.229938)
			(xy 31.176206 -347.257511) (xy 31.168263 -347.312081) (xy 31.152547 -347.36494) (xy 31.129386 -347.414986)
			(xy 31.099263 -347.461176) (xy 31.085249 -347.47708) (xy 32.5628 -347.47708) (xy 32.5628 -344.499438)
			(xy 32.563404 -344.46952) (xy 32.572768 -344.41042) (xy 32.591256 -344.353512) (xy 32.618414 -344.300193)
			(xy 32.653572 -344.251775) (xy 32.674306 -344.230198) (xy 33.424622 -343.480136) (xy 33.431442 -343.47272)
			(xy 33.439173 -343.454133) (xy 33.439608 -343.444068) (xy 33.439608 -342.44661) (xy 33.440192 -342.416691)
			(xy 33.449561 -342.357591) (xy 33.468053 -342.300681) (xy 33.495215 -342.247363) (xy 33.530378 -342.198946)
			(xy 33.551114 -342.17737) (xy 34.169096 -341.559388) (xy 34.190674 -341.538566) (xy 34.239182 -341.503315)
			(xy 34.292608 -341.476089) (xy 34.349637 -341.457559) (xy 34.408862 -341.448182) (xy 34.438844 -341.447628)
			(xy 41.71442 -341.447628) (xy 41.744397 -341.448215) (xy 41.803612 -341.457608) (xy 41.86063 -341.476144)
			(xy 41.914049 -341.503367) (xy 41.962554 -341.538608) (xy 41.984168 -341.559388) (xy 42.128948 -341.704168)
			(xy 42.136382 -341.710884) (xy 42.154882 -341.71852) (xy 42.174896 -341.71852) (xy 42.193396 -341.710884)
			(xy 42.20083 -341.704168) (xy 42.472356 -341.432388) (xy 42.493952 -341.411585) (xy 42.542455 -341.376331)
			(xy 42.595876 -341.349102) (xy 42.652901 -341.330568) (xy 42.712123 -341.321186) (xy 42.742104 -341.320628)
			(xy 49.89068 -341.320628) (xy 49.920656 -341.32124) (xy 49.97987 -341.330627) (xy 50.036888 -341.349157)
			(xy 50.090307 -341.376374) (xy 50.138813 -341.41161) (xy 50.160428 -341.432388) (xy 50.485548 -341.757508)
			(xy 50.492909 -341.764277) (xy 50.511371 -341.771924) (xy 50.531353 -341.771924) (xy 50.549815 -341.764277)
			(xy 50.557176 -341.757508) (xy 50.882296 -341.432388) (xy 50.903874 -341.411566) (xy 50.952382 -341.376315)
			(xy 51.005808 -341.349089) (xy 51.062837 -341.330559) (xy 51.122062 -341.321182) (xy 51.152044 -341.320628)
			(xy 58.3819 -341.320628) (xy 58.411877 -341.321227) (xy 58.471091 -341.330617) (xy 58.528109 -341.34915)
			(xy 58.581528 -341.376371) (xy 58.630033 -341.411609) (xy 58.651648 -341.432388) (xy 58.788554 -341.569548)
			(xy 58.795954 -341.576393) (xy 58.81455 -341.584134) (xy 58.834694 -341.584134) (xy 58.85329 -341.576393)
			(xy 58.86069 -341.569548) (xy 58.997596 -341.432388) (xy 59.019174 -341.411566) (xy 59.067682 -341.376315)
			(xy 59.121108 -341.349089) (xy 59.178137 -341.330559) (xy 59.237362 -341.321182) (xy 59.267344 -341.320628)
			(xy 63.971424 -341.320628) (xy 63.981497 -341.320234) (xy 64.000096 -341.312494) (xy 64.007492 -341.305642)
			(xy 64.389254 -340.924134) (xy 64.396065 -340.916711) (xy 64.403803 -340.89813) (xy 64.40424 -340.888066)
			(xy 64.40424 -337.256628) (xy 64.404826 -337.226709) (xy 64.414193 -337.167608) (xy 64.432685 -337.110699)
			(xy 64.459846 -337.05738) (xy 64.49501 -337.008964) (xy 64.515746 -336.987388) (xy 65.763394 -335.73974)
			(xy 65.784982 -335.718928) (xy 65.833486 -335.683673) (xy 65.886909 -335.656445) (xy 65.943936 -335.637913)
			(xy 66.003161 -335.628535) (xy 66.033142 -335.62798) (xy 66.294 -335.62798) (xy 66.304024 -335.62758)
			(xy 66.322545 -335.619906) (xy 66.336718 -335.605728) (xy 66.344384 -335.587204) (xy 66.3448 -335.57718)
			(xy 66.3448 -335.414366) (xy 66.344419 -335.404291) (xy 66.33667 -335.385692) (xy 66.329814 -335.378298)
			(xy 66.039746 -335.088484) (xy 66.019039 -335.066885) (xy 65.983896 -335.018462) (xy 65.956742 -334.965148)
			(xy 65.938242 -334.908249) (xy 65.92885 -334.849159) (xy 65.92824 -334.819244) (xy 65.92824 -333.00797)
			(xy 65.928853 -332.978052) (xy 65.938213 -332.918952) (xy 65.956698 -332.862043) (xy 65.983854 -332.808724)
			(xy 66.019012 -332.760307) (xy 66.039746 -332.73873) (xy 66.980562 -331.798168) (xy 66.987403 -331.790769)
			(xy 66.995123 -331.772169) (xy 66.995548 -331.7621) (xy 66.995548 -331.079856) (xy 66.99615 -331.049938)
			(xy 67.005512 -330.990837) (xy 67.024 -330.933928) (xy 67.051158 -330.880609) (xy 67.086319 -330.832192)
			(xy 67.107054 -330.810616) (xy 67.915282 -330.002388) (xy 67.936867 -329.981573) (xy 67.985372 -329.946321)
			(xy 68.038797 -329.919094) (xy 68.095824 -329.900562) (xy 68.155049 -329.891184) (xy 68.18503 -329.890628)
			(xy 75.1205 -329.890628) (xy 75.150477 -329.891227) (xy 75.209691 -329.900617) (xy 75.266709 -329.91915)
			(xy 75.320128 -329.946371) (xy 75.368633 -329.981609) (xy 75.390248 -330.002388) (xy 75.674728 -330.286868)
			(xy 75.682089 -330.293637) (xy 75.700551 -330.301284) (xy 75.720533 -330.301284) (xy 75.738995 -330.293637)
			(xy 75.746356 -330.286868) (xy 76.030836 -330.002388) (xy 76.052441 -329.981595) (xy 76.100941 -329.94634)
			(xy 76.154361 -329.919109) (xy 76.211383 -329.900572) (xy 76.270604 -329.891187) (xy 76.300584 -329.890628)
			(xy 83.52028 -329.890628) (xy 83.550256 -329.89124) (xy 83.60947 -329.900627) (xy 83.666488 -329.919157)
			(xy 83.719907 -329.946374) (xy 83.768413 -329.98161) (xy 83.790028 -330.002388) (xy 84.031328 -330.243688)
			(xy 84.038689 -330.250457) (xy 84.057151 -330.258104) (xy 84.077133 -330.258104) (xy 84.095595 -330.250457)
			(xy 84.102956 -330.243688) (xy 84.471256 -329.875388) (xy 84.492852 -329.854585) (xy 84.541355 -329.819331)
			(xy 84.594776 -329.792102) (xy 84.651801 -329.773568) (xy 84.711023 -329.764186) (xy 84.741004 -329.763628)
			(xy 91.71686 -329.763628) (xy 91.746836 -329.764252) (xy 91.806049 -329.773636) (xy 91.863067 -329.792163)
			(xy 91.916486 -329.819378) (xy 91.964992 -329.854611) (xy 91.986608 -329.875388) (xy 92.393008 -330.281788)
			(xy 92.400369 -330.288557) (xy 92.418831 -330.296204) (xy 92.438813 -330.296204) (xy 92.457275 -330.288557)
			(xy 92.464636 -330.281788) (xy 92.871036 -329.875388) (xy 92.892641 -329.854595) (xy 92.941141 -329.81934)
			(xy 92.994561 -329.792109) (xy 93.051583 -329.773572) (xy 93.110804 -329.764187) (xy 93.140784 -329.763628)
			(xy 100.726494 -329.763628) (xy 100.756471 -329.764231) (xy 100.815685 -329.77362) (xy 100.872703 -329.792152)
			(xy 100.926122 -329.819372) (xy 100.974627 -329.854609) (xy 100.996242 -329.875388) (xy 101.504242 -330.383388)
			(xy 101.524982 -330.404957) (xy 101.560121 -330.453388) (xy 101.587269 -330.50671) (xy 101.605761 -330.563616)
			(xy 101.615144 -330.622711) (xy 101.615748 -330.652628) (xy 101.615748 -334.463644) (xy 101.615147 -334.493563)
			(xy 101.605785 -334.552663) (xy 101.587297 -334.609572) (xy 101.560138 -334.662891) (xy 101.524977 -334.711308)
			(xy 101.504242 -334.732884) (xy 101.409246 -334.82788) (xy 101.402429 -334.835298) (xy 101.394694 -334.853883)
			(xy 101.39426 -334.863948) (xy 101.39426 -335.786222) (xy 101.393678 -335.8162) (xy 101.384285 -335.875415)
			(xy 101.365748 -335.932433) (xy 101.338523 -335.985852) (xy 101.303281 -336.034356) (xy 101.2825 -336.05597)
			(xy 100.345494 -336.992976) (xy 100.338671 -337.00039) (xy 100.330942 -337.018979) (xy 100.330508 -337.029044)
			(xy 100.330508 -339.108796) (xy 100.330585 -339.113816) (xy 100.332514 -339.123668) (xy 100.334318 -339.128354)
			(xy 100.39858 -339.283548) (xy 100.407721 -339.306713) (xy 100.420599 -339.354819) (xy 100.427113 -339.40419)
			(xy 100.427536 -339.42909) (xy 100.427536 -340.948772) (xy 100.42708 -340.976684) (xy 100.418935 -341.031911)
			(xy 100.402831 -341.085362) (xy 100.37911 -341.135896) (xy 100.34828 -341.182435) (xy 100.33 -341.203534)
			(xy 100.324089 -341.210701) (xy 100.317446 -341.228034) (xy 100.317046 -341.237316) (xy 100.317046 -341.314786)
			(xy 100.32365 -341.332058) (xy 100.33 -341.33917) (xy 100.348343 -341.360261) (xy 100.379249 -341.406835)
			(xy 100.403024 -341.457423) (xy 100.419158 -341.510939) (xy 100.427307 -341.566238) (xy 100.42779 -341.594186)
			(xy 100.427304 -341.621437) (xy 100.419548 -341.675385) (xy 100.404193 -341.72768) (xy 100.381551 -341.777257)
			(xy 100.352085 -341.823107) (xy 100.316394 -341.864298) (xy 100.275203 -341.899989) (xy 100.232084 -341.9277)
			(xy 104.047047 -341.9277) (xy 104.051215 -341.872088) (xy 104.063623 -341.817718) (xy 104.083996 -341.765805)
			(xy 104.111879 -341.717508) (xy 104.146648 -341.673905) (xy 104.187526 -341.635971) (xy 104.233602 -341.604553)
			(xy 104.283845 -341.580353) (xy 104.337134 -341.56391) (xy 104.392278 -341.555594) (xy 104.420162 -341.55507)
			(xy 104.446585 -341.555499) (xy 104.498901 -341.562957) (xy 104.54964 -341.577729) (xy 104.597784 -341.599519)
			(xy 104.642367 -341.62789) (xy 104.662732 -341.644732) (xy 104.66959 -341.650574) (xy 104.686608 -341.656924)
			(xy 104.770936 -341.656924) (xy 104.787954 -341.650574) (xy 104.794812 -341.644732) (xy 104.815178 -341.627893)
			(xy 104.859764 -341.599528) (xy 104.907908 -341.577741) (xy 104.958645 -341.56297) (xy 105.01096 -341.55551)
			(xy 105.063804 -341.55551) (xy 105.116119 -341.56297) (xy 105.166856 -341.577741) (xy 105.215 -341.599528)
			(xy 105.259586 -341.627893) (xy 105.279952 -341.644732) (xy 105.28681 -341.650574) (xy 105.303828 -341.656924)
			(xy 105.388156 -341.656924) (xy 105.405174 -341.650574) (xy 105.412032 -341.644732) (xy 105.432821 -341.627549)
			(xy 105.478409 -341.598732) (xy 105.527679 -341.576798) (xy 105.55351 -341.56904) (xy 105.553764 -341.56904)
			(xy 105.564805 -341.565251) (xy 105.58214 -341.549661) (xy 105.587038 -341.539068) (xy 105.61701 -341.464138)
			(xy 105.620746 -341.453059) (xy 105.618904 -341.429777) (xy 105.613454 -341.419434) (xy 105.601097 -341.397777)
			(xy 105.581621 -341.351876) (xy 105.568438 -341.303789) (xy 105.561785 -341.254373) (xy 105.561384 -341.229442)
			(xy 105.561878 -341.201799) (xy 105.570036 -341.14712) (xy 105.586179 -341.094244) (xy 105.609954 -341.044332)
			(xy 105.640839 -340.998478) (xy 105.678156 -340.957688) (xy 105.699306 -340.939882) (xy 105.707746 -340.932298)
			(xy 105.717501 -340.911844) (xy 105.718102 -340.900512) (xy 105.718102 -340.821772) (xy 105.717457 -340.810454)
			(xy 105.707701 -340.790021) (xy 105.699306 -340.782402) (xy 105.67818 -340.76457) (xy 105.640866 -340.723783)
			(xy 105.609982 -340.677933) (xy 105.586205 -340.628027) (xy 105.570056 -340.575157) (xy 105.561888 -340.520482)
			(xy 105.561384 -340.492842) (xy 105.561905 -340.464957) (xy 105.570217 -340.40981) (xy 105.586655 -340.356518)
			(xy 105.610853 -340.306272) (xy 105.642269 -340.260193) (xy 105.680202 -340.219311) (xy 105.723804 -340.184539)
			(xy 105.772102 -340.156654) (xy 105.824017 -340.136279) (xy 105.878388 -340.123869) (xy 105.934002 -340.119702)
			(xy 105.989616 -340.123869) (xy 106.043987 -340.136279) (xy 106.095902 -340.156654) (xy 106.1442 -340.184539)
			(xy 106.187802 -340.219311) (xy 106.225735 -340.260193) (xy 106.257151 -340.306272) (xy 106.281349 -340.356518)
			(xy 106.297787 -340.40981) (xy 106.306099 -340.464957) (xy 106.30662 -340.492842) (xy 106.306114 -340.520484)
			(xy 106.297958 -340.575163) (xy 106.281817 -340.628039) (xy 106.258045 -340.677951) (xy 106.227162 -340.723805)
			(xy 106.189847 -340.764596) (xy 106.168698 -340.782402) (xy 106.160266 -340.789993) (xy 106.150507 -340.810442)
			(xy 106.149902 -340.821772) (xy 106.149902 -340.900512) (xy 106.150554 -340.91183) (xy 106.160305 -340.932263)
			(xy 106.168698 -340.939882) (xy 106.189817 -340.957721) (xy 106.227132 -340.998508) (xy 106.258017 -341.044356)
			(xy 106.281795 -341.09426) (xy 106.297945 -341.147129) (xy 106.306114 -341.201802) (xy 106.30662 -341.229442)
			(xy 106.306104 -341.256283) (xy 106.298407 -341.30941) (xy 106.283166 -341.360883) (xy 106.260695 -341.409636)
			(xy 106.23146 -341.454658) (xy 106.196065 -341.495019) (xy 106.155245 -341.529882) (xy 106.109843 -341.558525)
			(xy 106.060801 -341.580356) (xy 106.035094 -341.58809) (xy 106.03484 -341.58809) (xy 106.023794 -341.591867)
			(xy 106.00646 -341.607465) (xy 106.001566 -341.618062) (xy 105.971594 -341.692992) (xy 105.967839 -341.704066)
			(xy 105.969694 -341.727353) (xy 105.97515 -341.737696) (xy 105.98752 -341.759346) (xy 106.006992 -341.805249)
			(xy 106.020171 -341.853339) (xy 106.026821 -341.902757) (xy 106.02722 -341.927688) (xy 106.026755 -341.954305)
			(xy 106.01918 -342.006999) (xy 106.004184 -342.058078) (xy 105.98207 -342.106502) (xy 105.95329 -342.151287)
			(xy 105.91843 -342.19152) (xy 105.878198 -342.226382) (xy 105.833415 -342.255163) (xy 105.784991 -342.277279)
			(xy 105.733912 -342.292277) (xy 105.681219 -342.299854) (xy 105.654602 -342.300306) (xy 105.62818 -342.299846)
			(xy 105.575865 -342.292396) (xy 105.525127 -342.277632) (xy 105.476982 -342.255848) (xy 105.432397 -342.227483)
			(xy 105.412032 -342.210644) (xy 105.405174 -342.204802) (xy 105.388156 -342.198452) (xy 105.303828 -342.198452)
			(xy 105.28681 -342.204802) (xy 105.279952 -342.210644) (xy 105.259586 -342.227483) (xy 105.215 -342.255848)
			(xy 105.166856 -342.277635) (xy 105.116119 -342.292406) (xy 105.063804 -342.299866) (xy 105.01096 -342.299866)
			(xy 104.958645 -342.292406) (xy 104.907908 -342.277635) (xy 104.859764 -342.255848) (xy 104.815178 -342.227483)
			(xy 104.794812 -342.210644) (xy 104.787954 -342.204802) (xy 104.770936 -342.198452) (xy 104.686608 -342.198452)
			(xy 104.66959 -342.204802) (xy 104.662732 -342.210644) (xy 104.642348 -342.227458) (xy 104.597764 -342.255819)
			(xy 104.549624 -342.277604) (xy 104.498891 -342.292377) (xy 104.446582 -342.299842) (xy 104.420162 -342.300306)
			(xy 104.392278 -342.299806) (xy 104.337134 -342.29149) (xy 104.283845 -342.275047) (xy 104.233602 -342.250847)
			(xy 104.187526 -342.219429) (xy 104.146648 -342.181495) (xy 104.111879 -342.137892) (xy 104.083996 -342.089595)
			(xy 104.063623 -342.037682) (xy 104.051215 -341.983312) (xy 104.047047 -341.9277) (xy 100.232084 -341.9277)
			(xy 100.229353 -341.929455) (xy 100.179776 -341.952097) (xy 100.127481 -341.967452) (xy 100.073533 -341.975208)
			(xy 100.019031 -341.975208) (xy 99.965083 -341.967452) (xy 99.912788 -341.952097) (xy 99.863211 -341.929455)
			(xy 99.817361 -341.899989) (xy 99.77617 -341.864298) (xy 99.740479 -341.823107) (xy 99.711013 -341.777257)
			(xy 99.688371 -341.72768) (xy 99.673016 -341.675385) (xy 99.66526 -341.621437) (xy 99.664774 -341.594186)
			(xy 99.66525 -341.56624) (xy 99.673419 -341.510947) (xy 99.689565 -341.457437) (xy 99.713343 -341.406854)
			(xy 99.744245 -341.360281) (xy 99.762564 -341.33917) (xy 99.768482 -341.332008) (xy 99.775119 -341.314671)
			(xy 99.775518 -341.305388) (xy 99.775518 -341.227918) (xy 99.768914 -341.210646) (xy 99.762564 -341.203534)
			(xy 99.744275 -341.182444) (xy 99.71345 -341.135902) (xy 99.689738 -341.085365) (xy 99.673644 -341.031912)
			(xy 99.665512 -340.976684) (xy 99.665028 -340.948772) (xy 99.665028 -339.515704) (xy 99.664949 -339.510684)
			(xy 99.663021 -339.500832) (xy 99.661218 -339.496146) (xy 99.596702 -339.340952) (xy 99.587446 -339.31773)
			(xy 99.574453 -339.269457) (xy 99.567894 -339.219898) (xy 99.567492 -339.194902) (xy 99.567492 -336.849974)
			(xy 99.568056 -336.819995) (xy 99.577452 -336.760779) (xy 99.595992 -336.70376) (xy 99.623221 -336.650342)
			(xy 99.658468 -336.601839) (xy 99.679252 -336.580226) (xy 100.616258 -335.64322) (xy 100.623076 -335.635802)
			(xy 100.63081 -335.617217) (xy 100.631244 -335.607152) (xy 100.631244 -334.684878) (xy 100.631825 -334.6549)
			(xy 100.641218 -334.595685) (xy 100.659756 -334.538667) (xy 100.68698 -334.485248) (xy 100.722223 -334.436744)
			(xy 100.743004 -334.41513) (xy 100.838254 -334.320134) (xy 100.845065 -334.312711) (xy 100.852803 -334.29413)
			(xy 100.85324 -334.284066) (xy 100.85324 -330.832206) (xy 100.852827 -330.822135) (xy 100.845099 -330.803536)
			(xy 100.838254 -330.796138) (xy 100.583492 -330.54163) (xy 100.576085 -330.534798) (xy 100.557491 -330.527073)
			(xy 100.547424 -330.526644) (xy 93.319854 -330.526644) (xy 93.309786 -330.527086) (xy 93.291188 -330.534794)
			(xy 93.283786 -330.54163) (xy 92.825062 -331.0001) (xy 92.818224 -331.007502) (xy 92.810504 -331.0261)
			(xy 92.810076 -331.036168) (xy 92.810076 -332.609698) (xy 92.809501 -332.639617) (xy 92.800131 -332.698719)
			(xy 92.781637 -332.755628) (xy 92.754472 -332.808946) (xy 92.719307 -332.857362) (xy 92.69857 -332.878938)
			(xy 91.912694 -333.66456) (xy 91.905878 -333.671979) (xy 91.898145 -333.690564) (xy 91.897708 -333.700628)
			(xy 91.897708 -335.605628) (xy 91.898117 -335.615699) (xy 91.905849 -335.634297) (xy 91.912694 -335.641696)
			(xy 92.040202 -335.76895) (xy 92.060934 -335.790526) (xy 92.096072 -335.838956) (xy 92.12322 -335.892276)
			(xy 92.141715 -335.94918) (xy 92.151101 -336.008273) (xy 92.151708 -336.03819) (xy 92.151708 -336.038698)
			(xy 92.151215 -336.066609) (xy 92.143081 -336.121835) (xy 92.126985 -336.175285) (xy 92.103272 -336.22582)
			(xy 92.072449 -336.27236) (xy 92.054172 -336.29346) (xy 92.048246 -336.300616) (xy 92.041613 -336.317958)
			(xy 92.041218 -336.327242) (xy 92.041218 -336.404712) (xy 92.047822 -336.421984) (xy 92.054172 -336.429096)
			(xy 92.072476 -336.45022) (xy 92.103388 -336.496785) (xy 92.127171 -336.547364) (xy 92.143315 -336.600873)
			(xy 92.151473 -336.656166) (xy 92.151962 -336.684112) (xy 92.151476 -336.711363) (xy 92.14372 -336.765311)
			(xy 92.128365 -336.817606) (xy 92.105723 -336.867183) (xy 92.076257 -336.913033) (xy 92.040566 -336.954224)
			(xy 91.999375 -336.989915) (xy 91.956296 -337.0176) (xy 95.771147 -337.0176) (xy 95.775316 -336.961981)
			(xy 95.787728 -336.907605) (xy 95.808105 -336.855686) (xy 95.835994 -336.807385) (xy 95.870771 -336.76378)
			(xy 95.911658 -336.725845) (xy 95.957743 -336.694429) (xy 96.007996 -336.670233) (xy 96.061294 -336.653797)
			(xy 96.116447 -336.645488) (xy 96.144334 -336.644996) (xy 96.170756 -336.645435) (xy 96.223073 -336.65289)
			(xy 96.273811 -336.667659) (xy 96.321955 -336.689447) (xy 96.366539 -336.717817) (xy 96.386904 -336.734658)
			(xy 96.393762 -336.7405) (xy 96.41078 -336.74685) (xy 96.495108 -336.74685) (xy 96.512126 -336.7405)
			(xy 96.518984 -336.734658) (xy 96.53935 -336.717819) (xy 96.583936 -336.689454) (xy 96.63208 -336.667667)
			(xy 96.682817 -336.652896) (xy 96.735132 -336.645436) (xy 96.787976 -336.645436) (xy 96.840291 -336.652896)
			(xy 96.891028 -336.667667) (xy 96.939172 -336.689454) (xy 96.983758 -336.717819) (xy 97.004124 -336.734658)
			(xy 97.010982 -336.7405) (xy 97.028 -336.74685) (xy 97.112328 -336.74685) (xy 97.129346 -336.7405)
			(xy 97.136204 -336.734658) (xy 97.157001 -336.717486) (xy 97.202585 -336.688665) (xy 97.251853 -336.666726)
			(xy 97.277682 -336.658966) (xy 97.277936 -336.658966) (xy 97.288984 -336.655196) (xy 97.306315 -336.639591)
			(xy 97.31121 -336.628994) (xy 97.341182 -336.554064) (xy 97.344904 -336.542981) (xy 97.343072 -336.519703)
			(xy 97.337626 -336.50936) (xy 97.325246 -336.487715) (xy 97.305774 -336.441811) (xy 97.292598 -336.393719)
			(xy 97.285952 -336.3443) (xy 97.285556 -336.319368) (xy 97.286078 -336.291727) (xy 97.294232 -336.237048)
			(xy 97.31037 -336.184174) (xy 97.33414 -336.134262) (xy 97.365019 -336.088407) (xy 97.402331 -336.047615)
			(xy 97.423478 -336.029808) (xy 97.431902 -336.022209) (xy 97.441666 -336.001766) (xy 97.442274 -335.990438)
			(xy 97.442274 -335.911698) (xy 97.441624 -335.90038) (xy 97.431873 -335.879946) (xy 97.423478 -335.872328)
			(xy 97.402359 -335.854489) (xy 97.365045 -335.813702) (xy 97.334161 -335.767854) (xy 97.310383 -335.717949)
			(xy 97.294232 -335.665081) (xy 97.286062 -335.610408) (xy 97.285556 -335.582768) (xy 97.286077 -335.554883)
			(xy 97.294389 -335.499736) (xy 97.310827 -335.446444) (xy 97.335025 -335.396198) (xy 97.366441 -335.350119)
			(xy 97.404374 -335.309237) (xy 97.447976 -335.274465) (xy 97.496274 -335.24658) (xy 97.548189 -335.226205)
			(xy 97.60256 -335.213795) (xy 97.658174 -335.209628) (xy 97.713788 -335.213795) (xy 97.768159 -335.226205)
			(xy 97.820074 -335.24658) (xy 97.868372 -335.274465) (xy 97.911974 -335.309237) (xy 97.949907 -335.350119)
			(xy 97.981323 -335.396198) (xy 98.005521 -335.446444) (xy 98.021959 -335.499736) (xy 98.030271 -335.554883)
			(xy 98.030792 -335.582768) (xy 98.030314 -335.610411) (xy 98.022154 -335.665092) (xy 98.006008 -335.717969)
			(xy 97.98223 -335.767881) (xy 97.951342 -335.813734) (xy 97.914021 -335.854523) (xy 97.89287 -335.872328)
			(xy 97.884438 -335.87992) (xy 97.874676 -335.900368) (xy 97.874074 -335.911698) (xy 97.874074 -335.990438)
			(xy 97.874688 -336.001761) (xy 97.884463 -336.022195) (xy 97.89287 -336.029808) (xy 97.914017 -336.047616)
			(xy 97.951326 -336.088411) (xy 97.982205 -336.134266) (xy 98.005978 -336.184177) (xy 98.022124 -336.23705)
			(xy 98.030288 -336.291726) (xy 98.030792 -336.319368) (xy 98.030319 -336.346211) (xy 98.022619 -336.399341)
			(xy 98.007372 -336.450816) (xy 97.984896 -336.499569) (xy 97.955655 -336.544593) (xy 97.920256 -336.584953)
			(xy 97.879429 -336.619815) (xy 97.834023 -336.648456) (xy 97.784975 -336.670284) (xy 97.759266 -336.678016)
			(xy 97.759012 -336.678016) (xy 97.747956 -336.68177) (xy 97.730626 -336.697384) (xy 97.725738 -336.707988)
			(xy 97.695766 -336.782918) (xy 97.691997 -336.793989) (xy 97.693862 -336.817279) (xy 97.699322 -336.827622)
			(xy 97.711699 -336.849268) (xy 97.731171 -336.895173) (xy 97.744348 -336.943264) (xy 97.750995 -336.992682)
			(xy 97.751392 -337.017614) (xy 97.750979 -337.044233) (xy 97.7434 -337.09693) (xy 97.728399 -337.148011)
			(xy 97.70628 -337.196438) (xy 97.677495 -337.241224) (xy 97.642629 -337.281457) (xy 97.602392 -337.316319)
			(xy 97.557603 -337.345099) (xy 97.509174 -337.367213) (xy 97.458091 -337.382208) (xy 97.405393 -337.389782)
			(xy 97.378774 -337.390232) (xy 97.352352 -337.389782) (xy 97.300037 -337.382329) (xy 97.249298 -337.367562)
			(xy 97.201154 -337.345776) (xy 97.156569 -337.31741) (xy 97.136204 -337.30057) (xy 97.129346 -337.294728)
			(xy 97.112328 -337.288378) (xy 97.028 -337.288378) (xy 97.010982 -337.294728) (xy 97.004124 -337.30057)
			(xy 96.983758 -337.317409) (xy 96.939172 -337.345774) (xy 96.891028 -337.367561) (xy 96.840291 -337.382332)
			(xy 96.787976 -337.389792) (xy 96.735132 -337.389792) (xy 96.682817 -337.382332) (xy 96.63208 -337.367561)
			(xy 96.583936 -337.345774) (xy 96.53935 -337.317409) (xy 96.518984 -337.30057) (xy 96.512126 -337.294728)
			(xy 96.495108 -337.288378) (xy 96.41078 -337.288378) (xy 96.393762 -337.294728) (xy 96.386904 -337.30057)
			(xy 96.366533 -337.317402) (xy 96.321945 -337.345759) (xy 96.273802 -337.36754) (xy 96.223066 -337.382309)
			(xy 96.170755 -337.38977) (xy 96.144334 -337.390232) (xy 96.116447 -337.389712) (xy 96.061294 -337.381403)
			(xy 96.007996 -337.364967) (xy 95.957743 -337.340771) (xy 95.911658 -337.309355) (xy 95.870771 -337.27142)
			(xy 95.835994 -337.227815) (xy 95.808105 -337.179514) (xy 95.787728 -337.127595) (xy 95.775316 -337.073219)
			(xy 95.771147 -337.0176) (xy 91.956296 -337.0176) (xy 91.953525 -337.019381) (xy 91.903948 -337.042023)
			(xy 91.851653 -337.057378) (xy 91.797705 -337.065134) (xy 91.743203 -337.065134) (xy 91.689255 -337.057378)
			(xy 91.63696 -337.042023) (xy 91.587383 -337.019381) (xy 91.541533 -336.989915) (xy 91.500342 -336.954224)
			(xy 91.464651 -336.913033) (xy 91.435185 -336.867183) (xy 91.412543 -336.817606) (xy 91.397188 -336.765311)
			(xy 91.389432 -336.711363) (xy 91.388946 -336.684112) (xy 91.389525 -336.653989) (xy 91.399004 -336.594493)
			(xy 91.417713 -336.537225) (xy 91.445187 -336.483608) (xy 91.480744 -336.434973) (xy 91.501722 -336.413348)
			(xy 91.508537 -336.405928) (xy 91.516271 -336.387344) (xy 91.516708 -336.37728) (xy 91.516708 -336.34553)
			(xy 91.516277 -336.33537) (xy 91.508417 -336.316633) (xy 91.501468 -336.309208) (xy 91.500706 -336.308446)
			(xy 91.246706 -336.054446) (xy 91.225974 -336.03287) (xy 91.190835 -335.984441) (xy 91.163687 -335.93112)
			(xy 91.145193 -335.874216) (xy 91.135807 -335.815123) (xy 91.1352 -335.785206) (xy 91.1352 -333.52105)
			(xy 91.135812 -333.491132) (xy 91.145174 -333.432033) (xy 91.16366 -333.375124) (xy 91.190816 -333.321805)
			(xy 91.225973 -333.273387) (xy 91.246706 -333.25181) (xy 92.032582 -332.466188) (xy 92.039417 -332.458784)
			(xy 92.047141 -332.440188) (xy 92.047568 -332.43012) (xy 92.047568 -331.036168) (xy 92.047167 -331.026096)
			(xy 92.03943 -331.007498) (xy 92.032582 -331.0001) (xy 91.573858 -330.54163) (xy 91.566463 -330.534783)
			(xy 91.54786 -330.527067) (xy 91.53779 -330.526644) (xy 84.920074 -330.526644) (xy 84.910002 -330.527044)
			(xy 84.891403 -330.534781) (xy 84.884006 -330.54163) (xy 84.463382 -330.962) (xy 84.456547 -330.969404)
			(xy 84.448825 -330.988) (xy 84.448396 -330.998068) (xy 84.448396 -331.713078) (xy 84.447803 -331.742997)
			(xy 84.438436 -331.802097) (xy 84.419946 -331.859006) (xy 84.392786 -331.912324) (xy 84.357625 -331.960741)
			(xy 84.33689 -331.982318) (xy 83.469734 -332.84922) (xy 83.462898 -332.856623) (xy 83.455175 -332.87522)
			(xy 83.454748 -332.885288) (xy 83.454748 -335.443068) (xy 83.455178 -335.453137) (xy 83.462894 -335.471736)
			(xy 83.469734 -335.479136) (xy 83.709002 -335.71815) (xy 83.729734 -335.739726) (xy 83.764872 -335.788156)
			(xy 83.79202 -335.841476) (xy 83.810515 -335.89838) (xy 83.819901 -335.957473) (xy 83.820508 -335.98739)
			(xy 83.820508 -335.987898) (xy 83.820015 -336.015809) (xy 83.811881 -336.071035) (xy 83.795785 -336.124485)
			(xy 83.772072 -336.17502) (xy 83.741249 -336.22156) (xy 83.722972 -336.24266) (xy 83.717046 -336.249816)
			(xy 83.710413 -336.267158) (xy 83.710018 -336.276442) (xy 83.710018 -336.353912) (xy 83.716622 -336.371184)
			(xy 83.722972 -336.378296) (xy 83.741276 -336.39942) (xy 83.772188 -336.445985) (xy 83.795971 -336.496564)
			(xy 83.812115 -336.550073) (xy 83.820273 -336.605366) (xy 83.820762 -336.633312) (xy 83.820276 -336.660563)
			(xy 83.81252 -336.714511) (xy 83.797165 -336.766806) (xy 83.774523 -336.816383) (xy 83.745057 -336.862233)
			(xy 83.709366 -336.903424) (xy 83.668175 -336.939115) (xy 83.625096 -336.9668) (xy 87.439947 -336.9668)
			(xy 87.444116 -336.911181) (xy 87.456528 -336.856805) (xy 87.476905 -336.804886) (xy 87.504794 -336.756585)
			(xy 87.539571 -336.71298) (xy 87.580458 -336.675045) (xy 87.626543 -336.643629) (xy 87.676796 -336.619433)
			(xy 87.730094 -336.602997) (xy 87.785247 -336.594688) (xy 87.813134 -336.594196) (xy 87.839556 -336.594635)
			(xy 87.891873 -336.60209) (xy 87.942611 -336.616859) (xy 87.990755 -336.638647) (xy 88.035339 -336.667017)
			(xy 88.055704 -336.683858) (xy 88.062562 -336.6897) (xy 88.07958 -336.69605) (xy 88.163908 -336.69605)
			(xy 88.180926 -336.6897) (xy 88.187784 -336.683858) (xy 88.20815 -336.667019) (xy 88.252736 -336.638654)
			(xy 88.30088 -336.616867) (xy 88.351617 -336.602096) (xy 88.403932 -336.594636) (xy 88.456776 -336.594636)
			(xy 88.509091 -336.602096) (xy 88.559828 -336.616867) (xy 88.607972 -336.638654) (xy 88.652558 -336.667019)
			(xy 88.672924 -336.683858) (xy 88.679782 -336.6897) (xy 88.6968 -336.69605) (xy 88.781128 -336.69605)
			(xy 88.798146 -336.6897) (xy 88.805004 -336.683858) (xy 88.825835 -336.666667) (xy 88.871508 -336.637844)
			(xy 88.920863 -336.615915) (xy 88.946736 -336.608166) (xy 88.95842 -336.604864) (xy 88.9762 -336.588608)
			(xy 89.009474 -336.501232) (xy 89.01313 -336.489877) (xy 89.010739 -336.46617) (xy 89.004902 -336.455766)
			(xy 88.99112 -336.43326) (xy 88.969376 -336.385174) (xy 88.954635 -336.334501) (xy 88.947192 -336.282255)
			(xy 88.946736 -336.255868) (xy 88.947229 -336.228225) (xy 88.955384 -336.173544) (xy 88.971527 -336.120668)
			(xy 88.995301 -336.070755) (xy 89.026187 -336.024902) (xy 89.063507 -335.984113) (xy 89.084658 -335.966308)
			(xy 89.093079 -335.958705) (xy 89.102846 -335.938266) (xy 89.103454 -335.926938) (xy 89.103454 -335.848198)
			(xy 89.102811 -335.836879) (xy 89.093055 -335.816445) (xy 89.084658 -335.808828) (xy 89.063534 -335.790994)
			(xy 89.026222 -335.750205) (xy 88.995339 -335.704356) (xy 88.971562 -335.65445) (xy 88.955412 -335.601581)
			(xy 88.947242 -335.546908) (xy 88.946736 -335.519268) (xy 88.947257 -335.491383) (xy 88.955569 -335.436236)
			(xy 88.972007 -335.382944) (xy 88.996205 -335.332698) (xy 89.027621 -335.286619) (xy 89.065554 -335.245737)
			(xy 89.109156 -335.210965) (xy 89.157454 -335.18308) (xy 89.209369 -335.162705) (xy 89.26374 -335.150295)
			(xy 89.319354 -335.146128) (xy 89.374968 -335.150295) (xy 89.429339 -335.162705) (xy 89.481254 -335.18308)
			(xy 89.529552 -335.210965) (xy 89.573154 -335.245737) (xy 89.611087 -335.286619) (xy 89.642503 -335.332698)
			(xy 89.666701 -335.382944) (xy 89.683139 -335.436236) (xy 89.691451 -335.491383) (xy 89.691972 -335.519268)
			(xy 89.691502 -335.546912) (xy 89.683341 -335.601593) (xy 89.667194 -335.65447) (xy 89.643415 -335.704382)
			(xy 89.612525 -335.750235) (xy 89.575202 -335.791023) (xy 89.55405 -335.808828) (xy 89.545615 -335.816417)
			(xy 89.535855 -335.836867) (xy 89.535254 -335.848198) (xy 89.535254 -335.926938) (xy 89.535874 -335.93826)
			(xy 89.545645 -335.958694) (xy 89.55405 -335.966308) (xy 89.575192 -335.984121) (xy 89.612503 -336.024914)
			(xy 89.643384 -336.070768) (xy 89.667157 -336.120678) (xy 89.683303 -336.17355) (xy 89.691468 -336.228227)
			(xy 89.691972 -336.255868) (xy 89.69155 -336.282722) (xy 89.683817 -336.335871) (xy 89.668536 -336.38736)
			(xy 89.646023 -336.436122) (xy 89.616744 -336.481149) (xy 89.581306 -336.521506) (xy 89.540442 -336.55636)
			(xy 89.494998 -336.584987) (xy 89.445917 -336.606796) (xy 89.420192 -336.614516) (xy 89.408508 -336.617818)
			(xy 89.390728 -336.634074) (xy 89.357454 -336.72145) (xy 89.353819 -336.732809) (xy 89.356199 -336.75651)
			(xy 89.362026 -336.766916) (xy 89.375793 -336.789431) (xy 89.397542 -336.837513) (xy 89.412288 -336.888183)
			(xy 89.419734 -336.940428) (xy 89.420192 -336.966814) (xy 89.419779 -336.993433) (xy 89.4122 -337.04613)
			(xy 89.397199 -337.097211) (xy 89.37508 -337.145638) (xy 89.346295 -337.190424) (xy 89.311429 -337.230657)
			(xy 89.271192 -337.265519) (xy 89.226403 -337.294299) (xy 89.177974 -337.316413) (xy 89.126891 -337.331408)
			(xy 89.074193 -337.338982) (xy 89.047574 -337.339432) (xy 89.021152 -337.338982) (xy 88.968837 -337.331529)
			(xy 88.918098 -337.316762) (xy 88.869954 -337.294976) (xy 88.825369 -337.26661) (xy 88.805004 -337.24977)
			(xy 88.798146 -337.243928) (xy 88.781128 -337.237578) (xy 88.6968 -337.237578) (xy 88.679782 -337.243928)
			(xy 88.672924 -337.24977) (xy 88.652558 -337.266609) (xy 88.607972 -337.294974) (xy 88.559828 -337.316761)
			(xy 88.509091 -337.331532) (xy 88.456776 -337.338992) (xy 88.403932 -337.338992) (xy 88.351617 -337.331532)
			(xy 88.30088 -337.316761) (xy 88.252736 -337.294974) (xy 88.20815 -337.266609) (xy 88.187784 -337.24977)
			(xy 88.180926 -337.243928) (xy 88.163908 -337.237578) (xy 88.07958 -337.237578) (xy 88.062562 -337.243928)
			(xy 88.055704 -337.24977) (xy 88.035333 -337.266602) (xy 87.990745 -337.294959) (xy 87.942602 -337.31674)
			(xy 87.891866 -337.331509) (xy 87.839555 -337.33897) (xy 87.813134 -337.339432) (xy 87.785247 -337.338912)
			(xy 87.730094 -337.330603) (xy 87.676796 -337.314167) (xy 87.626543 -337.289971) (xy 87.580458 -337.258555)
			(xy 87.539571 -337.22062) (xy 87.504794 -337.177015) (xy 87.476905 -337.128714) (xy 87.456528 -337.076795)
			(xy 87.444116 -337.022419) (xy 87.439947 -336.9668) (xy 83.625096 -336.9668) (xy 83.622325 -336.968581)
			(xy 83.572748 -336.991223) (xy 83.520453 -337.006578) (xy 83.466505 -337.014334) (xy 83.412003 -337.014334)
			(xy 83.358055 -337.006578) (xy 83.30576 -336.991223) (xy 83.256183 -336.968581) (xy 83.210333 -336.939115)
			(xy 83.169142 -336.903424) (xy 83.133451 -336.862233) (xy 83.103985 -336.816383) (xy 83.081343 -336.766806)
			(xy 83.065988 -336.714511) (xy 83.058232 -336.660563) (xy 83.057746 -336.633312) (xy 83.058325 -336.603189)
			(xy 83.067804 -336.543693) (xy 83.086513 -336.486425) (xy 83.113987 -336.432808) (xy 83.149544 -336.384173)
			(xy 83.170522 -336.362548) (xy 83.177337 -336.355128) (xy 83.185071 -336.336544) (xy 83.185508 -336.32648)
			(xy 83.185508 -336.29473) (xy 83.185077 -336.28457) (xy 83.177217 -336.265833) (xy 83.170268 -336.258408)
			(xy 83.169506 -336.257646) (xy 82.803746 -335.891886) (xy 82.78304 -335.870286) (xy 82.747897 -335.821864)
			(xy 82.720742 -335.76855) (xy 82.702242 -335.71165) (xy 82.69285 -335.652561) (xy 82.69224 -335.622646)
			(xy 82.69224 -332.70571) (xy 82.692815 -332.67579) (xy 82.702184 -332.616689) (xy 82.720679 -332.55978)
			(xy 82.747843 -332.506461) (xy 82.783009 -332.458045) (xy 82.803746 -332.43647) (xy 83.670902 -331.569568)
			(xy 83.677749 -331.562173) (xy 83.685465 -331.54357) (xy 83.685888 -331.5335) (xy 83.685888 -330.998068)
			(xy 83.685482 -330.987996) (xy 83.677748 -330.969399) (xy 83.670902 -330.962) (xy 83.377278 -330.66863)
			(xy 83.369876 -330.661792) (xy 83.351278 -330.65407) (xy 83.34121 -330.653644) (xy 76.479654 -330.653644)
			(xy 76.469586 -330.654086) (xy 76.450988 -330.661794) (xy 76.443586 -330.66863) (xy 76.106782 -331.00518)
			(xy 76.099956 -331.012591) (xy 76.092229 -331.031182) (xy 76.091796 -331.041248) (xy 76.091796 -332.294738)
			(xy 76.091178 -332.324656) (xy 76.081817 -332.383754) (xy 76.063333 -332.440663) (xy 76.036179 -332.493982)
			(xy 76.001022 -332.542401) (xy 75.98029 -332.563978) (xy 75.341734 -333.20228) (xy 75.334915 -333.209697)
			(xy 75.327182 -333.228283) (xy 75.326748 -333.238348) (xy 75.326748 -335.687162) (xy 75.327181 -335.697231)
			(xy 75.334895 -335.715829) (xy 75.341734 -335.72323) (xy 75.351386 -335.732628) (xy 75.372105 -335.754216)
			(xy 75.407245 -335.802643) (xy 75.434396 -335.85596) (xy 75.452894 -335.912861) (xy 75.462283 -335.971952)
			(xy 75.462892 -336.001868) (xy 75.462892 -336.002376) (xy 75.462365 -336.030285) (xy 75.454235 -336.085509)
			(xy 75.438147 -336.138958) (xy 75.414442 -336.189494) (xy 75.383628 -336.236036) (xy 75.365356 -336.257138)
			(xy 75.359438 -336.2643) (xy 75.352801 -336.281637) (xy 75.352402 -336.29092) (xy 75.352402 -336.36839)
			(xy 75.359006 -336.385662) (xy 75.365356 -336.392774) (xy 75.383663 -336.413895) (xy 75.414572 -336.460462)
			(xy 75.438353 -336.511042) (xy 75.454496 -336.564551) (xy 75.462656 -336.619844) (xy 75.463146 -336.64779)
			(xy 75.46266 -336.675041) (xy 75.454904 -336.728989) (xy 75.439549 -336.781284) (xy 75.416907 -336.830861)
			(xy 75.387441 -336.876711) (xy 75.35175 -336.917902) (xy 75.310559 -336.953593) (xy 75.267446 -336.9813)
			(xy 79.082325 -336.9813) (xy 79.086494 -336.92568) (xy 79.098906 -336.871302) (xy 79.119284 -336.819381)
			(xy 79.147173 -336.771078) (xy 79.18195 -336.727471) (xy 79.222838 -336.689534) (xy 79.268923 -336.658115)
			(xy 79.319177 -336.633917) (xy 79.372476 -336.617478) (xy 79.42763 -336.609168) (xy 79.455518 -336.608674)
			(xy 79.48194 -336.609127) (xy 79.534255 -336.616579) (xy 79.584994 -336.631346) (xy 79.633138 -336.65313)
			(xy 79.677723 -336.681496) (xy 79.698088 -336.698336) (xy 79.704946 -336.704178) (xy 79.721964 -336.710528)
			(xy 79.806292 -336.710528) (xy 79.82331 -336.704178) (xy 79.830168 -336.698336) (xy 79.850534 -336.681497)
			(xy 79.89512 -336.653132) (xy 79.943264 -336.631345) (xy 79.994001 -336.616574) (xy 80.046316 -336.609114)
			(xy 80.09916 -336.609114) (xy 80.151475 -336.616574) (xy 80.202212 -336.631345) (xy 80.250356 -336.653132)
			(xy 80.294942 -336.681497) (xy 80.315308 -336.698336) (xy 80.322166 -336.704178) (xy 80.339184 -336.710528)
			(xy 80.423512 -336.710528) (xy 80.44053 -336.704178) (xy 80.447388 -336.698336) (xy 80.471196 -336.678767)
			(xy 80.523961 -336.646931) (xy 80.581236 -336.624189) (xy 80.611218 -336.617056) (xy 80.62341 -336.614516)
			(xy 80.642968 -336.598006) (xy 80.683354 -336.495136) (xy 80.680306 -336.470244) (xy 80.67294 -336.459576)
			(xy 80.657025 -336.435937) (xy 80.631775 -336.384853) (xy 80.614606 -336.330517) (xy 80.60592 -336.2742)
			(xy 80.605376 -336.245708) (xy 80.605919 -336.218067) (xy 80.614067 -336.16339) (xy 80.630201 -336.110515)
			(xy 80.653967 -336.060603) (xy 80.684843 -336.014748) (xy 80.722152 -335.973956) (xy 80.743298 -335.956148)
			(xy 80.751752 -335.948578) (xy 80.761499 -335.928113) (xy 80.762094 -335.916778) (xy 80.762094 -335.838038)
			(xy 80.761415 -335.826724) (xy 80.751684 -335.80629) (xy 80.743298 -335.798668) (xy 80.722154 -335.780857)
			(xy 80.684841 -335.740064) (xy 80.65396 -335.694211) (xy 80.630186 -335.6443) (xy 80.614041 -335.591427)
			(xy 80.605878 -335.53675) (xy 80.605376 -335.509108) (xy 80.605897 -335.481223) (xy 80.614209 -335.426076)
			(xy 80.630647 -335.372784) (xy 80.654845 -335.322538) (xy 80.686261 -335.276459) (xy 80.724194 -335.235577)
			(xy 80.767796 -335.200805) (xy 80.816094 -335.17292) (xy 80.868009 -335.152545) (xy 80.92238 -335.140135)
			(xy 80.977994 -335.135968) (xy 81.033608 -335.140135) (xy 81.087979 -335.152545) (xy 81.139894 -335.17292)
			(xy 81.188192 -335.200805) (xy 81.231794 -335.235577) (xy 81.269727 -335.276459) (xy 81.301143 -335.322538)
			(xy 81.325341 -335.372784) (xy 81.341779 -335.426076) (xy 81.350091 -335.481223) (xy 81.350612 -335.509108)
			(xy 81.350085 -335.536749) (xy 81.341934 -335.591428) (xy 81.325797 -335.644303) (xy 81.302029 -335.694215)
			(xy 81.27115 -335.74007) (xy 81.233837 -335.780861) (xy 81.21269 -335.798668) (xy 81.204272 -335.806272)
			(xy 81.194506 -335.826711) (xy 81.193894 -335.838038) (xy 81.193894 -335.916778) (xy 81.194568 -335.928093)
			(xy 81.204304 -335.948526) (xy 81.21269 -335.956148) (xy 81.23386 -335.973929) (xy 81.271167 -336.014731)
			(xy 81.302043 -336.060591) (xy 81.325812 -336.110507) (xy 81.341952 -336.163384) (xy 81.350111 -336.218065)
			(xy 81.350612 -336.245708) (xy 81.350052 -336.273832) (xy 81.34161 -336.329444) (xy 81.324904 -336.383154)
			(xy 81.300313 -336.433743) (xy 81.268398 -336.48006) (xy 81.229882 -336.521053) (xy 81.185641 -336.55579)
			(xy 81.136681 -336.583482) (xy 81.084115 -336.603499) (xy 81.056734 -336.609944) (xy 81.044542 -336.612484)
			(xy 81.024984 -336.628994) (xy 80.984598 -336.731864) (xy 80.987646 -336.756756) (xy 80.995012 -336.767424)
			(xy 81.010922 -336.791067) (xy 81.036174 -336.842149) (xy 81.053345 -336.896483) (xy 81.062032 -336.9528)
			(xy 81.062576 -336.981292) (xy 81.062158 -337.007912) (xy 81.054582 -337.060609) (xy 81.039583 -337.111691)
			(xy 81.017466 -337.160119) (xy 80.988681 -337.204906) (xy 80.953816 -337.24514) (xy 80.913578 -337.280002)
			(xy 80.868789 -337.308782) (xy 80.820359 -337.330895) (xy 80.769275 -337.345889) (xy 80.716578 -337.353461)
			(xy 80.689958 -337.35391) (xy 80.663535 -337.353474) (xy 80.611219 -337.346019) (xy 80.56048 -337.331248)
			(xy 80.512336 -337.30946) (xy 80.467753 -337.28109) (xy 80.447388 -337.264248) (xy 80.44053 -337.258406)
			(xy 80.423512 -337.252056) (xy 80.339184 -337.252056) (xy 80.322166 -337.258406) (xy 80.315308 -337.264248)
			(xy 80.294942 -337.281087) (xy 80.250356 -337.309452) (xy 80.202212 -337.331239) (xy 80.151475 -337.34601)
			(xy 80.09916 -337.35347) (xy 80.046316 -337.35347) (xy 79.994001 -337.34601) (xy 79.943264 -337.331239)
			(xy 79.89512 -337.309452) (xy 79.850534 -337.281087) (xy 79.830168 -337.264248) (xy 79.82331 -337.258406)
			(xy 79.806292 -337.252056) (xy 79.721964 -337.252056) (xy 79.704946 -337.258406) (xy 79.698088 -337.264248)
			(xy 79.67772 -337.281084) (xy 79.633132 -337.309441) (xy 79.584988 -337.331221) (xy 79.534252 -337.34599)
			(xy 79.481939 -337.35345) (xy 79.455518 -337.35391) (xy 79.42763 -337.353432) (xy 79.372476 -337.345122)
			(xy 79.319177 -337.328683) (xy 79.268923 -337.304485) (xy 79.222838 -337.273066) (xy 79.18195 -337.235129)
			(xy 79.147173 -337.191522) (xy 79.119284 -337.143219) (xy 79.098906 -337.091298) (xy 79.086494 -337.03692)
			(xy 79.082325 -336.9813) (xy 75.267446 -336.9813) (xy 75.264709 -336.983059) (xy 75.215132 -337.005701)
			(xy 75.162837 -337.021056) (xy 75.108889 -337.028812) (xy 75.054387 -337.028812) (xy 75.000439 -337.021056)
			(xy 74.948144 -337.005701) (xy 74.898567 -336.983059) (xy 74.852717 -336.953593) (xy 74.811526 -336.917902)
			(xy 74.775835 -336.876711) (xy 74.746369 -336.830861) (xy 74.723727 -336.781284) (xy 74.708372 -336.728989)
			(xy 74.700616 -336.675041) (xy 74.70013 -336.64779) (xy 74.7007 -336.617667) (xy 74.710182 -336.55817)
			(xy 74.728894 -336.500903) (xy 74.756369 -336.447286) (xy 74.791927 -336.398651) (xy 74.812906 -336.377026)
			(xy 74.819728 -336.369612) (xy 74.827458 -336.351023) (xy 74.827892 -336.340958) (xy 74.827892 -336.309208)
			(xy 74.827477 -336.299046) (xy 74.819606 -336.280309) (xy 74.812652 -336.272886) (xy 74.81189 -336.272124)
			(xy 74.675746 -336.13598) (xy 74.655037 -336.114383) (xy 74.619894 -336.06596) (xy 74.59274 -336.012645)
			(xy 74.574241 -335.955745) (xy 74.564849 -335.896655) (xy 74.56424 -335.86674) (xy 74.56424 -333.05877)
			(xy 74.564853 -333.028852) (xy 74.574213 -332.969752) (xy 74.592698 -332.912843) (xy 74.619854 -332.859524)
			(xy 74.655012 -332.811107) (xy 74.675746 -332.78953) (xy 75.314302 -332.151228) (xy 75.321123 -332.143813)
			(xy 75.328854 -332.125225) (xy 75.329288 -332.11516) (xy 75.329288 -331.041248) (xy 75.32884 -331.031181)
			(xy 75.321135 -331.012583) (xy 75.314302 -331.00518) (xy 74.977498 -330.66863) (xy 74.970089 -330.661801)
			(xy 74.951497 -330.654074) (xy 74.94143 -330.653644) (xy 68.3641 -330.653644) (xy 68.354029 -330.654058)
			(xy 68.335431 -330.661785) (xy 68.328032 -330.66863) (xy 67.773042 -331.223366) (xy 67.76623 -331.230789)
			(xy 67.758493 -331.24937) (xy 67.758056 -331.259434) (xy 67.758056 -331.941678) (xy 67.757475 -331.971597)
			(xy 67.748107 -332.030698) (xy 67.729614 -332.087608) (xy 67.702452 -332.140926) (xy 67.667287 -332.189342)
			(xy 67.64655 -332.210918) (xy 66.705734 -333.15148) (xy 66.698915 -333.158897) (xy 66.691182 -333.177483)
			(xy 66.690748 -333.187548) (xy 66.690748 -334.639666) (xy 66.691179 -334.649735) (xy 66.698894 -334.668334)
			(xy 66.705734 -334.675734) (xy 66.995802 -334.965548) (xy 67.016533 -334.987125) (xy 67.051671 -335.035555)
			(xy 67.07882 -335.088875) (xy 67.097314 -335.145779) (xy 67.106701 -335.204872) (xy 67.107308 -335.234788)
			(xy 67.107308 -336.009488) (xy 67.106809 -336.037399) (xy 67.098676 -336.092624) (xy 67.082582 -336.146075)
			(xy 67.058871 -336.19661) (xy 67.028048 -336.24315) (xy 67.009772 -336.26425) (xy 67.00385 -336.271409)
			(xy 66.997215 -336.288748) (xy 66.996818 -336.298032) (xy 66.996818 -336.375502) (xy 67.003422 -336.392774)
			(xy 67.009772 -336.399886) (xy 67.028071 -336.421014) (xy 67.058984 -336.467577) (xy 67.082768 -336.518156)
			(xy 67.098913 -336.571664) (xy 67.107073 -336.626956) (xy 67.107562 -336.654902) (xy 67.107076 -336.682153)
			(xy 67.09932 -336.736101) (xy 67.083965 -336.788396) (xy 67.061323 -336.837973) (xy 67.031857 -336.883823)
			(xy 66.996166 -336.925014) (xy 66.954975 -336.960705) (xy 66.911881 -336.9884) (xy 70.726737 -336.9884)
			(xy 70.730906 -336.93278) (xy 70.743318 -336.878402) (xy 70.763696 -336.826482) (xy 70.791586 -336.778179)
			(xy 70.826364 -336.734573) (xy 70.867252 -336.696638) (xy 70.913338 -336.66522) (xy 70.963593 -336.641023)
			(xy 71.016892 -336.624587) (xy 71.072046 -336.616279) (xy 71.099934 -336.615786) (xy 71.126356 -336.616227)
			(xy 71.178672 -336.623682) (xy 71.229411 -336.638451) (xy 71.277555 -336.660238) (xy 71.322139 -336.688607)
			(xy 71.342504 -336.705448) (xy 71.349362 -336.71129) (xy 71.36638 -336.71764) (xy 71.450708 -336.71764)
			(xy 71.467726 -336.71129) (xy 71.474584 -336.705448) (xy 71.49495 -336.688609) (xy 71.539536 -336.660244)
			(xy 71.58768 -336.638457) (xy 71.638417 -336.623686) (xy 71.690732 -336.616226) (xy 71.743576 -336.616226)
			(xy 71.795891 -336.623686) (xy 71.846628 -336.638457) (xy 71.894772 -336.660244) (xy 71.939358 -336.688609)
			(xy 71.959724 -336.705448) (xy 71.966582 -336.71129) (xy 71.9836 -336.71764) (xy 72.067928 -336.71764)
			(xy 72.084946 -336.71129) (xy 72.091804 -336.705448) (xy 72.114863 -336.686472) (xy 72.165817 -336.655339)
			(xy 72.221092 -336.632749) (xy 72.250046 -336.625438) (xy 72.262238 -336.622644) (xy 72.281288 -336.606134)
			(xy 72.320658 -336.503772) (xy 72.31761 -336.47888) (xy 72.310244 -336.468466) (xy 72.294537 -336.444928)
			(xy 72.269667 -336.3941) (xy 72.252765 -336.340098) (xy 72.244219 -336.284161) (xy 72.243696 -336.255868)
			(xy 72.244204 -336.228226) (xy 72.252358 -336.173546) (xy 72.268498 -336.120671) (xy 72.292271 -336.070759)
			(xy 72.323153 -336.024905) (xy 72.360469 -335.984114) (xy 72.381618 -335.966308) (xy 72.390048 -335.958715)
			(xy 72.399807 -335.938267) (xy 72.400414 -335.926938) (xy 72.400414 -335.848198) (xy 72.399784 -335.836877)
			(xy 72.390021 -335.816442) (xy 72.381618 -335.808828) (xy 72.360486 -335.791003) (xy 72.323176 -335.750211)
			(xy 72.292295 -335.70436) (xy 72.26852 -335.654452) (xy 72.252371 -335.601583) (xy 72.244202 -335.546908)
			(xy 72.243696 -335.519268) (xy 72.244217 -335.491383) (xy 72.252529 -335.436236) (xy 72.268967 -335.382944)
			(xy 72.293165 -335.332698) (xy 72.324581 -335.286619) (xy 72.362514 -335.245737) (xy 72.406116 -335.210965)
			(xy 72.454414 -335.18308) (xy 72.506329 -335.162705) (xy 72.5607 -335.150295) (xy 72.616314 -335.146128)
			(xy 72.671928 -335.150295) (xy 72.726299 -335.162705) (xy 72.778214 -335.18308) (xy 72.826512 -335.210965)
			(xy 72.870114 -335.245737) (xy 72.908047 -335.286619) (xy 72.939463 -335.332698) (xy 72.963661 -335.382944)
			(xy 72.980099 -335.436236) (xy 72.988411 -335.491383) (xy 72.988932 -335.519268) (xy 72.98844 -335.546911)
			(xy 72.98028 -335.60159) (xy 72.964136 -335.654466) (xy 72.940361 -335.704377) (xy 72.909477 -335.750231)
			(xy 72.872159 -335.791022) (xy 72.85101 -335.808828) (xy 72.842568 -335.81641) (xy 72.832814 -335.836866)
			(xy 72.832214 -335.848198) (xy 72.832214 -335.926938) (xy 72.832848 -335.938258) (xy 72.842611 -335.958691)
			(xy 72.85101 -335.966308) (xy 72.872144 -335.98413) (xy 72.909457 -336.024921) (xy 72.94034 -336.070772)
			(xy 72.964115 -336.12068) (xy 72.980263 -336.173551) (xy 72.988428 -336.228227) (xy 72.988932 -336.255868)
			(xy 72.988393 -336.283672) (xy 72.980133 -336.338664) (xy 72.963792 -336.391817) (xy 72.939733 -336.441952)
			(xy 72.90849 -336.487954) (xy 72.870758 -336.528802) (xy 72.827373 -336.563589) (xy 72.779301 -336.591541)
			(xy 72.727608 -336.612039) (xy 72.700642 -336.618834) (xy 72.68845 -336.621628) (xy 72.6694 -336.638138)
			(xy 72.63003 -336.7405) (xy 72.633078 -336.765392) (xy 72.640444 -336.775806) (xy 72.65615 -336.799345)
			(xy 72.681017 -336.850173) (xy 72.697919 -336.904175) (xy 72.706468 -336.960111) (xy 72.706992 -336.988404)
			(xy 72.706569 -337.015023) (xy 72.698992 -337.067719) (xy 72.683992 -337.118801) (xy 72.661875 -337.167227)
			(xy 72.633091 -337.212013) (xy 72.598225 -337.252247) (xy 72.557989 -337.287109) (xy 72.513201 -337.315889)
			(xy 72.464773 -337.338002) (xy 72.41369 -337.352998) (xy 72.360993 -337.360572) (xy 72.334374 -337.361022)
			(xy 72.307952 -337.360574) (xy 72.255636 -337.353121) (xy 72.204898 -337.338353) (xy 72.156754 -337.316568)
			(xy 72.112169 -337.2882) (xy 72.091804 -337.27136) (xy 72.084946 -337.265518) (xy 72.067928 -337.259168)
			(xy 71.9836 -337.259168) (xy 71.966582 -337.265518) (xy 71.959724 -337.27136) (xy 71.939358 -337.288199)
			(xy 71.894772 -337.316564) (xy 71.846628 -337.338351) (xy 71.795891 -337.353122) (xy 71.743576 -337.360582)
			(xy 71.690732 -337.360582) (xy 71.638417 -337.353122) (xy 71.58768 -337.338351) (xy 71.539536 -337.316564)
			(xy 71.49495 -337.288199) (xy 71.474584 -337.27136) (xy 71.467726 -337.265518) (xy 71.450708 -337.259168)
			(xy 71.36638 -337.259168) (xy 71.349362 -337.265518) (xy 71.342504 -337.27136) (xy 71.322132 -337.28819)
			(xy 71.277545 -337.316548) (xy 71.229401 -337.338329) (xy 71.178666 -337.353099) (xy 71.126355 -337.36056)
			(xy 71.099934 -337.361022) (xy 71.072046 -337.360521) (xy 71.016892 -337.352213) (xy 70.963593 -337.335777)
			(xy 70.913338 -337.31158) (xy 70.867252 -337.280162) (xy 70.826364 -337.242227) (xy 70.791586 -337.198621)
			(xy 70.763696 -337.150318) (xy 70.743318 -337.098398) (xy 70.730906 -337.04402) (xy 70.726737 -336.9884)
			(xy 66.911881 -336.9884) (xy 66.909125 -336.990171) (xy 66.859548 -337.012813) (xy 66.807253 -337.028168)
			(xy 66.753305 -337.035924) (xy 66.698803 -337.035924) (xy 66.644855 -337.028168) (xy 66.59256 -337.012813)
			(xy 66.542983 -336.990171) (xy 66.497133 -336.960705) (xy 66.455942 -336.925014) (xy 66.420251 -336.883823)
			(xy 66.390785 -336.837973) (xy 66.368143 -336.788396) (xy 66.352788 -336.736101) (xy 66.345032 -336.682153)
			(xy 66.344546 -336.654902) (xy 66.344546 -336.654394) (xy 66.345214 -336.621798) (xy 66.356329 -336.55756)
			(xy 66.366644 -336.526632) (xy 66.370272 -336.514869) (xy 66.366949 -336.490506) (xy 66.360294 -336.48015)
			(xy 66.312542 -336.412586) (xy 66.304882 -336.403) (xy 66.283134 -336.391719) (xy 66.270886 -336.390996)
			(xy 66.212212 -336.390996) (xy 66.20214 -336.391402) (xy 66.183541 -336.399133) (xy 66.176144 -336.405982)
			(xy 65.181734 -337.400138) (xy 65.17489 -337.407535) (xy 65.167171 -337.426136) (xy 65.166748 -337.436206)
			(xy 65.166748 -337.886548) (xy 67.302378 -337.886548) (xy 67.306449 -337.830926) (xy 67.318575 -337.776489)
			(xy 67.338498 -337.724398) (xy 67.365794 -337.675763) (xy 67.39988 -337.63162) (xy 67.440029 -337.592911)
			(xy 67.485387 -337.56046) (xy 67.534987 -337.534959) (xy 67.587771 -337.516952) (xy 67.642614 -337.506822)
			(xy 67.698348 -337.504785) (xy 67.753785 -337.510885) (xy 67.807742 -337.524991) (xy 67.859071 -337.546803)
			(xy 67.906677 -337.575857) (xy 67.949545 -337.611532) (xy 67.986762 -337.653069) (xy 68.017535 -337.699582)
			(xy 68.041207 -337.750079) (xy 68.057275 -337.803486) (xy 68.065395 -337.858662) (xy 68.065904 -337.886548)
			(xy 68.065395 -337.914434) (xy 68.057275 -337.96961) (xy 68.041207 -338.023017) (xy 68.017535 -338.073514)
			(xy 67.986762 -338.120027) (xy 67.949545 -338.161564) (xy 67.906677 -338.197239) (xy 67.859071 -338.226293)
			(xy 67.807742 -338.248105) (xy 67.753785 -338.262211) (xy 67.698348 -338.268311) (xy 67.642614 -338.266274)
			(xy 67.587771 -338.256144) (xy 67.534987 -338.238137) (xy 67.485387 -338.212636) (xy 67.440029 -338.180185)
			(xy 67.39988 -338.141476) (xy 67.365794 -338.097333) (xy 67.338498 -338.048698) (xy 67.318575 -337.996607)
			(xy 67.306449 -337.94217) (xy 67.302378 -337.886548) (xy 65.166748 -337.886548) (xy 65.166748 -338.781898)
			(xy 66.723258 -338.781898) (xy 66.727329 -338.726276) (xy 66.739455 -338.671839) (xy 66.759378 -338.619748)
			(xy 66.786674 -338.571113) (xy 66.82076 -338.52697) (xy 66.860909 -338.488261) (xy 66.906267 -338.45581)
			(xy 66.955867 -338.430309) (xy 67.008651 -338.412302) (xy 67.063494 -338.402172) (xy 67.119228 -338.400135)
			(xy 67.174665 -338.406235) (xy 67.228622 -338.420341) (xy 67.279951 -338.442153) (xy 67.327557 -338.471207)
			(xy 67.370425 -338.506882) (xy 67.407642 -338.548419) (xy 67.438415 -338.594932) (xy 67.462087 -338.645429)
			(xy 67.478155 -338.698836) (xy 67.486275 -338.754012) (xy 67.486784 -338.781898) (xy 67.486275 -338.809784)
			(xy 67.478155 -338.86496) (xy 67.462087 -338.918367) (xy 67.438415 -338.968864) (xy 67.407642 -339.015377)
			(xy 67.370425 -339.056914) (xy 67.327557 -339.092589) (xy 67.279951 -339.121643) (xy 67.228622 -339.143455)
			(xy 67.174665 -339.157561) (xy 67.119228 -339.163661) (xy 67.063494 -339.161624) (xy 67.008651 -339.151494)
			(xy 66.955867 -339.133487) (xy 66.906267 -339.107986) (xy 66.860909 -339.075535) (xy 66.82076 -339.036826)
			(xy 66.786674 -338.992683) (xy 66.759378 -338.944048) (xy 66.739455 -338.891957) (xy 66.727329 -338.83752)
			(xy 66.723258 -338.781898) (xy 65.166748 -338.781898) (xy 65.166748 -341.067644) (xy 65.166147 -341.097563)
			(xy 65.156785 -341.156663) (xy 65.138297 -341.213572) (xy 65.111138 -341.266891) (xy 65.075977 -341.315308)
			(xy 65.055242 -341.336884) (xy 64.420242 -341.971884) (xy 64.398642 -341.992683) (xy 64.350141 -342.027938)
			(xy 64.29672 -342.055169) (xy 64.239696 -342.073704) (xy 64.180474 -342.083087) (xy 64.150494 -342.083644)
			(xy 59.446414 -342.083644) (xy 59.436365 -342.083983) (xy 59.417769 -342.091593) (xy 59.410346 -342.098376)
			(xy 59.220862 -342.28786) (xy 59.214042 -342.295275) (xy 59.206312 -342.313863) (xy 59.205876 -342.323928)
			(xy 59.205876 -343.706958) (xy 59.205276 -343.736876) (xy 59.195912 -343.795976) (xy 59.177424 -343.852886)
			(xy 59.150265 -343.906204) (xy 59.115105 -343.954622) (xy 59.09437 -343.976198) (xy 58.333894 -344.73642)
			(xy 58.327052 -344.743818) (xy 58.319334 -344.762419) (xy 58.318908 -344.772488) (xy 58.318908 -347.297502)
			(xy 58.319331 -347.307572) (xy 58.327053 -347.326169) (xy 58.333894 -347.33357) (xy 58.461402 -347.460824)
			(xy 58.482122 -347.482412) (xy 58.517261 -347.530838) (xy 58.544412 -347.584156) (xy 58.562909 -347.641057)
			(xy 58.572299 -347.700148) (xy 58.572908 -347.730064) (xy 58.572908 -347.730572) (xy 58.572459 -347.758484)
			(xy 58.564314 -347.813712) (xy 58.548208 -347.867163) (xy 58.524486 -347.917697) (xy 58.493653 -347.964235)
			(xy 58.475372 -347.985334) (xy 58.469457 -347.992498) (xy 58.462818 -348.009833) (xy 58.462418 -348.019116)
			(xy 58.462418 -348.096586) (xy 58.469022 -348.113858) (xy 58.475372 -348.12097) (xy 58.493711 -348.142065)
			(xy 58.524618 -348.188638) (xy 58.548394 -348.239224) (xy 58.56453 -348.29274) (xy 58.572679 -348.348038)
			(xy 58.573162 -348.375986) (xy 58.572676 -348.403237) (xy 58.56492 -348.457185) (xy 58.549565 -348.50948)
			(xy 58.526923 -348.559057) (xy 58.497457 -348.604907) (xy 58.461766 -348.646098) (xy 58.420575 -348.681789)
			(xy 58.377456 -348.7095) (xy 62.192321 -348.7095) (xy 62.19649 -348.653877) (xy 62.208903 -348.599498)
			(xy 62.229282 -348.547575) (xy 62.257173 -348.49927) (xy 62.291952 -348.455662) (xy 62.332842 -348.417725)
			(xy 62.37893 -348.386307) (xy 62.429187 -348.362108) (xy 62.482488 -348.345671) (xy 62.537645 -348.337363)
			(xy 62.565534 -348.33687) (xy 62.591956 -348.337315) (xy 62.644272 -348.344769) (xy 62.69501 -348.359538)
			(xy 62.743154 -348.381324) (xy 62.787739 -348.409692) (xy 62.808104 -348.426532) (xy 62.814962 -348.432374)
			(xy 62.83198 -348.438724) (xy 62.916308 -348.438724) (xy 62.933326 -348.432374) (xy 62.940184 -348.426532)
			(xy 62.96055 -348.409693) (xy 63.005136 -348.381328) (xy 63.05328 -348.359541) (xy 63.104017 -348.34477)
			(xy 63.156332 -348.33731) (xy 63.209176 -348.33731) (xy 63.261491 -348.34477) (xy 63.312228 -348.359541)
			(xy 63.360372 -348.381328) (xy 63.404958 -348.409693) (xy 63.425324 -348.426532) (xy 63.432182 -348.432374)
			(xy 63.4492 -348.438724) (xy 63.533528 -348.438724) (xy 63.550546 -348.432374) (xy 63.557404 -348.426532)
			(xy 63.575177 -348.411793) (xy 63.613713 -348.386357) (xy 63.655099 -348.365882) (xy 63.676784 -348.357952)
			(xy 63.677038 -348.357952) (xy 63.687058 -348.353786) (xy 63.702581 -348.338649) (xy 63.70701 -348.328742)
			(xy 63.739268 -348.246192) (xy 63.737998 -348.224094) (xy 63.732664 -348.214188) (xy 63.718927 -348.187081)
			(xy 63.699447 -348.129523) (xy 63.689577 -348.069565) (xy 63.688976 -348.039182) (xy 63.688976 -348.038928)
			(xy 63.689463 -348.011285) (xy 63.697623 -347.956605) (xy 63.713768 -347.903729) (xy 63.737544 -347.853818)
			(xy 63.76843 -347.807964) (xy 63.805748 -347.767174) (xy 63.826898 -347.749368) (xy 63.835343 -347.741789)
			(xy 63.845095 -347.721331) (xy 63.845694 -347.709998) (xy 63.845694 -347.631258) (xy 63.84506 -347.619938)
			(xy 63.835297 -347.599505) (xy 63.826898 -347.591888) (xy 63.805763 -347.574066) (xy 63.76845 -347.533276)
			(xy 63.737567 -347.487424) (xy 63.713792 -347.437516) (xy 63.697645 -347.384645) (xy 63.689479 -347.329969)
			(xy 63.688976 -347.302328) (xy 63.689497 -347.274443) (xy 63.697809 -347.219296) (xy 63.714247 -347.166004)
			(xy 63.738445 -347.115758) (xy 63.769861 -347.069679) (xy 63.807794 -347.028797) (xy 63.851396 -346.994025)
			(xy 63.899694 -346.96614) (xy 63.951609 -346.945765) (xy 64.00598 -346.933355) (xy 64.061594 -346.929188)
			(xy 64.117208 -346.933355) (xy 64.171579 -346.945765) (xy 64.223494 -346.96614) (xy 64.271792 -346.994025)
			(xy 64.315394 -347.028797) (xy 64.353327 -347.069679) (xy 64.384743 -347.115758) (xy 64.408941 -347.166004)
			(xy 64.425379 -347.219296) (xy 64.433691 -347.274443) (xy 64.434212 -347.302328) (xy 64.433699 -347.32997)
			(xy 64.425545 -347.384649) (xy 64.409406 -347.437524) (xy 64.385634 -347.487436) (xy 64.354753 -347.533291)
			(xy 64.317438 -347.574082) (xy 64.29629 -347.591888) (xy 64.287863 -347.599484) (xy 64.278102 -347.619929)
			(xy 64.277494 -347.631258) (xy 64.277494 -347.709998) (xy 64.278157 -347.721314) (xy 64.2879 -347.741747)
			(xy 64.29629 -347.749368) (xy 64.31747 -347.767139) (xy 64.354776 -347.807942) (xy 64.385651 -347.853805)
			(xy 64.409418 -347.903723) (xy 64.425556 -347.956602) (xy 64.433713 -348.011284) (xy 64.434212 -348.038928)
			(xy 64.433698 -348.067675) (xy 64.424872 -348.124486) (xy 64.407417 -348.179265) (xy 64.381749 -348.23071)
			(xy 64.348478 -348.277598) (xy 64.308395 -348.318815) (xy 64.262453 -348.35338) (xy 64.211743 -348.380472)
			(xy 64.184784 -348.390464) (xy 64.18453 -348.390464) (xy 64.174519 -348.394649) (xy 64.15899 -348.409771)
			(xy 64.154558 -348.419674) (xy 64.1223 -348.502224) (xy 64.12357 -348.524322) (xy 64.128904 -348.534228)
			(xy 64.142644 -348.561333) (xy 64.162124 -348.618892) (xy 64.171992 -348.678851) (xy 64.172592 -348.709234)
			(xy 64.172592 -348.709488) (xy 64.172155 -348.736107) (xy 64.164579 -348.788802) (xy 64.149581 -348.839884)
			(xy 64.127466 -348.88831) (xy 64.098683 -348.933096) (xy 64.06382 -348.97333) (xy 64.023585 -349.008192)
			(xy 63.978798 -349.036973) (xy 63.93037 -349.059086) (xy 63.879289 -349.074082) (xy 63.826593 -349.081656)
			(xy 63.799974 -349.082106) (xy 63.773552 -349.081662) (xy 63.721236 -349.074208) (xy 63.670497 -349.05944)
			(xy 63.622353 -349.037653) (xy 63.577769 -349.009285) (xy 63.557404 -348.992444) (xy 63.550546 -348.986602)
			(xy 63.533528 -348.980252) (xy 63.4492 -348.980252) (xy 63.432182 -348.986602) (xy 63.425324 -348.992444)
			(xy 63.404958 -349.009283) (xy 63.360372 -349.037648) (xy 63.312228 -349.059435) (xy 63.261491 -349.074206)
			(xy 63.209176 -349.081666) (xy 63.156332 -349.081666) (xy 63.104017 -349.074206) (xy 63.05328 -349.059435)
			(xy 63.005136 -349.037648) (xy 62.96055 -349.009283) (xy 62.940184 -348.992444) (xy 62.933326 -348.986602)
			(xy 62.916308 -348.980252) (xy 62.83198 -348.980252) (xy 62.814962 -348.986602) (xy 62.808104 -348.992444)
			(xy 62.78773 -349.009272) (xy 62.743143 -349.03763) (xy 62.695001 -349.059412) (xy 62.644266 -349.074182)
			(xy 62.591954 -349.081644) (xy 62.565534 -349.082106) (xy 62.537645 -349.081637) (xy 62.482488 -349.073329)
			(xy 62.429187 -349.056892) (xy 62.37893 -349.032693) (xy 62.332842 -349.001275) (xy 62.291952 -348.963338)
			(xy 62.257173 -348.91973) (xy 62.229282 -348.871425) (xy 62.208903 -348.819502) (xy 62.19649 -348.765123)
			(xy 62.192321 -348.7095) (xy 58.377456 -348.7095) (xy 58.374725 -348.711255) (xy 58.325148 -348.733897)
			(xy 58.272853 -348.749252) (xy 58.218905 -348.757008) (xy 58.164403 -348.757008) (xy 58.110455 -348.749252)
			(xy 58.05816 -348.733897) (xy 58.008583 -348.711255) (xy 57.962733 -348.681789) (xy 57.921542 -348.646098)
			(xy 57.885851 -348.604907) (xy 57.856385 -348.559057) (xy 57.833743 -348.50948) (xy 57.818388 -348.457185)
			(xy 57.810632 -348.403237) (xy 57.810146 -348.375986) (xy 57.810709 -348.345862) (xy 57.820192 -348.286366)
			(xy 57.838905 -348.229098) (xy 57.866382 -348.175481) (xy 57.901942 -348.126847) (xy 57.922922 -348.105222)
			(xy 57.929748 -348.097811) (xy 57.937475 -348.07922) (xy 57.937908 -348.069154) (xy 57.937908 -348.037404)
			(xy 57.93749 -348.027242) (xy 57.929621 -348.008505) (xy 57.922668 -348.001082) (xy 57.921906 -348.00032)
			(xy 57.667906 -347.74632) (xy 57.647161 -347.724756) (xy 57.612025 -347.676323) (xy 57.584878 -347.623)
			(xy 57.566387 -347.566093) (xy 57.557005 -347.506997) (xy 57.5564 -347.47708) (xy 57.5564 -344.59291)
			(xy 57.556987 -344.562991) (xy 57.566355 -344.503891) (xy 57.584847 -344.446982) (xy 57.612008 -344.393663)
			(xy 57.647171 -344.345246) (xy 57.667906 -344.32367) (xy 58.428382 -343.563448) (xy 58.435191 -343.556023)
			(xy 58.44293 -343.537443) (xy 58.443368 -343.52738) (xy 58.443368 -342.323928) (xy 58.442936 -342.313859)
			(xy 58.435221 -342.295261) (xy 58.428382 -342.28786) (xy 58.238898 -342.098376) (xy 58.231406 -342.091696)
			(xy 58.212855 -342.084097) (xy 58.20283 -342.083644) (xy 51.331114 -342.083644) (xy 51.321044 -342.084065)
			(xy 51.302446 -342.091788) (xy 51.295046 -342.09863) (xy 50.917602 -342.47582) (xy 50.910761 -342.483219)
			(xy 50.903042 -342.501819) (xy 50.902616 -342.511888) (xy 50.902616 -343.704926) (xy 50.901984 -343.734843)
			(xy 50.892626 -343.793941) (xy 50.874145 -343.850849) (xy 50.846994 -343.904169) (xy 50.811841 -343.952588)
			(xy 50.79111 -343.974166) (xy 50.068734 -344.696288) (xy 50.061912 -344.703702) (xy 50.054181 -344.72229)
			(xy 50.053748 -344.732356) (xy 50.053748 -347.368114) (xy 50.054153 -347.378186) (xy 50.061887 -347.396784)
			(xy 50.068734 -347.404182) (xy 50.09261 -347.428058) (xy 50.09515 -347.43009) (xy 50.117568 -347.448264)
			(xy 50.157166 -347.490244) (xy 50.189988 -347.53771) (xy 50.215284 -347.58958) (xy 50.232477 -347.644668)
			(xy 50.241175 -347.701718) (xy 50.241708 -347.730572) (xy 50.241259 -347.758484) (xy 50.233114 -347.813712)
			(xy 50.217008 -347.867163) (xy 50.193286 -347.917697) (xy 50.162453 -347.964235) (xy 50.144172 -347.985334)
			(xy 50.138257 -347.992498) (xy 50.131618 -348.009833) (xy 50.131218 -348.019116) (xy 50.131218 -348.096586)
			(xy 50.137822 -348.113858) (xy 50.144172 -348.12097) (xy 50.162511 -348.142065) (xy 50.193418 -348.188638)
			(xy 50.217194 -348.239224) (xy 50.23333 -348.29274) (xy 50.241479 -348.348038) (xy 50.241962 -348.375986)
			(xy 50.241476 -348.403237) (xy 50.23372 -348.457185) (xy 50.218365 -348.50948) (xy 50.195723 -348.559057)
			(xy 50.166257 -348.604907) (xy 50.130566 -348.646098) (xy 50.089375 -348.681789) (xy 50.046256 -348.7095)
			(xy 53.861121 -348.7095) (xy 53.86529 -348.653877) (xy 53.877703 -348.599498) (xy 53.898082 -348.547575)
			(xy 53.925973 -348.49927) (xy 53.960752 -348.455662) (xy 54.001642 -348.417725) (xy 54.04773 -348.386307)
			(xy 54.097987 -348.362108) (xy 54.151288 -348.345671) (xy 54.206445 -348.337363) (xy 54.234334 -348.33687)
			(xy 54.260756 -348.337315) (xy 54.313072 -348.344769) (xy 54.36381 -348.359538) (xy 54.411954 -348.381324)
			(xy 54.456539 -348.409692) (xy 54.476904 -348.426532) (xy 54.483762 -348.432374) (xy 54.50078 -348.438724)
			(xy 54.585108 -348.438724) (xy 54.602126 -348.432374) (xy 54.608984 -348.426532) (xy 54.62935 -348.409693)
			(xy 54.673936 -348.381328) (xy 54.72208 -348.359541) (xy 54.772817 -348.34477) (xy 54.825132 -348.33731)
			(xy 54.877976 -348.33731) (xy 54.930291 -348.34477) (xy 54.981028 -348.359541) (xy 55.029172 -348.381328)
			(xy 55.073758 -348.409693) (xy 55.094124 -348.426532) (xy 55.100982 -348.432374) (xy 55.118 -348.438724)
			(xy 55.202328 -348.438724) (xy 55.219346 -348.432374) (xy 55.226204 -348.426532) (xy 55.245009 -348.410904)
			(xy 55.285974 -348.384209) (xy 55.33008 -348.363102) (xy 55.353204 -348.355158) (xy 55.36438 -348.351602)
			(xy 55.381398 -348.335092) (xy 55.412386 -348.248224) (xy 55.415708 -348.236964) (xy 55.412936 -348.213678)
			(xy 55.407052 -348.20352) (xy 55.392675 -348.180322) (xy 55.369981 -348.130687) (xy 55.354589 -348.078326)
			(xy 55.346812 -348.024306) (xy 55.346346 -347.997018) (xy 55.346808 -347.969443) (xy 55.354759 -347.914869)
			(xy 55.370484 -347.862009) (xy 55.393654 -347.811962) (xy 55.423788 -347.765773) (xy 55.460258 -347.724403)
			(xy 55.480966 -347.706188) (xy 55.489058 -347.698648) (xy 55.4984 -347.678625) (xy 55.499 -347.66758)
			(xy 55.499 -347.589856) (xy 55.4984 -347.578811) (xy 55.489057 -347.558789) (xy 55.480966 -347.551248)
			(xy 55.460268 -347.533023) (xy 55.423798 -347.491656) (xy 55.393665 -347.445469) (xy 55.370498 -347.395424)
			(xy 55.354778 -347.342564) (xy 55.346834 -347.287992) (xy 55.346346 -347.260418) (xy 55.346832 -347.233167)
			(xy 55.354588 -347.179219) (xy 55.369943 -347.126924) (xy 55.392585 -347.077347) (xy 55.422051 -347.031497)
			(xy 55.457742 -346.990306) (xy 55.498933 -346.954615) (xy 55.544783 -346.925149) (xy 55.59436 -346.902507)
			(xy 55.646655 -346.887152) (xy 55.700603 -346.879396) (xy 55.755105 -346.879396) (xy 55.809053 -346.887152)
			(xy 55.861348 -346.902507) (xy 55.910925 -346.925149) (xy 55.956775 -346.954615) (xy 55.997966 -346.990306)
			(xy 56.033657 -347.031497) (xy 56.063123 -347.077347) (xy 56.085765 -347.126924) (xy 56.10112 -347.179219)
			(xy 56.108876 -347.233167) (xy 56.109362 -347.260418) (xy 56.108853 -347.287991) (xy 56.100911 -347.342563)
			(xy 56.085196 -347.395422) (xy 56.062034 -347.445469) (xy 56.031908 -347.491659) (xy 55.995447 -347.533032)
			(xy 55.974742 -347.551248) (xy 55.966636 -347.558775) (xy 55.957301 -347.578808) (xy 55.956708 -347.589856)
			(xy 55.956708 -347.66758) (xy 55.957285 -347.678628) (xy 55.966644 -347.698649) (xy 55.974742 -347.706188)
			(xy 55.995459 -347.724393) (xy 56.031927 -347.765764) (xy 56.062057 -347.811955) (xy 56.085222 -347.862005)
			(xy 56.100937 -347.914868) (xy 56.108877 -347.969443) (xy 56.109362 -347.997018) (xy 56.108932 -348.023945)
			(xy 56.101364 -348.077263) (xy 56.086367 -348.128986) (xy 56.06424 -348.178083) (xy 56.035422 -348.223577)
			(xy 56.000489 -348.264562) (xy 55.960135 -348.300223) (xy 55.915163 -348.329849) (xy 55.86647 -348.352851)
			(xy 55.840884 -348.361254) (xy 55.84063 -348.361254) (xy 55.829745 -348.365308) (xy 55.812942 -348.38131)
			(xy 55.808372 -348.391988) (xy 55.776114 -348.478856) (xy 55.7784 -348.50197) (xy 55.78475 -348.51213)
			(xy 55.798167 -348.534423) (xy 55.81936 -348.581941) (xy 55.833718 -348.63195) (xy 55.840962 -348.683473)
			(xy 55.841392 -348.709488) (xy 55.840955 -348.736107) (xy 55.833379 -348.788802) (xy 55.818381 -348.839884)
			(xy 55.796266 -348.88831) (xy 55.767483 -348.933096) (xy 55.73262 -348.97333) (xy 55.692385 -349.008192)
			(xy 55.647598 -349.036973) (xy 55.59917 -349.059086) (xy 55.548089 -349.074082) (xy 55.495393 -349.081656)
			(xy 55.468774 -349.082106) (xy 55.442352 -349.081662) (xy 55.390036 -349.074208) (xy 55.339297 -349.05944)
			(xy 55.291153 -349.037653) (xy 55.246569 -349.009285) (xy 55.226204 -348.992444) (xy 55.219346 -348.986602)
			(xy 55.202328 -348.980252) (xy 55.118 -348.980252) (xy 55.100982 -348.986602) (xy 55.094124 -348.992444)
			(xy 55.073758 -349.009283) (xy 55.029172 -349.037648) (xy 54.981028 -349.059435) (xy 54.930291 -349.074206)
			(xy 54.877976 -349.081666) (xy 54.825132 -349.081666) (xy 54.772817 -349.074206) (xy 54.72208 -349.059435)
			(xy 54.673936 -349.037648) (xy 54.62935 -349.009283) (xy 54.608984 -348.992444) (xy 54.602126 -348.986602)
			(xy 54.585108 -348.980252) (xy 54.50078 -348.980252) (xy 54.483762 -348.986602) (xy 54.476904 -348.992444)
			(xy 54.45653 -349.009272) (xy 54.411943 -349.03763) (xy 54.363801 -349.059412) (xy 54.313066 -349.074182)
			(xy 54.260754 -349.081644) (xy 54.234334 -349.082106) (xy 54.206445 -349.081637) (xy 54.151288 -349.073329)
			(xy 54.097987 -349.056892) (xy 54.04773 -349.032693) (xy 54.001642 -349.001275) (xy 53.960752 -348.963338)
			(xy 53.925973 -348.91973) (xy 53.898082 -348.871425) (xy 53.877703 -348.819502) (xy 53.86529 -348.765123)
			(xy 53.861121 -348.7095) (xy 50.046256 -348.7095) (xy 50.043525 -348.711255) (xy 49.993948 -348.733897)
			(xy 49.941653 -348.749252) (xy 49.887705 -348.757008) (xy 49.833203 -348.757008) (xy 49.779255 -348.749252)
			(xy 49.72696 -348.733897) (xy 49.677383 -348.711255) (xy 49.631533 -348.681789) (xy 49.590342 -348.646098)
			(xy 49.554651 -348.604907) (xy 49.525185 -348.559057) (xy 49.502543 -348.50948) (xy 49.487188 -348.457185)
			(xy 49.479432 -348.403237) (xy 49.478946 -348.375986) (xy 49.479517 -348.346152) (xy 49.48882 -348.287212)
			(xy 49.507182 -348.230439) (xy 49.534156 -348.177215) (xy 49.569084 -348.128836) (xy 49.58969 -348.107254)
			(xy 49.596398 -348.099785) (xy 49.603979 -348.081216) (xy 49.604422 -348.071186) (xy 49.604422 -348.039182)
			(xy 49.603917 -348.02906) (xy 49.595913 -348.010458) (xy 49.588928 -348.003114) (xy 49.586134 -348.00032)
			(xy 49.402746 -347.816932) (xy 49.382014 -347.795356) (xy 49.346874 -347.746927) (xy 49.319725 -347.693607)
			(xy 49.301231 -347.636702) (xy 49.291846 -347.577609) (xy 49.29124 -347.547692) (xy 49.29124 -344.552778)
			(xy 49.291795 -344.522858) (xy 49.301169 -344.463756) (xy 49.319668 -344.406846) (xy 49.346837 -344.353528)
			(xy 49.382007 -344.305113) (xy 49.402746 -344.283538) (xy 50.125122 -343.561416) (xy 50.131951 -343.554007)
			(xy 50.139677 -343.535415) (xy 50.140108 -343.525348) (xy 50.140108 -342.511888) (xy 50.139713 -342.501815)
			(xy 50.131974 -342.483216) (xy 50.125122 -342.47582) (xy 49.747678 -342.09863) (xy 49.740276 -342.091792)
			(xy 49.721678 -342.08407) (xy 49.71161 -342.083644) (xy 42.921174 -342.083644) (xy 42.911102 -342.084044)
			(xy 42.892503 -342.091781) (xy 42.885106 -342.09863) (xy 42.561002 -342.42248) (xy 42.554179 -342.429893)
			(xy 42.546449 -342.448482) (xy 42.546016 -342.458548) (xy 42.546016 -344.149426) (xy 42.545384 -344.179343)
			(xy 42.536026 -344.238441) (xy 42.517545 -344.295349) (xy 42.490394 -344.348669) (xy 42.455241 -344.397088)
			(xy 42.43451 -344.418666) (xy 41.628822 -345.2241) (xy 41.621992 -345.231508) (xy 41.614266 -345.250101)
			(xy 41.613836 -345.260168) (xy 41.613836 -347.28023) (xy 41.614236 -347.290302) (xy 41.621974 -347.3089)
			(xy 41.628822 -347.316298) (xy 41.773602 -347.460824) (xy 41.794322 -347.482412) (xy 41.829461 -347.530838)
			(xy 41.856612 -347.584156) (xy 41.875109 -347.641057) (xy 41.884499 -347.700148) (xy 41.885108 -347.730064)
			(xy 41.885108 -347.730572) (xy 41.884659 -347.758484) (xy 41.876514 -347.813712) (xy 41.860408 -347.867163)
			(xy 41.836686 -347.917697) (xy 41.805853 -347.964235) (xy 41.787572 -347.985334) (xy 41.781657 -347.992498)
			(xy 41.775018 -348.009833) (xy 41.774618 -348.019116) (xy 41.774618 -348.096586) (xy 41.781222 -348.113858)
			(xy 41.787572 -348.12097) (xy 41.805911 -348.142065) (xy 41.836818 -348.188638) (xy 41.860594 -348.239224)
			(xy 41.87673 -348.29274) (xy 41.884879 -348.348038) (xy 41.885362 -348.375986) (xy 41.884876 -348.403237)
			(xy 41.87712 -348.457185) (xy 41.861765 -348.50948) (xy 41.839123 -348.559057) (xy 41.809657 -348.604907)
			(xy 41.773966 -348.646098) (xy 41.732775 -348.681789) (xy 41.689656 -348.7095) (xy 45.504521 -348.7095)
			(xy 45.50869 -348.653877) (xy 45.521103 -348.599498) (xy 45.541482 -348.547575) (xy 45.569373 -348.49927)
			(xy 45.604152 -348.455662) (xy 45.645042 -348.417725) (xy 45.69113 -348.386307) (xy 45.741387 -348.362108)
			(xy 45.794688 -348.345671) (xy 45.849845 -348.337363) (xy 45.877734 -348.33687) (xy 45.904156 -348.337315)
			(xy 45.956472 -348.344769) (xy 46.00721 -348.359538) (xy 46.055354 -348.381324) (xy 46.099939 -348.409692)
			(xy 46.120304 -348.426532) (xy 46.127162 -348.432374) (xy 46.14418 -348.438724) (xy 46.228508 -348.438724)
			(xy 46.245526 -348.432374) (xy 46.252384 -348.426532) (xy 46.27275 -348.409693) (xy 46.317336 -348.381328)
			(xy 46.36548 -348.359541) (xy 46.416217 -348.34477) (xy 46.468532 -348.33731) (xy 46.521376 -348.33731)
			(xy 46.573691 -348.34477) (xy 46.624428 -348.359541) (xy 46.672572 -348.381328) (xy 46.717158 -348.409693)
			(xy 46.737524 -348.426532) (xy 46.744382 -348.432374) (xy 46.7614 -348.438724) (xy 46.845728 -348.438724)
			(xy 46.862746 -348.432374) (xy 46.869604 -348.426532) (xy 46.895641 -348.405213) (xy 46.953781 -348.371343)
			(xy 46.985174 -348.359222) (xy 46.995597 -348.354864) (xy 47.011554 -348.338913) (xy 47.015908 -348.328488)
			(xy 47.04207 -348.254828) (xy 47.045301 -348.244099) (xy 47.043211 -348.221822) (xy 47.038006 -348.211902)
			(xy 47.02535 -348.189724) (xy 47.005398 -348.14272) (xy 46.991893 -348.093476) (xy 46.985077 -348.042869)
			(xy 46.984666 -348.017338) (xy 46.985135 -347.989763) (xy 46.993083 -347.93519) (xy 47.008806 -347.882329)
			(xy 47.031976 -347.832282) (xy 47.062109 -347.786093) (xy 47.098578 -347.744723) (xy 47.119286 -347.726508)
			(xy 47.127356 -347.718948) (xy 47.136714 -347.69894) (xy 47.13732 -347.6879) (xy 47.13732 -347.610176)
			(xy 47.136735 -347.599128) (xy 47.127384 -347.579105) (xy 47.119286 -347.571568) (xy 47.098553 -347.55338)
			(xy 47.062085 -347.512006) (xy 47.031956 -347.465811) (xy 47.008794 -347.415759) (xy 46.993082 -347.362892)
			(xy 46.985148 -347.308314) (xy 46.984666 -347.280738) (xy 46.985152 -347.253487) (xy 46.992908 -347.199539)
			(xy 47.008263 -347.147244) (xy 47.030905 -347.097667) (xy 47.060371 -347.051817) (xy 47.096062 -347.010626)
			(xy 47.137253 -346.974935) (xy 47.183103 -346.945469) (xy 47.23268 -346.922827) (xy 47.284975 -346.907472)
			(xy 47.338923 -346.899716) (xy 47.393425 -346.899716) (xy 47.447373 -346.907472) (xy 47.499668 -346.922827)
			(xy 47.549245 -346.945469) (xy 47.595095 -346.974935) (xy 47.636286 -347.010626) (xy 47.671977 -347.051817)
			(xy 47.701443 -347.097667) (xy 47.724085 -347.147244) (xy 47.73944 -347.199539) (xy 47.747196 -347.253487)
			(xy 47.747682 -347.280738) (xy 47.74718 -347.308311) (xy 47.739236 -347.362883) (xy 47.723518 -347.415742)
			(xy 47.700355 -347.465789) (xy 47.670229 -347.511979) (xy 47.633767 -347.553351) (xy 47.613062 -347.571568)
			(xy 47.604995 -347.57913) (xy 47.595638 -347.599136) (xy 47.595028 -347.610176) (xy 47.595028 -347.6879)
			(xy 47.595643 -347.698944) (xy 47.604974 -347.718966) (xy 47.613062 -347.726508) (xy 47.633773 -347.74472)
			(xy 47.670245 -347.786088) (xy 47.700378 -347.832277) (xy 47.723544 -347.882325) (xy 47.73926 -347.935188)
			(xy 47.747198 -347.989763) (xy 47.747682 -348.017338) (xy 47.747249 -348.043602) (xy 47.740051 -348.095633)
			(xy 47.725782 -348.146185) (xy 47.704713 -348.194302) (xy 47.677241 -348.239072) (xy 47.643886 -348.27965)
			(xy 47.60528 -348.315268) (xy 47.562152 -348.345253) (xy 47.515318 -348.369037) (xy 47.490634 -348.378018)
			(xy 47.479712 -348.381574) (xy 47.46371 -348.397322) (xy 47.432214 -348.48165) (xy 47.42878 -348.492215)
			(xy 47.430365 -348.51435) (xy 47.435262 -348.524322) (xy 47.435516 -348.524322) (xy 47.435516 -348.52483)
			(xy 47.44719 -348.545996) (xy 47.465591 -348.590694) (xy 47.478056 -348.637397) (xy 47.484374 -348.68532)
			(xy 47.484792 -348.709488) (xy 47.484355 -348.736107) (xy 47.476779 -348.788802) (xy 47.461781 -348.839884)
			(xy 47.439666 -348.88831) (xy 47.410883 -348.933096) (xy 47.37602 -348.97333) (xy 47.335785 -349.008192)
			(xy 47.290998 -349.036973) (xy 47.24257 -349.059086) (xy 47.191489 -349.074082) (xy 47.138793 -349.081656)
			(xy 47.112174 -349.082106) (xy 47.085752 -349.081662) (xy 47.033436 -349.074208) (xy 46.982697 -349.05944)
			(xy 46.934553 -349.037653) (xy 46.889969 -349.009285) (xy 46.869604 -348.992444) (xy 46.862746 -348.986602)
			(xy 46.845728 -348.980252) (xy 46.7614 -348.980252) (xy 46.744382 -348.986602) (xy 46.737524 -348.992444)
			(xy 46.717158 -349.009283) (xy 46.672572 -349.037648) (xy 46.624428 -349.059435) (xy 46.573691 -349.074206)
			(xy 46.521376 -349.081666) (xy 46.468532 -349.081666) (xy 46.416217 -349.074206) (xy 46.36548 -349.059435)
			(xy 46.317336 -349.037648) (xy 46.27275 -349.009283) (xy 46.252384 -348.992444) (xy 46.245526 -348.986602)
			(xy 46.228508 -348.980252) (xy 46.14418 -348.980252) (xy 46.127162 -348.986602) (xy 46.120304 -348.992444)
			(xy 46.09993 -349.009272) (xy 46.055343 -349.03763) (xy 46.007201 -349.059412) (xy 45.956466 -349.074182)
			(xy 45.904154 -349.081644) (xy 45.877734 -349.082106) (xy 45.849845 -349.081637) (xy 45.794688 -349.073329)
			(xy 45.741387 -349.056892) (xy 45.69113 -349.032693) (xy 45.645042 -349.001275) (xy 45.604152 -348.963338)
			(xy 45.569373 -348.91973) (xy 45.541482 -348.871425) (xy 45.521103 -348.819502) (xy 45.50869 -348.765123)
			(xy 45.504521 -348.7095) (xy 41.689656 -348.7095) (xy 41.686925 -348.711255) (xy 41.637348 -348.733897)
			(xy 41.585053 -348.749252) (xy 41.531105 -348.757008) (xy 41.476603 -348.757008) (xy 41.422655 -348.749252)
			(xy 41.37036 -348.733897) (xy 41.320783 -348.711255) (xy 41.274933 -348.681789) (xy 41.233742 -348.646098)
			(xy 41.198051 -348.604907) (xy 41.168585 -348.559057) (xy 41.145943 -348.50948) (xy 41.130588 -348.457185)
			(xy 41.122832 -348.403237) (xy 41.122346 -348.375986) (xy 41.122909 -348.345862) (xy 41.132392 -348.286366)
			(xy 41.151105 -348.229098) (xy 41.178582 -348.175481) (xy 41.214142 -348.126847) (xy 41.235122 -348.105222)
			(xy 41.241948 -348.097811) (xy 41.249675 -348.07922) (xy 41.250108 -348.069154) (xy 41.250108 -348.037404)
			(xy 41.24969 -348.027242) (xy 41.241821 -348.008505) (xy 41.234868 -348.001082) (xy 41.234106 -348.00032)
			(xy 40.962834 -347.729048) (xy 40.942107 -347.707467) (xy 40.906967 -347.659039) (xy 40.879817 -347.60572)
			(xy 40.861322 -347.548817) (xy 40.851935 -347.489724) (xy 40.851328 -347.459808) (xy 40.851328 -345.08059)
			(xy 40.851894 -345.05067) (xy 40.861266 -344.991569) (xy 40.879763 -344.934659) (xy 40.906929 -344.881341)
			(xy 40.942096 -344.832925) (xy 40.962834 -344.81135) (xy 41.768522 -344.005916) (xy 41.775351 -343.998507)
			(xy 41.783077 -343.979915) (xy 41.783508 -343.969848) (xy 41.783508 -342.458548) (xy 41.783082 -342.448478)
			(xy 41.775364 -342.429879) (xy 41.768522 -342.42248) (xy 41.571418 -342.225376) (xy 41.563953 -342.218661)
			(xy 41.545382 -342.211083) (xy 41.53535 -342.210644) (xy 34.617914 -342.210644) (xy 34.607844 -342.211065)
			(xy 34.589246 -342.218788) (xy 34.581846 -342.22563) (xy 34.217102 -342.59012) (xy 34.210261 -342.597519)
			(xy 34.202542 -342.616119) (xy 34.202116 -342.626188) (xy 34.202116 -343.623646) (xy 34.201497 -343.653564)
			(xy 34.192136 -343.712662) (xy 34.173651 -343.769571) (xy 34.146497 -343.82289) (xy 34.111342 -343.871308)
			(xy 34.09061 -343.892886) (xy 33.340294 -344.642948) (xy 33.333483 -344.650371) (xy 33.325747 -344.668953)
			(xy 33.325308 -344.679016) (xy 33.325308 -347.297502) (xy 33.325731 -347.307572) (xy 33.333453 -347.326169)
			(xy 33.340294 -347.33357) (xy 33.467802 -347.460824) (xy 33.488522 -347.482412) (xy 33.523661 -347.530838)
			(xy 33.550812 -347.584156) (xy 33.569309 -347.641057) (xy 33.578699 -347.700148) (xy 33.579308 -347.730064)
			(xy 33.579308 -347.730572) (xy 33.578859 -347.758484) (xy 33.570714 -347.813712) (xy 33.554608 -347.867163)
			(xy 33.530886 -347.917697) (xy 33.500053 -347.964235) (xy 33.481772 -347.985334) (xy 33.475857 -347.992498)
			(xy 33.469218 -348.009833) (xy 33.468818 -348.019116) (xy 33.468818 -348.096586) (xy 33.475422 -348.113858)
			(xy 33.481772 -348.12097) (xy 33.500111 -348.142065) (xy 33.531018 -348.188638) (xy 33.554794 -348.239224)
			(xy 33.57093 -348.29274) (xy 33.579079 -348.348038) (xy 33.579562 -348.375986) (xy 33.579076 -348.403237)
			(xy 33.57132 -348.457185) (xy 33.555965 -348.50948) (xy 33.533323 -348.559057) (xy 33.503857 -348.604907)
			(xy 33.468166 -348.646098) (xy 33.426975 -348.681789) (xy 33.383856 -348.7095) (xy 37.198721 -348.7095)
			(xy 37.20289 -348.653877) (xy 37.215303 -348.599498) (xy 37.235682 -348.547575) (xy 37.263573 -348.49927)
			(xy 37.298352 -348.455662) (xy 37.339242 -348.417725) (xy 37.38533 -348.386307) (xy 37.435587 -348.362108)
			(xy 37.488888 -348.345671) (xy 37.544045 -348.337363) (xy 37.571934 -348.33687) (xy 37.598356 -348.337315)
			(xy 37.650672 -348.344769) (xy 37.70141 -348.359538) (xy 37.749554 -348.381324) (xy 37.794139 -348.409692)
			(xy 37.814504 -348.426532) (xy 37.821362 -348.432374) (xy 37.83838 -348.438724) (xy 37.922708 -348.438724)
			(xy 37.939726 -348.432374) (xy 37.946584 -348.426532) (xy 37.96695 -348.409693) (xy 38.011536 -348.381328)
			(xy 38.05968 -348.359541) (xy 38.110417 -348.34477) (xy 38.162732 -348.33731) (xy 38.215576 -348.33731)
			(xy 38.267891 -348.34477) (xy 38.318628 -348.359541) (xy 38.366772 -348.381328) (xy 38.411358 -348.409693)
			(xy 38.431724 -348.426532) (xy 38.438582 -348.432374) (xy 38.4556 -348.438724) (xy 38.539928 -348.438724)
			(xy 38.556946 -348.432374) (xy 38.563804 -348.426532) (xy 38.582653 -348.410899) (xy 38.623697 -348.384187)
			(xy 38.667889 -348.363089) (xy 38.691058 -348.355158) (xy 38.691312 -348.355158) (xy 38.702426 -348.350745)
			(xy 38.719249 -348.333795) (xy 38.72357 -348.322646) (xy 38.749224 -348.244414) (xy 38.752273 -348.232768)
			(xy 38.748427 -348.209037) (xy 38.741858 -348.198948) (xy 38.741858 -348.198694) (xy 38.724615 -348.1741)
			(xy 38.697284 -348.120617) (xy 38.678681 -348.063509) (xy 38.669266 -348.004189) (xy 38.668706 -347.974158)
			(xy 38.66921 -347.946585) (xy 38.677154 -347.892014) (xy 38.692871 -347.839154) (xy 38.716034 -347.789108)
			(xy 38.74616 -347.742918) (xy 38.782622 -347.701545) (xy 38.803326 -347.683328) (xy 38.811393 -347.675766)
			(xy 38.820751 -347.65576) (xy 38.82136 -347.64472) (xy 38.82136 -347.566996) (xy 38.820751 -347.555951)
			(xy 38.811416 -347.535929) (xy 38.803326 -347.528388) (xy 38.782611 -347.510181) (xy 38.74614 -347.468812)
			(xy 38.716008 -347.422621) (xy 38.692842 -347.372573) (xy 38.677127 -347.319709) (xy 38.66919 -347.265133)
			(xy 38.668706 -347.237558) (xy 38.669192 -347.210307) (xy 38.676948 -347.156359) (xy 38.692303 -347.104064)
			(xy 38.714945 -347.054487) (xy 38.744411 -347.008637) (xy 38.780102 -346.967446) (xy 38.821293 -346.931755)
			(xy 38.867143 -346.902289) (xy 38.91672 -346.879647) (xy 38.969015 -346.864292) (xy 39.022963 -346.856536)
			(xy 39.077465 -346.856536) (xy 39.131413 -346.864292) (xy 39.183708 -346.879647) (xy 39.233285 -346.902289)
			(xy 39.279135 -346.931755) (xy 39.320326 -346.967446) (xy 39.356017 -347.008637) (xy 39.385483 -347.054487)
			(xy 39.408125 -347.104064) (xy 39.42348 -347.156359) (xy 39.431236 -347.210307) (xy 39.431722 -347.237558)
			(xy 39.43122 -347.265131) (xy 39.423274 -347.319702) (xy 39.407555 -347.372561) (xy 39.384392 -347.422607)
			(xy 39.354266 -347.468797) (xy 39.317806 -347.510171) (xy 39.297102 -347.528388) (xy 39.289032 -347.535948)
			(xy 39.279675 -347.555956) (xy 39.279068 -347.566996) (xy 39.279068 -347.64472) (xy 39.279659 -347.655767)
			(xy 39.289006 -347.67579) (xy 39.297102 -347.683328) (xy 39.31783 -347.70152) (xy 39.354299 -347.742893)
			(xy 39.384429 -347.789087) (xy 39.407592 -347.839139) (xy 39.423305 -347.892005) (xy 39.431239 -347.946582)
			(xy 39.431722 -347.974158) (xy 39.431285 -348.001084) (xy 39.423713 -348.0544) (xy 39.408714 -348.10612)
			(xy 39.386586 -348.155215) (xy 39.357769 -348.200708) (xy 39.322837 -348.241693) (xy 39.282486 -348.277354)
			(xy 39.237518 -348.306983) (xy 39.188828 -348.329988) (xy 39.163244 -348.338394) (xy 39.16299 -348.338394)
			(xy 39.151826 -348.342701) (xy 39.134852 -348.359516) (xy 39.130478 -348.370652) (xy 39.103808 -348.448884)
			(xy 39.100616 -348.460369) (xy 39.103913 -348.483944) (xy 39.110158 -348.494096) (xy 39.110666 -348.494604)
			(xy 39.126771 -348.518304) (xy 39.152276 -348.569614) (xy 39.169637 -348.62422) (xy 39.178445 -348.680839)
			(xy 39.178992 -348.709488) (xy 39.178555 -348.736107) (xy 39.170979 -348.788802) (xy 39.155981 -348.839884)
			(xy 39.133866 -348.88831) (xy 39.105083 -348.933096) (xy 39.07022 -348.97333) (xy 39.029985 -349.008192)
			(xy 38.985198 -349.036973) (xy 38.93677 -349.059086) (xy 38.885689 -349.074082) (xy 38.832993 -349.081656)
			(xy 38.806374 -349.082106) (xy 38.779952 -349.081662) (xy 38.727636 -349.074208) (xy 38.676897 -349.05944)
			(xy 38.628753 -349.037653) (xy 38.584169 -349.009285) (xy 38.563804 -348.992444) (xy 38.556946 -348.986602)
			(xy 38.539928 -348.980252) (xy 38.4556 -348.980252) (xy 38.438582 -348.986602) (xy 38.431724 -348.992444)
			(xy 38.411358 -349.009283) (xy 38.366772 -349.037648) (xy 38.318628 -349.059435) (xy 38.267891 -349.074206)
			(xy 38.215576 -349.081666) (xy 38.162732 -349.081666) (xy 38.110417 -349.074206) (xy 38.05968 -349.059435)
			(xy 38.011536 -349.037648) (xy 37.96695 -349.009283) (xy 37.946584 -348.992444) (xy 37.939726 -348.986602)
			(xy 37.922708 -348.980252) (xy 37.83838 -348.980252) (xy 37.821362 -348.986602) (xy 37.814504 -348.992444)
			(xy 37.79413 -349.009272) (xy 37.749543 -349.03763) (xy 37.701401 -349.059412) (xy 37.650666 -349.074182)
			(xy 37.598354 -349.081644) (xy 37.571934 -349.082106) (xy 37.544045 -349.081637) (xy 37.488888 -349.073329)
			(xy 37.435587 -349.056892) (xy 37.38533 -349.032693) (xy 37.339242 -349.001275) (xy 37.298352 -348.963338)
			(xy 37.263573 -348.91973) (xy 37.235682 -348.871425) (xy 37.215303 -348.819502) (xy 37.20289 -348.765123)
			(xy 37.198721 -348.7095) (xy 33.383856 -348.7095) (xy 33.381125 -348.711255) (xy 33.331548 -348.733897)
			(xy 33.279253 -348.749252) (xy 33.225305 -348.757008) (xy 33.170803 -348.757008) (xy 33.116855 -348.749252)
			(xy 33.06456 -348.733897) (xy 33.014983 -348.711255) (xy 32.969133 -348.681789) (xy 32.927942 -348.646098)
			(xy 32.892251 -348.604907) (xy 32.862785 -348.559057) (xy 32.840143 -348.50948) (xy 32.824788 -348.457185)
			(xy 32.817032 -348.403237) (xy 32.816546 -348.375986) (xy 32.817109 -348.345862) (xy 32.826592 -348.286366)
			(xy 32.845305 -348.229098) (xy 32.872782 -348.175481) (xy 32.908342 -348.126847) (xy 32.929322 -348.105222)
			(xy 32.936148 -348.097811) (xy 32.943875 -348.07922) (xy 32.944308 -348.069154) (xy 32.944308 -348.037404)
			(xy 32.94389 -348.027242) (xy 32.936021 -348.008505) (xy 32.929068 -348.001082) (xy 32.928306 -348.00032)
			(xy 32.674306 -347.74632) (xy 32.653561 -347.724756) (xy 32.618425 -347.676323) (xy 32.591278 -347.623)
			(xy 32.572787 -347.566093) (xy 32.563405 -347.506997) (xy 32.5628 -347.47708) (xy 31.085249 -347.47708)
			(xy 31.062805 -347.50255) (xy 31.042102 -347.520768) (xy 31.034041 -347.528336) (xy 31.024679 -347.548338)
			(xy 31.024068 -347.559376) (xy 31.024068 -347.6371) (xy 31.02467 -347.648146) (xy 31.034009 -347.668168)
			(xy 31.042102 -347.675708) (xy 31.062821 -347.693911) (xy 31.09929 -347.735282) (xy 31.129421 -347.781473)
			(xy 31.152586 -347.831523) (xy 31.168301 -347.884387) (xy 31.176238 -347.938963) (xy 31.176722 -347.966538)
			(xy 31.176251 -347.994643) (xy 31.167999 -348.050245) (xy 31.151678 -348.104034) (xy 31.127642 -348.154846)
			(xy 31.096411 -348.201583) (xy 31.058662 -348.243231) (xy 31.01521 -348.27889) (xy 30.966997 -348.307789)
			(xy 30.915065 -348.329301) (xy 30.887924 -348.336616) (xy 30.876191 -348.340398) (xy 30.857883 -348.356849)
			(xy 30.852872 -348.368112) (xy 30.81909 -348.458536) (xy 30.822646 -348.483428) (xy 30.830012 -348.493842)
			(xy 30.84618 -348.517552) (xy 30.871785 -348.568909) (xy 30.889211 -348.623585) (xy 30.898046 -348.680287)
			(xy 30.898592 -348.70898) (xy 30.898592 -348.709488) (xy 30.898155 -348.736107) (xy 30.890579 -348.788802)
			(xy 30.875581 -348.839884) (xy 30.853466 -348.88831) (xy 30.824683 -348.933096) (xy 30.78982 -348.97333)
			(xy 30.749585 -349.008192) (xy 30.704798 -349.036973) (xy 30.65637 -349.059086) (xy 30.605289 -349.074082)
			(xy 30.552593 -349.081656) (xy 30.525974 -349.082106) (xy 30.499552 -349.081662) (xy 30.447236 -349.074208)
			(xy 30.396497 -349.05944) (xy 30.348353 -349.037653) (xy 30.303769 -349.009285) (xy 30.283404 -348.992444)
			(xy 30.276546 -348.986602) (xy 30.259528 -348.980252) (xy 30.1752 -348.980252) (xy 30.158182 -348.986602)
			(xy 30.151324 -348.992444) (xy 30.130958 -349.009283) (xy 30.086372 -349.037648) (xy 30.038228 -349.059435)
			(xy 29.987491 -349.074206) (xy 29.935176 -349.081666) (xy 29.882332 -349.081666) (xy 29.830017 -349.074206)
			(xy 29.77928 -349.059435) (xy 29.731136 -349.037648) (xy 29.68655 -349.009283) (xy 29.666184 -348.992444)
			(xy 29.659326 -348.986602) (xy 29.642308 -348.980252) (xy 29.55798 -348.980252) (xy 29.540962 -348.986602)
			(xy 29.534104 -348.992444) (xy 29.51373 -349.009272) (xy 29.469143 -349.03763) (xy 29.421001 -349.059412)
			(xy 29.370266 -349.074182) (xy 29.317954 -349.081644) (xy 29.291534 -349.082106) (xy 29.263645 -349.081637)
			(xy 29.208488 -349.073329) (xy 29.155187 -349.056892) (xy 29.10493 -349.032693) (xy 29.058842 -349.001275)
			(xy 29.017952 -348.963338) (xy 28.983173 -348.91973) (xy 28.955282 -348.871425) (xy 28.934903 -348.819502)
			(xy 28.92249 -348.765123) (xy 28.918321 -348.7095) (xy 25.103478 -348.7095) (xy 25.100736 -348.711262)
			(xy 25.051155 -348.7339) (xy 24.998857 -348.749251) (xy 24.944906 -348.757002) (xy 24.917654 -348.757494)
			(xy 24.9174 -348.757494) (xy 24.88742 -348.756935) (xy 24.8282 -348.747551) (xy 24.771178 -348.729014)
			(xy 24.71776 -348.70178) (xy 24.669263 -348.666521) (xy 24.647652 -348.645734) (xy 24.63673 -348.634812)
			(xy 24.606758 -348.628716) (xy 24.505666 -348.670626) (xy 24.496563 -348.67485) (xy 24.482397 -348.689042)
			(xy 24.474772 -348.707588) (xy 24.474424 -348.717616) (xy 24.474424 -349.435928) (xy 24.473637 -349.477742)
			(xy 24.461529 -349.56049) (xy 24.450294 -349.600774) (xy 24.448335 -349.607632) (xy 25.493978 -349.607632)
			(xy 25.498049 -349.55201) (xy 25.510175 -349.497573) (xy 25.530098 -349.445482) (xy 25.557394 -349.396847)
			(xy 25.59148 -349.352704) (xy 25.631629 -349.313995) (xy 25.676987 -349.281544) (xy 25.726587 -349.256043)
			(xy 25.779371 -349.238036) (xy 25.834214 -349.227906) (xy 25.889948 -349.225869) (xy 25.945385 -349.231969)
			(xy 25.999342 -349.246075) (xy 26.050671 -349.267887) (xy 26.098277 -349.296941) (xy 26.141145 -349.332616)
			(xy 26.178362 -349.374153) (xy 26.209135 -349.420666) (xy 26.232807 -349.471163) (xy 26.248875 -349.52457)
			(xy 26.256995 -349.579746) (xy 26.257504 -349.607632) (xy 26.256995 -349.635518) (xy 26.248875 -349.690694)
			(xy 26.232807 -349.744101) (xy 26.209135 -349.794598) (xy 26.178362 -349.841111) (xy 26.141145 -349.882648)
			(xy 26.098277 -349.918323) (xy 26.050671 -349.947377) (xy 25.999342 -349.969189) (xy 25.945385 -349.983295)
			(xy 25.889948 -349.989395) (xy 25.834214 -349.987358) (xy 25.779371 -349.977228) (xy 25.726587 -349.959221)
			(xy 25.676987 -349.93372) (xy 25.631629 -349.901269) (xy 25.59148 -349.86256) (xy 25.557394 -349.818417)
			(xy 25.530098 -349.769782) (xy 25.510175 -349.717691) (xy 25.498049 -349.663254) (xy 25.493978 -349.607632)
			(xy 24.448335 -349.607632) (xy 24.448262 -349.607886) (xy 24.448262 -350.502982) (xy 24.914858 -350.502982)
			(xy 24.918929 -350.44736) (xy 24.931055 -350.392923) (xy 24.950978 -350.340832) (xy 24.978274 -350.292197)
			(xy 25.01236 -350.248054) (xy 25.052509 -350.209345) (xy 25.097867 -350.176894) (xy 25.147467 -350.151393)
			(xy 25.200251 -350.133386) (xy 25.255094 -350.123256) (xy 25.310828 -350.121219) (xy 25.366265 -350.127319)
			(xy 25.420222 -350.141425) (xy 25.471551 -350.163237) (xy 25.519157 -350.192291) (xy 25.562025 -350.227966)
			(xy 25.599242 -350.269503) (xy 25.630015 -350.316016) (xy 25.653687 -350.366513) (xy 25.669755 -350.41992)
			(xy 25.677875 -350.475096) (xy 25.678384 -350.502982) (xy 25.677875 -350.530868) (xy 25.669755 -350.586044)
			(xy 25.653687 -350.639451) (xy 25.630015 -350.689948) (xy 25.599242 -350.736461) (xy 25.562025 -350.777998)
			(xy 25.519157 -350.813673) (xy 25.471551 -350.842727) (xy 25.420222 -350.864539) (xy 25.366265 -350.878645)
			(xy 25.310828 -350.884745) (xy 25.255094 -350.882708) (xy 25.200251 -350.872578) (xy 25.147467 -350.854571)
			(xy 25.097867 -350.82907) (xy 25.052509 -350.796619) (xy 25.01236 -350.75791) (xy 24.978274 -350.713767)
			(xy 24.950978 -350.665132) (xy 24.931055 -350.613041) (xy 24.918929 -350.558604) (xy 24.914858 -350.502982)
			(xy 24.448262 -350.502982) (xy 24.448262 -351.595182) (xy 24.448608 -351.603915) (xy 24.454481 -351.620362)
			(xy 24.465575 -351.63385) (xy 24.4729 -351.638616) (xy 24.547576 -351.683574) (xy 24.555262 -351.687762)
			(xy 24.572416 -351.691181) (xy 24.58972 -351.688626) (xy 24.597614 -351.684844) (xy 24.625353 -351.6708)
			(xy 24.684255 -351.650903) (xy 24.745599 -351.640796) (xy 24.776684 -351.64014) (xy 24.803935 -351.640626)
			(xy 24.857883 -351.648383) (xy 24.910177 -351.663739) (xy 24.959754 -351.68638) (xy 25.005604 -351.715847)
			(xy 25.046794 -351.751538) (xy 25.082486 -351.792729) (xy 25.111952 -351.838579) (xy 25.134593 -351.888156)
			(xy 25.149948 -351.940451) (xy 25.157704 -351.994399) (xy 25.157704 -352.048901) (xy 25.149948 -352.102849)
			(xy 25.134593 -352.155144) (xy 25.111952 -352.204721) (xy 25.082486 -352.250571) (xy 25.046794 -352.291762)
			(xy 25.005604 -352.327453) (xy 24.959754 -352.35692) (xy 24.910177 -352.379561) (xy 24.857883 -352.394917)
			(xy 24.803935 -352.402674) (xy 24.776684 -352.403156) (xy 24.745595 -352.402545) (xy 24.684244 -352.392448)
			(xy 24.62535 -352.37251) (xy 24.597614 -352.358452) (xy 24.589722 -352.354666) (xy 24.572415 -352.352121)
			(xy 24.555258 -352.355527) (xy 24.547576 -352.359722) (xy 24.4729 -352.40468) (xy 24.465613 -352.40949)
			(xy 24.454549 -352.42298) (xy 24.448628 -352.439392) (xy 24.448262 -352.448114) (xy 24.448262 -355.2444)
			(xy 28.446982 -355.2444) (xy 28.451053 -355.188778) (xy 28.463179 -355.134341) (xy 28.483102 -355.08225)
			(xy 28.510398 -355.033615) (xy 28.544484 -354.989472) (xy 28.584633 -354.950763) (xy 28.629991 -354.918312)
			(xy 28.679591 -354.892811) (xy 28.732375 -354.874804) (xy 28.787218 -354.864674) (xy 28.842952 -354.862637)
			(xy 28.898389 -354.868737) (xy 28.952346 -354.882843) (xy 29.003675 -354.904655) (xy 29.051281 -354.933709)
			(xy 29.094149 -354.969384) (xy 29.131366 -355.010921) (xy 29.162139 -355.057434) (xy 29.185811 -355.107931)
			(xy 29.201879 -355.161338) (xy 29.209999 -355.216514) (xy 29.210508 -355.2444) (xy 29.209999 -355.272286)
			(xy 29.201879 -355.327462) (xy 29.185811 -355.380869) (xy 29.162139 -355.431366) (xy 29.131366 -355.477879)
			(xy 29.094149 -355.519416) (xy 29.051281 -355.555091) (xy 29.003675 -355.584145) (xy 28.952346 -355.605957)
			(xy 28.898389 -355.620063) (xy 28.842952 -355.626163) (xy 28.787218 -355.624126) (xy 28.732375 -355.613996)
			(xy 28.679591 -355.595989) (xy 28.629991 -355.570488) (xy 28.584633 -355.538037) (xy 28.544484 -355.499328)
			(xy 28.510398 -355.455185) (xy 28.483102 -355.40655) (xy 28.463179 -355.354459) (xy 28.451053 -355.300022)
			(xy 28.446982 -355.2444) (xy 24.448262 -355.2444) (xy 24.448262 -358.431846) (xy 24.448695 -358.441911)
			(xy 24.456428 -358.460498) (xy 24.463248 -358.467914) (xy 24.977344 -358.98201) (xy 24.98474 -358.988859)
			(xy 25.00334 -358.996592) (xy 25.013412 -358.996996) (xy 26.110438 -358.996996) (xy 26.120505 -358.997426)
			(xy 26.1391 -359.00515) (xy 26.146506 -359.011982) (xy 28.098242 -360.963718) (xy 28.105092 -360.971115)
			(xy 28.112829 -360.989713) (xy 28.113228 -360.999786) (xy 28.113228 -365.99495) (xy 28.113661 -366.005016)
			(xy 28.121391 -366.023604) (xy 28.128214 -366.031018) (xy 28.326334 -366.229138) (xy 28.333731 -366.235986)
			(xy 28.35233 -366.243718) (xy 28.362402 -366.244124) (xy 31.539688 -366.244124) (xy 31.563368 -366.244501)
			(xy 31.610327 -366.250655) (xy 31.656084 -366.262872) (xy 31.678118 -366.271556) (xy 31.687516 -366.275366)
			(xy 32.560514 -366.275366) (xy 32.570582 -366.27494) (xy 32.58918 -366.267218) (xy 32.596582 -366.26038)
			(xy 32.799528 -366.057434) (xy 32.806372 -366.050035) (xy 32.814093 -366.031436) (xy 32.814514 -366.021366)
			(xy 32.814514 -362.074714) (xy 32.814076 -362.06465) (xy 32.806341 -362.046067) (xy 32.799528 -362.038646)
			(xy 32.57042 -361.809538) (xy 32.563019 -361.8027) (xy 32.54442 -361.794989) (xy 32.534352 -361.794552)
			(xy 30.02534 -361.794552) (xy 30.015276 -361.794116) (xy 29.996692 -361.786381) (xy 29.989272 -361.779566)
			(xy 28.302966 -360.09326) (xy 28.296119 -360.085863) (xy 28.288388 -360.067264) (xy 28.28798 -360.057192)
			(xy 28.28798 -358.693212) (xy 28.287634 -358.684478) (xy 28.281762 -358.668029) (xy 28.270673 -358.654535)
			(xy 28.263342 -358.649778) (xy 28.188666 -358.60482) (xy 28.180979 -358.600626) (xy 28.163821 -358.597193)
			(xy 28.146509 -358.599736) (xy 28.138628 -358.60355) (xy 28.110823 -358.617677) (xy 28.05176 -358.637696)
			(xy 27.990231 -358.647861) (xy 27.95905 -358.648508) (xy 27.931795 -358.648048) (xy 27.877838 -358.640297)
			(xy 27.825535 -358.624945) (xy 27.775948 -358.602306) (xy 27.730089 -358.572839) (xy 27.68889 -358.537145)
			(xy 27.653191 -358.495951) (xy 27.623718 -358.450096) (xy 27.601072 -358.400512) (xy 27.585714 -358.34821)
			(xy 27.577955 -358.294255) (xy 27.577542 -358.267) (xy 27.578097 -358.237812) (xy 27.586986 -358.180117)
			(xy 27.604558 -358.124449) (xy 27.630402 -358.072106) (xy 27.663916 -358.024308) (xy 27.704318 -357.982172)
			(xy 27.727148 -357.963978) (xy 27.736253 -357.956091) (xy 27.746579 -357.934363) (xy 27.74696 -357.922322)
			(xy 27.745182 -357.840534) (xy 27.744203 -357.828483) (xy 27.732659 -357.807279) (xy 27.723084 -357.799894)
			(xy 27.701673 -357.784544) (xy 27.662879 -357.748899) (xy 27.629354 -357.70826) (xy 27.601735 -357.663397)
			(xy 27.580547 -357.615162) (xy 27.566191 -357.564473) (xy 27.558941 -357.512291) (xy 27.558492 -357.48595)
			(xy 27.558952 -357.458695) (xy 27.566703 -357.404738) (xy 27.582055 -357.352435) (xy 27.604694 -357.302848)
			(xy 27.634161 -357.256989) (xy 27.669855 -357.21579) (xy 27.711049 -357.180091) (xy 27.756904 -357.150618)
			(xy 27.806488 -357.127972) (xy 27.85879 -357.112614) (xy 27.912745 -357.104855) (xy 27.94 -357.104442)
			(xy 27.965532 -357.10485) (xy 28.016141 -357.111661) (xy 28.065388 -357.125161) (xy 28.112395 -357.145109)
			(xy 28.134564 -357.157782) (xy 28.146502 -357.16464) (xy 28.17368 -357.164894) (xy 28.262326 -357.114602)
			(xy 28.269945 -357.109874) (xy 28.281523 -357.096197) (xy 28.287673 -357.079366) (xy 28.28798 -357.070406)
			(xy 28.28798 -356.788212) (xy 28.266898 -356.76078) (xy 28.250134 -356.756462) (xy 28.223253 -356.748973)
			(xy 28.171871 -356.727212) (xy 28.124211 -356.698191) (xy 28.081292 -356.662531) (xy 28.044032 -356.620993)
			(xy 28.013227 -356.574466) (xy 27.989535 -356.523945) (xy 27.973464 -356.470509) (xy 27.965356 -356.4153)
			(xy 27.964892 -356.3874) (xy 27.965378 -356.360149) (xy 27.973134 -356.306201) (xy 27.988489 -356.253906)
			(xy 28.011131 -356.204329) (xy 28.040597 -356.158479) (xy 28.076288 -356.117288) (xy 28.117479 -356.081597)
			(xy 28.163329 -356.052131) (xy 28.212906 -356.029489) (xy 28.265201 -356.014134) (xy 28.319149 -356.006378)
			(xy 28.3464 -356.005892) (xy 28.373338 -356.006355) (xy 28.426678 -356.013933) (xy 28.478423 -356.028938)
			(xy 28.527542 -356.051071) (xy 28.57306 -356.079893) (xy 28.614072 -356.114831) (xy 28.649762 -356.155189)
			(xy 28.679421 -356.200166) (xy 28.691332 -356.224332) (xy 28.695798 -356.232855) (xy 28.709815 -356.246017)
			(xy 28.727692 -356.253093) (xy 28.737306 -356.253542) (xy 30.7467 -356.253542) (xy 30.754666 -356.253276)
			(xy 30.76982 -356.248361) (xy 30.776418 -356.24389) (xy 30.801021 -356.226742) (xy 30.854454 -356.199518)
			(xy 30.911487 -356.180988) (xy 30.970716 -356.171607) (xy 31.0007 -356.170992) (xy 31.030687 -356.17155)
			(xy 31.089923 -356.180937) (xy 31.14696 -356.199478) (xy 31.200392 -356.226718) (xy 31.224982 -356.24389)
			(xy 31.231332 -356.248716) (xy 31.246572 -356.253542) (xy 31.293562 -356.253542) (xy 31.303056 -356.253151)
			(xy 31.320753 -356.246267) (xy 31.334765 -356.233452) (xy 31.339282 -356.225094) (xy 31.37916 -356.142798)
			(xy 31.38286 -356.134108) (xy 31.384354 -356.115298) (xy 31.378964 -356.097215) (xy 31.373572 -356.089458)
			(xy 31.373572 -356.089204) (xy 31.358247 -356.068994) (xy 31.332509 -356.025291) (xy 31.312793 -355.978561)
			(xy 31.299448 -355.929629) (xy 31.292709 -355.879359) (xy 31.292292 -355.854) (xy 31.292811 -355.825735)
			(xy 31.301163 -355.769827) (xy 31.317669 -355.715761) (xy 31.341968 -355.664721) (xy 31.373529 -355.617822)
			(xy 31.411662 -355.576092) (xy 31.455533 -355.540441) (xy 31.504181 -355.511651) (xy 31.556544 -355.49035)
			(xy 31.583884 -355.48316) (xy 31.600902 -355.479096) (xy 31.622492 -355.451664) (xy 31.622492 -354.46208)
			(xy 31.622065 -354.452012) (xy 31.614345 -354.433413) (xy 31.607506 -354.426012) (xy 30.307788 -353.126294)
			(xy 30.300389 -353.11945) (xy 30.281791 -353.111721) (xy 30.27172 -353.111308) (xy 27.034998 -353.111308)
			(xy 27.009996 -353.110716) (xy 26.960961 -353.100921) (xy 26.914779 -353.081747) (xy 26.873225 -353.053932)
			(xy 26.855166 -353.036632) (xy 25.931368 -352.112834) (xy 25.914109 -352.09474) (xy 25.886294 -352.053195)
			(xy 25.867115 -352.007024) (xy 25.857307 -351.957999) (xy 25.856692 -351.933002) (xy 25.856692 -350.9264)
			(xy 25.857284 -350.901398) (xy 25.867079 -350.852363) (xy 25.886252 -350.80618) (xy 25.914067 -350.764626)
			(xy 25.931368 -350.746568) (xy 26.282904 -350.395032) (xy 26.286714 -350.386396) (xy 26.298328 -350.361488)
			(xy 26.327652 -350.315009) (xy 26.363341 -350.273218) (xy 26.404656 -350.236979) (xy 26.450743 -350.207042)
			(xy 26.500648 -350.184026) (xy 26.553338 -350.168408) (xy 26.607724 -350.16051) (xy 26.635202 -350.160082)
			(xy 26.662453 -350.160568) (xy 26.716401 -350.168325) (xy 26.768697 -350.18368) (xy 26.818274 -350.206321)
			(xy 26.864125 -350.235787) (xy 26.905316 -350.271478) (xy 26.941008 -350.312669) (xy 26.970475 -350.358519)
			(xy 26.993117 -350.408096) (xy 27.008474 -350.460391) (xy 27.016232 -350.514339) (xy 27.01671 -350.54159)
			(xy 27.016239 -350.569031) (xy 27.008378 -350.623347) (xy 26.992804 -350.675972) (xy 26.990095 -350.681852)
			(xy 27.258475 -350.681852) (xy 27.258475 -350.627348) (xy 27.266232 -350.573398) (xy 27.281589 -350.521102)
			(xy 27.304231 -350.471523) (xy 27.333699 -350.425671) (xy 27.369393 -350.38448) (xy 27.410586 -350.348788)
			(xy 27.456439 -350.319322) (xy 27.506018 -350.296682) (xy 27.558316 -350.281329) (xy 27.612266 -350.273574)
			(xy 27.639518 -350.273112) (xy 27.639772 -350.273112) (xy 27.664975 -350.273528) (xy 27.714942 -350.280163)
			(xy 27.763597 -350.293335) (xy 27.810087 -350.312813) (xy 27.83205 -350.325182) (xy 27.841956 -350.331024)
			(xy 27.8638 -350.333056) (xy 27.958542 -350.299528) (xy 27.97429 -350.284034) (xy 27.978354 -350.27362)
			(xy 27.989083 -350.246857) (xy 28.017365 -350.196615) (xy 28.052889 -350.151205) (xy 28.094846 -350.111661)
			(xy 28.142279 -350.078885) (xy 28.194106 -350.053625) (xy 28.249145 -350.036457) (xy 28.306142 -350.027771)
			(xy 28.33497 -350.02724) (xy 28.362224 -350.027683) (xy 28.416178 -350.035437) (xy 28.46848 -350.050792)
			(xy 28.518063 -350.073435) (xy 28.563918 -350.102904) (xy 28.605113 -350.1386) (xy 28.640807 -350.179796)
			(xy 28.670274 -350.225653) (xy 28.692914 -350.275237) (xy 28.705636 -350.318578) (xy 30.846522 -350.318578)
			(xy 30.847034 -350.291005) (xy 30.854976 -350.236434) (xy 30.870691 -350.183575) (xy 30.893852 -350.133528)
			(xy 30.923977 -350.087337) (xy 30.960438 -350.045965) (xy 30.981142 -350.027748) (xy 30.989203 -350.02018)
			(xy 30.998563 -350.000178) (xy 30.999176 -349.98914) (xy 30.999176 -349.911416) (xy 30.998607 -349.900367)
			(xy 30.989243 -349.880345) (xy 30.981142 -349.872808) (xy 30.96044 -349.854587) (xy 30.923967 -349.813221)
			(xy 30.893833 -349.767034) (xy 30.870665 -349.716988) (xy 30.854947 -349.664126) (xy 30.847007 -349.609552)
			(xy 30.846522 -349.581978) (xy 30.846934 -349.554723) (xy 30.854695 -349.500769) (xy 30.870056 -349.448468)
			(xy 30.892703 -349.398886) (xy 30.922176 -349.353031) (xy 30.957875 -349.311838) (xy 30.999073 -349.276145)
			(xy 31.044932 -349.246678) (xy 31.094517 -349.224037) (xy 31.14682 -349.208684) (xy 31.200775 -349.200931)
			(xy 31.22803 -349.20047) (xy 31.228538 -349.20047) (xy 31.26232 -349.201994) (xy 31.27248 -349.20301)
			(xy 31.291784 -349.196914) (xy 31.354776 -349.144082) (xy 31.362049 -349.137342) (xy 31.371341 -349.11985)
			(xy 31.37281 -349.110046) (xy 31.37281 -349.109284) (xy 31.375762 -349.081135) (xy 31.388956 -349.026097)
			(xy 31.410141 -348.973613) (xy 31.438849 -348.924837) (xy 31.474452 -348.88084) (xy 31.516166 -348.842588)
			(xy 31.563076 -348.810921) (xy 31.614151 -348.786535) (xy 31.668269 -348.769966) (xy 31.724241 -348.761577)
			(xy 31.75254 -348.76105) (xy 31.752794 -348.76105) (xy 31.770813 -348.761277) (xy 31.806688 -348.764707)
			(xy 31.824422 -348.767908) (xy 31.834074 -348.769686) (xy 31.853124 -348.76613) (xy 31.928054 -348.718124)
			(xy 31.939484 -348.702376) (xy 31.94177 -348.692978) (xy 31.949225 -348.665951) (xy 31.970848 -348.614227)
			(xy 31.999805 -348.566223) (xy 32.035473 -348.522971) (xy 32.077085 -348.485403) (xy 32.123745 -348.454326)
			(xy 32.174449 -348.43041) (xy 32.228107 -348.414169) (xy 32.283563 -348.405952) (xy 32.311594 -348.40545)
			(xy 32.338843 -348.405983) (xy 32.392787 -348.413738) (xy 32.445078 -348.42909) (xy 32.494653 -348.451727)
			(xy 32.540501 -348.481189) (xy 32.58169 -348.516876) (xy 32.617382 -348.55806) (xy 32.64685 -348.603905)
			(xy 32.669493 -348.653477) (xy 32.684852 -348.705766) (xy 32.692613 -348.759709) (xy 32.693102 -348.786958)
			(xy 32.692607 -348.814531) (xy 32.68466 -348.869103) (xy 32.668941 -348.921962) (xy 32.645776 -348.972008)
			(xy 32.615649 -349.018199) (xy 32.579187 -349.059571) (xy 32.558482 -349.077788) (xy 32.550409 -349.085345)
			(xy 32.541054 -349.105355) (xy 32.540448 -349.116396) (xy 32.540448 -349.19412) (xy 32.541045 -349.205166)
			(xy 32.550388 -349.225188) (xy 32.558482 -349.232728) (xy 32.579206 -349.250925) (xy 32.615676 -349.292296)
			(xy 32.645807 -349.338489) (xy 32.668971 -349.38854) (xy 32.684684 -349.441405) (xy 32.692619 -349.495982)
			(xy 32.693102 -349.523558) (xy 32.692607 -349.551131) (xy 32.68466 -349.605703) (xy 32.684086 -349.607632)
			(xy 33.774378 -349.607632) (xy 33.778449 -349.55201) (xy 33.790575 -349.497573) (xy 33.810498 -349.445482)
			(xy 33.837794 -349.396847) (xy 33.87188 -349.352704) (xy 33.912029 -349.313995) (xy 33.957387 -349.281544)
			(xy 34.006987 -349.256043) (xy 34.059771 -349.238036) (xy 34.114614 -349.227906) (xy 34.170348 -349.225869)
			(xy 34.225785 -349.231969) (xy 34.279742 -349.246075) (xy 34.331071 -349.267887) (xy 34.378677 -349.296941)
			(xy 34.421545 -349.332616) (xy 34.458762 -349.374153) (xy 34.489535 -349.420666) (xy 34.513207 -349.471163)
			(xy 34.529275 -349.52457) (xy 34.537395 -349.579746) (xy 34.537904 -349.607632) (xy 34.537395 -349.635518)
			(xy 34.529275 -349.690694) (xy 34.513207 -349.744101) (xy 34.489535 -349.794598) (xy 34.458762 -349.841111)
			(xy 34.421545 -349.882648) (xy 34.378677 -349.918323) (xy 34.331071 -349.947377) (xy 34.279742 -349.969189)
			(xy 34.225785 -349.983295) (xy 34.170348 -349.989395) (xy 34.114614 -349.987358) (xy 34.059771 -349.977228)
			(xy 34.006987 -349.959221) (xy 33.957387 -349.93372) (xy 33.912029 -349.901269) (xy 33.87188 -349.86256)
			(xy 33.837794 -349.818417) (xy 33.810498 -349.769782) (xy 33.790575 -349.717691) (xy 33.778449 -349.663254)
			(xy 33.774378 -349.607632) (xy 32.684086 -349.607632) (xy 32.668941 -349.658562) (xy 32.645776 -349.708608)
			(xy 32.615649 -349.754799) (xy 32.579187 -349.796171) (xy 32.558482 -349.814388) (xy 32.550409 -349.821945)
			(xy 32.541054 -349.841955) (xy 32.540448 -349.852996) (xy 32.540448 -349.93072) (xy 32.541045 -349.941766)
			(xy 32.550388 -349.961788) (xy 32.558482 -349.969328) (xy 32.579206 -349.987525) (xy 32.615676 -350.028896)
			(xy 32.645807 -350.075089) (xy 32.668971 -350.12514) (xy 32.684684 -350.178005) (xy 32.692619 -350.232582)
			(xy 32.693102 -350.260158) (xy 32.692606 -350.28741) (xy 32.684854 -350.34136) (xy 32.669503 -350.393658)
			(xy 32.646865 -350.443238) (xy 32.617401 -350.489092) (xy 32.605367 -350.502982) (xy 33.195258 -350.502982)
			(xy 33.199329 -350.44736) (xy 33.211455 -350.392923) (xy 33.231378 -350.340832) (xy 33.258674 -350.292197)
			(xy 33.29276 -350.248054) (xy 33.332909 -350.209345) (xy 33.378267 -350.176894) (xy 33.427867 -350.151393)
			(xy 33.480651 -350.133386) (xy 33.535494 -350.123256) (xy 33.591228 -350.121219) (xy 33.646665 -350.127319)
			(xy 33.700622 -350.141425) (xy 33.751951 -350.163237) (xy 33.799557 -350.192291) (xy 33.842425 -350.227966)
			(xy 33.879642 -350.269503) (xy 33.910415 -350.316016) (xy 33.934087 -350.366513) (xy 33.950155 -350.41992)
			(xy 33.958275 -350.475096) (xy 33.958784 -350.502982) (xy 33.958275 -350.530868) (xy 33.950155 -350.586044)
			(xy 33.934087 -350.639451) (xy 33.910415 -350.689948) (xy 33.879642 -350.736461) (xy 33.842425 -350.777998)
			(xy 33.799557 -350.813673) (xy 33.751951 -350.842727) (xy 33.700622 -350.864539) (xy 33.646665 -350.878645)
			(xy 33.591228 -350.884745) (xy 33.535494 -350.882708) (xy 33.480651 -350.872578) (xy 33.427867 -350.854571)
			(xy 33.378267 -350.82907) (xy 33.332909 -350.796619) (xy 33.29276 -350.75791) (xy 33.258674 -350.713767)
			(xy 33.231378 -350.665132) (xy 33.211455 -350.613041) (xy 33.199329 -350.558604) (xy 33.195258 -350.502982)
			(xy 32.605367 -350.502982) (xy 32.581711 -350.530285) (xy 32.540521 -350.565979) (xy 32.49467 -350.595448)
			(xy 32.445092 -350.618091) (xy 32.392795 -350.633447) (xy 32.338846 -350.641203) (xy 32.311594 -350.641666)
			(xy 32.283737 -350.641174) (xy 32.228619 -350.633048) (xy 32.175267 -350.617) (xy 32.124813 -350.59337)
			(xy 32.078327 -350.56266) (xy 32.036798 -350.52552) (xy 32.001106 -350.482741) (xy 31.972009 -350.435229)
			(xy 31.950124 -350.383993) (xy 31.942532 -350.357186) (xy 31.940246 -350.348296) (xy 31.929578 -350.333056)
			(xy 31.857696 -350.285304) (xy 31.839662 -350.28124) (xy 31.830518 -350.28251) (xy 31.817501 -350.284175)
			(xy 31.791317 -350.285958) (xy 31.778194 -350.286066) (xy 31.764045 -350.285973) (xy 31.735822 -350.283938)
			(xy 31.721806 -350.282002) (xy 31.7119 -350.280478) (xy 31.692088 -350.285304) (xy 31.617666 -350.341184)
			(xy 31.607506 -350.35871) (xy 31.606236 -350.36887) (xy 31.60215 -350.396023) (xy 31.587174 -350.448852)
			(xy 31.564781 -350.498989) (xy 31.535432 -350.545399) (xy 31.499735 -350.587122) (xy 31.458425 -350.623298)
			(xy 31.412357 -350.653179) (xy 31.362481 -350.676149) (xy 31.309828 -350.691732) (xy 31.255485 -350.699607)
			(xy 31.22803 -350.700086) (xy 31.200777 -350.699617) (xy 31.146825 -350.691863) (xy 31.094526 -350.67651)
			(xy 31.044944 -350.653869) (xy 30.99909 -350.624402) (xy 30.957897 -350.588709) (xy 30.922202 -350.547516)
			(xy 30.892735 -350.501663) (xy 30.870093 -350.452082) (xy 30.854738 -350.399783) (xy 30.846984 -350.345831)
			(xy 30.846522 -350.318578) (xy 28.705636 -350.318578) (xy 28.708266 -350.327539) (xy 28.716018 -350.381494)
			(xy 28.716478 -350.408748) (xy 28.715825 -350.440311) (xy 28.705435 -350.502577) (xy 28.684947 -350.562286)
			(xy 28.670504 -350.590358) (xy 28.665678 -350.599248) (xy 28.663646 -350.618806) (xy 28.686506 -350.697292)
			(xy 28.689755 -350.706712) (xy 28.702165 -350.722273) (xy 28.710636 -350.727518) (xy 28.735715 -350.742104)
			(xy 28.7816 -350.777599) (xy 28.821578 -350.819635) (xy 28.854727 -350.867242) (xy 28.880282 -350.919322)
			(xy 28.897652 -350.974672) (xy 28.906437 -351.032014) (xy 28.906978 -351.06102) (xy 28.906492 -351.088271)
			(xy 28.898736 -351.142219) (xy 28.883381 -351.194514) (xy 28.860739 -351.244091) (xy 28.831273 -351.289941)
			(xy 28.795582 -351.331132) (xy 28.754391 -351.366823) (xy 28.708541 -351.396289) (xy 28.658964 -351.418931)
			(xy 28.606669 -351.434286) (xy 28.552721 -351.442042) (xy 28.498219 -351.442042) (xy 28.444271 -351.434286)
			(xy 28.391976 -351.418931) (xy 28.342399 -351.396289) (xy 28.296549 -351.366823) (xy 28.255358 -351.331132)
			(xy 28.219667 -351.289941) (xy 28.190201 -351.244091) (xy 28.167559 -351.194514) (xy 28.152204 -351.142219)
			(xy 28.144448 -351.088271) (xy 28.143962 -351.06102) (xy 28.14461 -351.029457) (xy 28.155003 -350.967191)
			(xy 28.175493 -350.907483) (xy 28.189936 -350.87941) (xy 28.194762 -350.87052) (xy 28.196794 -350.850962)
			(xy 28.173934 -350.772476) (xy 28.170719 -350.763041) (xy 28.158286 -350.747487) (xy 28.149804 -350.74225)
			(xy 28.142438 -350.738186) (xy 28.132532 -350.732344) (xy 28.110688 -350.730312) (xy 28.015946 -350.76384)
			(xy 28.000198 -350.779334) (xy 27.996134 -350.789748) (xy 27.985452 -350.81653) (xy 27.95716 -350.86677)
			(xy 27.921627 -350.912178) (xy 27.879663 -350.951719) (xy 27.832224 -350.984492) (xy 27.780392 -351.009749)
			(xy 27.725348 -351.026915) (xy 27.668347 -351.035598) (xy 27.639518 -351.036128) (xy 27.612266 -351.035626)
			(xy 27.558316 -351.027871) (xy 27.506018 -351.012518) (xy 27.456439 -350.989878) (xy 27.410586 -350.960412)
			(xy 27.369393 -350.92472) (xy 27.333699 -350.883529) (xy 27.304231 -350.837677) (xy 27.281589 -350.788098)
			(xy 27.266232 -350.735802) (xy 27.258475 -350.681852) (xy 26.990095 -350.681852) (xy 26.969838 -350.725817)
			(xy 26.939957 -350.771851) (xy 26.922222 -350.792796) (xy 26.921714 -350.793304) (xy 26.916128 -350.800391)
			(xy 26.909886 -350.817308) (xy 26.909522 -350.826324) (xy 26.909522 -350.893888) (xy 26.90988 -350.902905)
			(xy 26.916126 -350.919822) (xy 26.921714 -350.926908) (xy 26.921968 -350.927162) (xy 26.939734 -350.948125)
			(xy 26.969682 -350.994194) (xy 26.992703 -351.044087) (xy 27.00832 -351.096769) (xy 27.016208 -351.151148)
			(xy 27.01671 -351.178622) (xy 27.01613 -351.208649) (xy 27.006682 -351.267955) (xy 26.988054 -351.325048)
			(xy 26.960707 -351.378514) (xy 26.925318 -351.427033) (xy 26.904442 -351.448624) (xy 26.897595 -351.456022)
			(xy 26.889862 -351.47462) (xy 26.889456 -351.484692) (xy 26.889456 -351.769172) (xy 26.889894 -351.779235)
			(xy 26.897633 -351.797815) (xy 26.904442 -351.80524) (xy 27.305762 -352.206306) (xy 27.313164 -352.213142)
			(xy 27.331762 -352.220853) (xy 27.34183 -352.221292) (xy 30.5562 -352.221292) (xy 30.581202 -352.221884)
			(xy 30.630237 -352.231679) (xy 30.67642 -352.250852) (xy 30.717974 -352.278667) (xy 30.736032 -352.295968)
			(xy 32.437832 -353.997768) (xy 32.455091 -354.015862) (xy 32.482905 -354.057407) (xy 32.502085 -354.103578)
			(xy 32.511892 -354.152603) (xy 32.512508 -354.1776) (xy 32.512508 -355.415596) (xy 32.512814 -355.424084)
			(xy 32.518364 -355.440126) (xy 32.528883 -355.453449) (xy 32.535876 -355.458268) (xy 32.618934 -355.511608)
			(xy 32.644842 -355.513386) (xy 32.656526 -355.507798) (xy 32.68176 -355.496655) (xy 32.734634 -355.480936)
			(xy 32.78922 -355.472994) (xy 32.8168 -355.472492) (xy 32.843267 -355.472944) (xy 32.895693 -355.480262)
			(xy 32.946604 -355.494758) (xy 32.995022 -355.516152) (xy 33.040017 -355.544035) (xy 33.06064 -355.56063)
			(xy 33.07588 -355.57333) (xy 33.114996 -355.571298) (xy 34.062162 -354.624386) (xy 34.06901 -354.616989)
			(xy 34.076746 -354.59839) (xy 34.077148 -354.588318) (xy 34.077148 -350.82607) (xy 34.077762 -350.801088)
			(xy 34.087508 -350.752083) (xy 34.106621 -350.705918) (xy 34.134366 -350.664365) (xy 34.15157 -350.646238)
			(xy 34.43605 -350.361758) (xy 34.454161 -350.344538) (xy 34.495722 -350.316803) (xy 34.541892 -350.297699)
			(xy 34.590899 -350.287959) (xy 34.615882 -350.287336) (xy 34.631376 -350.287336) (xy 34.649532 -350.267694)
			(xy 34.690396 -350.233182) (xy 34.735682 -350.204719) (xy 34.784502 -350.182865) (xy 34.835897 -350.168048)
			(xy 34.888858 -350.160559) (xy 34.915602 -350.160082) (xy 34.942853 -350.160568) (xy 34.996801 -350.168325)
			(xy 35.049097 -350.18368) (xy 35.098674 -350.206321) (xy 35.144525 -350.235787) (xy 35.185716 -350.271478)
			(xy 35.221408 -350.312669) (xy 35.250875 -350.358519) (xy 35.273517 -350.408096) (xy 35.288874 -350.460391)
			(xy 35.296632 -350.514339) (xy 35.29711 -350.54159) (xy 35.296639 -350.569031) (xy 35.288778 -350.623347)
			(xy 35.273204 -350.675972) (xy 35.270495 -350.681852) (xy 35.538875 -350.681852) (xy 35.538875 -350.627348)
			(xy 35.546632 -350.573398) (xy 35.561989 -350.521102) (xy 35.584631 -350.471523) (xy 35.614099 -350.425671)
			(xy 35.649793 -350.38448) (xy 35.690986 -350.348788) (xy 35.736839 -350.319322) (xy 35.786418 -350.296682)
			(xy 35.838716 -350.281329) (xy 35.892666 -350.273574) (xy 35.919918 -350.273112) (xy 35.920172 -350.273112)
			(xy 35.945375 -350.273528) (xy 35.995342 -350.280163) (xy 36.043997 -350.293335) (xy 36.090487 -350.312813)
			(xy 36.11245 -350.325182) (xy 36.122356 -350.331024) (xy 36.1442 -350.333056) (xy 36.238942 -350.299528)
			(xy 36.25469 -350.284034) (xy 36.258754 -350.27362) (xy 36.269483 -350.246857) (xy 36.297765 -350.196615)
			(xy 36.333289 -350.151205) (xy 36.375246 -350.111661) (xy 36.422679 -350.078885) (xy 36.474506 -350.053625)
			(xy 36.529545 -350.036457) (xy 36.586542 -350.027771) (xy 36.61537 -350.02724) (xy 36.642624 -350.027683)
			(xy 36.696578 -350.035437) (xy 36.74888 -350.050792) (xy 36.798463 -350.073435) (xy 36.844318 -350.102904)
			(xy 36.885513 -350.1386) (xy 36.921207 -350.179796) (xy 36.950674 -350.225653) (xy 36.973314 -350.275237)
			(xy 36.986036 -350.318578) (xy 39.126922 -350.318578) (xy 39.127434 -350.291005) (xy 39.135376 -350.236434)
			(xy 39.151091 -350.183575) (xy 39.174252 -350.133528) (xy 39.204377 -350.087337) (xy 39.240838 -350.045965)
			(xy 39.261542 -350.027748) (xy 39.269603 -350.02018) (xy 39.278963 -350.000178) (xy 39.279576 -349.98914)
			(xy 39.279576 -349.911416) (xy 39.279007 -349.900367) (xy 39.269643 -349.880345) (xy 39.261542 -349.872808)
			(xy 39.24084 -349.854587) (xy 39.204367 -349.813221) (xy 39.174233 -349.767034) (xy 39.151065 -349.716988)
			(xy 39.135347 -349.664126) (xy 39.127407 -349.609552) (xy 39.126922 -349.581978) (xy 39.127334 -349.554723)
			(xy 39.135095 -349.500769) (xy 39.150456 -349.448468) (xy 39.173103 -349.398886) (xy 39.202576 -349.353031)
			(xy 39.238275 -349.311838) (xy 39.279473 -349.276145) (xy 39.325332 -349.246678) (xy 39.374917 -349.224037)
			(xy 39.42722 -349.208684) (xy 39.481175 -349.200931) (xy 39.50843 -349.20047) (xy 39.508938 -349.20047)
			(xy 39.54272 -349.201994) (xy 39.55288 -349.20301) (xy 39.572184 -349.196914) (xy 39.635176 -349.144082)
			(xy 39.642449 -349.137342) (xy 39.651741 -349.11985) (xy 39.65321 -349.110046) (xy 39.65321 -349.109284)
			(xy 39.656162 -349.081135) (xy 39.669356 -349.026097) (xy 39.690541 -348.973613) (xy 39.719249 -348.924837)
			(xy 39.754852 -348.88084) (xy 39.796566 -348.842588) (xy 39.843476 -348.810921) (xy 39.894551 -348.786535)
			(xy 39.948669 -348.769966) (xy 40.004641 -348.761577) (xy 40.03294 -348.76105) (xy 40.033194 -348.76105)
			(xy 40.051213 -348.761277) (xy 40.087088 -348.764707) (xy 40.104822 -348.767908) (xy 40.114474 -348.769686)
			(xy 40.133524 -348.76613) (xy 40.208454 -348.718124) (xy 40.219884 -348.702376) (xy 40.22217 -348.692978)
			(xy 40.229625 -348.665951) (xy 40.251248 -348.614227) (xy 40.280205 -348.566223) (xy 40.315873 -348.522971)
			(xy 40.357485 -348.485403) (xy 40.404145 -348.454326) (xy 40.454849 -348.43041) (xy 40.508507 -348.414169)
			(xy 40.563963 -348.405952) (xy 40.591994 -348.40545) (xy 40.619243 -348.405983) (xy 40.673187 -348.413738)
			(xy 40.725478 -348.42909) (xy 40.775053 -348.451727) (xy 40.820901 -348.481189) (xy 40.86209 -348.516876)
			(xy 40.897782 -348.55806) (xy 40.92725 -348.603905) (xy 40.949893 -348.653477) (xy 40.965252 -348.705766)
			(xy 40.973013 -348.759709) (xy 40.973502 -348.786958) (xy 40.973007 -348.814531) (xy 40.96506 -348.869103)
			(xy 40.949341 -348.921962) (xy 40.926176 -348.972008) (xy 40.896049 -349.018199) (xy 40.859587 -349.059571)
			(xy 40.838882 -349.077788) (xy 40.830809 -349.085345) (xy 40.821454 -349.105355) (xy 40.820848 -349.116396)
			(xy 40.820848 -349.19412) (xy 40.821445 -349.205166) (xy 40.830788 -349.225188) (xy 40.838882 -349.232728)
			(xy 40.859606 -349.250925) (xy 40.896076 -349.292296) (xy 40.926207 -349.338489) (xy 40.949371 -349.38854)
			(xy 40.965084 -349.441405) (xy 40.973019 -349.495982) (xy 40.973502 -349.523558) (xy 40.973007 -349.551131)
			(xy 40.96506 -349.605703) (xy 40.964486 -349.607632) (xy 42.080178 -349.607632) (xy 42.084249 -349.55201)
			(xy 42.096375 -349.497573) (xy 42.116298 -349.445482) (xy 42.143594 -349.396847) (xy 42.17768 -349.352704)
			(xy 42.217829 -349.313995) (xy 42.263187 -349.281544) (xy 42.312787 -349.256043) (xy 42.365571 -349.238036)
			(xy 42.420414 -349.227906) (xy 42.476148 -349.225869) (xy 42.531585 -349.231969) (xy 42.585542 -349.246075)
			(xy 42.636871 -349.267887) (xy 42.684477 -349.296941) (xy 42.727345 -349.332616) (xy 42.764562 -349.374153)
			(xy 42.795335 -349.420666) (xy 42.819007 -349.471163) (xy 42.835075 -349.52457) (xy 42.843195 -349.579746)
			(xy 42.843704 -349.607632) (xy 42.843195 -349.635518) (xy 42.835075 -349.690694) (xy 42.819007 -349.744101)
			(xy 42.795335 -349.794598) (xy 42.764562 -349.841111) (xy 42.727345 -349.882648) (xy 42.684477 -349.918323)
			(xy 42.636871 -349.947377) (xy 42.585542 -349.969189) (xy 42.531585 -349.983295) (xy 42.476148 -349.989395)
			(xy 42.420414 -349.987358) (xy 42.365571 -349.977228) (xy 42.312787 -349.959221) (xy 42.263187 -349.93372)
			(xy 42.217829 -349.901269) (xy 42.17768 -349.86256) (xy 42.143594 -349.818417) (xy 42.116298 -349.769782)
			(xy 42.096375 -349.717691) (xy 42.084249 -349.663254) (xy 42.080178 -349.607632) (xy 40.964486 -349.607632)
			(xy 40.949341 -349.658562) (xy 40.926176 -349.708608) (xy 40.896049 -349.754799) (xy 40.859587 -349.796171)
			(xy 40.838882 -349.814388) (xy 40.830809 -349.821945) (xy 40.821454 -349.841955) (xy 40.820848 -349.852996)
			(xy 40.820848 -349.93072) (xy 40.821445 -349.941766) (xy 40.830788 -349.961788) (xy 40.838882 -349.969328)
			(xy 40.859606 -349.987525) (xy 40.896076 -350.028896) (xy 40.926207 -350.075089) (xy 40.949371 -350.12514)
			(xy 40.965084 -350.178005) (xy 40.973019 -350.232582) (xy 40.973502 -350.260158) (xy 40.973006 -350.28741)
			(xy 40.965254 -350.34136) (xy 40.949903 -350.393658) (xy 40.927265 -350.443238) (xy 40.897801 -350.489092)
			(xy 40.885767 -350.502982) (xy 41.501058 -350.502982) (xy 41.505129 -350.44736) (xy 41.517255 -350.392923)
			(xy 41.537178 -350.340832) (xy 41.564474 -350.292197) (xy 41.59856 -350.248054) (xy 41.638709 -350.209345)
			(xy 41.684067 -350.176894) (xy 41.733667 -350.151393) (xy 41.786451 -350.133386) (xy 41.841294 -350.123256)
			(xy 41.897028 -350.121219) (xy 41.952465 -350.127319) (xy 42.006422 -350.141425) (xy 42.057751 -350.163237)
			(xy 42.105357 -350.192291) (xy 42.148225 -350.227966) (xy 42.185442 -350.269503) (xy 42.216215 -350.316016)
			(xy 42.239887 -350.366513) (xy 42.255955 -350.41992) (xy 42.264075 -350.475096) (xy 42.264584 -350.502982)
			(xy 42.264075 -350.530868) (xy 42.255955 -350.586044) (xy 42.239887 -350.639451) (xy 42.216215 -350.689948)
			(xy 42.185442 -350.736461) (xy 42.148225 -350.777998) (xy 42.105357 -350.813673) (xy 42.057751 -350.842727)
			(xy 42.006422 -350.864539) (xy 41.952465 -350.878645) (xy 41.897028 -350.884745) (xy 41.841294 -350.882708)
			(xy 41.786451 -350.872578) (xy 41.733667 -350.854571) (xy 41.684067 -350.82907) (xy 41.638709 -350.796619)
			(xy 41.59856 -350.75791) (xy 41.564474 -350.713767) (xy 41.537178 -350.665132) (xy 41.517255 -350.613041)
			(xy 41.505129 -350.558604) (xy 41.501058 -350.502982) (xy 40.885767 -350.502982) (xy 40.862111 -350.530285)
			(xy 40.820921 -350.565979) (xy 40.77507 -350.595448) (xy 40.725492 -350.618091) (xy 40.673195 -350.633447)
			(xy 40.619246 -350.641203) (xy 40.591994 -350.641666) (xy 40.564137 -350.641174) (xy 40.509019 -350.633048)
			(xy 40.455667 -350.617) (xy 40.405213 -350.59337) (xy 40.358727 -350.56266) (xy 40.317198 -350.52552)
			(xy 40.281506 -350.482741) (xy 40.252409 -350.435229) (xy 40.230524 -350.383993) (xy 40.222932 -350.357186)
			(xy 40.220646 -350.348296) (xy 40.209978 -350.333056) (xy 40.138096 -350.285304) (xy 40.120062 -350.28124)
			(xy 40.110918 -350.28251) (xy 40.097901 -350.284175) (xy 40.071717 -350.285958) (xy 40.058594 -350.286066)
			(xy 40.044445 -350.285973) (xy 40.016222 -350.283938) (xy 40.002206 -350.282002) (xy 39.9923 -350.280478)
			(xy 39.972488 -350.285304) (xy 39.898066 -350.341184) (xy 39.887906 -350.35871) (xy 39.886636 -350.36887)
			(xy 39.88255 -350.396023) (xy 39.867574 -350.448852) (xy 39.845181 -350.498989) (xy 39.815832 -350.545399)
			(xy 39.780135 -350.587122) (xy 39.738825 -350.623298) (xy 39.692757 -350.653179) (xy 39.642881 -350.676149)
			(xy 39.590228 -350.691732) (xy 39.535885 -350.699607) (xy 39.50843 -350.700086) (xy 39.481177 -350.699617)
			(xy 39.427225 -350.691863) (xy 39.374926 -350.67651) (xy 39.325344 -350.653869) (xy 39.27949 -350.624402)
			(xy 39.238297 -350.588709) (xy 39.202602 -350.547516) (xy 39.173135 -350.501663) (xy 39.150493 -350.452082)
			(xy 39.135138 -350.399783) (xy 39.127384 -350.345831) (xy 39.126922 -350.318578) (xy 36.986036 -350.318578)
			(xy 36.988666 -350.327539) (xy 36.996418 -350.381494) (xy 36.996878 -350.408748) (xy 36.996225 -350.440311)
			(xy 36.985835 -350.502577) (xy 36.965347 -350.562286) (xy 36.950904 -350.590358) (xy 36.946078 -350.599248)
			(xy 36.944046 -350.618806) (xy 36.966906 -350.697292) (xy 36.970155 -350.706712) (xy 36.982565 -350.722273)
			(xy 36.991036 -350.727518) (xy 37.016115 -350.742104) (xy 37.062 -350.777599) (xy 37.101978 -350.819635)
			(xy 37.135127 -350.867242) (xy 37.160682 -350.919322) (xy 37.178052 -350.974672) (xy 37.186837 -351.032014)
			(xy 37.187378 -351.06102) (xy 37.186892 -351.088271) (xy 37.179136 -351.142219) (xy 37.163781 -351.194514)
			(xy 37.141139 -351.244091) (xy 37.111673 -351.289941) (xy 37.075982 -351.331132) (xy 37.034791 -351.366823)
			(xy 36.988941 -351.396289) (xy 36.939364 -351.418931) (xy 36.887069 -351.434286) (xy 36.833121 -351.442042)
			(xy 36.778619 -351.442042) (xy 36.724671 -351.434286) (xy 36.672376 -351.418931) (xy 36.622799 -351.396289)
			(xy 36.576949 -351.366823) (xy 36.535758 -351.331132) (xy 36.500067 -351.289941) (xy 36.470601 -351.244091)
			(xy 36.447959 -351.194514) (xy 36.432604 -351.142219) (xy 36.424848 -351.088271) (xy 36.424362 -351.06102)
			(xy 36.42501 -351.029457) (xy 36.435403 -350.967191) (xy 36.455893 -350.907483) (xy 36.470336 -350.87941)
			(xy 36.475162 -350.87052) (xy 36.477194 -350.850962) (xy 36.454334 -350.772476) (xy 36.451119 -350.763041)
			(xy 36.438686 -350.747487) (xy 36.430204 -350.74225) (xy 36.422838 -350.738186) (xy 36.412932 -350.732344)
			(xy 36.391088 -350.730312) (xy 36.296346 -350.76384) (xy 36.280598 -350.779334) (xy 36.276534 -350.789748)
			(xy 36.265852 -350.81653) (xy 36.23756 -350.86677) (xy 36.202027 -350.912178) (xy 36.160063 -350.951719)
			(xy 36.112624 -350.984492) (xy 36.060792 -351.009749) (xy 36.005748 -351.026915) (xy 35.948747 -351.035598)
			(xy 35.919918 -351.036128) (xy 35.892666 -351.035626) (xy 35.838716 -351.027871) (xy 35.786418 -351.012518)
			(xy 35.736839 -350.989878) (xy 35.690986 -350.960412) (xy 35.649793 -350.92472) (xy 35.614099 -350.883529)
			(xy 35.584631 -350.837677) (xy 35.561989 -350.788098) (xy 35.546632 -350.735802) (xy 35.538875 -350.681852)
			(xy 35.270495 -350.681852) (xy 35.250238 -350.725817) (xy 35.220357 -350.771851) (xy 35.202622 -350.792796)
			(xy 35.202114 -350.793304) (xy 35.196528 -350.800391) (xy 35.190286 -350.817308) (xy 35.189922 -350.826324)
			(xy 35.189922 -350.893888) (xy 35.19028 -350.902905) (xy 35.196526 -350.919822) (xy 35.202114 -350.926908)
			(xy 35.202368 -350.927162) (xy 35.220134 -350.948125) (xy 35.250082 -350.994194) (xy 35.273103 -351.044087)
			(xy 35.28872 -351.096769) (xy 35.296608 -351.151148) (xy 35.29711 -351.178622) (xy 35.296597 -351.20689)
			(xy 35.288254 -351.262807) (xy 35.271756 -351.316882) (xy 35.247461 -351.367932) (xy 35.215903 -351.41484)
			(xy 35.17777 -351.45658) (xy 35.133898 -351.49224) (xy 35.085246 -351.521038) (xy 35.032879 -351.542344)
			(xy 35.005518 -351.549462) (xy 34.994669 -351.552734) (xy 34.977105 -351.567005) (xy 34.967346 -351.587425)
			(xy 34.966656 -351.598738) (xy 34.966656 -354.872798) (xy 34.966045 -354.897782) (xy 34.956304 -354.94679)
			(xy 34.937196 -354.99296) (xy 34.909453 -355.034518) (xy 34.892234 -355.05263) (xy 34.192592 -355.7524)
			(xy 34.669982 -355.7524) (xy 34.674053 -355.696778) (xy 34.686179 -355.642341) (xy 34.706102 -355.59025)
			(xy 34.733398 -355.541615) (xy 34.767484 -355.497472) (xy 34.807633 -355.458763) (xy 34.852991 -355.426312)
			(xy 34.902591 -355.400811) (xy 34.955375 -355.382804) (xy 35.010218 -355.372674) (xy 35.065952 -355.370637)
			(xy 35.121389 -355.376737) (xy 35.175346 -355.390843) (xy 35.226675 -355.412655) (xy 35.274281 -355.441709)
			(xy 35.317149 -355.477384) (xy 35.354366 -355.518921) (xy 35.385139 -355.565434) (xy 35.408811 -355.615931)
			(xy 35.424879 -355.669338) (xy 35.432999 -355.724514) (xy 35.433508 -355.7524) (xy 35.432999 -355.780286)
			(xy 35.424879 -355.835462) (xy 35.408811 -355.888869) (xy 35.385139 -355.939366) (xy 35.354366 -355.985879)
			(xy 35.317149 -356.027416) (xy 35.274281 -356.063091) (xy 35.226675 -356.092145) (xy 35.175346 -356.113957)
			(xy 35.121389 -356.128063) (xy 35.065952 -356.134163) (xy 35.010218 -356.132126) (xy 34.955375 -356.121996)
			(xy 34.902591 -356.103989) (xy 34.852991 -356.078488) (xy 34.807633 -356.046037) (xy 34.767484 -356.007328)
			(xy 34.733398 -355.963185) (xy 34.706102 -355.91455) (xy 34.686179 -355.862459) (xy 34.674053 -355.808022)
			(xy 34.669982 -355.7524) (xy 34.192592 -355.7524) (xy 33.505902 -356.439216) (xy 33.499227 -356.446629)
			(xy 33.491645 -356.465057) (xy 33.491654 -356.484985) (xy 33.499251 -356.503407) (xy 33.505902 -356.510844)
			(xy 33.838388 -356.84333) (xy 33.845231 -356.85073) (xy 33.852956 -356.869328) (xy 33.853374 -356.879398)
			(xy 33.853374 -357.266748) (xy 33.853752 -357.276116) (xy 33.860407 -357.293625) (xy 33.872917 -357.307566)
			(xy 33.88106 -357.312214) (xy 33.974532 -357.359712) (xy 34.00298 -357.357426) (xy 34.014664 -357.34879)
			(xy 34.039278 -357.331596) (xy 34.092774 -357.304342) (xy 34.149878 -357.285802) (xy 34.209181 -357.276431)
			(xy 34.2392 -357.275892) (xy 34.264184 -357.276287) (xy 34.313728 -357.282783) (xy 34.362001 -357.29569)
			(xy 34.38525 -357.304848) (xy 34.399474 -357.31069) (xy 34.429446 -357.304848) (xy 39.117016 -352.617532)
			(xy 39.135113 -352.600279) (xy 39.17666 -352.572476) (xy 39.222831 -352.553308) (xy 39.271853 -352.543512)
			(xy 39.296848 -352.542856) (xy 42.008552 -352.542856) (xy 42.018617 -352.542422) (xy 42.037204 -352.534689)
			(xy 42.04462 -352.52787) (xy 42.395902 -352.176842) (xy 42.402739 -352.16944) (xy 42.410452 -352.150842)
			(xy 42.410888 -352.140774) (xy 42.410888 -350.821498) (xy 42.411499 -350.796515) (xy 42.421242 -350.747508)
			(xy 42.440354 -350.701341) (xy 42.4681 -350.659787) (xy 42.48531 -350.641666) (xy 42.765218 -350.361758)
			(xy 42.78088 -350.346723) (xy 42.816346 -350.321685) (xy 42.855546 -350.303028) (xy 42.897344 -350.291293)
			(xy 42.918888 -350.288606) (xy 42.927542 -350.287295) (xy 42.943265 -350.279635) (xy 42.949622 -350.27362)
			(xy 42.9713 -350.25251) (xy 43.020086 -350.216718) (xy 43.0739 -350.189058) (xy 43.1314 -350.17022)
			(xy 43.191149 -350.160674) (xy 43.221402 -350.160082) (xy 43.248653 -350.160568) (xy 43.302601 -350.168325)
			(xy 43.354897 -350.18368) (xy 43.404474 -350.206321) (xy 43.450325 -350.235787) (xy 43.491516 -350.271478)
			(xy 43.527208 -350.312669) (xy 43.556675 -350.358519) (xy 43.579317 -350.408096) (xy 43.594674 -350.460391)
			(xy 43.602432 -350.514339) (xy 43.60291 -350.54159) (xy 43.602439 -350.569031) (xy 43.594578 -350.623347)
			(xy 43.579004 -350.675972) (xy 43.576295 -350.681852) (xy 43.844675 -350.681852) (xy 43.844675 -350.627348)
			(xy 43.852432 -350.573398) (xy 43.867789 -350.521102) (xy 43.890431 -350.471523) (xy 43.919899 -350.425671)
			(xy 43.955593 -350.38448) (xy 43.996786 -350.348788) (xy 44.042639 -350.319322) (xy 44.092218 -350.296682)
			(xy 44.144516 -350.281329) (xy 44.198466 -350.273574) (xy 44.225718 -350.273112) (xy 44.225972 -350.273112)
			(xy 44.251175 -350.273528) (xy 44.301142 -350.280163) (xy 44.349797 -350.293335) (xy 44.396287 -350.312813)
			(xy 44.41825 -350.325182) (xy 44.428156 -350.331024) (xy 44.45 -350.333056) (xy 44.544742 -350.299528)
			(xy 44.56049 -350.284034) (xy 44.564554 -350.27362) (xy 44.575283 -350.246857) (xy 44.603565 -350.196615)
			(xy 44.639089 -350.151205) (xy 44.681046 -350.111661) (xy 44.728479 -350.078885) (xy 44.780306 -350.053625)
			(xy 44.835345 -350.036457) (xy 44.892342 -350.027771) (xy 44.92117 -350.02724) (xy 44.948424 -350.027683)
			(xy 45.002378 -350.035437) (xy 45.05468 -350.050792) (xy 45.104263 -350.073435) (xy 45.150118 -350.102904)
			(xy 45.191313 -350.1386) (xy 45.227007 -350.179796) (xy 45.256474 -350.225653) (xy 45.279114 -350.275237)
			(xy 45.291836 -350.318578) (xy 47.432722 -350.318578) (xy 47.433234 -350.291005) (xy 47.441176 -350.236434)
			(xy 47.456891 -350.183575) (xy 47.480052 -350.133528) (xy 47.510177 -350.087337) (xy 47.546638 -350.045965)
			(xy 47.567342 -350.027748) (xy 47.575403 -350.02018) (xy 47.584763 -350.000178) (xy 47.585376 -349.98914)
			(xy 47.585376 -349.911416) (xy 47.584807 -349.900367) (xy 47.575443 -349.880345) (xy 47.567342 -349.872808)
			(xy 47.54664 -349.854587) (xy 47.510167 -349.813221) (xy 47.480033 -349.767034) (xy 47.456865 -349.716988)
			(xy 47.441147 -349.664126) (xy 47.433207 -349.609552) (xy 47.432722 -349.581978) (xy 47.433134 -349.554723)
			(xy 47.440895 -349.500769) (xy 47.456256 -349.448468) (xy 47.478903 -349.398886) (xy 47.508376 -349.353031)
			(xy 47.544075 -349.311838) (xy 47.585273 -349.276145) (xy 47.631132 -349.246678) (xy 47.680717 -349.224037)
			(xy 47.73302 -349.208684) (xy 47.786975 -349.200931) (xy 47.81423 -349.20047) (xy 47.814738 -349.20047)
			(xy 47.84852 -349.201994) (xy 47.85868 -349.20301) (xy 47.877984 -349.196914) (xy 47.940976 -349.144082)
			(xy 47.948249 -349.137342) (xy 47.957541 -349.11985) (xy 47.95901 -349.110046) (xy 47.95901 -349.109284)
			(xy 47.961962 -349.081135) (xy 47.975156 -349.026097) (xy 47.996341 -348.973613) (xy 48.025049 -348.924837)
			(xy 48.060652 -348.88084) (xy 48.102366 -348.842588) (xy 48.149276 -348.810921) (xy 48.200351 -348.786535)
			(xy 48.254469 -348.769966) (xy 48.310441 -348.761577) (xy 48.33874 -348.76105) (xy 48.338994 -348.76105)
			(xy 48.357013 -348.761277) (xy 48.392888 -348.764707) (xy 48.410622 -348.767908) (xy 48.420274 -348.769686)
			(xy 48.439324 -348.76613) (xy 48.514254 -348.718124) (xy 48.525684 -348.702376) (xy 48.52797 -348.692978)
			(xy 48.535425 -348.665951) (xy 48.557048 -348.614227) (xy 48.586005 -348.566223) (xy 48.621673 -348.522971)
			(xy 48.663285 -348.485403) (xy 48.709945 -348.454326) (xy 48.760649 -348.43041) (xy 48.814307 -348.414169)
			(xy 48.869763 -348.405952) (xy 48.897794 -348.40545) (xy 48.925043 -348.405983) (xy 48.978987 -348.413738)
			(xy 49.031278 -348.42909) (xy 49.080853 -348.451727) (xy 49.126701 -348.481189) (xy 49.16789 -348.516876)
			(xy 49.203582 -348.55806) (xy 49.23305 -348.603905) (xy 49.255693 -348.653477) (xy 49.271052 -348.705766)
			(xy 49.278813 -348.759709) (xy 49.279302 -348.786958) (xy 49.278807 -348.814531) (xy 49.27086 -348.869103)
			(xy 49.255141 -348.921962) (xy 49.231976 -348.972008) (xy 49.201849 -349.018199) (xy 49.165387 -349.059571)
			(xy 49.144682 -349.077788) (xy 49.136609 -349.085345) (xy 49.127254 -349.105355) (xy 49.126648 -349.116396)
			(xy 49.126648 -349.19412) (xy 49.127245 -349.205166) (xy 49.136588 -349.225188) (xy 49.144682 -349.232728)
			(xy 49.165406 -349.250925) (xy 49.201876 -349.292296) (xy 49.232007 -349.338489) (xy 49.255171 -349.38854)
			(xy 49.270884 -349.441405) (xy 49.278819 -349.495982) (xy 49.279302 -349.523558) (xy 49.278807 -349.551131)
			(xy 49.27086 -349.605703) (xy 49.270286 -349.607632) (xy 50.436778 -349.607632) (xy 50.440849 -349.55201)
			(xy 50.452975 -349.497573) (xy 50.472898 -349.445482) (xy 50.500194 -349.396847) (xy 50.53428 -349.352704)
			(xy 50.574429 -349.313995) (xy 50.619787 -349.281544) (xy 50.669387 -349.256043) (xy 50.722171 -349.238036)
			(xy 50.777014 -349.227906) (xy 50.832748 -349.225869) (xy 50.888185 -349.231969) (xy 50.942142 -349.246075)
			(xy 50.993471 -349.267887) (xy 51.041077 -349.296941) (xy 51.083945 -349.332616) (xy 51.121162 -349.374153)
			(xy 51.151935 -349.420666) (xy 51.175607 -349.471163) (xy 51.191675 -349.52457) (xy 51.199795 -349.579746)
			(xy 51.200304 -349.607632) (xy 51.199795 -349.635518) (xy 51.191675 -349.690694) (xy 51.175607 -349.744101)
			(xy 51.151935 -349.794598) (xy 51.121162 -349.841111) (xy 51.083945 -349.882648) (xy 51.041077 -349.918323)
			(xy 50.993471 -349.947377) (xy 50.942142 -349.969189) (xy 50.888185 -349.983295) (xy 50.832748 -349.989395)
			(xy 50.777014 -349.987358) (xy 50.722171 -349.977228) (xy 50.669387 -349.959221) (xy 50.619787 -349.93372)
			(xy 50.574429 -349.901269) (xy 50.53428 -349.86256) (xy 50.500194 -349.818417) (xy 50.472898 -349.769782)
			(xy 50.452975 -349.717691) (xy 50.440849 -349.663254) (xy 50.436778 -349.607632) (xy 49.270286 -349.607632)
			(xy 49.255141 -349.658562) (xy 49.231976 -349.708608) (xy 49.201849 -349.754799) (xy 49.165387 -349.796171)
			(xy 49.144682 -349.814388) (xy 49.136609 -349.821945) (xy 49.127254 -349.841955) (xy 49.126648 -349.852996)
			(xy 49.126648 -349.93072) (xy 49.127245 -349.941766) (xy 49.136588 -349.961788) (xy 49.144682 -349.969328)
			(xy 49.165406 -349.987525) (xy 49.201876 -350.028896) (xy 49.232007 -350.075089) (xy 49.255171 -350.12514)
			(xy 49.270884 -350.178005) (xy 49.278819 -350.232582) (xy 49.279302 -350.260158) (xy 49.278806 -350.28741)
			(xy 49.271054 -350.34136) (xy 49.255703 -350.393658) (xy 49.233065 -350.443238) (xy 49.203601 -350.489092)
			(xy 49.191567 -350.502982) (xy 49.857658 -350.502982) (xy 49.861729 -350.44736) (xy 49.873855 -350.392923)
			(xy 49.893778 -350.340832) (xy 49.921074 -350.292197) (xy 49.95516 -350.248054) (xy 49.995309 -350.209345)
			(xy 50.040667 -350.176894) (xy 50.090267 -350.151393) (xy 50.143051 -350.133386) (xy 50.197894 -350.123256)
			(xy 50.253628 -350.121219) (xy 50.309065 -350.127319) (xy 50.363022 -350.141425) (xy 50.414351 -350.163237)
			(xy 50.461957 -350.192291) (xy 50.504825 -350.227966) (xy 50.542042 -350.269503) (xy 50.572815 -350.316016)
			(xy 50.596487 -350.366513) (xy 50.612555 -350.41992) (xy 50.620675 -350.475096) (xy 50.621184 -350.502982)
			(xy 50.620675 -350.530868) (xy 50.612555 -350.586044) (xy 50.596487 -350.639451) (xy 50.572815 -350.689948)
			(xy 50.542042 -350.736461) (xy 50.504825 -350.777998) (xy 50.461957 -350.813673) (xy 50.414351 -350.842727)
			(xy 50.363022 -350.864539) (xy 50.309065 -350.878645) (xy 50.253628 -350.884745) (xy 50.197894 -350.882708)
			(xy 50.143051 -350.872578) (xy 50.090267 -350.854571) (xy 50.040667 -350.82907) (xy 49.995309 -350.796619)
			(xy 49.95516 -350.75791) (xy 49.921074 -350.713767) (xy 49.893778 -350.665132) (xy 49.873855 -350.613041)
			(xy 49.861729 -350.558604) (xy 49.857658 -350.502982) (xy 49.191567 -350.502982) (xy 49.167911 -350.530285)
			(xy 49.126721 -350.565979) (xy 49.08087 -350.595448) (xy 49.031292 -350.618091) (xy 48.978995 -350.633447)
			(xy 48.925046 -350.641203) (xy 48.897794 -350.641666) (xy 48.869937 -350.641174) (xy 48.814819 -350.633048)
			(xy 48.761467 -350.617) (xy 48.711013 -350.59337) (xy 48.664527 -350.56266) (xy 48.622998 -350.52552)
			(xy 48.587306 -350.482741) (xy 48.558209 -350.435229) (xy 48.536324 -350.383993) (xy 48.528732 -350.357186)
			(xy 48.526446 -350.348296) (xy 48.515778 -350.333056) (xy 48.443896 -350.285304) (xy 48.425862 -350.28124)
			(xy 48.416718 -350.28251) (xy 48.403701 -350.284175) (xy 48.377517 -350.285958) (xy 48.364394 -350.286066)
			(xy 48.350245 -350.285973) (xy 48.322022 -350.283938) (xy 48.308006 -350.282002) (xy 48.2981 -350.280478)
			(xy 48.278288 -350.285304) (xy 48.203866 -350.341184) (xy 48.193706 -350.35871) (xy 48.192436 -350.36887)
			(xy 48.18835 -350.396023) (xy 48.173374 -350.448852) (xy 48.150981 -350.498989) (xy 48.121632 -350.545399)
			(xy 48.085935 -350.587122) (xy 48.044625 -350.623298) (xy 47.998557 -350.653179) (xy 47.948681 -350.676149)
			(xy 47.896028 -350.691732) (xy 47.841685 -350.699607) (xy 47.81423 -350.700086) (xy 47.786977 -350.699617)
			(xy 47.733025 -350.691863) (xy 47.680726 -350.67651) (xy 47.631144 -350.653869) (xy 47.58529 -350.624402)
			(xy 47.544097 -350.588709) (xy 47.508402 -350.547516) (xy 47.478935 -350.501663) (xy 47.456293 -350.452082)
			(xy 47.440938 -350.399783) (xy 47.433184 -350.345831) (xy 47.432722 -350.318578) (xy 45.291836 -350.318578)
			(xy 45.294466 -350.327539) (xy 45.302218 -350.381494) (xy 45.302678 -350.408748) (xy 45.302025 -350.440311)
			(xy 45.291635 -350.502577) (xy 45.271147 -350.562286) (xy 45.256704 -350.590358) (xy 45.251878 -350.599248)
			(xy 45.249846 -350.618806) (xy 45.272706 -350.697292) (xy 45.275955 -350.706712) (xy 45.288365 -350.722273)
			(xy 45.296836 -350.727518) (xy 45.321915 -350.742104) (xy 45.3678 -350.777599) (xy 45.407778 -350.819635)
			(xy 45.440927 -350.867242) (xy 45.466482 -350.919322) (xy 45.483852 -350.974672) (xy 45.492637 -351.032014)
			(xy 45.493178 -351.06102) (xy 45.492692 -351.088271) (xy 45.484936 -351.142219) (xy 45.474247 -351.178622)
			(xy 51.196494 -351.178622) (xy 51.196995 -351.151148) (xy 51.204883 -351.096769) (xy 51.2205 -351.044087)
			(xy 51.243522 -350.994194) (xy 51.27347 -350.948124) (xy 51.291236 -350.927162) (xy 51.29149 -350.926908)
			(xy 51.297078 -350.919823) (xy 51.303324 -350.902905) (xy 51.303682 -350.893888) (xy 51.303682 -350.826324)
			(xy 51.303317 -350.817308) (xy 51.297075 -350.800391) (xy 51.29149 -350.793304) (xy 51.290982 -350.792796)
			(xy 51.273248 -350.77185) (xy 51.243366 -350.725817) (xy 51.2204 -350.675972) (xy 51.204826 -350.623347)
			(xy 51.196965 -350.569031) (xy 51.196494 -350.54159) (xy 51.19698 -350.514339) (xy 51.204736 -350.460391)
			(xy 51.220091 -350.408096) (xy 51.242733 -350.358519) (xy 51.272199 -350.312669) (xy 51.30789 -350.271478)
			(xy 51.349081 -350.235787) (xy 51.394931 -350.206321) (xy 51.444508 -350.183679) (xy 51.496803 -350.168324)
			(xy 51.550751 -350.160568) (xy 51.605253 -350.160568) (xy 51.659201 -350.168324) (xy 51.711496 -350.183679)
			(xy 51.761073 -350.206321) (xy 51.806923 -350.235787) (xy 51.848114 -350.271478) (xy 51.883805 -350.312669)
			(xy 51.913271 -350.358519) (xy 51.935913 -350.408096) (xy 51.951268 -350.460391) (xy 51.959024 -350.514339)
			(xy 51.95951 -350.54159) (xy 51.959015 -350.569064) (xy 51.951125 -350.623443) (xy 51.935507 -350.676126)
			(xy 51.932865 -350.681852) (xy 52.201275 -350.681852) (xy 52.201275 -350.627348) (xy 52.209032 -350.573398)
			(xy 52.224389 -350.521102) (xy 52.247031 -350.471523) (xy 52.276499 -350.425671) (xy 52.312193 -350.38448)
			(xy 52.353386 -350.348788) (xy 52.399239 -350.319322) (xy 52.448818 -350.296682) (xy 52.501116 -350.281329)
			(xy 52.555066 -350.273574) (xy 52.582318 -350.273112) (xy 52.582572 -350.273112) (xy 52.607775 -350.273528)
			(xy 52.657742 -350.280163) (xy 52.706397 -350.293335) (xy 52.752887 -350.312813) (xy 52.77485 -350.325182)
			(xy 52.784756 -350.331024) (xy 52.8066 -350.333056) (xy 52.901342 -350.299528) (xy 52.91709 -350.284034)
			(xy 52.921154 -350.27362) (xy 52.931883 -350.246857) (xy 52.960165 -350.196615) (xy 52.995689 -350.151205)
			(xy 53.037646 -350.111661) (xy 53.085079 -350.078885) (xy 53.136906 -350.053625) (xy 53.191945 -350.036457)
			(xy 53.248942 -350.027771) (xy 53.27777 -350.02724) (xy 53.305024 -350.027683) (xy 53.358978 -350.035437)
			(xy 53.41128 -350.050792) (xy 53.460863 -350.073435) (xy 53.506718 -350.102904) (xy 53.547913 -350.1386)
			(xy 53.583607 -350.179796) (xy 53.613074 -350.225653) (xy 53.635714 -350.275237) (xy 53.648436 -350.318578)
			(xy 55.789322 -350.318578) (xy 55.789834 -350.291005) (xy 55.797776 -350.236434) (xy 55.813491 -350.183575)
			(xy 55.836652 -350.133528) (xy 55.866777 -350.087337) (xy 55.903238 -350.045965) (xy 55.923942 -350.027748)
			(xy 55.932003 -350.02018) (xy 55.941363 -350.000178) (xy 55.941976 -349.98914) (xy 55.941976 -349.911416)
			(xy 55.941407 -349.900367) (xy 55.932043 -349.880345) (xy 55.923942 -349.872808) (xy 55.90324 -349.854587)
			(xy 55.866767 -349.813221) (xy 55.836633 -349.767034) (xy 55.813465 -349.716988) (xy 55.797747 -349.664126)
			(xy 55.789807 -349.609552) (xy 55.789322 -349.581978) (xy 55.789734 -349.554723) (xy 55.797495 -349.500769)
			(xy 55.812856 -349.448468) (xy 55.835503 -349.398886) (xy 55.864976 -349.353031) (xy 55.900675 -349.311838)
			(xy 55.941873 -349.276145) (xy 55.987732 -349.246678) (xy 56.037317 -349.224037) (xy 56.08962 -349.208684)
			(xy 56.143575 -349.200931) (xy 56.17083 -349.20047) (xy 56.171338 -349.20047) (xy 56.20512 -349.201994)
			(xy 56.21528 -349.20301) (xy 56.234584 -349.196914) (xy 56.297576 -349.144082) (xy 56.304849 -349.137342)
			(xy 56.314141 -349.11985) (xy 56.31561 -349.110046) (xy 56.31561 -349.109284) (xy 56.318562 -349.081135)
			(xy 56.331756 -349.026097) (xy 56.352941 -348.973613) (xy 56.381649 -348.924837) (xy 56.417252 -348.88084)
			(xy 56.458966 -348.842588) (xy 56.505876 -348.810921) (xy 56.556951 -348.786535) (xy 56.611069 -348.769966)
			(xy 56.667041 -348.761577) (xy 56.69534 -348.76105) (xy 56.695594 -348.76105) (xy 56.713613 -348.761277)
			(xy 56.749488 -348.764707) (xy 56.767222 -348.767908) (xy 56.776874 -348.769686) (xy 56.795924 -348.76613)
			(xy 56.870854 -348.718124) (xy 56.882284 -348.702376) (xy 56.88457 -348.692978) (xy 56.892025 -348.665951)
			(xy 56.913648 -348.614227) (xy 56.942605 -348.566223) (xy 56.978273 -348.522971) (xy 57.019885 -348.485403)
			(xy 57.066545 -348.454326) (xy 57.117249 -348.43041) (xy 57.170907 -348.414169) (xy 57.226363 -348.405952)
			(xy 57.254394 -348.40545) (xy 57.281643 -348.405983) (xy 57.335587 -348.413738) (xy 57.387878 -348.42909)
			(xy 57.437453 -348.451727) (xy 57.483301 -348.481189) (xy 57.52449 -348.516876) (xy 57.560182 -348.55806)
			(xy 57.58965 -348.603905) (xy 57.612293 -348.653477) (xy 57.627652 -348.705766) (xy 57.635413 -348.759709)
			(xy 57.635902 -348.786958) (xy 57.635407 -348.814531) (xy 57.62746 -348.869103) (xy 57.611741 -348.921962)
			(xy 57.588576 -348.972008) (xy 57.558449 -349.018199) (xy 57.521987 -349.059571) (xy 57.501282 -349.077788)
			(xy 57.493209 -349.085345) (xy 57.483854 -349.105355) (xy 57.483248 -349.116396) (xy 57.483248 -349.19412)
			(xy 57.483845 -349.205166) (xy 57.493188 -349.225188) (xy 57.501282 -349.232728) (xy 57.522006 -349.250925)
			(xy 57.558476 -349.292296) (xy 57.588607 -349.338489) (xy 57.611771 -349.38854) (xy 57.627484 -349.441405)
			(xy 57.635419 -349.495982) (xy 57.635902 -349.523558) (xy 57.635407 -349.551131) (xy 57.62746 -349.605703)
			(xy 57.626886 -349.607632) (xy 58.767978 -349.607632) (xy 58.772049 -349.55201) (xy 58.784175 -349.497573)
			(xy 58.804098 -349.445482) (xy 58.831394 -349.396847) (xy 58.86548 -349.352704) (xy 58.905629 -349.313995)
			(xy 58.950987 -349.281544) (xy 59.000587 -349.256043) (xy 59.053371 -349.238036) (xy 59.108214 -349.227906)
			(xy 59.163948 -349.225869) (xy 59.219385 -349.231969) (xy 59.273342 -349.246075) (xy 59.324671 -349.267887)
			(xy 59.372277 -349.296941) (xy 59.415145 -349.332616) (xy 59.452362 -349.374153) (xy 59.483135 -349.420666)
			(xy 59.506807 -349.471163) (xy 59.522875 -349.52457) (xy 59.530995 -349.579746) (xy 59.531504 -349.607632)
			(xy 59.530995 -349.635518) (xy 59.522875 -349.690694) (xy 59.506807 -349.744101) (xy 59.483135 -349.794598)
			(xy 59.452362 -349.841111) (xy 59.415145 -349.882648) (xy 59.372277 -349.918323) (xy 59.324671 -349.947377)
			(xy 59.273342 -349.969189) (xy 59.219385 -349.983295) (xy 59.163948 -349.989395) (xy 59.108214 -349.987358)
			(xy 59.053371 -349.977228) (xy 59.000587 -349.959221) (xy 58.950987 -349.93372) (xy 58.905629 -349.901269)
			(xy 58.86548 -349.86256) (xy 58.831394 -349.818417) (xy 58.804098 -349.769782) (xy 58.784175 -349.717691)
			(xy 58.772049 -349.663254) (xy 58.767978 -349.607632) (xy 57.626886 -349.607632) (xy 57.611741 -349.658562)
			(xy 57.588576 -349.708608) (xy 57.558449 -349.754799) (xy 57.521987 -349.796171) (xy 57.501282 -349.814388)
			(xy 57.493209 -349.821945) (xy 57.483854 -349.841955) (xy 57.483248 -349.852996) (xy 57.483248 -349.93072)
			(xy 57.483845 -349.941766) (xy 57.493188 -349.961788) (xy 57.501282 -349.969328) (xy 57.522006 -349.987525)
			(xy 57.558476 -350.028896) (xy 57.588607 -350.075089) (xy 57.611771 -350.12514) (xy 57.627484 -350.178005)
			(xy 57.635419 -350.232582) (xy 57.635902 -350.260158) (xy 57.635406 -350.28741) (xy 57.627654 -350.34136)
			(xy 57.612303 -350.393658) (xy 57.589665 -350.443238) (xy 57.560201 -350.489092) (xy 57.548167 -350.502982)
			(xy 58.188858 -350.502982) (xy 58.192929 -350.44736) (xy 58.205055 -350.392923) (xy 58.224978 -350.340832)
			(xy 58.252274 -350.292197) (xy 58.28636 -350.248054) (xy 58.326509 -350.209345) (xy 58.371867 -350.176894)
			(xy 58.421467 -350.151393) (xy 58.474251 -350.133386) (xy 58.529094 -350.123256) (xy 58.584828 -350.121219)
			(xy 58.640265 -350.127319) (xy 58.694222 -350.141425) (xy 58.745551 -350.163237) (xy 58.793157 -350.192291)
			(xy 58.836025 -350.227966) (xy 58.873242 -350.269503) (xy 58.904015 -350.316016) (xy 58.927687 -350.366513)
			(xy 58.943755 -350.41992) (xy 58.951875 -350.475096) (xy 58.952384 -350.502982) (xy 58.951875 -350.530868)
			(xy 58.943755 -350.586044) (xy 58.927687 -350.639451) (xy 58.904015 -350.689948) (xy 58.873242 -350.736461)
			(xy 58.836025 -350.777998) (xy 58.793157 -350.813673) (xy 58.745551 -350.842727) (xy 58.694222 -350.864539)
			(xy 58.640265 -350.878645) (xy 58.584828 -350.884745) (xy 58.529094 -350.882708) (xy 58.474251 -350.872578)
			(xy 58.421467 -350.854571) (xy 58.371867 -350.82907) (xy 58.326509 -350.796619) (xy 58.28636 -350.75791)
			(xy 58.252274 -350.713767) (xy 58.224978 -350.665132) (xy 58.205055 -350.613041) (xy 58.192929 -350.558604)
			(xy 58.188858 -350.502982) (xy 57.548167 -350.502982) (xy 57.524511 -350.530285) (xy 57.483321 -350.565979)
			(xy 57.43747 -350.595448) (xy 57.387892 -350.618091) (xy 57.335595 -350.633447) (xy 57.281646 -350.641203)
			(xy 57.254394 -350.641666) (xy 57.226537 -350.641174) (xy 57.171419 -350.633048) (xy 57.118067 -350.617)
			(xy 57.067613 -350.59337) (xy 57.021127 -350.56266) (xy 56.979598 -350.52552) (xy 56.943906 -350.482741)
			(xy 56.914809 -350.435229) (xy 56.892924 -350.383993) (xy 56.885332 -350.357186) (xy 56.883046 -350.348296)
			(xy 56.872378 -350.333056) (xy 56.800496 -350.285304) (xy 56.782462 -350.28124) (xy 56.773318 -350.28251)
			(xy 56.760301 -350.284175) (xy 56.734117 -350.285958) (xy 56.720994 -350.286066) (xy 56.706845 -350.285973)
			(xy 56.678622 -350.283938) (xy 56.664606 -350.282002) (xy 56.6547 -350.280478) (xy 56.634888 -350.285304)
			(xy 56.560466 -350.341184) (xy 56.550306 -350.35871) (xy 56.549036 -350.36887) (xy 56.54495 -350.396023)
			(xy 56.529974 -350.448852) (xy 56.507581 -350.498989) (xy 56.478232 -350.545399) (xy 56.442535 -350.587122)
			(xy 56.401225 -350.623298) (xy 56.355157 -350.653179) (xy 56.305281 -350.676149) (xy 56.252628 -350.691732)
			(xy 56.198285 -350.699607) (xy 56.17083 -350.700086) (xy 56.143577 -350.699617) (xy 56.089625 -350.691863)
			(xy 56.037326 -350.67651) (xy 55.987744 -350.653869) (xy 55.94189 -350.624402) (xy 55.900697 -350.588709)
			(xy 55.865002 -350.547516) (xy 55.835535 -350.501663) (xy 55.812893 -350.452082) (xy 55.797538 -350.399783)
			(xy 55.789784 -350.345831) (xy 55.789322 -350.318578) (xy 53.648436 -350.318578) (xy 53.651066 -350.327539)
			(xy 53.658818 -350.381494) (xy 53.659278 -350.408748) (xy 53.658625 -350.440311) (xy 53.648235 -350.502577)
			(xy 53.627747 -350.562286) (xy 53.613304 -350.590358) (xy 53.608478 -350.599248) (xy 53.606446 -350.618806)
			(xy 53.629306 -350.697292) (xy 53.632555 -350.706712) (xy 53.644965 -350.722273) (xy 53.653436 -350.727518)
			(xy 53.678515 -350.742104) (xy 53.7244 -350.777599) (xy 53.764378 -350.819635) (xy 53.797527 -350.867242)
			(xy 53.823082 -350.919322) (xy 53.840452 -350.974672) (xy 53.849237 -351.032014) (xy 53.849778 -351.06102)
			(xy 53.849292 -351.088271) (xy 53.841536 -351.142219) (xy 53.826181 -351.194514) (xy 53.803539 -351.244091)
			(xy 53.774073 -351.289941) (xy 53.738382 -351.331132) (xy 53.697191 -351.366823) (xy 53.651341 -351.396289)
			(xy 53.601764 -351.418931) (xy 53.549469 -351.434286) (xy 53.495521 -351.442042) (xy 53.441019 -351.442042)
			(xy 53.387071 -351.434286) (xy 53.334776 -351.418931) (xy 53.285199 -351.396289) (xy 53.239349 -351.366823)
			(xy 53.198158 -351.331132) (xy 53.162467 -351.289941) (xy 53.133001 -351.244091) (xy 53.110359 -351.194514)
			(xy 53.095004 -351.142219) (xy 53.087248 -351.088271) (xy 53.086762 -351.06102) (xy 53.08741 -351.029457)
			(xy 53.097803 -350.967191) (xy 53.118293 -350.907483) (xy 53.132736 -350.87941) (xy 53.137562 -350.87052)
			(xy 53.139594 -350.850962) (xy 53.116734 -350.772476) (xy 53.113519 -350.763041) (xy 53.101086 -350.747487)
			(xy 53.092604 -350.74225) (xy 53.085238 -350.738186) (xy 53.075332 -350.732344) (xy 53.053488 -350.730312)
			(xy 52.958746 -350.76384) (xy 52.942998 -350.779334) (xy 52.938934 -350.789748) (xy 52.928252 -350.81653)
			(xy 52.89996 -350.86677) (xy 52.864427 -350.912178) (xy 52.822463 -350.951719) (xy 52.775024 -350.984492)
			(xy 52.723192 -351.009749) (xy 52.668148 -351.026915) (xy 52.611147 -351.035598) (xy 52.582318 -351.036128)
			(xy 52.555066 -351.035626) (xy 52.501116 -351.027871) (xy 52.448818 -351.012518) (xy 52.399239 -350.989878)
			(xy 52.353386 -350.960412) (xy 52.312193 -350.92472) (xy 52.276499 -350.883529) (xy 52.247031 -350.837677)
			(xy 52.224389 -350.788098) (xy 52.209032 -350.735802) (xy 52.201275 -350.681852) (xy 51.932865 -350.681852)
			(xy 51.912484 -350.726018) (xy 51.882534 -350.772088) (xy 51.864768 -350.79305) (xy 51.864514 -350.793304)
			(xy 51.858921 -350.800386) (xy 51.852678 -350.817306) (xy 51.852322 -350.826324) (xy 51.852322 -350.893888)
			(xy 51.85268 -350.902905) (xy 51.858926 -350.919822) (xy 51.864514 -350.926908) (xy 51.865022 -350.927416)
			(xy 51.882762 -350.948356) (xy 51.912643 -350.994391) (xy 51.935608 -351.044238) (xy 51.951181 -351.096864)
			(xy 51.95904 -351.151181) (xy 51.95951 -351.178622) (xy 51.959024 -351.205873) (xy 51.951268 -351.259821)
			(xy 51.935913 -351.312116) (xy 51.913271 -351.361693) (xy 51.883805 -351.407543) (xy 51.848114 -351.448734)
			(xy 51.806923 -351.484425) (xy 51.761073 -351.513891) (xy 51.711496 -351.536533) (xy 51.659201 -351.551888)
			(xy 51.605253 -351.559644) (xy 51.550751 -351.559644) (xy 51.496803 -351.551888) (xy 51.444508 -351.536533)
			(xy 51.394931 -351.513891) (xy 51.349081 -351.484425) (xy 51.30789 -351.448734) (xy 51.272199 -351.407543)
			(xy 51.242733 -351.361693) (xy 51.220091 -351.312116) (xy 51.204736 -351.259821) (xy 51.19698 -351.205873)
			(xy 51.196494 -351.178622) (xy 45.474247 -351.178622) (xy 45.469581 -351.194514) (xy 45.446939 -351.244091)
			(xy 45.417473 -351.289941) (xy 45.381782 -351.331132) (xy 45.340591 -351.366823) (xy 45.294741 -351.396289)
			(xy 45.245164 -351.418931) (xy 45.192869 -351.434286) (xy 45.138921 -351.442042) (xy 45.084419 -351.442042)
			(xy 45.030471 -351.434286) (xy 44.978176 -351.418931) (xy 44.928599 -351.396289) (xy 44.882749 -351.366823)
			(xy 44.841558 -351.331132) (xy 44.805867 -351.289941) (xy 44.776401 -351.244091) (xy 44.753759 -351.194514)
			(xy 44.738404 -351.142219) (xy 44.730648 -351.088271) (xy 44.730162 -351.06102) (xy 44.73081 -351.029457)
			(xy 44.741203 -350.967191) (xy 44.761693 -350.907483) (xy 44.776136 -350.87941) (xy 44.780962 -350.87052)
			(xy 44.782994 -350.850962) (xy 44.760134 -350.772476) (xy 44.756919 -350.763041) (xy 44.744486 -350.747487)
			(xy 44.736004 -350.74225) (xy 44.728638 -350.738186) (xy 44.718732 -350.732344) (xy 44.696888 -350.730312)
			(xy 44.602146 -350.76384) (xy 44.586398 -350.779334) (xy 44.582334 -350.789748) (xy 44.571652 -350.81653)
			(xy 44.54336 -350.86677) (xy 44.507827 -350.912178) (xy 44.465863 -350.951719) (xy 44.418424 -350.984492)
			(xy 44.366592 -351.009749) (xy 44.311548 -351.026915) (xy 44.254547 -351.035598) (xy 44.225718 -351.036128)
			(xy 44.198466 -351.035626) (xy 44.144516 -351.027871) (xy 44.092218 -351.012518) (xy 44.042639 -350.989878)
			(xy 43.996786 -350.960412) (xy 43.955593 -350.92472) (xy 43.919899 -350.883529) (xy 43.890431 -350.837677)
			(xy 43.867789 -350.788098) (xy 43.852432 -350.735802) (xy 43.844675 -350.681852) (xy 43.576295 -350.681852)
			(xy 43.556038 -350.725817) (xy 43.526157 -350.771851) (xy 43.508422 -350.792796) (xy 43.507914 -350.793304)
			(xy 43.502328 -350.800391) (xy 43.496086 -350.817308) (xy 43.495722 -350.826324) (xy 43.495722 -350.893888)
			(xy 43.49608 -350.902905) (xy 43.502326 -350.919822) (xy 43.507914 -350.926908) (xy 43.508168 -350.927162)
			(xy 43.525934 -350.948125) (xy 43.555882 -350.994194) (xy 43.578903 -351.044087) (xy 43.59452 -351.096769)
			(xy 43.602408 -351.151148) (xy 43.60291 -351.178622) (xy 43.602452 -351.205467) (xy 43.594925 -351.258627)
			(xy 43.580023 -351.310208) (xy 43.558041 -351.359192) (xy 43.529411 -351.404611) (xy 43.494698 -351.445571)
			(xy 43.454589 -351.481262) (xy 43.409874 -351.510981) (xy 43.361435 -351.53414) (xy 43.335956 -351.542604)
			(xy 43.319954 -351.547684) (xy 43.300396 -351.574354) (xy 43.300396 -352.425254) (xy 43.29979 -352.45024)
			(xy 43.290057 -352.499254) (xy 43.270957 -352.545431) (xy 43.243221 -352.586998) (xy 43.225974 -352.605086)
			(xy 42.472864 -353.358196) (xy 42.454769 -353.375453) (xy 42.413223 -353.403266) (xy 42.367053 -353.422446)
			(xy 42.318029 -353.432257) (xy 42.293032 -353.432872) (xy 39.581328 -353.432872) (xy 39.571277 -353.433376)
			(xy 39.552714 -353.441095) (xy 39.54526 -353.447858) (xy 34.634932 -358.357932) (xy 34.616838 -358.375191)
			(xy 34.575293 -358.403005) (xy 34.529122 -358.422185) (xy 34.480097 -358.431992) (xy 34.4551 -358.432608)
			(xy 34.0233 -358.432608) (xy 33.997762 -358.431969) (xy 33.947725 -358.421725) (xy 33.923986 -358.412288)
			(xy 33.914588 -358.408224) (xy 33.904174 -358.408224) (xy 33.894172 -358.408717) (xy 33.875693 -358.416382)
			(xy 33.861554 -358.430535) (xy 33.853907 -358.449021) (xy 33.853374 -358.459024) (xy 33.853374 -358.473502)
			(xy 33.853797 -358.483573) (xy 33.861509 -358.502179) (xy 33.86836 -358.50957) (xy 34.01695 -358.65816)
			(xy 34.024375 -358.664939) (xy 34.042971 -358.672542) (xy 34.053018 -358.672892) (xy 34.886138 -358.672892)
			(xy 34.896205 -358.672462) (xy 34.914799 -358.664737) (xy 34.922206 -358.657906) (xy 39.360856 -354.21951)
			(xy 39.378966 -354.202288) (xy 39.420526 -354.174549) (xy 39.466696 -354.155442) (xy 39.515704 -354.1457)
			(xy 39.540688 -354.145088) (xy 44.931076 -354.145088) (xy 44.94114 -354.144651) (xy 44.959723 -354.136916)
			(xy 44.967144 -354.130102) (xy 46.39818 -352.699066) (xy 46.416291 -352.681848) (xy 46.457854 -352.654117)
			(xy 46.504023 -352.635018) (xy 46.55303 -352.625283) (xy 46.578012 -352.624644) (xy 58.52287 -352.624644)
			(xy 58.532933 -352.624207) (xy 58.551514 -352.616468) (xy 58.558938 -352.609658) (xy 59.083702 -352.084894)
			(xy 59.090547 -352.077495) (xy 59.098279 -352.058897) (xy 59.098688 -352.048826) (xy 59.098688 -350.821498)
			(xy 59.099299 -350.796515) (xy 59.109042 -350.747508) (xy 59.128154 -350.701341) (xy 59.1559 -350.659787)
			(xy 59.17311 -350.641666) (xy 59.453018 -350.361758) (xy 59.46868 -350.346723) (xy 59.504146 -350.321685)
			(xy 59.543346 -350.303028) (xy 59.585144 -350.291293) (xy 59.606688 -350.288606) (xy 59.615342 -350.287295)
			(xy 59.631065 -350.279635) (xy 59.637422 -350.27362) (xy 59.6591 -350.25251) (xy 59.707886 -350.216718)
			(xy 59.7617 -350.189058) (xy 59.8192 -350.17022) (xy 59.878949 -350.160674) (xy 59.909202 -350.160082)
			(xy 59.936453 -350.160568) (xy 59.990401 -350.168325) (xy 60.042697 -350.18368) (xy 60.092274 -350.206321)
			(xy 60.138125 -350.235787) (xy 60.179316 -350.271478) (xy 60.215008 -350.312669) (xy 60.244475 -350.358519)
			(xy 60.267117 -350.408096) (xy 60.282474 -350.460391) (xy 60.290232 -350.514339) (xy 60.29071 -350.54159)
			(xy 60.290239 -350.569031) (xy 60.282378 -350.623347) (xy 60.266804 -350.675972) (xy 60.264095 -350.681852)
			(xy 60.532475 -350.681852) (xy 60.532475 -350.627348) (xy 60.540232 -350.573398) (xy 60.555589 -350.521102)
			(xy 60.578231 -350.471523) (xy 60.607699 -350.425671) (xy 60.643393 -350.38448) (xy 60.684586 -350.348788)
			(xy 60.730439 -350.319322) (xy 60.780018 -350.296682) (xy 60.832316 -350.281329) (xy 60.886266 -350.273574)
			(xy 60.913518 -350.273112) (xy 60.913772 -350.273112) (xy 60.938975 -350.273528) (xy 60.988942 -350.280163)
			(xy 61.037597 -350.293335) (xy 61.084087 -350.312813) (xy 61.10605 -350.325182) (xy 61.115956 -350.331024)
			(xy 61.1378 -350.333056) (xy 61.232542 -350.299528) (xy 61.24829 -350.284034) (xy 61.252354 -350.27362)
			(xy 61.263083 -350.246857) (xy 61.291365 -350.196615) (xy 61.326889 -350.151205) (xy 61.368846 -350.111661)
			(xy 61.416279 -350.078885) (xy 61.468106 -350.053625) (xy 61.523145 -350.036457) (xy 61.580142 -350.027771)
			(xy 61.60897 -350.02724) (xy 61.636224 -350.027683) (xy 61.690178 -350.035437) (xy 61.74248 -350.050792)
			(xy 61.792063 -350.073435) (xy 61.837918 -350.102904) (xy 61.879113 -350.1386) (xy 61.914807 -350.179796)
			(xy 61.944274 -350.225653) (xy 61.966914 -350.275237) (xy 61.979636 -350.318578) (xy 64.120522 -350.318578)
			(xy 64.121034 -350.291005) (xy 64.128976 -350.236434) (xy 64.144691 -350.183575) (xy 64.167852 -350.133528)
			(xy 64.197977 -350.087337) (xy 64.234438 -350.045965) (xy 64.255142 -350.027748) (xy 64.263203 -350.02018)
			(xy 64.272563 -350.000178) (xy 64.273176 -349.98914) (xy 64.273176 -349.911416) (xy 64.272607 -349.900367)
			(xy 64.263243 -349.880345) (xy 64.255142 -349.872808) (xy 64.23444 -349.854587) (xy 64.197967 -349.813221)
			(xy 64.167833 -349.767034) (xy 64.144665 -349.716988) (xy 64.128947 -349.664126) (xy 64.121007 -349.609552)
			(xy 64.120522 -349.581978) (xy 64.120934 -349.554723) (xy 64.128695 -349.500769) (xy 64.144056 -349.448468)
			(xy 64.166703 -349.398886) (xy 64.196176 -349.353031) (xy 64.231875 -349.311838) (xy 64.273073 -349.276145)
			(xy 64.318932 -349.246678) (xy 64.368517 -349.224037) (xy 64.42082 -349.208684) (xy 64.474775 -349.200931)
			(xy 64.50203 -349.20047) (xy 64.502538 -349.20047) (xy 64.53632 -349.201994) (xy 64.54648 -349.20301)
			(xy 64.565784 -349.196914) (xy 64.628776 -349.144082) (xy 64.636049 -349.137342) (xy 64.645341 -349.11985)
			(xy 64.64681 -349.110046) (xy 64.64681 -349.109284) (xy 64.649762 -349.081135) (xy 64.662956 -349.026097)
			(xy 64.684141 -348.973613) (xy 64.712849 -348.924837) (xy 64.748452 -348.88084) (xy 64.790166 -348.842588)
			(xy 64.837076 -348.810921) (xy 64.888151 -348.786535) (xy 64.942269 -348.769966) (xy 64.998241 -348.761577)
			(xy 65.02654 -348.76105) (xy 65.026794 -348.76105) (xy 65.044813 -348.761277) (xy 65.080688 -348.764707)
			(xy 65.098422 -348.767908) (xy 65.108074 -348.769686) (xy 65.127124 -348.76613) (xy 65.202054 -348.718124)
			(xy 65.213484 -348.702376) (xy 65.21577 -348.692978) (xy 65.223225 -348.665951) (xy 65.244848 -348.614227)
			(xy 65.273805 -348.566223) (xy 65.309473 -348.522971) (xy 65.351085 -348.485403) (xy 65.397745 -348.454326)
			(xy 65.448449 -348.43041) (xy 65.502107 -348.414169) (xy 65.557563 -348.405952) (xy 65.585594 -348.40545)
			(xy 65.612843 -348.405983) (xy 65.666787 -348.413738) (xy 65.719078 -348.42909) (xy 65.768653 -348.451727)
			(xy 65.814501 -348.481189) (xy 65.85569 -348.516876) (xy 65.891382 -348.55806) (xy 65.92085 -348.603905)
			(xy 65.943493 -348.653477) (xy 65.958852 -348.705766) (xy 65.966613 -348.759709) (xy 65.967102 -348.786958)
			(xy 65.966607 -348.814531) (xy 65.95866 -348.869103) (xy 65.942941 -348.921962) (xy 65.919776 -348.972008)
			(xy 65.889649 -349.018199) (xy 65.853187 -349.059571) (xy 65.832482 -349.077788) (xy 65.824409 -349.085345)
			(xy 65.815054 -349.105355) (xy 65.814448 -349.116396) (xy 65.814448 -349.19412) (xy 65.815045 -349.205166)
			(xy 65.824388 -349.225188) (xy 65.832482 -349.232728) (xy 65.853206 -349.250925) (xy 65.889676 -349.292296)
			(xy 65.919807 -349.338489) (xy 65.942971 -349.38854) (xy 65.958684 -349.441405) (xy 65.966619 -349.495982)
			(xy 65.967102 -349.523558) (xy 65.966607 -349.551131) (xy 65.95866 -349.605703) (xy 65.942941 -349.658562)
			(xy 65.919776 -349.708608) (xy 65.889649 -349.754799) (xy 65.853187 -349.796171) (xy 65.832482 -349.814388)
			(xy 65.824409 -349.821945) (xy 65.815054 -349.841955) (xy 65.814448 -349.852996) (xy 65.814448 -349.93072)
			(xy 65.815045 -349.941766) (xy 65.824388 -349.961788) (xy 65.832482 -349.969328) (xy 65.853206 -349.987525)
			(xy 65.889676 -350.028896) (xy 65.919807 -350.075089) (xy 65.942971 -350.12514) (xy 65.958684 -350.178005)
			(xy 65.966619 -350.232582) (xy 65.967102 -350.260158) (xy 65.966606 -350.28741) (xy 65.958854 -350.34136)
			(xy 65.943503 -350.393658) (xy 65.920865 -350.443238) (xy 65.891401 -350.489092) (xy 65.855711 -350.530285)
			(xy 65.814521 -350.565979) (xy 65.76867 -350.595448) (xy 65.719092 -350.618091) (xy 65.666795 -350.633447)
			(xy 65.612846 -350.641203) (xy 65.585594 -350.641666) (xy 65.557737 -350.641174) (xy 65.502619 -350.633048)
			(xy 65.449267 -350.617) (xy 65.398813 -350.59337) (xy 65.352327 -350.56266) (xy 65.310798 -350.52552)
			(xy 65.275106 -350.482741) (xy 65.246009 -350.435229) (xy 65.224124 -350.383993) (xy 65.216532 -350.357186)
			(xy 65.214246 -350.348296) (xy 65.203578 -350.333056) (xy 65.131696 -350.285304) (xy 65.113662 -350.28124)
			(xy 65.104518 -350.28251) (xy 65.091501 -350.284175) (xy 65.065317 -350.285958) (xy 65.052194 -350.286066)
			(xy 65.038045 -350.285973) (xy 65.009822 -350.283938) (xy 64.995806 -350.282002) (xy 64.9859 -350.280478)
			(xy 64.966088 -350.285304) (xy 64.891666 -350.341184) (xy 64.881506 -350.35871) (xy 64.880236 -350.36887)
			(xy 64.87615 -350.396023) (xy 64.861174 -350.448852) (xy 64.838781 -350.498989) (xy 64.809432 -350.545399)
			(xy 64.773735 -350.587122) (xy 64.732425 -350.623298) (xy 64.686357 -350.653179) (xy 64.636481 -350.676149)
			(xy 64.583828 -350.691732) (xy 64.529485 -350.699607) (xy 64.50203 -350.700086) (xy 64.474777 -350.699617)
			(xy 64.420825 -350.691863) (xy 64.368526 -350.67651) (xy 64.318944 -350.653869) (xy 64.27309 -350.624402)
			(xy 64.231897 -350.588709) (xy 64.196202 -350.547516) (xy 64.166735 -350.501663) (xy 64.144093 -350.452082)
			(xy 64.128738 -350.399783) (xy 64.120984 -350.345831) (xy 64.120522 -350.318578) (xy 61.979636 -350.318578)
			(xy 61.982266 -350.327539) (xy 61.990018 -350.381494) (xy 61.990478 -350.408748) (xy 61.989825 -350.440311)
			(xy 61.979435 -350.502577) (xy 61.958947 -350.562286) (xy 61.944504 -350.590358) (xy 61.939678 -350.599248)
			(xy 61.937646 -350.618806) (xy 61.960506 -350.697292) (xy 61.963755 -350.706712) (xy 61.976165 -350.722273)
			(xy 61.984636 -350.727518) (xy 62.009715 -350.742104) (xy 62.0556 -350.777599) (xy 62.095578 -350.819635)
			(xy 62.128727 -350.867242) (xy 62.154282 -350.919322) (xy 62.171652 -350.974672) (xy 62.180437 -351.032014)
			(xy 62.180978 -351.06102) (xy 62.180492 -351.088271) (xy 62.172736 -351.142219) (xy 62.157381 -351.194514)
			(xy 62.134739 -351.244091) (xy 62.105273 -351.289941) (xy 62.069582 -351.331132) (xy 62.028391 -351.366823)
			(xy 61.982541 -351.396289) (xy 61.932964 -351.418931) (xy 61.880669 -351.434286) (xy 61.826721 -351.442042)
			(xy 61.772219 -351.442042) (xy 61.718271 -351.434286) (xy 61.665976 -351.418931) (xy 61.616399 -351.396289)
			(xy 61.570549 -351.366823) (xy 61.529358 -351.331132) (xy 61.493667 -351.289941) (xy 61.464201 -351.244091)
			(xy 61.441559 -351.194514) (xy 61.426204 -351.142219) (xy 61.418448 -351.088271) (xy 61.417962 -351.06102)
			(xy 61.41861 -351.029457) (xy 61.429003 -350.967191) (xy 61.449493 -350.907483) (xy 61.463936 -350.87941)
			(xy 61.468762 -350.87052) (xy 61.470794 -350.850962) (xy 61.447934 -350.772476) (xy 61.444719 -350.763041)
			(xy 61.432286 -350.747487) (xy 61.423804 -350.74225) (xy 61.416438 -350.738186) (xy 61.406532 -350.732344)
			(xy 61.384688 -350.730312) (xy 61.289946 -350.76384) (xy 61.274198 -350.779334) (xy 61.270134 -350.789748)
			(xy 61.259452 -350.81653) (xy 61.23116 -350.86677) (xy 61.195627 -350.912178) (xy 61.153663 -350.951719)
			(xy 61.106224 -350.984492) (xy 61.054392 -351.009749) (xy 60.999348 -351.026915) (xy 60.942347 -351.035598)
			(xy 60.913518 -351.036128) (xy 60.886266 -351.035626) (xy 60.832316 -351.027871) (xy 60.780018 -351.012518)
			(xy 60.730439 -350.989878) (xy 60.684586 -350.960412) (xy 60.643393 -350.92472) (xy 60.607699 -350.883529)
			(xy 60.578231 -350.837677) (xy 60.555589 -350.788098) (xy 60.540232 -350.735802) (xy 60.532475 -350.681852)
			(xy 60.264095 -350.681852) (xy 60.243838 -350.725817) (xy 60.213957 -350.771851) (xy 60.196222 -350.792796)
			(xy 60.195714 -350.793304) (xy 60.190128 -350.800391) (xy 60.183886 -350.817308) (xy 60.183522 -350.826324)
			(xy 60.183522 -350.893888) (xy 60.18388 -350.902905) (xy 60.190126 -350.919822) (xy 60.195714 -350.926908)
			(xy 60.195968 -350.927162) (xy 60.213734 -350.948125) (xy 60.243682 -350.994194) (xy 60.266703 -351.044087)
			(xy 60.28232 -351.096769) (xy 60.290208 -351.151148) (xy 60.29071 -351.178622) (xy 60.290252 -351.205467)
			(xy 60.282725 -351.258627) (xy 60.267823 -351.310208) (xy 60.245841 -351.359192) (xy 60.217211 -351.404611)
			(xy 60.182498 -351.445571) (xy 60.142389 -351.481262) (xy 60.097674 -351.510981) (xy 60.049235 -351.53414)
			(xy 60.023756 -351.542604) (xy 60.007754 -351.547684) (xy 59.988196 -351.574354) (xy 59.988196 -352.333306)
			(xy 59.987585 -352.35829) (xy 59.977844 -352.407299) (xy 59.958736 -352.453469) (xy 59.930996 -352.495028)
			(xy 59.913774 -352.513138) (xy 58.987182 -353.43973) (xy 58.969072 -353.456953) (xy 58.927512 -353.484694)
			(xy 58.881343 -353.503805) (xy 58.832334 -353.513552) (xy 58.80735 -353.514152) (xy 46.862492 -353.514152)
			(xy 46.852424 -353.514578) (xy 46.833826 -353.5223) (xy 46.826424 -353.529138) (xy 45.395388 -354.960174)
			(xy 45.377277 -354.977394) (xy 45.335716 -355.005132) (xy 45.289547 -355.024241) (xy 45.240539 -355.033987)
			(xy 45.215556 -355.034596) (xy 39.833804 -355.034596) (xy 39.823733 -355.035018) (xy 39.805128 -355.042731)
			(xy 39.797736 -355.049582) (xy 36.106608 -358.740964) (xy 36.100499 -358.747604) (xy 36.092976 -358.76399)
			(xy 36.091578 -358.781966) (xy 36.093654 -358.790748) (xy 36.121848 -358.889554) (xy 36.141406 -358.90835)
			(xy 36.155122 -358.911652) (xy 36.179315 -358.917719) (xy 36.225977 -358.935334) (xy 36.269941 -358.958892)
			(xy 36.310452 -358.987987) (xy 36.346818 -359.022123) (xy 36.362894 -359.041192) (xy 36.370514 -359.050336)
			(xy 36.391596 -359.059988) (xy 36.495482 -359.057194) (xy 36.516056 -359.046526) (xy 36.523168 -359.037128)
			(xy 36.541305 -359.013584) (xy 36.583643 -358.971876) (xy 36.63193 -358.937231) (xy 36.685001 -358.910483)
			(xy 36.741574 -358.892278) (xy 36.800285 -358.883057) (xy 36.83 -358.882442) (xy 36.857252 -358.882905)
			(xy 36.9112 -358.890663) (xy 36.963495 -358.906019) (xy 37.013072 -358.928662) (xy 37.058921 -358.958131)
			(xy 37.10011 -358.993826) (xy 37.135799 -359.035019) (xy 37.165262 -359.080872) (xy 37.187898 -359.130452)
			(xy 37.203248 -359.182749) (xy 37.210998 -359.236698) (xy 37.211508 -359.26395) (xy 37.211 -359.282746)
			(xy 37.210238 -359.298494) (xy 37.226748 -359.325164) (xy 37.32784 -359.370122) (xy 37.337377 -359.37378)
			(xy 37.357785 -359.37403) (xy 37.376695 -359.366352) (xy 37.384228 -359.359454) (xy 39.083234 -357.660448)
			(xy 39.09008 -357.65305) (xy 39.097805 -357.634451) (xy 39.09822 -357.62438) (xy 39.09822 -357.316024)
			(xy 39.098859 -357.291029) (xy 39.108662 -357.242007) (xy 39.127838 -357.195839) (xy 39.15565 -357.154297)
			(xy 39.172896 -357.136192) (xy 40.665654 -355.643434) (xy 40.683766 -355.626216) (xy 40.725328 -355.598484)
			(xy 40.771497 -355.579383) (xy 40.820504 -355.569644) (xy 40.845486 -355.569012) (xy 45.555154 -355.569012)
			(xy 45.56522 -355.56858) (xy 45.583812 -355.560853) (xy 45.591222 -355.554026) (xy 47.182024 -353.963224)
			(xy 47.200121 -353.945972) (xy 47.241669 -353.918171) (xy 47.287839 -353.899006) (xy 47.336861 -353.889211)
			(xy 47.361856 -353.888548) (xy 63.0301 -353.888548) (xy 63.040169 -353.888123) (xy 63.058769 -353.880403)
			(xy 63.066168 -353.873562) (xy 66.74485 -350.195134) (xy 66.751692 -350.187734) (xy 66.75941 -350.169136)
			(xy 66.759836 -350.159066) (xy 66.759836 -348.055438) (xy 66.7594 -348.045374) (xy 66.751662 -348.026792)
			(xy 66.74485 -348.01937) (xy 65.79235 -347.06687) (xy 65.775129 -347.048759) (xy 65.747392 -347.007198)
			(xy 65.728285 -346.961029) (xy 65.718541 -346.912021) (xy 65.717928 -346.887038) (xy 65.717928 -342.333326)
			(xy 65.718536 -342.308341) (xy 65.728273 -342.25933) (xy 65.747377 -342.213157) (xy 65.775117 -342.171594)
			(xy 65.79235 -342.153494) (xy 67.657726 -340.288118) (xy 67.664568 -340.280719) (xy 67.672284 -340.262119)
			(xy 67.672712 -340.25205) (xy 67.672712 -339.229446) (xy 67.673319 -339.20446) (xy 67.683051 -339.155446)
			(xy 67.702152 -339.10927) (xy 67.729889 -339.067703) (xy 67.747134 -339.049614) (xy 68.065904 -338.73059)
			(xy 68.070145 -338.726112) (xy 68.076563 -338.715583) (xy 68.078604 -338.709762) (xy 68.078604 -338.709508)
			(xy 68.086924 -338.683768) (xy 68.109816 -338.634755) (xy 68.139401 -338.589468) (xy 68.175086 -338.548814)
			(xy 68.216157 -338.513608) (xy 68.261789 -338.484557) (xy 68.311067 -338.462243) (xy 68.363002 -338.447114)
			(xy 68.416555 -338.439473) (xy 68.443602 -338.438998) (xy 68.470855 -338.439461) (xy 68.524805 -338.447219)
			(xy 68.577102 -338.462575) (xy 68.626682 -338.485218) (xy 68.672534 -338.514686) (xy 68.713726 -338.55038)
			(xy 68.749419 -338.591572) (xy 68.778886 -338.637425) (xy 68.801528 -338.687005) (xy 68.816883 -338.739303)
			(xy 68.824639 -338.793253) (xy 68.82511 -338.820506) (xy 68.824638 -338.847947) (xy 68.816775 -338.902261)
			(xy 68.801199 -338.954885) (xy 68.798496 -338.960751) (xy 69.066891 -338.960751) (xy 69.066891 -338.906249)
			(xy 69.074648 -338.852301) (xy 69.090004 -338.800007) (xy 69.112645 -338.75043) (xy 69.142112 -338.704581)
			(xy 69.177804 -338.663392) (xy 69.218995 -338.627701) (xy 69.264846 -338.598237) (xy 69.314424 -338.575597)
			(xy 69.366719 -338.560244) (xy 69.420667 -338.55249) (xy 69.447918 -338.552028) (xy 69.448172 -338.552028)
			(xy 69.473375 -338.552441) (xy 69.523343 -338.559077) (xy 69.571997 -338.57225) (xy 69.618487 -338.591728)
			(xy 69.64045 -338.604098) (xy 69.650356 -338.60994) (xy 69.6722 -338.611972) (xy 69.766942 -338.578444)
			(xy 69.78269 -338.56295) (xy 69.786754 -338.552536) (xy 69.797438 -338.525755) (xy 69.82573 -338.475516)
			(xy 69.861264 -338.430108) (xy 69.903228 -338.390568) (xy 69.950666 -338.357795) (xy 70.002498 -338.332538)
			(xy 70.057541 -338.315371) (xy 70.114541 -338.306687) (xy 70.14337 -338.306156) (xy 70.170619 -338.306706)
			(xy 70.224562 -338.314458) (xy 70.276854 -338.329807) (xy 70.326428 -338.352442) (xy 70.372277 -338.381902)
			(xy 70.413467 -338.417587) (xy 70.449159 -338.45877) (xy 70.478626 -338.504614) (xy 70.50127 -338.554184)
			(xy 70.513991 -338.597494) (xy 72.654922 -338.597494) (xy 72.655376 -338.569919) (xy 72.66333 -338.515345)
			(xy 72.679057 -338.462485) (xy 72.702229 -338.412439) (xy 72.732364 -338.366249) (xy 72.768834 -338.324879)
			(xy 72.789542 -338.306664) (xy 72.79764 -338.29913) (xy 72.80698 -338.279102) (xy 72.807576 -338.268056)
			(xy 72.807576 -338.190332) (xy 72.806997 -338.179284) (xy 72.79764 -338.159262) (xy 72.789542 -338.151724)
			(xy 72.768848 -338.133494) (xy 72.732374 -338.092131) (xy 72.702239 -338.045945) (xy 72.67907 -337.9959)
			(xy 72.66335 -337.943041) (xy 72.655408 -337.888468) (xy 72.654922 -337.860894) (xy 72.65535 -337.83364)
			(xy 72.663108 -337.779686) (xy 72.678467 -337.727386) (xy 72.701112 -337.677803) (xy 72.730584 -337.631949)
			(xy 72.766281 -337.590755) (xy 72.807478 -337.555062) (xy 72.853335 -337.525595) (xy 72.902919 -337.502954)
			(xy 72.955221 -337.487601) (xy 73.009176 -337.479847) (xy 73.03643 -337.479386) (xy 73.036938 -337.479386)
			(xy 73.07072 -337.48091) (xy 73.08088 -337.481926) (xy 73.100184 -337.47583) (xy 73.163176 -337.422998)
			(xy 73.170481 -337.416288) (xy 73.179755 -337.398774) (xy 73.18121 -337.388962) (xy 73.18121 -337.3882)
			(xy 73.184175 -337.360053) (xy 73.197368 -337.305015) (xy 73.21855 -337.252531) (xy 73.247257 -337.203755)
			(xy 73.282858 -337.159757) (xy 73.32457 -337.121505) (xy 73.371479 -337.089837) (xy 73.422553 -337.065451)
			(xy 73.47667 -337.048882) (xy 73.532642 -337.040493) (xy 73.56094 -337.039966) (xy 73.561194 -337.039966)
			(xy 73.579213 -337.040192) (xy 73.615088 -337.043623) (xy 73.632822 -337.046824) (xy 73.642474 -337.048602)
			(xy 73.661524 -337.045046) (xy 73.736454 -336.99704) (xy 73.747884 -336.981292) (xy 73.75017 -336.971894)
			(xy 73.757635 -336.94487) (xy 73.779256 -336.893146) (xy 73.808211 -336.845141) (xy 73.843878 -336.801889)
			(xy 73.885489 -336.76432) (xy 73.932148 -336.733243) (xy 73.982851 -336.709327) (xy 74.036508 -336.693085)
			(xy 74.091964 -336.684868) (xy 74.119994 -336.684366) (xy 74.147244 -336.684883) (xy 74.201189 -336.692638)
			(xy 74.253482 -336.707991) (xy 74.303057 -336.73063) (xy 74.348906 -336.760093) (xy 74.390096 -336.795781)
			(xy 74.425788 -336.836968) (xy 74.455255 -336.882815) (xy 74.477897 -336.932388) (xy 74.493255 -336.98468)
			(xy 74.501014 -337.038624) (xy 74.501502 -337.065874) (xy 74.501018 -337.093448) (xy 74.493069 -337.14802)
			(xy 74.477347 -337.200879) (xy 74.454181 -337.250925) (xy 74.424052 -337.297115) (xy 74.387588 -337.338488)
			(xy 74.366882 -337.356704) (xy 74.358802 -337.364255) (xy 74.349451 -337.38427) (xy 74.348848 -337.395312)
			(xy 74.348848 -337.473036) (xy 74.349437 -337.484083) (xy 74.358786 -337.504105) (xy 74.366882 -337.511644)
			(xy 74.387566 -337.529885) (xy 74.424039 -337.571247) (xy 74.454175 -337.617431) (xy 74.477346 -337.667473)
			(xy 74.493068 -337.72033) (xy 74.501013 -337.774901) (xy 74.501502 -337.802474) (xy 74.501018 -337.830048)
			(xy 74.493824 -337.879436) (xy 75.657962 -337.879436) (xy 75.662033 -337.823814) (xy 75.674159 -337.769377)
			(xy 75.694082 -337.717286) (xy 75.721378 -337.668651) (xy 75.755464 -337.624508) (xy 75.795613 -337.585799)
			(xy 75.840971 -337.553348) (xy 75.890571 -337.527847) (xy 75.943355 -337.50984) (xy 75.998198 -337.49971)
			(xy 76.053932 -337.497673) (xy 76.109369 -337.503773) (xy 76.163326 -337.517879) (xy 76.214655 -337.539691)
			(xy 76.262261 -337.568745) (xy 76.305129 -337.60442) (xy 76.342346 -337.645957) (xy 76.373119 -337.69247)
			(xy 76.396791 -337.742967) (xy 76.412859 -337.796374) (xy 76.420979 -337.85155) (xy 76.421488 -337.879436)
			(xy 76.420979 -337.907322) (xy 76.412859 -337.962498) (xy 76.396791 -338.015905) (xy 76.373119 -338.066402)
			(xy 76.342346 -338.112915) (xy 76.305129 -338.154452) (xy 76.262261 -338.190127) (xy 76.214655 -338.219181)
			(xy 76.163326 -338.240993) (xy 76.109369 -338.255099) (xy 76.053932 -338.261199) (xy 75.998198 -338.259162)
			(xy 75.943355 -338.249032) (xy 75.890571 -338.231025) (xy 75.840971 -338.205524) (xy 75.795613 -338.173073)
			(xy 75.755464 -338.134364) (xy 75.721378 -338.090221) (xy 75.694082 -338.041586) (xy 75.674159 -337.989495)
			(xy 75.662033 -337.935058) (xy 75.657962 -337.879436) (xy 74.493824 -337.879436) (xy 74.493069 -337.88462)
			(xy 74.477347 -337.937479) (xy 74.454181 -337.987525) (xy 74.424052 -338.033715) (xy 74.387588 -338.075088)
			(xy 74.366882 -338.093304) (xy 74.358802 -338.100855) (xy 74.349451 -338.12087) (xy 74.348848 -338.131912)
			(xy 74.348848 -338.209636) (xy 74.349437 -338.220683) (xy 74.358786 -338.240705) (xy 74.366882 -338.248244)
			(xy 74.387566 -338.266485) (xy 74.424039 -338.307847) (xy 74.454175 -338.354031) (xy 74.477346 -338.404073)
			(xy 74.493068 -338.45693) (xy 74.501013 -338.511501) (xy 74.501502 -338.539074) (xy 74.50102 -338.566326)
			(xy 74.493267 -338.620277) (xy 74.477914 -338.672575) (xy 74.455274 -338.722155) (xy 74.425808 -338.768009)
			(xy 74.419936 -338.774786) (xy 75.078842 -338.774786) (xy 75.082913 -338.719164) (xy 75.095039 -338.664727)
			(xy 75.114962 -338.612636) (xy 75.142258 -338.564001) (xy 75.176344 -338.519858) (xy 75.216493 -338.481149)
			(xy 75.261851 -338.448698) (xy 75.311451 -338.423197) (xy 75.364235 -338.40519) (xy 75.419078 -338.39506)
			(xy 75.474812 -338.393023) (xy 75.530249 -338.399123) (xy 75.584206 -338.413229) (xy 75.635535 -338.435041)
			(xy 75.683141 -338.464095) (xy 75.726009 -338.49977) (xy 75.763226 -338.541307) (xy 75.793999 -338.58782)
			(xy 75.817671 -338.638317) (xy 75.833739 -338.691724) (xy 75.841859 -338.7469) (xy 75.842368 -338.774786)
			(xy 75.841859 -338.802672) (xy 75.833739 -338.857848) (xy 75.817671 -338.911255) (xy 75.793999 -338.961752)
			(xy 75.763226 -339.008265) (xy 75.726009 -339.049802) (xy 75.683141 -339.085477) (xy 75.635535 -339.114531)
			(xy 75.584206 -339.136343) (xy 75.530249 -339.150449) (xy 75.474812 -339.156549) (xy 75.419078 -339.154512)
			(xy 75.364235 -339.144382) (xy 75.311451 -339.126375) (xy 75.261851 -339.100874) (xy 75.216493 -339.068423)
			(xy 75.176344 -339.029714) (xy 75.142258 -338.985571) (xy 75.114962 -338.936936) (xy 75.095039 -338.884845)
			(xy 75.082913 -338.830408) (xy 75.078842 -338.774786) (xy 74.419936 -338.774786) (xy 74.390116 -338.809202)
			(xy 74.348925 -338.844896) (xy 74.303073 -338.874364) (xy 74.253494 -338.897007) (xy 74.201197 -338.912363)
			(xy 74.147246 -338.920119) (xy 74.119994 -338.920582) (xy 74.092138 -338.920078) (xy 74.037021 -338.911953)
			(xy 73.983669 -338.895906) (xy 73.933216 -338.872277) (xy 73.886731 -338.841568) (xy 73.845201 -338.80443)
			(xy 73.809509 -338.761652) (xy 73.780411 -338.714142) (xy 73.758525 -338.662908) (xy 73.750932 -338.636102)
			(xy 73.748646 -338.627212) (xy 73.737978 -338.611972) (xy 73.666096 -338.56422) (xy 73.648062 -338.560156)
			(xy 73.638918 -338.561426) (xy 73.625901 -338.563091) (xy 73.599717 -338.564874) (xy 73.586594 -338.564982)
			(xy 73.572445 -338.564889) (xy 73.544222 -338.562854) (xy 73.530206 -338.560918) (xy 73.5203 -338.559394)
			(xy 73.500488 -338.56422) (xy 73.426066 -338.6201) (xy 73.415906 -338.637626) (xy 73.414636 -338.647786)
			(xy 73.410562 -338.674941) (xy 73.395584 -338.727771) (xy 73.373189 -338.777907) (xy 73.343839 -338.824317)
			(xy 73.30814 -338.86604) (xy 73.266829 -338.902215) (xy 73.22076 -338.932096) (xy 73.170883 -338.955065)
			(xy 73.118229 -338.970648) (xy 73.063886 -338.978523) (xy 73.03643 -338.979002) (xy 73.009178 -338.978517)
			(xy 72.955227 -338.970764) (xy 72.902929 -338.955411) (xy 72.853349 -338.932772) (xy 72.807495 -338.903306)
			(xy 72.766302 -338.867615) (xy 72.730608 -338.826424) (xy 72.70114 -338.780572) (xy 72.678497 -338.730993)
			(xy 72.663141 -338.678696) (xy 72.655385 -338.624746) (xy 72.654922 -338.597494) (xy 70.513991 -338.597494)
			(xy 70.516628 -338.606473) (xy 70.524389 -338.660415) (xy 70.524878 -338.687664) (xy 70.524231 -338.719227)
			(xy 70.513839 -338.781493) (xy 70.493348 -338.841202) (xy 70.478904 -338.869274) (xy 70.474078 -338.878164)
			(xy 70.472046 -338.897722) (xy 70.494906 -338.976208) (xy 70.498149 -338.98563) (xy 70.510563 -339.00119)
			(xy 70.519036 -339.006434) (xy 70.544122 -339.021008) (xy 70.590007 -339.056505) (xy 70.629985 -339.098543)
			(xy 70.663133 -339.146153) (xy 70.688687 -339.198234) (xy 70.706055 -339.253586) (xy 70.714838 -339.31093)
			(xy 70.715378 -339.339936) (xy 70.714892 -339.367187) (xy 70.707136 -339.421135) (xy 70.698535 -339.450426)
			(xy 76.417678 -339.450426) (xy 76.418185 -339.422952) (xy 76.426073 -339.368574) (xy 76.441688 -339.315892)
			(xy 76.464708 -339.265999) (xy 76.494655 -339.219929) (xy 76.51242 -339.198966) (xy 76.512674 -339.198712)
			(xy 76.51827 -339.191632) (xy 76.524509 -339.17471) (xy 76.524866 -339.165692) (xy 76.524866 -339.098128)
			(xy 76.524503 -339.089112) (xy 76.51826 -339.072194) (xy 76.512674 -339.065108) (xy 76.512166 -339.0646)
			(xy 76.494447 -339.043642) (xy 76.46456 -338.997613) (xy 76.44159 -338.947771) (xy 76.426012 -338.895148)
			(xy 76.418149 -338.840834) (xy 76.417678 -338.813394) (xy 76.418164 -338.786143) (xy 76.42592 -338.732195)
			(xy 76.441275 -338.6799) (xy 76.463917 -338.630323) (xy 76.493383 -338.584473) (xy 76.529074 -338.543282)
			(xy 76.570265 -338.507591) (xy 76.616115 -338.478125) (xy 76.665692 -338.455483) (xy 76.717987 -338.440128)
			(xy 76.771935 -338.432372) (xy 76.826437 -338.432372) (xy 76.880385 -338.440128) (xy 76.93268 -338.455483)
			(xy 76.982257 -338.478125) (xy 77.028107 -338.507591) (xy 77.069298 -338.543282) (xy 77.104989 -338.584473)
			(xy 77.134455 -338.630323) (xy 77.157097 -338.6799) (xy 77.172452 -338.732195) (xy 77.180208 -338.786143)
			(xy 77.180694 -338.813394) (xy 77.180206 -338.840869) (xy 77.172314 -338.895248) (xy 77.156695 -338.947931)
			(xy 77.154055 -338.953651) (xy 77.422479 -338.953651) (xy 77.422479 -338.899149) (xy 77.430236 -338.845201)
			(xy 77.445591 -338.792906) (xy 77.468232 -338.743329) (xy 77.497699 -338.697479) (xy 77.53339 -338.656289)
			(xy 77.57458 -338.620597) (xy 77.620431 -338.591131) (xy 77.670008 -338.56849) (xy 77.722303 -338.553135)
			(xy 77.776251 -338.545379) (xy 77.803502 -338.544916) (xy 77.803756 -338.544916) (xy 77.828959 -338.545338)
			(xy 77.878926 -338.551972) (xy 77.92758 -338.565142) (xy 77.974071 -338.584618) (xy 77.996034 -338.596986)
			(xy 78.00594 -338.602828) (xy 78.027784 -338.60486) (xy 78.122526 -338.571332) (xy 78.138274 -338.555838)
			(xy 78.142338 -338.545424) (xy 78.153082 -338.518668) (xy 78.181362 -338.468427) (xy 78.216884 -338.423016)
			(xy 78.258839 -338.383472) (xy 78.30627 -338.350695) (xy 78.358094 -338.325434) (xy 78.413132 -338.308264)
			(xy 78.470127 -338.299576) (xy 78.498954 -338.299044) (xy 78.526202 -338.299621) (xy 78.580144 -338.30737)
			(xy 78.632434 -338.322717) (xy 78.682008 -338.345349) (xy 78.727856 -338.374806) (xy 78.769045 -338.410488)
			(xy 78.804738 -338.451669) (xy 78.834206 -338.49751) (xy 78.85685 -338.547078) (xy 78.869571 -338.590382)
			(xy 81.010506 -338.590382) (xy 81.011026 -338.562809) (xy 81.018967 -338.508239) (xy 81.034681 -338.45538)
			(xy 81.057841 -338.405334) (xy 81.087964 -338.359143) (xy 81.124423 -338.317769) (xy 81.145126 -338.299552)
			(xy 81.153227 -338.292021) (xy 81.162566 -338.271991) (xy 81.16316 -338.260944) (xy 81.16316 -338.18322)
			(xy 81.162593 -338.17217) (xy 81.153228 -338.152149) (xy 81.145126 -338.144612) (xy 81.124423 -338.126392)
			(xy 81.087951 -338.085026) (xy 81.057817 -338.038838) (xy 81.03465 -337.988792) (xy 81.018932 -337.93593)
			(xy 81.010991 -337.881356) (xy 81.010506 -337.853782) (xy 81.010961 -337.82653) (xy 81.01872 -337.77258)
			(xy 81.034079 -337.720284) (xy 81.056723 -337.670706) (xy 81.086192 -337.624855) (xy 81.121887 -337.583664)
			(xy 81.16308 -337.547973) (xy 81.208934 -337.518507) (xy 81.258514 -337.495867) (xy 81.310811 -337.480514)
			(xy 81.364762 -337.472759) (xy 81.392014 -337.472274) (xy 81.392522 -337.472274) (xy 81.426304 -337.473798)
			(xy 81.436464 -337.474814) (xy 81.455768 -337.468718) (xy 81.51876 -337.415886) (xy 81.526045 -337.409158)
			(xy 81.535327 -337.391657) (xy 81.536794 -337.38185) (xy 81.536794 -337.381088) (xy 81.539765 -337.352942)
			(xy 81.552958 -337.297905) (xy 81.574141 -337.245422) (xy 81.602848 -337.196647) (xy 81.638448 -337.15265)
			(xy 81.68016 -337.114398) (xy 81.727067 -337.08273) (xy 81.77814 -337.058344) (xy 81.832256 -337.041773)
			(xy 81.888226 -337.033382) (xy 81.916524 -337.032854) (xy 81.916778 -337.032854) (xy 81.934798 -337.033069)
			(xy 81.970672 -337.036507) (xy 81.988406 -337.039712) (xy 81.998058 -337.04149) (xy 82.017108 -337.037934)
			(xy 82.092038 -336.989928) (xy 82.103468 -336.97418) (xy 82.105754 -336.964782) (xy 82.113135 -336.937733)
			(xy 82.134764 -336.886004) (xy 82.163729 -336.837996) (xy 82.199406 -336.794743) (xy 82.241027 -336.757175)
			(xy 82.287697 -336.726101) (xy 82.338412 -336.70219) (xy 82.392079 -336.685957) (xy 82.447544 -336.67775)
			(xy 82.475578 -336.677254) (xy 82.502827 -336.677799) (xy 82.556771 -336.685551) (xy 82.609062 -336.700902)
			(xy 82.658636 -336.723537) (xy 82.704485 -336.752998) (xy 82.745674 -336.788683) (xy 82.781366 -336.829867)
			(xy 82.810834 -336.875711) (xy 82.833477 -336.925282) (xy 82.848836 -336.977571) (xy 82.856597 -337.031513)
			(xy 82.857086 -337.058762) (xy 82.856599 -337.086336) (xy 82.848652 -337.140908) (xy 82.832931 -337.193768)
			(xy 82.809765 -337.243814) (xy 82.779636 -337.290004) (xy 82.743172 -337.331376) (xy 82.722466 -337.349592)
			(xy 82.714389 -337.357145) (xy 82.705037 -337.377158) (xy 82.704432 -337.3882) (xy 82.704432 -337.465924)
			(xy 82.705033 -337.47697) (xy 82.714374 -337.496991) (xy 82.722466 -337.504532) (xy 82.743189 -337.52273)
			(xy 82.77966 -337.564101) (xy 82.809791 -337.610293) (xy 82.832955 -337.660344) (xy 82.848669 -337.713209)
			(xy 82.856604 -337.767786) (xy 82.857086 -337.795362) (xy 82.856599 -337.822936) (xy 82.85048 -337.864958)
			(xy 84.015578 -337.864958) (xy 84.019649 -337.809336) (xy 84.031775 -337.754899) (xy 84.051698 -337.702808)
			(xy 84.078994 -337.654173) (xy 84.11308 -337.61003) (xy 84.153229 -337.571321) (xy 84.198587 -337.53887)
			(xy 84.248187 -337.513369) (xy 84.300971 -337.495362) (xy 84.355814 -337.485232) (xy 84.411548 -337.483195)
			(xy 84.466985 -337.489295) (xy 84.520942 -337.503401) (xy 84.572271 -337.525213) (xy 84.619877 -337.554267)
			(xy 84.662745 -337.589942) (xy 84.699962 -337.631479) (xy 84.730735 -337.677992) (xy 84.754407 -337.728489)
			(xy 84.770475 -337.781896) (xy 84.778595 -337.837072) (xy 84.779104 -337.864958) (xy 84.778595 -337.892844)
			(xy 84.770475 -337.94802) (xy 84.754407 -338.001427) (xy 84.730735 -338.051924) (xy 84.699962 -338.098437)
			(xy 84.662745 -338.139974) (xy 84.619877 -338.175649) (xy 84.572271 -338.204703) (xy 84.520942 -338.226515)
			(xy 84.466985 -338.240621) (xy 84.411548 -338.246721) (xy 84.355814 -338.244684) (xy 84.300971 -338.234554)
			(xy 84.248187 -338.216547) (xy 84.198587 -338.191046) (xy 84.153229 -338.158595) (xy 84.11308 -338.119886)
			(xy 84.078994 -338.075743) (xy 84.051698 -338.027108) (xy 84.031775 -337.975017) (xy 84.019649 -337.92058)
			(xy 84.015578 -337.864958) (xy 82.85048 -337.864958) (xy 82.848652 -337.877508) (xy 82.832931 -337.930368)
			(xy 82.809765 -337.980414) (xy 82.779636 -338.026604) (xy 82.743172 -338.067976) (xy 82.722466 -338.086192)
			(xy 82.714389 -338.093745) (xy 82.705037 -338.113758) (xy 82.704432 -338.1248) (xy 82.704432 -338.202524)
			(xy 82.705033 -338.21357) (xy 82.714374 -338.233591) (xy 82.722466 -338.241132) (xy 82.743189 -338.25933)
			(xy 82.77966 -338.300701) (xy 82.809791 -338.346893) (xy 82.832955 -338.396944) (xy 82.848669 -338.449809)
			(xy 82.856604 -338.504386) (xy 82.857086 -338.531962) (xy 82.856609 -338.559215) (xy 82.848857 -338.613167)
			(xy 82.833505 -338.665465) (xy 82.810865 -338.715047) (xy 82.78178 -338.760308) (xy 83.436458 -338.760308)
			(xy 83.440529 -338.704686) (xy 83.452655 -338.650249) (xy 83.472578 -338.598158) (xy 83.499874 -338.549523)
			(xy 83.53396 -338.50538) (xy 83.574109 -338.466671) (xy 83.619467 -338.43422) (xy 83.669067 -338.408719)
			(xy 83.721851 -338.390712) (xy 83.776694 -338.380582) (xy 83.832428 -338.378545) (xy 83.887865 -338.384645)
			(xy 83.941822 -338.398751) (xy 83.993151 -338.420563) (xy 84.040757 -338.449617) (xy 84.083625 -338.485292)
			(xy 84.120842 -338.526829) (xy 84.151615 -338.573342) (xy 84.175287 -338.623839) (xy 84.191355 -338.677246)
			(xy 84.199475 -338.732422) (xy 84.199984 -338.760308) (xy 84.199475 -338.788194) (xy 84.191355 -338.84337)
			(xy 84.175287 -338.896777) (xy 84.151615 -338.947274) (xy 84.120842 -338.993787) (xy 84.083625 -339.035324)
			(xy 84.040757 -339.070999) (xy 83.993151 -339.100053) (xy 83.941822 -339.121865) (xy 83.887865 -339.135971)
			(xy 83.832428 -339.142071) (xy 83.776694 -339.140034) (xy 83.721851 -339.129904) (xy 83.669067 -339.111897)
			(xy 83.619467 -339.086396) (xy 83.574109 -339.053945) (xy 83.53396 -339.015236) (xy 83.499874 -338.971093)
			(xy 83.472578 -338.922458) (xy 83.452655 -338.870367) (xy 83.440529 -338.81593) (xy 83.436458 -338.760308)
			(xy 82.78178 -338.760308) (xy 82.781399 -338.760901) (xy 82.745706 -338.802095) (xy 82.704514 -338.837789)
			(xy 82.658661 -338.867257) (xy 82.60908 -338.889899) (xy 82.556782 -338.905254) (xy 82.502831 -338.913008)
			(xy 82.475578 -338.91347) (xy 82.447721 -338.912989) (xy 82.392603 -338.904862) (xy 82.33925 -338.888812)
			(xy 82.288796 -338.86518) (xy 82.242311 -338.834468) (xy 82.200782 -338.797327) (xy 82.16509 -338.754547)
			(xy 82.135993 -338.707034) (xy 82.114108 -338.655797) (xy 82.106516 -338.62899) (xy 82.10423 -338.6201)
			(xy 82.093562 -338.60486) (xy 82.02168 -338.557108) (xy 82.003646 -338.553044) (xy 81.994502 -338.554314)
			(xy 81.981485 -338.555981) (xy 81.955301 -338.557762) (xy 81.942178 -338.55787) (xy 81.928029 -338.557779)
			(xy 81.899806 -338.555743) (xy 81.88579 -338.553806) (xy 81.875884 -338.552282) (xy 81.856072 -338.557108)
			(xy 81.78165 -338.612988) (xy 81.77149 -338.630514) (xy 81.77022 -338.640674) (xy 81.766152 -338.667831)
			(xy 81.751175 -338.720661) (xy 81.72878 -338.770799) (xy 81.69943 -338.817209) (xy 81.66373 -338.858933)
			(xy 81.622418 -338.895108) (xy 81.576348 -338.924989) (xy 81.52647 -338.947957) (xy 81.473815 -338.963539)
			(xy 81.41947 -338.971412) (xy 81.392014 -338.97189) (xy 81.364761 -338.971432) (xy 81.310809 -338.963676)
			(xy 81.25851 -338.948321) (xy 81.208928 -338.925679) (xy 81.163074 -338.896211) (xy 81.121881 -338.860516)
			(xy 81.086187 -338.819323) (xy 81.056719 -338.773468) (xy 81.034078 -338.723887) (xy 81.018723 -338.671587)
			(xy 81.010968 -338.617635) (xy 81.010506 -338.590382) (xy 78.869571 -338.590382) (xy 78.87221 -338.599364)
			(xy 78.879972 -338.653304) (xy 78.880462 -338.680552) (xy 78.879812 -338.712115) (xy 78.869421 -338.774381)
			(xy 78.848932 -338.83409) (xy 78.834488 -338.862162) (xy 78.829662 -338.871052) (xy 78.82763 -338.89061)
			(xy 78.85049 -338.969096) (xy 78.853744 -338.978514) (xy 78.86615 -338.994076) (xy 78.87462 -338.999322)
			(xy 78.89972 -339.013872) (xy 78.945601 -339.049377) (xy 78.985575 -339.091421) (xy 79.01872 -339.139034)
			(xy 79.044271 -339.191118) (xy 79.061638 -339.246472) (xy 79.070422 -339.303817) (xy 79.070962 -339.332824)
			(xy 79.070476 -339.360075) (xy 79.06272 -339.414023) (xy 79.056282 -339.435948) (xy 84.775294 -339.435948)
			(xy 84.775751 -339.408472) (xy 84.78365 -339.354092) (xy 84.799277 -339.301409) (xy 84.822308 -339.251517)
			(xy 84.852266 -339.205449) (xy 84.870036 -339.184488) (xy 84.87029 -339.184234) (xy 84.875867 -339.177141)
			(xy 84.88212 -339.160229) (xy 84.882482 -339.151214) (xy 84.882482 -339.08365) (xy 84.882105 -339.074635)
			(xy 84.875872 -339.057718) (xy 84.87029 -339.05063) (xy 84.869782 -339.050122) (xy 84.85206 -339.029167)
			(xy 84.822176 -338.983136) (xy 84.799208 -338.933293) (xy 84.783631 -338.88067) (xy 84.775767 -338.826356)
			(xy 84.775294 -338.798916) (xy 84.77578 -338.771665) (xy 84.783536 -338.717717) (xy 84.798891 -338.665422)
			(xy 84.821533 -338.615845) (xy 84.850999 -338.569995) (xy 84.88669 -338.528804) (xy 84.927881 -338.493113)
			(xy 84.973731 -338.463647) (xy 85.023308 -338.441005) (xy 85.075603 -338.42565) (xy 85.129551 -338.417894)
			(xy 85.184053 -338.417894) (xy 85.238001 -338.42565) (xy 85.290296 -338.441005) (xy 85.339873 -338.463647)
			(xy 85.385723 -338.493113) (xy 85.426914 -338.528804) (xy 85.462605 -338.569995) (xy 85.492071 -338.615845)
			(xy 85.514713 -338.665422) (xy 85.530068 -338.717717) (xy 85.537824 -338.771665) (xy 85.53831 -338.798916)
			(xy 85.537831 -338.826391) (xy 85.529937 -338.880771) (xy 85.514315 -338.933453) (xy 85.511686 -338.93915)
			(xy 85.780101 -338.93915) (xy 85.780101 -338.88465) (xy 85.787858 -338.830704) (xy 85.803213 -338.778411)
			(xy 85.825854 -338.728835) (xy 85.85532 -338.682987) (xy 85.891011 -338.641799) (xy 85.932201 -338.606109)
			(xy 85.978051 -338.576645) (xy 86.027628 -338.554007) (xy 86.079921 -338.538654) (xy 86.133868 -338.5309)
			(xy 86.161118 -338.530438) (xy 86.161372 -338.530438) (xy 86.186575 -338.53085) (xy 86.236543 -338.537486)
			(xy 86.285197 -338.550659) (xy 86.331688 -338.570138) (xy 86.35365 -338.582508) (xy 86.363556 -338.58835)
			(xy 86.3854 -338.590382) (xy 86.480142 -338.556854) (xy 86.49589 -338.54136) (xy 86.499954 -338.530946)
			(xy 86.510643 -338.504167) (xy 86.538934 -338.453928) (xy 86.574467 -338.40852) (xy 86.61643 -338.368979)
			(xy 86.663868 -338.336206) (xy 86.715699 -338.310948) (xy 86.770741 -338.293782) (xy 86.827741 -338.285097)
			(xy 86.85657 -338.284566) (xy 86.883821 -338.285083) (xy 86.937769 -338.292835) (xy 86.990064 -338.308186)
			(xy 87.039642 -338.330823) (xy 87.085494 -338.360286) (xy 87.126686 -338.395974) (xy 87.162381 -338.437161)
			(xy 87.19185 -338.483009) (xy 87.214494 -338.532584) (xy 87.227218 -338.575904) (xy 89.368122 -338.575904)
			(xy 89.368583 -338.548329) (xy 89.376535 -338.493756) (xy 89.392261 -338.440895) (xy 89.415432 -338.390849)
			(xy 89.445565 -338.34466) (xy 89.482034 -338.303289) (xy 89.502742 -338.285074) (xy 89.510836 -338.277536)
			(xy 89.520178 -338.257511) (xy 89.520776 -338.246466) (xy 89.520776 -338.168742) (xy 89.520192 -338.157694)
			(xy 89.510839 -338.137673) (xy 89.502742 -338.130134) (xy 89.482052 -338.111899) (xy 89.445579 -338.070536)
			(xy 89.415443 -338.024352) (xy 89.392273 -337.974308) (xy 89.376552 -337.921449) (xy 89.368609 -337.866878)
			(xy 89.368122 -337.839304) (xy 89.368559 -337.81205) (xy 89.376316 -337.758096) (xy 89.391673 -337.705796)
			(xy 89.414318 -337.656214) (xy 89.443788 -337.61036) (xy 89.479485 -337.569166) (xy 89.52068 -337.533472)
			(xy 89.566537 -337.504005) (xy 89.616121 -337.481364) (xy 89.668422 -337.466011) (xy 89.722376 -337.458257)
			(xy 89.74963 -337.457796) (xy 89.750138 -337.457796) (xy 89.78392 -337.45932) (xy 89.79408 -337.460336)
			(xy 89.813384 -337.45424) (xy 89.876376 -337.401408) (xy 89.883678 -337.394695) (xy 89.892954 -337.377183)
			(xy 89.89441 -337.367372) (xy 89.89441 -337.36661) (xy 89.8973 -337.338454) (xy 89.910505 -337.283414)
			(xy 89.931698 -337.230931) (xy 89.960416 -337.182155) (xy 89.996025 -337.138159) (xy 90.037746 -337.099908)
			(xy 90.084661 -337.068243) (xy 90.135741 -337.043859) (xy 90.189863 -337.027291) (xy 90.24584 -337.018903)
			(xy 90.27414 -337.018376) (xy 90.274394 -337.018376) (xy 90.292413 -337.018602) (xy 90.328288 -337.022033)
			(xy 90.346022 -337.025234) (xy 90.355674 -337.027012) (xy 90.374724 -337.023456) (xy 90.449654 -336.97545)
			(xy 90.461084 -336.959702) (xy 90.46337 -336.950304) (xy 90.470776 -336.923263) (xy 90.492409 -336.87154)
			(xy 90.521374 -336.823538) (xy 90.55705 -336.780288) (xy 90.598668 -336.742722) (xy 90.645333 -336.711648)
			(xy 90.696041 -336.687734) (xy 90.749702 -336.671494) (xy 90.805162 -336.663278) (xy 90.833194 -336.662776)
			(xy 90.860444 -336.663283) (xy 90.914391 -336.671039) (xy 90.966684 -336.686392) (xy 91.01626 -336.709031)
			(xy 91.06211 -336.738496) (xy 91.1033 -336.774185) (xy 91.138991 -336.815373) (xy 91.168458 -336.861221)
			(xy 91.1911 -336.910795) (xy 91.206457 -336.963088) (xy 91.214215 -337.017034) (xy 91.214702 -337.044284)
			(xy 91.214225 -337.071858) (xy 91.206274 -337.12643) (xy 91.190552 -337.17929) (xy 91.167384 -337.229336)
			(xy 91.137253 -337.275526) (xy 91.100788 -337.316898) (xy 91.080082 -337.335114) (xy 91.071997 -337.342661)
			(xy 91.062649 -337.362679) (xy 91.062048 -337.373722) (xy 91.062048 -337.451446) (xy 91.062631 -337.462494)
			(xy 91.071984 -337.482516) (xy 91.080082 -337.490054) (xy 91.100771 -337.50829) (xy 91.137243 -337.549653)
			(xy 91.167379 -337.595837) (xy 91.190549 -337.645881) (xy 91.20627 -337.698739) (xy 91.214214 -337.753311)
			(xy 91.214702 -337.780884) (xy 91.214225 -337.808458) (xy 91.206274 -337.86303) (xy 91.190591 -337.915758)
			(xy 92.346778 -337.915758) (xy 92.350849 -337.860136) (xy 92.362975 -337.805699) (xy 92.382898 -337.753608)
			(xy 92.410194 -337.704973) (xy 92.44428 -337.66083) (xy 92.484429 -337.622121) (xy 92.529787 -337.58967)
			(xy 92.579387 -337.564169) (xy 92.632171 -337.546162) (xy 92.687014 -337.536032) (xy 92.742748 -337.533995)
			(xy 92.798185 -337.540095) (xy 92.852142 -337.554201) (xy 92.903471 -337.576013) (xy 92.951077 -337.605067)
			(xy 92.993945 -337.640742) (xy 93.031162 -337.682279) (xy 93.061935 -337.728792) (xy 93.085607 -337.779289)
			(xy 93.101675 -337.832696) (xy 93.109795 -337.887872) (xy 93.110304 -337.915758) (xy 93.109795 -337.943644)
			(xy 93.101675 -337.99882) (xy 93.085607 -338.052227) (xy 93.061935 -338.102724) (xy 93.031162 -338.149237)
			(xy 92.993945 -338.190774) (xy 92.951077 -338.226449) (xy 92.903471 -338.255503) (xy 92.852142 -338.277315)
			(xy 92.798185 -338.291421) (xy 92.742748 -338.297521) (xy 92.687014 -338.295484) (xy 92.632171 -338.285354)
			(xy 92.579387 -338.267347) (xy 92.529787 -338.241846) (xy 92.484429 -338.209395) (xy 92.44428 -338.170686)
			(xy 92.410194 -338.126543) (xy 92.382898 -338.077908) (xy 92.362975 -338.025817) (xy 92.350849 -337.97138)
			(xy 92.346778 -337.915758) (xy 91.190591 -337.915758) (xy 91.190552 -337.91589) (xy 91.167384 -337.965936)
			(xy 91.137253 -338.012126) (xy 91.100788 -338.053498) (xy 91.080082 -338.071714) (xy 91.071997 -338.079261)
			(xy 91.062649 -338.099279) (xy 91.062048 -338.110322) (xy 91.062048 -338.188046) (xy 91.062631 -338.199094)
			(xy 91.071984 -338.219116) (xy 91.080082 -338.226654) (xy 91.100771 -338.24489) (xy 91.137243 -338.286253)
			(xy 91.167379 -338.332437) (xy 91.190549 -338.382481) (xy 91.20627 -338.435339) (xy 91.214214 -338.489911)
			(xy 91.214702 -338.517484) (xy 91.21423 -338.544737) (xy 91.206475 -338.598688) (xy 91.191121 -338.650986)
			(xy 91.168479 -338.700566) (xy 91.139013 -338.74642) (xy 91.10332 -338.787613) (xy 91.076206 -338.811108)
			(xy 91.767658 -338.811108) (xy 91.771729 -338.755486) (xy 91.783855 -338.701049) (xy 91.803778 -338.648958)
			(xy 91.831074 -338.600323) (xy 91.86516 -338.55618) (xy 91.905309 -338.517471) (xy 91.950667 -338.48502)
			(xy 92.000267 -338.459519) (xy 92.053051 -338.441512) (xy 92.107894 -338.431382) (xy 92.163628 -338.429345)
			(xy 92.219065 -338.435445) (xy 92.273022 -338.449551) (xy 92.324351 -338.471363) (xy 92.371957 -338.500417)
			(xy 92.414825 -338.536092) (xy 92.452042 -338.577629) (xy 92.482815 -338.624142) (xy 92.506487 -338.674639)
			(xy 92.522555 -338.728046) (xy 92.530675 -338.783222) (xy 92.531184 -338.811108) (xy 92.530675 -338.838994)
			(xy 92.522555 -338.89417) (xy 92.506487 -338.947577) (xy 92.482815 -338.998074) (xy 92.452042 -339.044587)
			(xy 92.414825 -339.086124) (xy 92.371957 -339.121799) (xy 92.324351 -339.150853) (xy 92.273022 -339.172665)
			(xy 92.219065 -339.186771) (xy 92.163628 -339.192871) (xy 92.107894 -339.190834) (xy 92.053051 -339.180704)
			(xy 92.000267 -339.162697) (xy 91.950667 -339.137196) (xy 91.905309 -339.104745) (xy 91.86516 -339.066036)
			(xy 91.831074 -339.021893) (xy 91.803778 -338.973258) (xy 91.783855 -338.921167) (xy 91.771729 -338.86673)
			(xy 91.767658 -338.811108) (xy 91.076206 -338.811108) (xy 91.062128 -338.823307) (xy 91.016275 -338.852775)
			(xy 90.966695 -338.875417) (xy 90.914397 -338.890773) (xy 90.860447 -338.898529) (xy 90.833194 -338.898992)
			(xy 90.805338 -338.89848) (xy 90.750222 -338.890356) (xy 90.696871 -338.874309) (xy 90.646418 -338.850681)
			(xy 90.599933 -338.819973) (xy 90.558404 -338.782836) (xy 90.522711 -338.740059) (xy 90.493612 -338.69255)
			(xy 90.471725 -338.641318) (xy 90.464132 -338.614512) (xy 90.461846 -338.605622) (xy 90.451178 -338.590382)
			(xy 90.379296 -338.54263) (xy 90.361262 -338.538566) (xy 90.352118 -338.539836) (xy 90.339101 -338.541502)
			(xy 90.312917 -338.543284) (xy 90.299794 -338.543392) (xy 90.285645 -338.543299) (xy 90.257422 -338.541264)
			(xy 90.243406 -338.539328) (xy 90.2335 -338.537804) (xy 90.213688 -338.54263) (xy 90.139266 -338.59851)
			(xy 90.129106 -338.616036) (xy 90.127836 -338.626196) (xy 90.12377 -338.653353) (xy 90.108791 -338.706182)
			(xy 90.086395 -338.756319) (xy 90.057043 -338.802728) (xy 90.021343 -338.844451) (xy 89.980032 -338.880626)
			(xy 89.933961 -338.910507) (xy 89.884084 -338.933475) (xy 89.83143 -338.949058) (xy 89.777086 -338.956933)
			(xy 89.74963 -338.957412) (xy 89.722378 -338.956917) (xy 89.668428 -338.949164) (xy 89.616131 -338.933812)
			(xy 89.566552 -338.911173) (xy 89.520699 -338.881709) (xy 89.479506 -338.846018) (xy 89.443812 -338.804829)
			(xy 89.414343 -338.758978) (xy 89.3917 -338.7094) (xy 89.376343 -338.657105) (xy 89.368586 -338.603156)
			(xy 89.368122 -338.575904) (xy 87.227218 -338.575904) (xy 87.229853 -338.584877) (xy 87.237613 -338.638823)
			(xy 87.238078 -338.666074) (xy 87.237435 -338.697638) (xy 87.227041 -338.759903) (xy 87.206549 -338.819612)
			(xy 87.192104 -338.847684) (xy 87.187278 -338.856574) (xy 87.185246 -338.876132) (xy 87.208106 -338.954618)
			(xy 87.211345 -338.964042) (xy 87.223762 -338.979601) (xy 87.232236 -338.984844) (xy 87.257326 -338.999411)
			(xy 87.303211 -339.034909) (xy 87.343189 -339.076948) (xy 87.376337 -339.124559) (xy 87.40189 -339.176642)
			(xy 87.419257 -339.231994) (xy 87.428039 -339.289339) (xy 87.428578 -339.318346) (xy 87.428092 -339.345597)
			(xy 87.420336 -339.399545) (xy 87.404981 -339.45184) (xy 87.389038 -339.486748) (xy 93.106494 -339.486748)
			(xy 93.106951 -339.459272) (xy 93.11485 -339.404892) (xy 93.130477 -339.352209) (xy 93.153508 -339.302317)
			(xy 93.183466 -339.256249) (xy 93.201236 -339.235288) (xy 93.20149 -339.235034) (xy 93.207067 -339.227941)
			(xy 93.21332 -339.211029) (xy 93.213682 -339.202014) (xy 93.213682 -339.13445) (xy 93.213305 -339.125435)
			(xy 93.207072 -339.108518) (xy 93.20149 -339.10143) (xy 93.200982 -339.100922) (xy 93.18326 -339.079967)
			(xy 93.153376 -339.033936) (xy 93.130408 -338.984093) (xy 93.114831 -338.93147) (xy 93.106967 -338.877156)
			(xy 93.106494 -338.849716) (xy 93.10698 -338.822465) (xy 93.114736 -338.768517) (xy 93.130091 -338.716222)
			(xy 93.152733 -338.666645) (xy 93.182199 -338.620795) (xy 93.21789 -338.579604) (xy 93.259081 -338.543913)
			(xy 93.304931 -338.514447) (xy 93.354508 -338.491805) (xy 93.406803 -338.47645) (xy 93.460751 -338.468694)
			(xy 93.515253 -338.468694) (xy 93.569201 -338.47645) (xy 93.621496 -338.491805) (xy 93.671073 -338.514447)
			(xy 93.716923 -338.543913) (xy 93.758114 -338.579604) (xy 93.793805 -338.620795) (xy 93.823271 -338.666645)
			(xy 93.845913 -338.716222) (xy 93.861268 -338.768517) (xy 93.869024 -338.822465) (xy 93.86951 -338.849716)
			(xy 93.869031 -338.877191) (xy 93.861137 -338.931571) (xy 93.845515 -338.984253) (xy 93.842886 -338.98995)
			(xy 94.111301 -338.98995) (xy 94.111301 -338.93545) (xy 94.119058 -338.881504) (xy 94.134413 -338.829211)
			(xy 94.157054 -338.779635) (xy 94.18652 -338.733787) (xy 94.222211 -338.692599) (xy 94.263401 -338.656909)
			(xy 94.309251 -338.627445) (xy 94.358828 -338.604807) (xy 94.411121 -338.589454) (xy 94.465068 -338.5817)
			(xy 94.492318 -338.581238) (xy 94.492572 -338.581238) (xy 94.517775 -338.58165) (xy 94.567743 -338.588286)
			(xy 94.616397 -338.601459) (xy 94.662888 -338.620938) (xy 94.68485 -338.633308) (xy 94.694756 -338.63915)
			(xy 94.7166 -338.641182) (xy 94.811342 -338.607654) (xy 94.82709 -338.59216) (xy 94.831154 -338.581746)
			(xy 94.841843 -338.554967) (xy 94.870134 -338.504728) (xy 94.905667 -338.45932) (xy 94.94763 -338.419779)
			(xy 94.995068 -338.387006) (xy 95.046899 -338.361748) (xy 95.101941 -338.344582) (xy 95.158941 -338.335897)
			(xy 95.18777 -338.335366) (xy 95.215021 -338.335883) (xy 95.268969 -338.343635) (xy 95.321264 -338.358986)
			(xy 95.370842 -338.381623) (xy 95.416694 -338.411086) (xy 95.457886 -338.446774) (xy 95.493581 -338.487961)
			(xy 95.52305 -338.533809) (xy 95.545694 -338.583384) (xy 95.558418 -338.626704) (xy 97.699322 -338.626704)
			(xy 97.699783 -338.599129) (xy 97.707735 -338.544556) (xy 97.723461 -338.491695) (xy 97.746632 -338.441649)
			(xy 97.776765 -338.39546) (xy 97.813234 -338.354089) (xy 97.833942 -338.335874) (xy 97.842036 -338.328336)
			(xy 97.851378 -338.308311) (xy 97.851976 -338.297266) (xy 97.851976 -338.219542) (xy 97.851392 -338.208494)
			(xy 97.842039 -338.188473) (xy 97.833942 -338.180934) (xy 97.813252 -338.162699) (xy 97.776779 -338.121336)
			(xy 97.746643 -338.075152) (xy 97.723473 -338.025108) (xy 97.707752 -337.972249) (xy 97.699809 -337.917678)
			(xy 97.699322 -337.890104) (xy 97.699759 -337.86285) (xy 97.707516 -337.808896) (xy 97.722873 -337.756596)
			(xy 97.745518 -337.707014) (xy 97.774988 -337.66116) (xy 97.810685 -337.619966) (xy 97.85188 -337.584272)
			(xy 97.897737 -337.554805) (xy 97.947321 -337.532164) (xy 97.999622 -337.516811) (xy 98.053576 -337.509057)
			(xy 98.08083 -337.508596) (xy 98.081338 -337.508596) (xy 98.11512 -337.51012) (xy 98.12528 -337.511136)
			(xy 98.144584 -337.50504) (xy 98.207576 -337.452208) (xy 98.214878 -337.445495) (xy 98.224154 -337.427983)
			(xy 98.22561 -337.418172) (xy 98.22561 -337.41741) (xy 98.228502 -337.389241) (xy 98.241716 -337.334178)
			(xy 98.262927 -337.281674) (xy 98.291666 -337.232882) (xy 98.327304 -337.188876) (xy 98.369056 -337.150622)
			(xy 98.416005 -337.118961) (xy 98.467119 -337.09459) (xy 98.521274 -337.078043) (xy 98.57728 -337.069685)
			(xy 98.605594 -337.069176) (xy 98.632844 -337.069683) (xy 98.686791 -337.077439) (xy 98.739084 -337.092792)
			(xy 98.78866 -337.115431) (xy 98.83451 -337.144896) (xy 98.8757 -337.180585) (xy 98.911391 -337.221773)
			(xy 98.940858 -337.267621) (xy 98.9635 -337.317195) (xy 98.978857 -337.369488) (xy 98.986615 -337.423434)
			(xy 98.987102 -337.450684) (xy 98.986613 -337.478546) (xy 98.978512 -337.533679) (xy 98.962482 -337.587049)
			(xy 98.938862 -337.63752) (xy 98.908154 -337.68402) (xy 98.871012 -337.725562) (xy 98.849942 -337.7438)
			(xy 98.840798 -337.75142) (xy 98.8314 -337.772502) (xy 98.834448 -337.864704) (xy 98.835391 -337.876182)
			(xy 98.846094 -337.896547) (xy 98.855022 -337.90382) (xy 98.855276 -337.904074) (xy 98.875807 -337.919521)
			(xy 98.91294 -337.95503) (xy 98.944972 -337.995202) (xy 98.971323 -338.039309) (xy 98.991515 -338.086554)
			(xy 99.005184 -338.136081) (xy 99.012082 -338.186995) (xy 99.012502 -338.212684) (xy 99.011987 -338.242127)
			(xy 99.002939 -338.300314) (xy 98.985057 -338.356419) (xy 98.958764 -338.409109) (xy 98.924687 -338.457133)
			(xy 98.904552 -338.478622) (xy 98.904298 -338.478876) (xy 98.896575 -338.487741) (xy 98.889414 -338.510104)
			(xy 98.890582 -338.521802) (xy 98.904806 -338.614004) (xy 98.918522 -338.633308) (xy 98.928936 -338.638896)
			(xy 98.954506 -338.6533) (xy 99.001281 -338.688741) (xy 99.042078 -338.730927) (xy 99.075934 -338.778862)
			(xy 99.102052 -338.831415) (xy 99.119814 -338.887348) (xy 99.128803 -338.945341) (xy 99.129342 -338.974684)
			(xy 99.128834 -339.003602) (xy 99.120106 -339.060774) (xy 99.102848 -339.115974) (xy 99.077454 -339.167936)
			(xy 99.044508 -339.21547) (xy 99.004763 -339.257485) (xy 98.982276 -339.275674) (xy 98.973486 -339.283298)
			(xy 98.963294 -339.304186) (xy 98.962718 -339.315806) (xy 98.962718 -339.395562) (xy 98.963229 -339.407198)
			(xy 98.973437 -339.428107) (xy 98.982276 -339.435694) (xy 99.004752 -339.453894) (xy 99.044488 -339.495912)
			(xy 99.077429 -339.543444) (xy 99.102819 -339.595404) (xy 99.120077 -339.6506) (xy 99.128807 -339.707768)
			(xy 99.129342 -339.736684) (xy 99.128807 -339.763933) (xy 99.121054 -339.817877) (xy 99.105702 -339.870169)
			(xy 99.083065 -339.919744) (xy 99.053604 -339.965593) (xy 99.017918 -340.006782) (xy 98.976733 -340.042474)
			(xy 98.930888 -340.071941) (xy 98.881316 -340.094585) (xy 98.829026 -340.109943) (xy 98.775083 -340.117703)
			(xy 98.747834 -340.118192) (xy 98.718894 -340.117667) (xy 98.661681 -340.108901) (xy 98.606448 -340.091596)
			(xy 98.554462 -340.066148) (xy 98.506915 -340.033142) (xy 98.464898 -339.993334) (xy 98.429374 -339.947637)
			(xy 98.401158 -339.897099) (xy 98.380898 -339.842881) (xy 98.374454 -339.814662) (xy 98.374454 -339.814408)
			(xy 98.37202 -339.80506) (xy 98.361327 -339.788995) (xy 98.353626 -339.783166) (xy 98.287332 -339.7377)
			(xy 98.26879 -339.733382) (xy 98.259138 -339.734906) (xy 98.25863 -339.734906) (xy 98.243871 -339.737128)
			(xy 98.214119 -339.739547) (xy 98.199194 -339.739732) (xy 98.171944 -339.739228) (xy 98.117998 -339.731471)
			(xy 98.065705 -339.716116) (xy 98.016129 -339.693476) (xy 97.97028 -339.664012) (xy 97.929091 -339.628322)
			(xy 97.893399 -339.587134) (xy 97.863932 -339.541287) (xy 97.84129 -339.491712) (xy 97.825933 -339.43942)
			(xy 97.818173 -339.385474) (xy 97.817686 -339.358224) (xy 97.818159 -339.330984) (xy 97.825925 -339.277061)
			(xy 97.841289 -339.224793) (xy 97.863937 -339.175245) (xy 97.893407 -339.129424) (xy 97.910904 -339.108542)
			(xy 97.917723 -339.099699) (xy 97.923796 -339.07824) (xy 97.922588 -339.06714) (xy 97.908364 -338.978748)
			(xy 97.895918 -338.96046) (xy 97.886012 -338.954618) (xy 97.862006 -338.939797) (xy 97.818266 -338.904163)
			(xy 97.780254 -338.862474) (xy 97.748798 -338.81564) (xy 97.724585 -338.764683) (xy 97.708143 -338.710714)
			(xy 97.699831 -338.654913) (xy 97.699322 -338.626704) (xy 95.558418 -338.626704) (xy 95.561053 -338.635677)
			(xy 95.568813 -338.689623) (xy 95.569278 -338.716874) (xy 95.568635 -338.748438) (xy 95.558241 -338.810703)
			(xy 95.537749 -338.870412) (xy 95.523304 -338.898484) (xy 95.518478 -338.907374) (xy 95.516446 -338.926932)
			(xy 95.539306 -339.005418) (xy 95.542545 -339.014842) (xy 95.554962 -339.030401) (xy 95.563436 -339.035644)
			(xy 95.588526 -339.050211) (xy 95.634411 -339.085709) (xy 95.674389 -339.127748) (xy 95.707537 -339.175359)
			(xy 95.73309 -339.227442) (xy 95.750457 -339.282794) (xy 95.759239 -339.340139) (xy 95.759778 -339.369146)
			(xy 95.759292 -339.396397) (xy 95.751536 -339.450345) (xy 95.736181 -339.50264) (xy 95.713539 -339.552217)
			(xy 95.684073 -339.598067) (xy 95.648382 -339.639258) (xy 95.607191 -339.674949) (xy 95.561341 -339.704415)
			(xy 95.511764 -339.727057) (xy 95.459469 -339.742412) (xy 95.405521 -339.750168) (xy 95.351019 -339.750168)
			(xy 95.297071 -339.742412) (xy 95.244776 -339.727057) (xy 95.195199 -339.704415) (xy 95.149349 -339.674949)
			(xy 95.108158 -339.639258) (xy 95.072467 -339.598067) (xy 95.043001 -339.552217) (xy 95.020359 -339.50264)
			(xy 95.005004 -339.450345) (xy 94.997248 -339.396397) (xy 94.996762 -339.369146) (xy 94.99742 -339.337583)
			(xy 95.007809 -339.275318) (xy 95.028295 -339.215609) (xy 95.042736 -339.187536) (xy 95.047562 -339.178646)
			(xy 95.049594 -339.159088) (xy 95.026734 -339.080602) (xy 95.023509 -339.071172) (xy 95.011083 -339.055615)
			(xy 95.002604 -339.050376) (xy 94.995238 -339.046312) (xy 94.985332 -339.04047) (xy 94.963488 -339.038438)
			(xy 94.868746 -339.071966) (xy 94.852998 -339.08746) (xy 94.848934 -339.097874) (xy 94.838212 -339.12464)
			(xy 94.80993 -339.174882) (xy 94.774404 -339.220293) (xy 94.732447 -339.259837) (xy 94.685013 -339.292613)
			(xy 94.633185 -339.317872) (xy 94.578144 -339.33504) (xy 94.521146 -339.343724) (xy 94.492318 -339.344254)
			(xy 94.465068 -339.3437) (xy 94.411121 -339.335946) (xy 94.358828 -339.320593) (xy 94.309251 -339.297955)
			(xy 94.263401 -339.268491) (xy 94.222211 -339.232801) (xy 94.18652 -339.191613) (xy 94.157054 -339.145765)
			(xy 94.134413 -339.096189) (xy 94.119058 -339.043896) (xy 94.111301 -338.98995) (xy 93.842886 -338.98995)
			(xy 93.822489 -339.034146) (xy 93.792536 -339.080214) (xy 93.774768 -339.101176) (xy 93.774514 -339.10143)
			(xy 93.768952 -339.108534) (xy 93.76269 -339.125437) (xy 93.762322 -339.13445) (xy 93.762322 -339.202014)
			(xy 93.762667 -339.211032) (xy 93.768922 -339.227949) (xy 93.774514 -339.235034) (xy 93.775022 -339.235542)
			(xy 93.792775 -339.256473) (xy 93.822654 -339.30251) (xy 93.845616 -339.352359) (xy 93.861186 -339.404988)
			(xy 93.869042 -339.459306) (xy 93.86951 -339.486748) (xy 93.869024 -339.513999) (xy 93.861268 -339.567947)
			(xy 93.845913 -339.620242) (xy 93.823271 -339.669819) (xy 93.793805 -339.715669) (xy 93.758114 -339.75686)
			(xy 93.716923 -339.792551) (xy 93.671073 -339.822017) (xy 93.621496 -339.844659) (xy 93.569201 -339.860014)
			(xy 93.515253 -339.86777) (xy 93.460751 -339.86777) (xy 93.406803 -339.860014) (xy 93.354508 -339.844659)
			(xy 93.304931 -339.822017) (xy 93.259081 -339.792551) (xy 93.21789 -339.75686) (xy 93.182199 -339.715669)
			(xy 93.152733 -339.669819) (xy 93.130091 -339.620242) (xy 93.114736 -339.567947) (xy 93.10698 -339.513999)
			(xy 93.106494 -339.486748) (xy 87.389038 -339.486748) (xy 87.382339 -339.501417) (xy 87.352873 -339.547267)
			(xy 87.317182 -339.588458) (xy 87.275991 -339.624149) (xy 87.230141 -339.653615) (xy 87.180564 -339.676257)
			(xy 87.128269 -339.691612) (xy 87.074321 -339.699368) (xy 87.019819 -339.699368) (xy 86.965871 -339.691612)
			(xy 86.913576 -339.676257) (xy 86.863999 -339.653615) (xy 86.818149 -339.624149) (xy 86.776958 -339.588458)
			(xy 86.741267 -339.547267) (xy 86.711801 -339.501417) (xy 86.689159 -339.45184) (xy 86.673804 -339.399545)
			(xy 86.666048 -339.345597) (xy 86.665562 -339.318346) (xy 86.66622 -339.286783) (xy 86.676609 -339.224518)
			(xy 86.697095 -339.164809) (xy 86.711536 -339.136736) (xy 86.716362 -339.127846) (xy 86.718394 -339.108288)
			(xy 86.695534 -339.029802) (xy 86.692309 -339.020372) (xy 86.679883 -339.004815) (xy 86.671404 -338.999576)
			(xy 86.664038 -338.995512) (xy 86.654132 -338.98967) (xy 86.632288 -338.987638) (xy 86.537546 -339.021166)
			(xy 86.521798 -339.03666) (xy 86.517734 -339.047074) (xy 86.507012 -339.07384) (xy 86.47873 -339.124082)
			(xy 86.443204 -339.169493) (xy 86.401247 -339.209037) (xy 86.353813 -339.241813) (xy 86.301985 -339.267072)
			(xy 86.246944 -339.28424) (xy 86.189946 -339.292924) (xy 86.161118 -339.293454) (xy 86.133868 -339.2929)
			(xy 86.079921 -339.285146) (xy 86.027628 -339.269793) (xy 85.978051 -339.247155) (xy 85.932201 -339.217691)
			(xy 85.891011 -339.182001) (xy 85.85532 -339.140813) (xy 85.825854 -339.094965) (xy 85.803213 -339.045389)
			(xy 85.787858 -338.993096) (xy 85.780101 -338.93915) (xy 85.511686 -338.93915) (xy 85.491289 -338.983346)
			(xy 85.461336 -339.029414) (xy 85.443568 -339.050376) (xy 85.443314 -339.05063) (xy 85.437752 -339.057734)
			(xy 85.43149 -339.074637) (xy 85.431122 -339.08365) (xy 85.431122 -339.151214) (xy 85.431467 -339.160232)
			(xy 85.437722 -339.177149) (xy 85.443314 -339.184234) (xy 85.443822 -339.184742) (xy 85.461575 -339.205673)
			(xy 85.491454 -339.25171) (xy 85.514416 -339.301559) (xy 85.529986 -339.354188) (xy 85.537842 -339.408506)
			(xy 85.53831 -339.435948) (xy 85.537824 -339.463199) (xy 85.530068 -339.517147) (xy 85.514713 -339.569442)
			(xy 85.492071 -339.619019) (xy 85.462605 -339.664869) (xy 85.426914 -339.70606) (xy 85.385723 -339.741751)
			(xy 85.339873 -339.771217) (xy 85.290296 -339.793859) (xy 85.238001 -339.809214) (xy 85.184053 -339.81697)
			(xy 85.129551 -339.81697) (xy 85.075603 -339.809214) (xy 85.023308 -339.793859) (xy 84.973731 -339.771217)
			(xy 84.927881 -339.741751) (xy 84.88669 -339.70606) (xy 84.850999 -339.664869) (xy 84.821533 -339.619019)
			(xy 84.798891 -339.569442) (xy 84.783536 -339.517147) (xy 84.77578 -339.463199) (xy 84.775294 -339.435948)
			(xy 79.056282 -339.435948) (xy 79.047365 -339.466318) (xy 79.024723 -339.515895) (xy 78.995257 -339.561745)
			(xy 78.959566 -339.602936) (xy 78.918375 -339.638627) (xy 78.872525 -339.668093) (xy 78.822948 -339.690735)
			(xy 78.770653 -339.70609) (xy 78.716705 -339.713846) (xy 78.662203 -339.713846) (xy 78.608255 -339.70609)
			(xy 78.55596 -339.690735) (xy 78.506383 -339.668093) (xy 78.460533 -339.638627) (xy 78.419342 -339.602936)
			(xy 78.383651 -339.561745) (xy 78.354185 -339.515895) (xy 78.331543 -339.466318) (xy 78.316188 -339.414023)
			(xy 78.308432 -339.360075) (xy 78.307946 -339.332824) (xy 78.308586 -339.30126) (xy 78.31898 -339.238994)
			(xy 78.339474 -339.179286) (xy 78.35392 -339.151214) (xy 78.358746 -339.142324) (xy 78.360778 -339.122766)
			(xy 78.337918 -339.04428) (xy 78.334671 -339.03486) (xy 78.322259 -339.0193) (xy 78.313788 -339.014054)
			(xy 78.306422 -339.00999) (xy 78.296516 -339.004148) (xy 78.274672 -339.002116) (xy 78.17993 -339.035644)
			(xy 78.164182 -339.051138) (xy 78.160118 -339.061552) (xy 78.149451 -339.088341) (xy 78.121157 -339.138581)
			(xy 78.085622 -339.183989) (xy 78.043656 -339.22353) (xy 77.996215 -339.256302) (xy 77.94438 -339.281558)
			(xy 77.889334 -339.298722) (xy 77.832332 -339.307403) (xy 77.803502 -339.307932) (xy 77.776251 -339.307421)
			(xy 77.722303 -339.299665) (xy 77.670008 -339.28431) (xy 77.620431 -339.261669) (xy 77.57458 -339.232203)
			(xy 77.53339 -339.196511) (xy 77.497699 -339.155321) (xy 77.468232 -339.109471) (xy 77.445591 -339.059894)
			(xy 77.430236 -339.007599) (xy 77.422479 -338.953651) (xy 77.154055 -338.953651) (xy 77.133671 -338.997823)
			(xy 77.103719 -339.043892) (xy 77.085952 -339.064854) (xy 77.085698 -339.065108) (xy 77.080102 -339.072188)
			(xy 77.073861 -339.08911) (xy 77.073506 -339.098128) (xy 77.073506 -339.165692) (xy 77.073865 -339.174709)
			(xy 77.080111 -339.191626) (xy 77.085698 -339.198712) (xy 77.086206 -339.19922) (xy 77.103946 -339.220161)
			(xy 77.133827 -339.266195) (xy 77.156792 -339.316042) (xy 77.172365 -339.368668) (xy 77.180224 -339.422985)
			(xy 77.180694 -339.450426) (xy 77.180208 -339.477677) (xy 77.172452 -339.531625) (xy 77.157097 -339.58392)
			(xy 77.134455 -339.633497) (xy 77.104989 -339.679347) (xy 77.069298 -339.720538) (xy 77.028107 -339.756229)
			(xy 76.982257 -339.785695) (xy 76.93268 -339.808337) (xy 76.880385 -339.823692) (xy 76.826437 -339.831448)
			(xy 76.771935 -339.831448) (xy 76.717987 -339.823692) (xy 76.665692 -339.808337) (xy 76.616115 -339.785695)
			(xy 76.570265 -339.756229) (xy 76.529074 -339.720538) (xy 76.493383 -339.679347) (xy 76.463917 -339.633497)
			(xy 76.441275 -339.58392) (xy 76.42592 -339.531625) (xy 76.418164 -339.477677) (xy 76.417678 -339.450426)
			(xy 70.698535 -339.450426) (xy 70.691781 -339.47343) (xy 70.669139 -339.523007) (xy 70.639673 -339.568857)
			(xy 70.603982 -339.610048) (xy 70.562791 -339.645739) (xy 70.516941 -339.675205) (xy 70.467364 -339.697847)
			(xy 70.415069 -339.713202) (xy 70.361121 -339.720958) (xy 70.306619 -339.720958) (xy 70.252671 -339.713202)
			(xy 70.200376 -339.697847) (xy 70.150799 -339.675205) (xy 70.104949 -339.645739) (xy 70.063758 -339.610048)
			(xy 70.028067 -339.568857) (xy 69.998601 -339.523007) (xy 69.975959 -339.47343) (xy 69.960604 -339.421135)
			(xy 69.952848 -339.367187) (xy 69.952362 -339.339936) (xy 69.953016 -339.308373) (xy 69.963407 -339.246108)
			(xy 69.983894 -339.186399) (xy 69.998336 -339.158326) (xy 70.003162 -339.149436) (xy 70.005194 -339.129878)
			(xy 69.982334 -339.051392) (xy 69.979113 -339.04196) (xy 69.966684 -339.026404) (xy 69.958204 -339.021166)
			(xy 69.950838 -339.017102) (xy 69.940932 -339.01126) (xy 69.919088 -339.009228) (xy 69.824346 -339.042756)
			(xy 69.808598 -339.05825) (xy 69.804534 -339.068664) (xy 69.79386 -339.095449) (xy 69.765567 -339.145689)
			(xy 69.730032 -339.191097) (xy 69.688066 -339.230637) (xy 69.640626 -339.263409) (xy 69.588793 -339.288665)
			(xy 69.533749 -339.305831) (xy 69.476747 -339.314514) (xy 69.447918 -339.315044) (xy 69.420667 -339.31451)
			(xy 69.366719 -339.306756) (xy 69.314424 -339.291403) (xy 69.264846 -339.268763) (xy 69.218995 -339.239299)
			(xy 69.177804 -339.203608) (xy 69.142112 -339.162419) (xy 69.112645 -339.11657) (xy 69.090004 -339.066993)
			(xy 69.074648 -339.014699) (xy 69.066891 -338.960751) (xy 68.798496 -338.960751) (xy 68.778232 -339.004729)
			(xy 68.748349 -339.050761) (xy 68.730622 -339.071712) (xy 68.730114 -339.07222) (xy 68.724531 -339.079307)
			(xy 68.718294 -339.096225) (xy 68.717922 -339.10524) (xy 68.717922 -339.172804) (xy 68.718282 -339.18182)
			(xy 68.724533 -339.198734) (xy 68.730114 -339.205824) (xy 68.730368 -339.206078) (xy 68.748133 -339.227041)
			(xy 68.778079 -339.273111) (xy 68.801098 -339.323004) (xy 68.816713 -339.375686) (xy 68.824599 -339.430064)
			(xy 68.82511 -339.457538) (xy 68.824529 -339.487564) (xy 68.815079 -339.54687) (xy 68.796449 -339.60396)
			(xy 68.769101 -339.657425) (xy 68.73371 -339.705942) (xy 68.712842 -339.72754) (xy 68.705997 -339.734939)
			(xy 68.698271 -339.753537) (xy 68.697856 -339.763608) (xy 68.697856 -340.400894) (xy 68.697246 -340.425878)
			(xy 68.687505 -340.474887) (xy 68.668397 -340.521057) (xy 68.640655 -340.562615) (xy 68.623434 -340.580726)
			(xy 66.622422 -342.581738) (xy 66.615579 -342.589137) (xy 66.607855 -342.607736) (xy 66.607436 -342.617806)
			(xy 66.607436 -342.825832) (xy 100.622606 -342.825832) (xy 100.626677 -342.77021) (xy 100.638803 -342.715773)
			(xy 100.658726 -342.663682) (xy 100.686022 -342.615047) (xy 100.720108 -342.570904) (xy 100.760257 -342.532195)
			(xy 100.805615 -342.499744) (xy 100.855215 -342.474243) (xy 100.907999 -342.456236) (xy 100.962842 -342.446106)
			(xy 101.018576 -342.444069) (xy 101.074013 -342.450169) (xy 101.12797 -342.464275) (xy 101.179299 -342.486087)
			(xy 101.226905 -342.515141) (xy 101.269773 -342.550816) (xy 101.30699 -342.592353) (xy 101.337763 -342.638866)
			(xy 101.361435 -342.689363) (xy 101.377503 -342.74277) (xy 101.385623 -342.797946) (xy 101.386132 -342.825832)
			(xy 101.385623 -342.853718) (xy 101.377503 -342.908894) (xy 101.361435 -342.962301) (xy 101.337763 -343.012798)
			(xy 101.30699 -343.059311) (xy 101.269773 -343.100848) (xy 101.226905 -343.136523) (xy 101.179299 -343.165577)
			(xy 101.12797 -343.187389) (xy 101.074013 -343.201495) (xy 101.018576 -343.207595) (xy 100.962842 -343.205558)
			(xy 100.907999 -343.195428) (xy 100.855215 -343.177421) (xy 100.805615 -343.15192) (xy 100.760257 -343.119469)
			(xy 100.720108 -343.08076) (xy 100.686022 -343.036617) (xy 100.658726 -342.987982) (xy 100.638803 -342.935891)
			(xy 100.626677 -342.881454) (xy 100.622606 -342.825832) (xy 66.607436 -342.825832) (xy 66.607436 -343.721182)
			(xy 100.043486 -343.721182) (xy 100.047557 -343.66556) (xy 100.059683 -343.611123) (xy 100.079606 -343.559032)
			(xy 100.106902 -343.510397) (xy 100.140988 -343.466254) (xy 100.181137 -343.427545) (xy 100.226495 -343.395094)
			(xy 100.276095 -343.369593) (xy 100.328879 -343.351586) (xy 100.383722 -343.341456) (xy 100.439456 -343.339419)
			(xy 100.494893 -343.345519) (xy 100.54885 -343.359625) (xy 100.600179 -343.381437) (xy 100.647785 -343.410491)
			(xy 100.690653 -343.446166) (xy 100.72787 -343.487703) (xy 100.758643 -343.534216) (xy 100.782315 -343.584713)
			(xy 100.798383 -343.63812) (xy 100.806503 -343.693296) (xy 100.807012 -343.721182) (xy 100.806503 -343.749068)
			(xy 100.798383 -343.804244) (xy 100.782315 -343.857651) (xy 100.758643 -343.908148) (xy 100.72787 -343.954661)
			(xy 100.690653 -343.996198) (xy 100.647785 -344.031873) (xy 100.600179 -344.060927) (xy 100.54885 -344.082739)
			(xy 100.494893 -344.096845) (xy 100.439456 -344.102945) (xy 100.383722 -344.100908) (xy 100.328879 -344.090778)
			(xy 100.276095 -344.072771) (xy 100.226495 -344.04727) (xy 100.181137 -344.014819) (xy 100.140988 -343.97611)
			(xy 100.106902 -343.931967) (xy 100.079606 -343.883332) (xy 100.059683 -343.831241) (xy 100.047557 -343.776804)
			(xy 100.043486 -343.721182) (xy 66.607436 -343.721182) (xy 66.607436 -344.396822) (xy 101.382322 -344.396822)
			(xy 101.382816 -344.369348) (xy 101.390705 -344.314968) (xy 101.406323 -344.262286) (xy 101.429346 -344.212393)
			(xy 101.459297 -344.166324) (xy 101.477064 -344.145362) (xy 101.477318 -344.145108) (xy 101.482909 -344.138025)
			(xy 101.489153 -344.121105) (xy 101.48951 -344.112088) (xy 101.48951 -344.044524) (xy 101.489139 -344.035509)
			(xy 101.482901 -344.018592) (xy 101.477318 -344.011504) (xy 101.47681 -344.010996) (xy 101.45908 -343.990047)
			(xy 101.429197 -343.944015) (xy 101.40623 -343.894171) (xy 101.390654 -343.841546) (xy 101.382793 -343.787231)
			(xy 101.382322 -343.75979) (xy 101.382808 -343.732539) (xy 101.390564 -343.678591) (xy 101.405919 -343.626296)
			(xy 101.428561 -343.576719) (xy 101.458027 -343.530869) (xy 101.493718 -343.489678) (xy 101.534909 -343.453987)
			(xy 101.580759 -343.424521) (xy 101.630336 -343.401879) (xy 101.682631 -343.386524) (xy 101.736579 -343.378768)
			(xy 101.791081 -343.378768) (xy 101.845029 -343.386524) (xy 101.897324 -343.401879) (xy 101.946901 -343.424521)
			(xy 101.992751 -343.453987) (xy 102.033942 -343.489678) (xy 102.069633 -343.530869) (xy 102.099099 -343.576719)
			(xy 102.121741 -343.626296) (xy 102.137096 -343.678591) (xy 102.144852 -343.732539) (xy 102.145338 -343.75979)
			(xy 102.144836 -343.787264) (xy 102.136947 -343.841643) (xy 102.12133 -343.894324) (xy 102.118686 -343.900054)
			(xy 102.387075 -343.900054) (xy 102.387075 -343.845546) (xy 102.394833 -343.791594) (xy 102.410191 -343.739296)
			(xy 102.432835 -343.689715) (xy 102.462306 -343.643862) (xy 102.498003 -343.60267) (xy 102.539199 -343.566979)
			(xy 102.585055 -343.537513) (xy 102.634639 -343.514875) (xy 102.686939 -343.499523) (xy 102.740892 -343.491772)
			(xy 102.768146 -343.491312) (xy 102.7684 -343.491312) (xy 102.793604 -343.491715) (xy 102.843571 -343.498354)
			(xy 102.892226 -343.51153) (xy 102.938716 -343.531011) (xy 102.960678 -343.543382) (xy 102.970584 -343.549224)
			(xy 102.992428 -343.551256) (xy 103.08717 -343.517728) (xy 103.102918 -343.502234) (xy 103.106982 -343.49182)
			(xy 103.117687 -343.465047) (xy 103.145972 -343.414804) (xy 103.1815 -343.369393) (xy 103.22346 -343.32985)
			(xy 103.270896 -343.297075) (xy 103.322727 -343.271817) (xy 103.377769 -343.254651) (xy 103.434769 -343.245969)
			(xy 103.463598 -343.24544) (xy 103.490853 -343.245857) (xy 103.544808 -343.253615) (xy 103.59711 -343.268973)
			(xy 103.646693 -343.291619) (xy 103.692548 -343.321092) (xy 103.733742 -343.35679) (xy 103.769436 -343.397988)
			(xy 103.798903 -343.443847) (xy 103.801787 -343.450164) (xy 105.961942 -343.450164) (xy 105.962437 -343.42259)
			(xy 105.970382 -343.368018) (xy 105.9861 -343.315158) (xy 106.009264 -343.265112) (xy 106.039392 -343.218922)
			(xy 106.075856 -343.17755) (xy 106.096562 -343.159334) (xy 106.104632 -343.151775) (xy 106.113987 -343.131766)
			(xy 106.114596 -343.120726) (xy 106.114596 -343.043002) (xy 106.114028 -343.031953) (xy 106.104663 -343.011932)
			(xy 106.096562 -343.004394) (xy 106.075837 -342.986198) (xy 106.03937 -342.944825) (xy 106.00924 -342.898632)
			(xy 105.986077 -342.848581) (xy 105.970363 -342.795716) (xy 105.962426 -342.741139) (xy 105.961942 -342.713564)
			(xy 105.962322 -342.686308) (xy 105.970085 -342.632351) (xy 105.985448 -342.580049) (xy 106.008098 -342.530465)
			(xy 106.037575 -342.48461) (xy 106.073277 -342.443416) (xy 106.114479 -342.407723) (xy 106.160341 -342.378257)
			(xy 106.20993 -342.355618) (xy 106.262236 -342.340266) (xy 106.316194 -342.332515) (xy 106.34345 -342.332056)
			(xy 106.375072 -342.33266) (xy 106.437445 -342.343115) (xy 106.497234 -342.363729) (xy 106.525314 -342.378284)
			(xy 106.53395 -342.382856) (xy 106.553254 -342.385142) (xy 106.639868 -342.362028) (xy 106.655362 -342.350344)
			(xy 106.660442 -342.341962) (xy 106.676797 -342.316317) (xy 106.716359 -342.270121) (xy 106.739182 -342.250014)
			(xy 106.747248 -342.24245) (xy 106.756608 -342.222446) (xy 106.757216 -342.211406) (xy 106.757216 -342.133682)
			(xy 106.756629 -342.122634) (xy 106.74728 -342.102611) (xy 106.739182 -342.095074) (xy 106.718451 -342.076884)
			(xy 106.681983 -342.03551) (xy 106.651854 -341.989316) (xy 106.628692 -341.939264) (xy 106.61298 -341.886398)
			(xy 106.605045 -341.83182) (xy 106.604562 -341.804244) (xy 106.605048 -341.776993) (xy 106.612804 -341.723045)
			(xy 106.628159 -341.67075) (xy 106.650801 -341.621173) (xy 106.680267 -341.575323) (xy 106.715958 -341.534132)
			(xy 106.757149 -341.498441) (xy 106.802999 -341.468975) (xy 106.852576 -341.446333) (xy 106.904871 -341.430978)
			(xy 106.958819 -341.423222) (xy 107.013321 -341.423222) (xy 107.067269 -341.430978) (xy 107.119564 -341.446333)
			(xy 107.169141 -341.468975) (xy 107.214991 -341.498441) (xy 107.256182 -341.534132) (xy 107.291873 -341.575323)
			(xy 107.321339 -341.621173) (xy 107.343981 -341.67075) (xy 107.359336 -341.723045) (xy 107.367092 -341.776993)
			(xy 107.367578 -341.804244) (xy 107.367081 -341.831818) (xy 107.359136 -341.886389) (xy 107.343418 -341.939249)
			(xy 107.320254 -341.989295) (xy 107.290126 -342.035486) (xy 107.253663 -342.076858) (xy 107.232958 -342.095074)
			(xy 107.224887 -342.102633) (xy 107.215532 -342.122642) (xy 107.214924 -342.133682) (xy 107.214924 -342.211406)
			(xy 107.215537 -342.22245) (xy 107.22487 -342.242472) (xy 107.232958 -342.250014) (xy 107.253671 -342.268224)
			(xy 107.290143 -342.309592) (xy 107.320276 -342.355781) (xy 107.343442 -342.40583) (xy 107.359157 -342.458693)
			(xy 107.367094 -342.513269) (xy 107.367578 -342.540844) (xy 107.367008 -342.570786) (xy 107.357634 -342.629932)
			(xy 107.339138 -342.686889) (xy 107.311974 -342.740259) (xy 107.27681 -342.788732) (xy 107.256072 -342.810338)
			(xy 107.248971 -342.818108) (xy 107.241235 -342.837659) (xy 107.241086 -342.848184) (xy 107.244134 -342.922606)
			(xy 107.245046 -342.933142) (xy 107.254233 -342.952166) (xy 107.261914 -342.959436) (xy 107.282469 -342.977667)
			(xy 107.318675 -343.018991) (xy 107.34858 -343.065079) (xy 107.371568 -343.114979) (xy 107.387162 -343.167661)
			(xy 107.39504 -343.222034) (xy 107.395518 -343.249504) (xy 107.395049 -343.277078) (xy 107.387096 -343.331651)
			(xy 107.371371 -343.38451) (xy 107.348202 -343.434556) (xy 107.31807 -343.480746) (xy 107.281604 -343.522118)
			(xy 107.260898 -343.540334) (xy 107.252807 -343.547875) (xy 107.243462 -343.567897) (xy 107.242864 -343.578942)
			(xy 107.242864 -343.656666) (xy 107.243431 -343.667716) (xy 107.252795 -343.687738) (xy 107.260898 -343.695274)
			(xy 107.281599 -343.713496) (xy 107.318071 -343.754862) (xy 107.348204 -343.80105) (xy 107.371371 -343.851096)
			(xy 107.38709 -343.903957) (xy 107.395032 -343.95853) (xy 107.395518 -343.986104) (xy 107.395032 -344.013355)
			(xy 107.387276 -344.067303) (xy 107.371921 -344.119598) (xy 107.349279 -344.169175) (xy 107.319813 -344.215025)
			(xy 107.284122 -344.256216) (xy 107.242931 -344.291907) (xy 107.197081 -344.321373) (xy 107.147504 -344.344015)
			(xy 107.095209 -344.35937) (xy 107.041261 -344.367126) (xy 106.986759 -344.367126) (xy 106.932811 -344.35937)
			(xy 106.880516 -344.344015) (xy 106.830939 -344.321373) (xy 106.785089 -344.291907) (xy 106.743898 -344.256216)
			(xy 106.708207 -344.215025) (xy 106.678741 -344.169175) (xy 106.656099 -344.119598) (xy 106.640744 -344.067303)
			(xy 106.632988 -344.013355) (xy 106.632502 -343.986104) (xy 106.632502 -343.985342) (xy 106.632746 -343.966675)
			(xy 106.636431 -343.929523) (xy 106.639868 -343.911174) (xy 106.642662 -343.897204) (xy 106.63301 -343.870534)
			(xy 106.540046 -343.796366) (xy 106.512106 -343.79281) (xy 106.498898 -343.798652) (xy 106.474378 -343.809107)
			(xy 106.423142 -343.823814) (xy 106.370356 -343.831233) (xy 106.343704 -343.831672) (xy 106.34345 -343.831672)
			(xy 106.316197 -343.831198) (xy 106.262244 -343.823447) (xy 106.209944 -343.808095) (xy 106.160362 -343.785456)
			(xy 106.114507 -343.75599) (xy 106.073313 -343.720297) (xy 106.037618 -343.679104) (xy 106.008151 -343.63325)
			(xy 105.985509 -343.583669) (xy 105.970156 -343.531369) (xy 105.962403 -343.477417) (xy 105.961942 -343.450164)
			(xy 103.801787 -343.450164) (xy 103.821543 -343.493433) (xy 103.836895 -343.545737) (xy 103.844646 -343.599693)
			(xy 103.845106 -343.626948) (xy 103.844449 -343.658511) (xy 103.834061 -343.720776) (xy 103.813574 -343.780485)
			(xy 103.799132 -343.808558) (xy 103.794306 -343.817448) (xy 103.792274 -343.837006) (xy 103.815134 -343.915492)
			(xy 103.818373 -343.924916) (xy 103.83079 -343.940476) (xy 103.839264 -343.945718) (xy 103.864349 -343.960293)
			(xy 103.910233 -343.995791) (xy 103.95021 -344.037829) (xy 103.983358 -344.085439) (xy 104.008911 -344.13752)
			(xy 104.026281 -344.192871) (xy 104.035065 -344.250214) (xy 104.035606 -344.27922) (xy 104.03512 -344.306471)
			(xy 104.027364 -344.360419) (xy 104.012009 -344.412714) (xy 103.989367 -344.462291) (xy 103.959901 -344.508141)
			(xy 103.92421 -344.549332) (xy 103.883019 -344.585023) (xy 103.837169 -344.614489) (xy 103.787592 -344.637131)
			(xy 103.735297 -344.652486) (xy 103.681349 -344.660242) (xy 103.626847 -344.660242) (xy 103.572899 -344.652486)
			(xy 103.520604 -344.637131) (xy 103.471027 -344.614489) (xy 103.425177 -344.585023) (xy 103.383986 -344.549332)
			(xy 103.348295 -344.508141) (xy 103.318829 -344.462291) (xy 103.296187 -344.412714) (xy 103.280832 -344.360419)
			(xy 103.273076 -344.306471) (xy 103.27259 -344.27922) (xy 103.273235 -344.247657) (xy 103.283628 -344.185391)
			(xy 103.30412 -344.125682) (xy 103.318564 -344.09761) (xy 103.32339 -344.08872) (xy 103.325422 -344.069162)
			(xy 103.302562 -343.990676) (xy 103.299337 -343.981246) (xy 103.28691 -343.96569) (xy 103.278432 -343.96045)
			(xy 103.271066 -343.956386) (xy 103.26116 -343.950544) (xy 103.239316 -343.948512) (xy 103.144574 -343.98204)
			(xy 103.128826 -343.997534) (xy 103.124762 -344.007948) (xy 103.114056 -344.03472) (xy 103.085767 -344.084959)
			(xy 103.050238 -344.130367) (xy 103.008277 -344.169908) (xy 102.960841 -344.202682) (xy 102.909013 -344.227941)
			(xy 102.853972 -344.245109) (xy 102.796974 -344.253796) (xy 102.768146 -344.254328) (xy 102.740892 -344.253828)
			(xy 102.686939 -344.246077) (xy 102.634639 -344.230725) (xy 102.585055 -344.208087) (xy 102.539199 -344.178621)
			(xy 102.498003 -344.14293) (xy 102.462306 -344.101738) (xy 102.432835 -344.055885) (xy 102.410191 -344.006304)
			(xy 102.394833 -343.954006) (xy 102.387075 -343.900054) (xy 102.118686 -343.900054) (xy 102.098309 -343.944217)
			(xy 102.068361 -343.990287) (xy 102.050596 -344.01125) (xy 102.050342 -344.011504) (xy 102.044741 -344.01858)
			(xy 102.038504 -344.035505) (xy 102.03815 -344.044524) (xy 102.03815 -344.112088) (xy 102.038502 -344.121106)
			(xy 102.044752 -344.138023) (xy 102.050342 -344.145108) (xy 102.05085 -344.145616) (xy 102.068579 -344.166566)
			(xy 102.098464 -344.212597) (xy 102.121432 -344.262441) (xy 102.137007 -344.315066) (xy 102.144868 -344.369381)
			(xy 102.145338 -344.396822) (xy 102.144852 -344.424073) (xy 102.137096 -344.478021) (xy 102.121741 -344.530316)
			(xy 102.099099 -344.579893) (xy 102.069633 -344.625743) (xy 102.033942 -344.666934) (xy 101.992751 -344.702625)
			(xy 101.946901 -344.732091) (xy 101.897324 -344.754733) (xy 101.845029 -344.770088) (xy 101.791081 -344.777844)
			(xy 101.736579 -344.777844) (xy 101.682631 -344.770088) (xy 101.630336 -344.754733) (xy 101.580759 -344.732091)
			(xy 101.534909 -344.702625) (xy 101.493718 -344.666934) (xy 101.458027 -344.625743) (xy 101.428561 -344.579893)
			(xy 101.405919 -344.530316) (xy 101.390564 -344.478021) (xy 101.382808 -344.424073) (xy 101.382322 -344.396822)
			(xy 66.607436 -344.396822) (xy 66.607436 -345.237562) (xy 88.93302 -345.237562) (xy 88.933443 -345.210309)
			(xy 88.941205 -345.156357) (xy 88.956566 -345.104059) (xy 88.979214 -345.05448) (xy 89.008687 -345.008629)
			(xy 89.044385 -344.967438) (xy 89.085582 -344.931747) (xy 89.131438 -344.902282) (xy 89.181021 -344.879643)
			(xy 89.233322 -344.864291) (xy 89.287274 -344.856538) (xy 89.314528 -344.856054) (xy 89.339987 -344.856488)
			(xy 89.390452 -344.863253) (xy 89.439569 -344.876671) (xy 89.486464 -344.896505) (xy 89.530304 -344.922402)
			(xy 89.570308 -344.953902) (xy 89.58834 -344.971878) (xy 89.595447 -344.978501) (xy 89.613201 -344.986344)
			(xy 89.622884 -344.987118) (xy 89.702894 -344.989912) (xy 89.721436 -344.983308) (xy 89.728802 -344.976704)
			(xy 89.749893 -344.958526) (xy 89.796364 -344.927857) (xy 89.8468 -344.904269) (xy 89.900128 -344.888262)
			(xy 89.955217 -344.880177) (xy 89.983056 -344.879676) (xy 90.010426 -344.880149) (xy 90.064606 -344.887963)
			(xy 90.117109 -344.903449) (xy 90.166857 -344.92629) (xy 90.212823 -344.956014) (xy 90.233754 -344.973656)
			(xy 90.234008 -344.97391) (xy 90.241087 -344.979507) (xy 90.25801 -344.985747) (xy 90.267028 -344.986102)
			(xy 90.334084 -344.986102) (xy 90.3431 -344.985737) (xy 90.360017 -344.979495) (xy 90.367104 -344.97391)
			(xy 90.367104 -344.973656) (xy 90.367358 -344.973656) (xy 90.388289 -344.956016) (xy 90.434263 -344.926306)
			(xy 90.484011 -344.90347) (xy 90.536511 -344.887979) (xy 90.590687 -344.88015) (xy 90.618056 -344.879676)
			(xy 90.646973 -344.880197) (xy 90.704145 -344.888922) (xy 90.759345 -344.906177) (xy 90.811308 -344.931568)
			(xy 90.858841 -344.964513) (xy 90.900857 -345.004256) (xy 90.919046 -345.026742) (xy 90.926636 -345.035567)
			(xy 90.94755 -345.045739) (xy 90.959178 -345.0463) (xy 91.038934 -345.0463) (xy 91.050566 -345.045766)
			(xy 91.071476 -345.035573) (xy 91.079066 -345.026742) (xy 91.097287 -345.004284) (xy 91.139299 -344.964545)
			(xy 91.186827 -344.931602) (xy 91.238783 -344.906209) (xy 91.293976 -344.888947) (xy 91.351142 -344.880213)
			(xy 91.380056 -344.879676) (xy 91.407426 -344.880149) (xy 91.461606 -344.887963) (xy 91.514109 -344.903449)
			(xy 91.563857 -344.92629) (xy 91.609823 -344.956014) (xy 91.630754 -344.973656) (xy 91.631008 -344.97391)
			(xy 91.638087 -344.979507) (xy 91.65501 -344.985747) (xy 91.664028 -344.986102) (xy 91.731084 -344.986102)
			(xy 91.7401 -344.985737) (xy 91.757017 -344.979495) (xy 91.764104 -344.97391) (xy 91.764104 -344.973656)
			(xy 91.764358 -344.973656) (xy 91.785291 -344.956015) (xy 91.831259 -344.926291) (xy 91.881005 -344.903445)
			(xy 91.933507 -344.887949) (xy 91.987685 -344.88012) (xy 92.042427 -344.88012) (xy 92.096605 -344.887949)
			(xy 92.149107 -344.903445) (xy 92.198853 -344.926291) (xy 92.244821 -344.956015) (xy 92.265754 -344.973656)
			(xy 92.266008 -344.97391) (xy 92.273087 -344.979507) (xy 92.29001 -344.985747) (xy 92.299028 -344.986102)
			(xy 92.366084 -344.986102) (xy 92.3751 -344.985737) (xy 92.392017 -344.979495) (xy 92.399104 -344.97391)
			(xy 92.399104 -344.973656) (xy 92.399358 -344.973656) (xy 92.420289 -344.956016) (xy 92.466263 -344.926306)
			(xy 92.516011 -344.90347) (xy 92.568511 -344.887979) (xy 92.622687 -344.88015) (xy 92.650056 -344.879676)
			(xy 92.677307 -344.880196) (xy 92.731255 -344.887947) (xy 92.783551 -344.903296) (xy 92.83313 -344.925933)
			(xy 92.878982 -344.955395) (xy 92.920175 -344.991082) (xy 92.955869 -345.03227) (xy 92.985339 -345.078117)
			(xy 93.007983 -345.127693) (xy 93.02334 -345.179986) (xy 93.0311 -345.233933) (xy 93.031564 -345.261184)
			(xy 93.031019 -345.289629) (xy 93.022568 -345.345888) (xy 93.00585 -345.400266) (xy 92.981238 -345.451556)
			(xy 92.949277 -345.49862) (xy 92.910677 -345.540411) (xy 92.888816 -345.558618) (xy 92.880986 -345.565633)
			(xy 92.871273 -345.584249) (xy 92.87002 -345.594686) (xy 92.86494 -345.669362) (xy 92.864763 -345.679888)
			(xy 92.871843 -345.699691) (xy 92.878656 -345.707716) (xy 92.898109 -345.72907) (xy 92.930987 -345.776563)
			(xy 92.956328 -345.828471) (xy 92.973551 -345.883606) (xy 92.982263 -345.940709) (xy 92.982796 -345.96959)
			(xy 92.98234 -345.996725) (xy 92.974645 -346.050445) (xy 92.959409 -346.102532) (xy 92.936941 -346.151931)
			(xy 92.907694 -346.197645) (xy 92.89034 -346.21851) (xy 92.890086 -346.218764) (xy 92.884144 -346.226452)
			(xy 92.877994 -346.244864) (xy 92.878148 -346.254578) (xy 92.881958 -346.324936) (xy 92.882979 -346.334743)
			(xy 92.891491 -346.352511) (xy 92.898468 -346.35948) (xy 92.917459 -346.377615) (xy 92.950775 -346.418205)
			(xy 92.978215 -346.462976) (xy 92.999261 -346.511085) (xy 93.013517 -346.561624) (xy 93.020713 -346.61364)
			(xy 93.02115 -346.639896) (xy 93.020619 -346.667145) (xy 93.012864 -346.721089) (xy 92.997511 -346.77338)
			(xy 92.974874 -346.822955) (xy 92.945412 -346.868803) (xy 92.909725 -346.909992) (xy 92.86854 -346.945684)
			(xy 92.822695 -346.975152) (xy 92.773124 -346.997795) (xy 92.720834 -347.013154) (xy 92.666891 -347.020915)
			(xy 92.639642 -347.021404) (xy 92.612273 -347.020912) (xy 92.558095 -347.013101) (xy 92.505592 -346.997617)
			(xy 92.455845 -346.974781) (xy 92.409877 -346.945063) (xy 92.388944 -346.927424) (xy 92.38869 -346.92717)
			(xy 92.381613 -346.92157) (xy 92.364689 -346.915332) (xy 92.35567 -346.914978) (xy 92.288614 -346.914978)
			(xy 92.279598 -346.915347) (xy 92.262682 -346.921587) (xy 92.255594 -346.92717) (xy 92.255594 -346.927424)
			(xy 92.25534 -346.927424) (xy 92.234407 -346.945062) (xy 92.188434 -346.974773) (xy 92.138687 -346.997609)
			(xy 92.086186 -347.0131) (xy 92.032011 -347.020929) (xy 92.004642 -347.021404) (xy 91.978327 -347.020974)
			(xy 91.926197 -347.013731) (xy 91.875553 -346.999405) (xy 91.827355 -346.978265) (xy 91.782512 -346.950713)
			(xy 91.741874 -346.917268) (xy 91.723718 -346.898214) (xy 91.71619 -346.89082) (xy 91.696915 -346.882291)
			(xy 91.68638 -346.881704) (xy 91.611704 -346.881704) (xy 91.601153 -346.882221) (xy 91.581858 -346.890765)
			(xy 91.574366 -346.898214) (xy 91.556223 -346.917282) (xy 91.51559 -346.950737) (xy 91.470747 -346.978294)
			(xy 91.422544 -346.999431) (xy 91.371894 -347.013745) (xy 91.319759 -347.020967) (xy 91.293442 -347.021404)
			(xy 91.266073 -347.020912) (xy 91.211895 -347.013101) (xy 91.159392 -346.997617) (xy 91.109645 -346.974781)
			(xy 91.063677 -346.945063) (xy 91.042744 -346.927424) (xy 91.04249 -346.92717) (xy 91.035413 -346.92157)
			(xy 91.018489 -346.915332) (xy 91.00947 -346.914978) (xy 90.942414 -346.914978) (xy 90.933398 -346.915347)
			(xy 90.916482 -346.921587) (xy 90.909394 -346.92717) (xy 90.909394 -346.927424) (xy 90.90914 -346.927424)
			(xy 90.888207 -346.945065) (xy 90.842239 -346.974789) (xy 90.792493 -346.997635) (xy 90.739991 -347.013131)
			(xy 90.685813 -347.02096) (xy 90.631071 -347.02096) (xy 90.576893 -347.013131) (xy 90.524391 -346.997635)
			(xy 90.474645 -346.974789) (xy 90.428677 -346.945065) (xy 90.407744 -346.927424) (xy 90.40749 -346.92717)
			(xy 90.400413 -346.92157) (xy 90.383489 -346.915332) (xy 90.37447 -346.914978) (xy 90.307414 -346.914978)
			(xy 90.298398 -346.915347) (xy 90.281482 -346.921587) (xy 90.274394 -346.92717) (xy 90.274394 -346.927424)
			(xy 90.27414 -346.927424) (xy 90.253207 -346.945065) (xy 90.207239 -346.974789) (xy 90.157493 -346.997635)
			(xy 90.104991 -347.013131) (xy 90.050813 -347.02096) (xy 89.996071 -347.02096) (xy 89.941893 -347.013131)
			(xy 89.889391 -346.997635) (xy 89.839645 -346.974789) (xy 89.793677 -346.945065) (xy 89.772744 -346.927424)
			(xy 89.77249 -346.92717) (xy 89.765413 -346.92157) (xy 89.748489 -346.915332) (xy 89.73947 -346.914978)
			(xy 89.672414 -346.914978) (xy 89.663398 -346.915347) (xy 89.646482 -346.921587) (xy 89.639394 -346.92717)
			(xy 89.639394 -346.927424) (xy 89.63914 -346.927424) (xy 89.618207 -346.945062) (xy 89.572234 -346.974773)
			(xy 89.522487 -346.997609) (xy 89.469986 -347.0131) (xy 89.415811 -347.020929) (xy 89.388442 -347.021404)
			(xy 89.36119 -347.020906) (xy 89.30724 -347.013154) (xy 89.254943 -346.997803) (xy 89.205362 -346.975165)
			(xy 89.159509 -346.945701) (xy 89.118316 -346.910011) (xy 89.082621 -346.868822) (xy 89.053153 -346.822971)
			(xy 89.03051 -346.773393) (xy 89.015154 -346.721097) (xy 89.007397 -346.667148) (xy 89.006934 -346.639896)
			(xy 89.007433 -346.612763) (xy 89.015116 -346.559044) (xy 89.030342 -346.506957) (xy 89.0528 -346.457557)
			(xy 89.082039 -346.411842) (xy 89.09939 -346.390976) (xy 89.099644 -346.390722) (xy 89.105596 -346.383041)
			(xy 89.111739 -346.364624) (xy 89.111582 -346.354908) (xy 89.107772 -346.28455) (xy 89.1067 -346.274752)
			(xy 89.098224 -346.256981) (xy 89.091262 -346.250006) (xy 89.07227 -346.231872) (xy 89.038953 -346.191283)
			(xy 89.011512 -346.146511) (xy 88.990466 -346.098402) (xy 88.976211 -346.047862) (xy 88.969016 -345.995846)
			(xy 88.96858 -345.96959) (xy 88.968982 -345.943757) (xy 88.975961 -345.892564) (xy 88.989789 -345.842783)
			(xy 89.010214 -345.795326) (xy 89.036861 -345.751062) (xy 89.069241 -345.710801) (xy 89.087706 -345.69273)
			(xy 89.08796 -345.692476) (xy 89.095447 -345.684537) (xy 89.103483 -345.664272) (xy 89.103454 -345.65336)
			(xy 89.099644 -345.576144) (xy 89.098606 -345.565329) (xy 89.088744 -345.545991) (xy 89.080594 -345.538806)
			(xy 89.080086 -345.538552) (xy 89.057625 -345.520335) (xy 89.017889 -345.47832) (xy 88.984947 -345.430791)
			(xy 88.959555 -345.378835) (xy 88.942294 -345.323642) (xy 88.933559 -345.266476) (xy 88.93302 -345.237562)
			(xy 66.607436 -345.237562) (xy 66.607436 -346.602558) (xy 66.60787 -346.612623) (xy 66.615604 -346.631209)
			(xy 66.622422 -346.638626) (xy 67.574922 -347.591126) (xy 67.592145 -347.609236) (xy 67.619886 -347.650796)
			(xy 67.638996 -347.696965) (xy 67.648741 -347.745974) (xy 67.649344 -347.770958) (xy 67.649344 -348.89948)
			(xy 81.802478 -348.89948) (xy 81.802982 -348.871033) (xy 81.81144 -348.814772) (xy 81.828164 -348.760392)
			(xy 81.852784 -348.709102) (xy 81.884753 -348.66204) (xy 81.923361 -348.620251) (xy 81.945226 -348.602046)
			(xy 81.953061 -348.595036) (xy 81.962773 -348.576416) (xy 81.964022 -348.565978) (xy 81.969102 -348.491302)
			(xy 81.969289 -348.480776) (xy 81.962201 -348.460973) (xy 81.955386 -348.452948) (xy 81.93597 -348.431562)
			(xy 81.903085 -348.384078) (xy 81.877737 -348.332179) (xy 81.860505 -348.27705) (xy 81.851784 -348.219953)
			(xy 81.851246 -348.191074) (xy 81.851732 -348.163823) (xy 81.859488 -348.109875) (xy 81.874843 -348.05758)
			(xy 81.897485 -348.008003) (xy 81.926951 -347.962153) (xy 81.962642 -347.920962) (xy 82.003833 -347.885271)
			(xy 82.049683 -347.855805) (xy 82.09926 -347.833163) (xy 82.151555 -347.817808) (xy 82.205503 -347.810052)
			(xy 82.260005 -347.810052) (xy 82.313953 -347.817808) (xy 82.366248 -347.833163) (xy 82.415825 -347.855805)
			(xy 82.461675 -347.885271) (xy 82.502866 -347.920962) (xy 82.538557 -347.962153) (xy 82.568023 -348.008003)
			(xy 82.590665 -348.05758) (xy 82.60602 -348.109875) (xy 82.613776 -348.163823) (xy 82.614262 -348.191074)
			(xy 82.613711 -348.219519) (xy 82.605261 -348.275777) (xy 82.588544 -348.330155) (xy 82.563933 -348.381446)
			(xy 82.531973 -348.428509) (xy 82.493375 -348.470301) (xy 82.471514 -348.488508) (xy 82.463647 -348.495487)
			(xy 82.453955 -348.51413) (xy 82.452718 -348.524576) (xy 82.447638 -348.599252) (xy 82.447467 -348.609778)
			(xy 82.454543 -348.62958) (xy 82.461354 -348.637606) (xy 82.480802 -348.658964) (xy 82.513681 -348.706456)
			(xy 82.539022 -348.758363) (xy 82.556247 -348.813497) (xy 82.563515 -348.861126) (xy 84.464144 -348.861126)
			(xy 84.464693 -348.832681) (xy 84.473143 -348.776422) (xy 84.48986 -348.722044) (xy 84.514471 -348.670754)
			(xy 84.546432 -348.62369) (xy 84.585031 -348.581899) (xy 84.606892 -348.563692) (xy 84.61476 -348.556714)
			(xy 84.624452 -348.53807) (xy 84.625688 -348.527624) (xy 84.630768 -348.452948) (xy 84.630938 -348.442422)
			(xy 84.623863 -348.42262) (xy 84.617052 -348.414594) (xy 84.597605 -348.393235) (xy 84.564726 -348.345743)
			(xy 84.539384 -348.293837) (xy 84.522159 -348.238702) (xy 84.513446 -348.181601) (xy 84.512912 -348.15272)
			(xy 84.513398 -348.125469) (xy 84.521154 -348.071521) (xy 84.536509 -348.019226) (xy 84.559151 -347.969649)
			(xy 84.588617 -347.923799) (xy 84.624308 -347.882608) (xy 84.665499 -347.846917) (xy 84.711349 -347.817451)
			(xy 84.760926 -347.794809) (xy 84.813221 -347.779454) (xy 84.867169 -347.771698) (xy 84.921671 -347.771698)
			(xy 84.975619 -347.779454) (xy 85.027914 -347.794809) (xy 85.077491 -347.817451) (xy 85.123341 -347.846917)
			(xy 85.164532 -347.882608) (xy 85.200223 -347.923799) (xy 85.229689 -347.969649) (xy 85.252331 -348.019226)
			(xy 85.267686 -348.071521) (xy 85.275442 -348.125469) (xy 85.275928 -348.15272) (xy 85.275422 -348.181167)
			(xy 85.266964 -348.237428) (xy 85.25024 -348.291807) (xy 85.22562 -348.343098) (xy 85.193652 -348.39016)
			(xy 85.155045 -348.431949) (xy 85.13318 -348.450154) (xy 85.125346 -348.457165) (xy 85.115633 -348.475784)
			(xy 85.114384 -348.486222) (xy 85.109304 -348.560898) (xy 85.109116 -348.571424) (xy 85.116205 -348.591227)
			(xy 85.12302 -348.599252) (xy 85.142437 -348.620638) (xy 85.175321 -348.668121) (xy 85.200669 -348.720021)
			(xy 85.217901 -348.77515) (xy 85.226622 -348.832247) (xy 85.22716 -348.861126) (xy 85.226675 -348.88826)
			(xy 85.218989 -348.94198) (xy 85.20376 -348.994066) (xy 85.181298 -349.043466) (xy 85.152056 -349.089181)
			(xy 85.134704 -349.110046) (xy 85.13445 -349.1103) (xy 85.128487 -349.117974) (xy 85.122351 -349.136397)
			(xy 85.122512 -349.146114) (xy 85.126322 -349.216472) (xy 85.127385 -349.226271) (xy 85.135868 -349.244041)
			(xy 85.142832 -349.251016) (xy 85.161804 -349.26917) (xy 85.19512 -349.309756) (xy 85.222561 -349.354524)
			(xy 85.24361 -349.40263) (xy 85.257871 -349.453165) (xy 85.265073 -349.505178) (xy 85.265514 -349.531432)
			(xy 85.265084 -349.557607) (xy 85.257906 -349.609464) (xy 85.243704 -349.659852) (xy 85.222744 -349.707825)
			(xy 85.195421 -349.75248) (xy 85.162246 -349.792978) (xy 85.14334 -349.811086) (xy 85.135996 -349.818627)
			(xy 85.127606 -349.83791) (xy 85.127084 -349.848424) (xy 85.127084 -349.922846) (xy 85.127591 -349.933366)
			(xy 85.135975 -349.952657) (xy 85.14334 -349.960184) (xy 85.162244 -349.978296) (xy 85.195432 -350.018785)
			(xy 85.222764 -350.063437) (xy 85.243724 -350.11141) (xy 85.25792 -350.161801) (xy 85.265082 -350.213662)
			(xy 85.265514 -350.239838) (xy 85.265028 -350.267089) (xy 85.257272 -350.321037) (xy 85.241917 -350.373332)
			(xy 85.219275 -350.422909) (xy 85.189809 -350.468759) (xy 85.154118 -350.50995) (xy 85.112927 -350.545641)
			(xy 85.067077 -350.575107) (xy 85.0175 -350.597749) (xy 84.965205 -350.613104) (xy 84.911257 -350.62086)
			(xy 84.856755 -350.62086) (xy 84.802807 -350.613104) (xy 84.750512 -350.597749) (xy 84.700935 -350.575107)
			(xy 84.655085 -350.545641) (xy 84.613894 -350.50995) (xy 84.578203 -350.468759) (xy 84.548737 -350.422909)
			(xy 84.526095 -350.373332) (xy 84.51074 -350.321037) (xy 84.502984 -350.267089) (xy 84.502498 -350.239838)
			(xy 84.502904 -350.213662) (xy 84.510086 -350.161804) (xy 84.524293 -350.111415) (xy 84.545257 -350.063443)
			(xy 84.572585 -350.018788) (xy 84.605763 -349.978291) (xy 84.624672 -349.960184) (xy 84.632031 -349.952655)
			(xy 84.640412 -349.933363) (xy 84.640928 -349.922846) (xy 84.640928 -349.848424) (xy 84.640462 -349.837899)
			(xy 84.632052 -349.818606) (xy 84.624672 -349.811086) (xy 84.605736 -349.793006) (xy 84.572555 -349.752508)
			(xy 84.545229 -349.707849) (xy 84.524274 -349.65987) (xy 84.510085 -349.609474) (xy 84.502927 -349.55761)
			(xy 84.502498 -349.531432) (xy 84.502968 -349.504298) (xy 84.51066 -349.450578) (xy 84.525892 -349.398491)
			(xy 84.548357 -349.349092) (xy 84.577601 -349.303377) (xy 84.594954 -349.282512) (xy 84.595208 -349.282258)
			(xy 84.60114 -349.274563) (xy 84.607296 -349.256157) (xy 84.607146 -349.246444) (xy 84.603336 -349.176086)
			(xy 84.602306 -349.166281) (xy 84.593801 -349.148512) (xy 84.586826 -349.141542) (xy 84.567845 -349.123397)
			(xy 84.534528 -349.08281) (xy 84.507087 -349.03804) (xy 84.486039 -348.989933) (xy 84.471781 -348.939396)
			(xy 84.464582 -348.887381) (xy 84.464144 -348.861126) (xy 82.563515 -348.861126) (xy 82.56496 -348.870599)
			(xy 82.565494 -348.89948) (xy 82.565032 -348.926614) (xy 82.557339 -348.980335) (xy 82.542105 -349.032421)
			(xy 82.519638 -349.081821) (xy 82.490392 -349.127535) (xy 82.473038 -349.1484) (xy 82.472784 -349.148654)
			(xy 82.466846 -349.156345) (xy 82.460694 -349.174754) (xy 82.460846 -349.184468) (xy 82.464656 -349.254826)
			(xy 82.465682 -349.264632) (xy 82.47419 -349.282401) (xy 82.481166 -349.28937) (xy 82.500152 -349.307511)
			(xy 82.533468 -349.348099) (xy 82.560909 -349.392869) (xy 82.581956 -349.440977) (xy 82.596213 -349.491515)
			(xy 82.60341 -349.543531) (xy 82.603848 -349.569786) (xy 82.603378 -349.597599) (xy 82.595301 -349.652636)
			(xy 82.579317 -349.705916) (xy 82.555764 -349.756309) (xy 82.525142 -349.802748) (xy 82.4881 -349.844246)
			(xy 82.445423 -349.879925) (xy 82.421984 -349.894906) (xy 82.410554 -349.901764) (xy 82.397854 -349.924624)
			(xy 82.3976 -350.0247) (xy 82.397893 -350.033379) (xy 82.403646 -350.049756) (xy 82.414528 -350.063278)
			(xy 82.42173 -350.068134) (xy 82.421984 -350.068134) (xy 82.445372 -350.083138) (xy 82.487977 -350.118807)
			(xy 82.524956 -350.16028) (xy 82.555528 -350.206678) (xy 82.579045 -350.257021) (xy 82.59501 -350.310243)
			(xy 82.603085 -350.365218) (xy 82.603594 -350.393) (xy 82.603108 -350.420251) (xy 82.595352 -350.474199)
			(xy 82.579997 -350.526494) (xy 82.557355 -350.576071) (xy 82.527889 -350.621921) (xy 82.492198 -350.663112)
			(xy 82.451007 -350.698803) (xy 82.405157 -350.728269) (xy 82.35558 -350.750911) (xy 82.303285 -350.766266)
			(xy 82.249337 -350.774022) (xy 82.194835 -350.774022) (xy 82.140887 -350.766266) (xy 82.088592 -350.750911)
			(xy 82.039015 -350.728269) (xy 81.993165 -350.698803) (xy 81.951974 -350.663112) (xy 81.916283 -350.621921)
			(xy 81.886817 -350.576071) (xy 81.864175 -350.526494) (xy 81.84882 -350.474199) (xy 81.841064 -350.420251)
			(xy 81.840578 -350.393) (xy 81.841025 -350.365186) (xy 81.849104 -350.310148) (xy 81.865092 -350.256867)
			(xy 81.888648 -350.206473) (xy 81.919274 -350.160034) (xy 81.95632 -350.118537) (xy 81.999001 -350.082859)
			(xy 82.022442 -350.06788) (xy 82.033872 -350.061022) (xy 82.046572 -350.038162) (xy 82.046826 -349.938086)
			(xy 82.046531 -349.929407) (xy 82.040776 -349.913032) (xy 82.029896 -349.899509) (xy 82.022696 -349.894652)
			(xy 82.022442 -349.894652) (xy 81.999053 -349.879648) (xy 81.956447 -349.84398) (xy 81.919467 -349.802508)
			(xy 81.888895 -349.756109) (xy 81.865378 -349.705766) (xy 81.849414 -349.652544) (xy 81.84134 -349.597568)
			(xy 81.840832 -349.569786) (xy 81.841326 -349.542653) (xy 81.84901 -349.488933) (xy 81.864237 -349.436847)
			(xy 81.886697 -349.387447) (xy 81.915937 -349.341731) (xy 81.933288 -349.320866) (xy 81.933542 -349.320612)
			(xy 81.939499 -349.312934) (xy 81.945639 -349.294515) (xy 81.94548 -349.284798) (xy 81.94167 -349.21444)
			(xy 81.940604 -349.204641) (xy 81.932123 -349.186871) (xy 81.92516 -349.179896) (xy 81.906163 -349.161767)
			(xy 81.872846 -349.121177) (xy 81.845406 -349.076404) (xy 81.824361 -349.028294) (xy 81.810107 -348.977753)
			(xy 81.802913 -348.925736) (xy 81.802478 -348.89948) (xy 67.649344 -348.89948) (xy 67.649344 -350.443546)
			(xy 67.648738 -350.468532) (xy 67.639005 -350.517545) (xy 67.619903 -350.563721) (xy 67.592164 -350.605286)
			(xy 67.574922 -350.623378) (xy 66.560446 -351.637854) (xy 74.429874 -351.637854) (xy 74.430361 -351.609407)
			(xy 74.438823 -351.553145) (xy 74.455551 -351.498765) (xy 74.480174 -351.447474) (xy 74.512146 -351.400413)
			(xy 74.550756 -351.358624) (xy 74.572622 -351.34042) (xy 74.580467 -351.333419) (xy 74.590174 -351.314793)
			(xy 74.591418 -351.304352) (xy 74.596498 -351.229676) (xy 74.596645 -351.219152) (xy 74.589585 -351.199351)
			(xy 74.582782 -351.191322) (xy 74.563353 -351.169947) (xy 74.53047 -351.12246) (xy 74.505125 -351.070558)
			(xy 74.487896 -351.015427) (xy 74.479178 -350.958328) (xy 74.478642 -350.929448) (xy 74.479128 -350.902197)
			(xy 74.486884 -350.848249) (xy 74.502239 -350.795954) (xy 74.524881 -350.746377) (xy 74.554347 -350.700527)
			(xy 74.590038 -350.659336) (xy 74.631229 -350.623645) (xy 74.677079 -350.594179) (xy 74.726656 -350.571537)
			(xy 74.778951 -350.556182) (xy 74.832899 -350.548426) (xy 74.887401 -350.548426) (xy 74.941349 -350.556182)
			(xy 74.993644 -350.571537) (xy 75.043221 -350.594179) (xy 75.089071 -350.623645) (xy 75.130262 -350.659336)
			(xy 75.165953 -350.700527) (xy 75.195419 -350.746377) (xy 75.218061 -350.795954) (xy 75.233416 -350.848249)
			(xy 75.241172 -350.902197) (xy 75.241658 -350.929448) (xy 75.24116 -350.957895) (xy 75.232699 -351.014156)
			(xy 75.215973 -351.068535) (xy 75.191351 -351.119825) (xy 75.159382 -351.166887) (xy 75.120775 -351.208677)
			(xy 75.09891 -351.226882) (xy 75.091053 -351.233871) (xy 75.081355 -351.252507) (xy 75.080114 -351.26295)
			(xy 75.075034 -351.337626) (xy 75.074878 -351.348151) (xy 75.081943 -351.367953) (xy 75.08875 -351.37598)
			(xy 75.108185 -351.39735) (xy 75.141066 -351.444838) (xy 75.16641 -351.496742) (xy 75.183637 -351.551874)
			(xy 75.190908 -351.5995) (xy 77.09154 -351.5995) (xy 77.092072 -351.571055) (xy 77.100526 -351.514795)
			(xy 77.117246 -351.460417) (xy 77.141861 -351.409126) (xy 77.173824 -351.362063) (xy 77.212426 -351.320272)
			(xy 77.234288 -351.302066) (xy 77.242125 -351.295058) (xy 77.251835 -351.276436) (xy 77.253084 -351.265998)
			(xy 77.258164 -351.191322) (xy 77.25835 -351.180796) (xy 77.251264 -351.160992) (xy 77.244448 -351.152968)
			(xy 77.224988 -351.13162) (xy 77.192111 -351.084126) (xy 77.166771 -351.032216) (xy 77.14955 -350.977079)
			(xy 77.14084 -350.919976) (xy 77.140308 -350.891094) (xy 77.140794 -350.863843) (xy 77.14855 -350.809895)
			(xy 77.163905 -350.7576) (xy 77.186547 -350.708023) (xy 77.216013 -350.662173) (xy 77.251704 -350.620982)
			(xy 77.292895 -350.585291) (xy 77.338745 -350.555825) (xy 77.388322 -350.533183) (xy 77.440617 -350.517828)
			(xy 77.494565 -350.510072) (xy 77.549067 -350.510072) (xy 77.603015 -350.517828) (xy 77.65531 -350.533183)
			(xy 77.704887 -350.555825) (xy 77.750737 -350.585291) (xy 77.791928 -350.620982) (xy 77.827619 -350.662173)
			(xy 77.857085 -350.708023) (xy 77.879727 -350.7576) (xy 77.895082 -350.809895) (xy 77.902838 -350.863843)
			(xy 77.903324 -350.891094) (xy 77.902801 -350.91954) (xy 77.894347 -350.9758) (xy 77.877626 -351.03018)
			(xy 77.85301 -351.08147) (xy 77.821044 -351.128533) (xy 77.78244 -351.170323) (xy 77.760576 -351.188528)
			(xy 77.752752 -351.195549) (xy 77.743033 -351.21416) (xy 77.74178 -351.224596) (xy 77.7367 -351.299272)
			(xy 77.736527 -351.309797) (xy 77.743605 -351.3296) (xy 77.750416 -351.337626) (xy 77.769867 -351.358982)
			(xy 77.802747 -351.406473) (xy 77.828089 -351.458381) (xy 77.845312 -351.513516) (xy 77.854023 -351.570619)
			(xy 77.854556 -351.5995) (xy 77.854057 -351.626633) (xy 77.846374 -351.680352) (xy 77.831149 -351.732439)
			(xy 77.80869 -351.781839) (xy 77.779451 -351.827555) (xy 77.7621 -351.84842) (xy 77.761846 -351.848674)
			(xy 77.755895 -351.856356) (xy 77.749752 -351.874772) (xy 77.749908 -351.884488) (xy 77.753718 -351.954846)
			(xy 77.754795 -351.964643) (xy 77.763268 -351.982414) (xy 77.770228 -351.98939) (xy 77.789235 -352.007508)
			(xy 77.822548 -352.048103) (xy 77.849984 -352.092878) (xy 77.871028 -352.14099) (xy 77.88528 -352.191532)
			(xy 77.892474 -352.24355) (xy 77.89291 -352.269806) (xy 77.892464 -352.295981) (xy 77.88529 -352.347837)
			(xy 77.871091 -352.398225) (xy 77.850134 -352.446197) (xy 77.822813 -352.490853) (xy 77.789641 -352.531352)
			(xy 77.770736 -352.54946) (xy 77.763403 -352.55701) (xy 77.755007 -352.576286) (xy 77.75448 -352.586798)
			(xy 77.75448 -352.66122) (xy 77.754974 -352.671742) (xy 77.763364 -352.691035) (xy 77.770736 -352.698558)
			(xy 77.789627 -352.716683) (xy 77.822816 -352.757169) (xy 77.850149 -352.801818) (xy 77.871113 -352.849789)
			(xy 77.885311 -352.900178) (xy 77.892477 -352.952036) (xy 77.89291 -352.978212) (xy 77.892424 -353.005463)
			(xy 77.884668 -353.059411) (xy 77.869313 -353.111706) (xy 77.846671 -353.161283) (xy 77.817205 -353.207133)
			(xy 77.781514 -353.248324) (xy 77.740323 -353.284015) (xy 77.694473 -353.313481) (xy 77.644896 -353.336123)
			(xy 77.592601 -353.351478) (xy 77.538653 -353.359234) (xy 77.484151 -353.359234) (xy 77.430203 -353.351478)
			(xy 77.377908 -353.336123) (xy 77.328331 -353.313481) (xy 77.282481 -353.284015) (xy 77.24129 -353.248324)
			(xy 77.205599 -353.207133) (xy 77.176133 -353.161283) (xy 77.153491 -353.111706) (xy 77.138136 -353.059411)
			(xy 77.13038 -353.005463) (xy 77.129894 -352.978212) (xy 77.130351 -352.952037) (xy 77.137522 -352.900182)
			(xy 77.151719 -352.849794) (xy 77.172674 -352.801822) (xy 77.199993 -352.757166) (xy 77.233163 -352.716666)
			(xy 77.252068 -352.698558) (xy 77.259393 -352.691002) (xy 77.267794 -352.67173) (xy 77.268324 -352.66122)
			(xy 77.268324 -352.586798) (xy 77.267873 -352.576271) (xy 77.259452 -352.556979) (xy 77.252068 -352.54946)
			(xy 77.233187 -352.531325) (xy 77.199997 -352.490841) (xy 77.172662 -352.446194) (xy 77.151697 -352.398226)
			(xy 77.137497 -352.347838) (xy 77.130328 -352.295981) (xy 77.129894 -352.269806) (xy 77.130385 -352.242672)
			(xy 77.138068 -352.188952) (xy 77.153294 -352.136865) (xy 77.175756 -352.087465) (xy 77.204998 -352.041751)
			(xy 77.22235 -352.020886) (xy 77.222604 -352.020632) (xy 77.228547 -352.012944) (xy 77.234697 -351.994533)
			(xy 77.234542 -351.984818) (xy 77.230732 -351.91446) (xy 77.229667 -351.904661) (xy 77.221186 -351.88689)
			(xy 77.214222 -351.879916) (xy 77.195227 -351.861784) (xy 77.161912 -351.821194) (xy 77.134473 -351.776422)
			(xy 77.113427 -351.728312) (xy 77.099172 -351.677772) (xy 77.091977 -351.625756) (xy 77.09154 -351.5995)
			(xy 75.190908 -351.5995) (xy 75.192354 -351.608974) (xy 75.19289 -351.637854) (xy 75.192414 -351.664988)
			(xy 75.184724 -351.718708) (xy 75.169494 -351.770794) (xy 75.14703 -351.820194) (xy 75.117787 -351.865909)
			(xy 75.100434 -351.886774) (xy 75.10018 -351.887028) (xy 75.094208 -351.894696) (xy 75.088076 -351.913123)
			(xy 75.088242 -351.922842) (xy 75.092052 -351.9932) (xy 75.093093 -352.003003) (xy 75.101591 -352.020773)
			(xy 75.108562 -352.027744) (xy 75.127534 -352.045898) (xy 75.160852 -352.086483) (xy 75.188295 -352.131251)
			(xy 75.209345 -352.179356) (xy 75.223604 -352.229892) (xy 75.230805 -352.281905) (xy 75.231244 -352.30816)
			(xy 75.230756 -352.335972) (xy 75.222682 -352.391008) (xy 75.206701 -352.444288) (xy 75.183151 -352.494681)
			(xy 75.152532 -352.54112) (xy 75.115492 -352.582619) (xy 75.072818 -352.618299) (xy 75.04938 -352.63328)
			(xy 75.03795 -352.640138) (xy 75.02525 -352.662998) (xy 75.024996 -352.763074) (xy 75.025309 -352.771752)
			(xy 75.031054 -352.788127) (xy 75.041928 -352.801651) (xy 75.049126 -352.806508) (xy 75.04938 -352.806508)
			(xy 75.072801 -352.821464) (xy 75.115406 -352.857141) (xy 75.152383 -352.898621) (xy 75.182951 -352.945028)
			(xy 75.206463 -352.995379) (xy 75.22242 -353.048608) (xy 75.230486 -353.103589) (xy 75.23099 -353.131374)
			(xy 75.230504 -353.158625) (xy 75.222748 -353.212573) (xy 75.207393 -353.264868) (xy 75.184751 -353.314445)
			(xy 75.155285 -353.360295) (xy 75.119594 -353.401486) (xy 75.078403 -353.437177) (xy 75.032553 -353.466643)
			(xy 74.982976 -353.489285) (xy 74.930681 -353.50464) (xy 74.876733 -353.512396) (xy 74.822231 -353.512396)
			(xy 74.768283 -353.50464) (xy 74.715988 -353.489285) (xy 74.666411 -353.466643) (xy 74.620561 -353.437177)
			(xy 74.57937 -353.401486) (xy 74.543679 -353.360295) (xy 74.514213 -353.314445) (xy 74.491571 -353.264868)
			(xy 74.476216 -353.212573) (xy 74.46846 -353.158625) (xy 74.467974 -353.131374) (xy 74.46848 -353.103562)
			(xy 74.476549 -353.048527) (xy 74.492526 -352.995247) (xy 74.516073 -352.944853) (xy 74.54669 -352.898414)
			(xy 74.583728 -352.856915) (xy 74.6264 -352.821235) (xy 74.649838 -352.806254) (xy 74.661268 -352.799396)
			(xy 74.673968 -352.776536) (xy 74.674222 -352.67646) (xy 74.673877 -352.667785) (xy 74.668146 -352.651412)
			(xy 74.657284 -352.637886) (xy 74.650092 -352.633026) (xy 74.649838 -352.633026) (xy 74.626436 -352.618041)
			(xy 74.583831 -352.58237) (xy 74.546852 -352.540894) (xy 74.516281 -352.494492) (xy 74.492766 -352.444146)
			(xy 74.476805 -352.390921) (xy 74.468734 -352.335943) (xy 74.468228 -352.30816) (xy 74.468708 -352.281026)
			(xy 74.476396 -352.227306) (xy 74.491626 -352.17522) (xy 74.514089 -352.12582) (xy 74.543331 -352.080105)
			(xy 74.560684 -352.05924) (xy 74.560938 -352.058986) (xy 74.566906 -352.051316) (xy 74.57304 -352.03289)
			(xy 74.572876 -352.023172) (xy 74.569066 -351.952814) (xy 74.568013 -351.943013) (xy 74.559523 -351.925243)
			(xy 74.552556 -351.91827) (xy 74.533594 -351.900106) (xy 74.500274 -351.859523) (xy 74.47283 -351.814758)
			(xy 74.451778 -351.766655) (xy 74.437517 -351.71612) (xy 74.430314 -351.664108) (xy 74.429874 -351.637854)
			(xy 66.560446 -351.637854) (xy 63.826136 -354.372164) (xy 86.93785 -354.372164) (xy 86.938309 -354.346244)
			(xy 86.945343 -354.294883) (xy 86.959263 -354.244946) (xy 86.979813 -354.197352) (xy 87.006615 -354.152978)
			(xy 87.039176 -354.112639) (xy 87.057738 -354.094542) (xy 87.064596 -354.087938) (xy 87.072724 -354.07092)
			(xy 87.079074 -353.98329) (xy 87.073486 -353.965256) (xy 87.067644 -353.957636) (xy 87.052104 -353.937355)
			(xy 87.026046 -353.893404) (xy 87.006084 -353.84637) (xy 86.992574 -353.797094) (xy 86.985757 -353.746455)
			(xy 86.985348 -353.720908) (xy 86.985807 -353.693537) (xy 86.993625 -353.639358) (xy 87.009115 -353.586854)
			(xy 87.031958 -353.537107) (xy 87.061685 -353.491141) (xy 87.079328 -353.47021) (xy 87.079582 -353.469956)
			(xy 87.085149 -353.462856) (xy 87.091408 -353.44595) (xy 87.091774 -353.436936) (xy 87.091774 -353.36988)
			(xy 87.091432 -353.360861) (xy 87.085175 -353.343944) (xy 87.079582 -353.33686) (xy 87.079328 -353.33686)
			(xy 87.079328 -353.336606) (xy 87.061695 -353.315667) (xy 87.03197 -353.2697) (xy 87.009124 -353.219955)
			(xy 86.993627 -353.167454) (xy 86.985798 -353.113276) (xy 86.985797 -353.058536) (xy 86.993625 -353.004358)
			(xy 87.00912 -352.951856) (xy 87.031964 -352.90211) (xy 87.061688 -352.856143) (xy 87.079328 -352.83521)
			(xy 87.079582 -352.834956) (xy 87.085149 -352.827856) (xy 87.091408 -352.81095) (xy 87.091774 -352.801936)
			(xy 87.091774 -352.73488) (xy 87.091432 -352.725861) (xy 87.085175 -352.708944) (xy 87.079582 -352.70186)
			(xy 87.079328 -352.70186) (xy 87.079328 -352.701606) (xy 87.061695 -352.680667) (xy 87.03197 -352.6347)
			(xy 87.009124 -352.584955) (xy 86.993627 -352.532454) (xy 86.985798 -352.478276) (xy 86.985797 -352.423536)
			(xy 86.993625 -352.369358) (xy 87.00912 -352.316856) (xy 87.031964 -352.26711) (xy 87.061688 -352.221143)
			(xy 87.079328 -352.20021) (xy 87.079582 -352.199956) (xy 87.085149 -352.192856) (xy 87.091408 -352.17595)
			(xy 87.091774 -352.166936) (xy 87.091774 -352.09988) (xy 87.091432 -352.090861) (xy 87.085175 -352.073944)
			(xy 87.079582 -352.06686) (xy 87.079328 -352.06686) (xy 87.079328 -352.066606) (xy 87.061695 -352.045667)
			(xy 87.03197 -351.9997) (xy 87.009124 -351.949955) (xy 86.993627 -351.897454) (xy 86.985798 -351.843276)
			(xy 86.985797 -351.788536) (xy 86.993625 -351.734358) (xy 87.00912 -351.681856) (xy 87.031964 -351.63211)
			(xy 87.061688 -351.586143) (xy 87.079328 -351.56521) (xy 87.079582 -351.564956) (xy 87.085149 -351.557856)
			(xy 87.091408 -351.54095) (xy 87.091774 -351.531936) (xy 87.091774 -351.46488) (xy 87.091432 -351.455861)
			(xy 87.085175 -351.438944) (xy 87.079582 -351.43186) (xy 87.079328 -351.43186) (xy 87.079328 -351.431606)
			(xy 87.061695 -351.410667) (xy 87.03197 -351.3647) (xy 87.009124 -351.314955) (xy 86.993627 -351.262454)
			(xy 86.985798 -351.208276) (xy 86.985797 -351.153536) (xy 86.993625 -351.099358) (xy 87.00912 -351.046856)
			(xy 87.031964 -350.99711) (xy 87.061688 -350.951143) (xy 87.079328 -350.93021) (xy 87.079582 -350.929956)
			(xy 87.085149 -350.922856) (xy 87.091408 -350.90595) (xy 87.091774 -350.896936) (xy 87.091774 -350.82988)
			(xy 87.091432 -350.820861) (xy 87.085175 -350.803944) (xy 87.079582 -350.79686) (xy 87.079328 -350.79686)
			(xy 87.079328 -350.796606) (xy 87.061683 -350.775679) (xy 87.031971 -350.729705) (xy 87.009136 -350.679956)
			(xy 86.993646 -350.627455) (xy 86.98582 -350.573278) (xy 86.985348 -350.545908) (xy 86.985885 -350.518659)
			(xy 86.993639 -350.464715) (xy 87.008991 -350.412424) (xy 87.031628 -350.36285) (xy 87.06109 -350.317002)
			(xy 87.096776 -350.275812) (xy 87.13796 -350.240121) (xy 87.183804 -350.210653) (xy 87.233375 -350.188009)
			(xy 87.285664 -350.17265) (xy 87.339607 -350.164889) (xy 87.366856 -350.1644) (xy 87.394225 -350.164892)
			(xy 87.448403 -350.172703) (xy 87.500906 -350.188187) (xy 87.550653 -350.211022) (xy 87.596621 -350.240741)
			(xy 87.617554 -350.25838) (xy 87.617808 -350.258634) (xy 87.624885 -350.264234) (xy 87.641809 -350.270471)
			(xy 87.650828 -350.270826) (xy 87.717884 -350.270826) (xy 87.726899 -350.270456) (xy 87.743816 -350.264217)
			(xy 87.750904 -350.258634) (xy 87.750904 -350.25838) (xy 87.751158 -350.25838) (xy 87.772091 -350.240739)
			(xy 87.818059 -350.211015) (xy 87.867805 -350.188169) (xy 87.920307 -350.172673) (xy 87.974485 -350.164844)
			(xy 88.029227 -350.164844) (xy 88.083405 -350.172673) (xy 88.135907 -350.188169) (xy 88.185653 -350.211015)
			(xy 88.231621 -350.240739) (xy 88.252554 -350.25838) (xy 88.252808 -350.258634) (xy 88.259885 -350.264234)
			(xy 88.276809 -350.270471) (xy 88.285828 -350.270826) (xy 88.352884 -350.270826) (xy 88.361899 -350.270456)
			(xy 88.378816 -350.264217) (xy 88.385904 -350.258634) (xy 88.385904 -350.25838) (xy 88.386158 -350.25838)
			(xy 88.407091 -350.240739) (xy 88.453059 -350.211015) (xy 88.502805 -350.188169) (xy 88.555307 -350.172673)
			(xy 88.609485 -350.164844) (xy 88.664227 -350.164844) (xy 88.718405 -350.172673) (xy 88.770907 -350.188169)
			(xy 88.820653 -350.211015) (xy 88.866621 -350.240739) (xy 88.887554 -350.25838) (xy 88.887808 -350.258634)
			(xy 88.894885 -350.264234) (xy 88.911809 -350.270471) (xy 88.920828 -350.270826) (xy 88.987884 -350.270826)
			(xy 88.996899 -350.270456) (xy 89.013816 -350.264217) (xy 89.020904 -350.258634) (xy 89.020904 -350.25838)
			(xy 89.021158 -350.25838) (xy 89.042091 -350.240739) (xy 89.088059 -350.211015) (xy 89.137805 -350.188169)
			(xy 89.190307 -350.172673) (xy 89.244485 -350.164844) (xy 89.299227 -350.164844) (xy 89.353405 -350.172673)
			(xy 89.405907 -350.188169) (xy 89.455653 -350.211015) (xy 89.501621 -350.240739) (xy 89.522554 -350.25838)
			(xy 89.522808 -350.258634) (xy 89.529885 -350.264234) (xy 89.546809 -350.270471) (xy 89.555828 -350.270826)
			(xy 89.622884 -350.270826) (xy 89.631899 -350.270456) (xy 89.648816 -350.264217) (xy 89.655904 -350.258634)
			(xy 89.655904 -350.25838) (xy 89.656158 -350.25838) (xy 89.677091 -350.240739) (xy 89.723059 -350.211015)
			(xy 89.772805 -350.188169) (xy 89.825307 -350.172673) (xy 89.879485 -350.164844) (xy 89.934227 -350.164844)
			(xy 89.988405 -350.172673) (xy 90.040907 -350.188169) (xy 90.090653 -350.211015) (xy 90.136621 -350.240739)
			(xy 90.157554 -350.25838) (xy 90.157808 -350.258634) (xy 90.164885 -350.264234) (xy 90.181809 -350.270471)
			(xy 90.190828 -350.270826) (xy 90.257884 -350.270826) (xy 90.266899 -350.270456) (xy 90.283816 -350.264217)
			(xy 90.290904 -350.258634) (xy 90.290904 -350.25838) (xy 90.291158 -350.25838) (xy 90.312091 -350.240739)
			(xy 90.358059 -350.211015) (xy 90.407805 -350.188169) (xy 90.460307 -350.172673) (xy 90.514485 -350.164844)
			(xy 90.569227 -350.164844) (xy 90.623405 -350.172673) (xy 90.675907 -350.188169) (xy 90.725653 -350.211015)
			(xy 90.771621 -350.240739) (xy 90.792554 -350.25838) (xy 90.792808 -350.258634) (xy 90.799885 -350.264234)
			(xy 90.816809 -350.270471) (xy 90.825828 -350.270826) (xy 90.892884 -350.270826) (xy 90.901899 -350.270456)
			(xy 90.918816 -350.264217) (xy 90.925904 -350.258634) (xy 90.925904 -350.25838) (xy 90.926158 -350.25838)
			(xy 90.947091 -350.240739) (xy 90.993059 -350.211015) (xy 91.042805 -350.188169) (xy 91.095307 -350.172673)
			(xy 91.149485 -350.164844) (xy 91.204227 -350.164844) (xy 91.258405 -350.172673) (xy 91.310907 -350.188169)
			(xy 91.360653 -350.211015) (xy 91.406621 -350.240739) (xy 91.427554 -350.25838) (xy 91.427808 -350.258634)
			(xy 91.434885 -350.264234) (xy 91.451809 -350.270471) (xy 91.460828 -350.270826) (xy 91.527884 -350.270826)
			(xy 91.536899 -350.270456) (xy 91.553816 -350.264217) (xy 91.560904 -350.258634) (xy 91.560904 -350.25838)
			(xy 91.561158 -350.25838) (xy 91.582091 -350.240739) (xy 91.628059 -350.211015) (xy 91.677805 -350.188169)
			(xy 91.730307 -350.172673) (xy 91.784485 -350.164844) (xy 91.839227 -350.164844) (xy 91.893405 -350.172673)
			(xy 91.945907 -350.188169) (xy 91.995653 -350.211015) (xy 92.041621 -350.240739) (xy 92.062554 -350.25838)
			(xy 92.062808 -350.258634) (xy 92.069885 -350.264234) (xy 92.086809 -350.270471) (xy 92.095828 -350.270826)
			(xy 92.162884 -350.270826) (xy 92.171899 -350.270456) (xy 92.188816 -350.264217) (xy 92.195904 -350.258634)
			(xy 92.195904 -350.25838) (xy 92.196158 -350.25838) (xy 92.217091 -350.240739) (xy 92.263059 -350.211015)
			(xy 92.312805 -350.188169) (xy 92.365307 -350.172673) (xy 92.419485 -350.164844) (xy 92.474227 -350.164844)
			(xy 92.528405 -350.172673) (xy 92.580907 -350.188169) (xy 92.630653 -350.211015) (xy 92.676621 -350.240739)
			(xy 92.697554 -350.25838) (xy 92.697808 -350.258634) (xy 92.704885 -350.264234) (xy 92.721809 -350.270471)
			(xy 92.730828 -350.270826) (xy 92.797884 -350.270826) (xy 92.806899 -350.270456) (xy 92.823816 -350.264217)
			(xy 92.830904 -350.258634) (xy 92.830904 -350.25838) (xy 92.831158 -350.25838) (xy 92.852091 -350.240739)
			(xy 92.898059 -350.211015) (xy 92.947805 -350.188169) (xy 93.000307 -350.172673) (xy 93.054485 -350.164844)
			(xy 93.109227 -350.164844) (xy 93.163405 -350.172673) (xy 93.215907 -350.188169) (xy 93.265653 -350.211015)
			(xy 93.311621 -350.240739) (xy 93.332554 -350.25838) (xy 93.332808 -350.258634) (xy 93.339885 -350.264234)
			(xy 93.356809 -350.270471) (xy 93.365828 -350.270826) (xy 93.432884 -350.270826) (xy 93.441899 -350.270456)
			(xy 93.458816 -350.264217) (xy 93.465904 -350.258634) (xy 93.465904 -350.25838) (xy 93.466158 -350.25838)
			(xy 93.487093 -350.240744) (xy 93.533065 -350.211032) (xy 93.582812 -350.188196) (xy 93.635312 -350.172704)
			(xy 93.689487 -350.164875) (xy 93.716856 -350.1644) (xy 93.744108 -350.164896) (xy 93.798058 -350.172647)
			(xy 93.850356 -350.187998) (xy 93.899937 -350.210636) (xy 93.94579 -350.2401) (xy 93.986984 -350.275791)
			(xy 94.022678 -350.316981) (xy 94.052146 -350.362832) (xy 94.074789 -350.41241) (xy 94.090145 -350.464706)
			(xy 94.097901 -350.518656) (xy 94.098364 -350.545908) (xy 94.097911 -350.573279) (xy 94.090092 -350.627459)
			(xy 94.0746 -350.679962) (xy 94.051755 -350.729709) (xy 94.022027 -350.775675) (xy 94.004384 -350.796606)
			(xy 94.00413 -350.79686) (xy 93.998546 -350.803948) (xy 93.9923 -350.820864) (xy 93.991938 -350.82988)
			(xy 93.991938 -350.896936) (xy 93.99227 -350.905956) (xy 93.998534 -350.922873) (xy 94.00413 -350.929956)
			(xy 94.004384 -350.929956) (xy 94.004384 -350.93021) (xy 94.022032 -350.951137) (xy 94.051756 -350.997106)
			(xy 94.0746 -351.046853) (xy 94.090095 -351.099356) (xy 94.097923 -351.153535) (xy 94.097922 -351.208277)
			(xy 94.090093 -351.262456) (xy 94.074596 -351.314958) (xy 94.05175 -351.364705) (xy 94.022025 -351.410673)
			(xy 94.004384 -351.431606) (xy 94.00413 -351.43186) (xy 93.998546 -351.438948) (xy 93.9923 -351.455864)
			(xy 93.991938 -351.46488) (xy 93.991938 -351.531936) (xy 93.99227 -351.540956) (xy 93.998534 -351.557873)
			(xy 94.00413 -351.564956) (xy 94.004384 -351.564956) (xy 94.004384 -351.56521) (xy 94.022039 -351.58613)
			(xy 94.051749 -351.632106) (xy 94.074582 -351.681856) (xy 94.090069 -351.73436) (xy 94.097893 -351.788538)
			(xy 94.098364 -351.815908) (xy 94.097824 -351.844763) (xy 94.089138 -351.901815) (xy 94.07195 -351.956905)
			(xy 94.046654 -352.008775) (xy 94.013827 -352.056238) (xy 93.97422 -352.098211) (xy 93.951806 -352.11639)
			(xy 93.94467 -352.122532) (xy 93.935035 -352.138691) (xy 93.93301 -352.147886) (xy 93.92031 -352.22561)
			(xy 93.92412 -352.244152) (xy 93.9292 -352.252026) (xy 93.943856 -352.275367) (xy 93.966997 -352.325387)
			(xy 93.982711 -352.378213) (xy 93.990672 -352.432749) (xy 93.991176 -352.460306) (xy 93.990727 -352.486168)
			(xy 93.983745 -352.537418) (xy 93.969896 -352.587253) (xy 93.949435 -352.634758) (xy 93.922738 -352.679059)
			(xy 93.890296 -352.719343) (xy 93.871796 -352.73742) (xy 93.871542 -352.737674) (xy 93.864419 -352.745175)
			(xy 93.856286 -352.764172) (xy 93.855794 -352.774504) (xy 93.855794 -352.858832) (xy 93.864176 -352.878136)
			(xy 93.871796 -352.885248) (xy 93.890305 -352.903358) (xy 93.922813 -352.943663) (xy 93.949569 -352.987995)
			(xy 93.970082 -353.03554) (xy 93.983975 -353.085422) (xy 93.990991 -353.136726) (xy 93.99143 -353.162616)
			(xy 93.99099 -353.189987) (xy 93.983169 -353.244168) (xy 93.967674 -353.296672) (xy 93.944826 -353.346419)
			(xy 93.915095 -353.392384) (xy 93.89745 -353.413314) (xy 93.897196 -353.413568) (xy 93.891616 -353.420659)
			(xy 93.885366 -353.437572) (xy 93.885004 -353.446588) (xy 93.885004 -353.513644) (xy 93.885387 -353.522658)
			(xy 93.891617 -353.539575) (xy 93.897196 -353.546664) (xy 93.89745 -353.546664) (xy 93.89745 -353.546918)
			(xy 93.915056 -353.567877) (xy 93.944775 -353.613841) (xy 93.967618 -353.663582) (xy 93.983116 -353.716077)
			(xy 93.990952 -353.770249) (xy 93.99143 -353.797616) (xy 93.990974 -353.823944) (xy 93.983748 -353.876102)
			(xy 93.969409 -353.926768) (xy 93.948229 -353.974977) (xy 93.920612 -354.01981) (xy 93.887085 -354.060413)
			(xy 93.867986 -354.07854) (xy 93.861184 -354.085297) (xy 93.852836 -354.102543) (xy 93.85173 -354.112068)
			(xy 93.846904 -354.181664) (xy 93.846559 -354.191229) (xy 93.852162 -354.209511) (xy 93.857826 -354.217224)
			(xy 93.85808 -354.217478) (xy 93.874192 -354.237978) (xy 93.901292 -354.282522) (xy 93.922072 -354.330342)
			(xy 93.936146 -354.380546) (xy 93.943251 -354.4322) (xy 93.943678 -354.45827) (xy 93.943217 -354.485523)
			(xy 93.935463 -354.539476) (xy 93.920109 -354.591776) (xy 93.897468 -354.641358) (xy 93.868 -354.687213)
			(xy 93.832306 -354.728406) (xy 93.791113 -354.7641) (xy 93.745258 -354.793568) (xy 93.695676 -354.816209)
			(xy 93.643376 -354.831563) (xy 93.589423 -354.839317) (xy 93.56217 -354.839778) (xy 93.533989 -354.839267)
			(xy 93.478242 -354.830966) (xy 93.42432 -354.814563) (xy 93.373394 -354.790415) (xy 93.326569 -354.759046)
			(xy 93.305376 -354.740464) (xy 93.298518 -354.734114) (xy 93.280738 -354.727256) (xy 93.193108 -354.727256)
			(xy 93.175328 -354.734114) (xy 93.16847 -354.740464) (xy 93.147286 -354.759166) (xy 93.100394 -354.790697)
			(xy 93.049364 -354.814968) (xy 92.995313 -354.831449) (xy 92.939422 -354.839777) (xy 92.911168 -354.840286)
			(xy 92.883666 -354.839821) (xy 92.829232 -354.831924) (xy 92.776495 -354.816297) (xy 92.726546 -354.793264)
			(xy 92.68042 -354.763302) (xy 92.63907 -354.727031) (xy 92.620846 -354.706428) (xy 92.613662 -354.698707)
			(xy 92.594769 -354.68939) (xy 92.58427 -354.688394) (xy 92.510102 -354.6856) (xy 92.499539 -354.685655)
			(xy 92.479859 -354.69327) (xy 92.472002 -354.700332) (xy 92.450393 -354.720963) (xy 92.401994 -354.755981)
			(xy 92.348726 -354.783024) (xy 92.291893 -354.80143) (xy 92.232886 -354.810748) (xy 92.203016 -354.81133)
			(xy 92.202762 -354.81133) (xy 92.1747 -354.810835) (xy 92.119184 -354.802595) (xy 92.065474 -354.786314)
			(xy 92.014727 -354.762341) (xy 91.968039 -354.731195) (xy 91.926415 -354.693547) (xy 91.890754 -354.650209)
			(xy 91.875864 -354.626418) (xy 91.868918 -354.616097) (xy 91.847599 -354.603323) (xy 91.835224 -354.602034)
			(xy 91.73845 -354.5967) (xy 91.71559 -354.607368) (xy 91.70797 -354.617528) (xy 91.689791 -354.640507)
			(xy 91.647619 -354.681181) (xy 91.599726 -354.71493) (xy 91.547235 -354.740961) (xy 91.491383 -354.758662)
			(xy 91.433481 -354.767617) (xy 91.404186 -354.76815) (xy 91.374745 -354.767578) (xy 91.316562 -354.758542)
			(xy 91.260458 -354.740672) (xy 91.207767 -354.714393) (xy 91.15974 -354.680328) (xy 91.138248 -354.6602)
			(xy 91.130882 -354.653088) (xy 91.113102 -354.645976) (xy 91.021916 -354.645976) (xy 91.004136 -354.653088)
			(xy 90.99677 -354.6602) (xy 90.975265 -354.680314) (xy 90.927241 -354.714383) (xy 90.874554 -354.74067)
			(xy 90.818454 -354.758551) (xy 90.760272 -354.767602) (xy 90.730832 -354.76815) (xy 90.702652 -354.767668)
			(xy 90.64691 -354.759354) (xy 90.592996 -354.742931) (xy 90.542085 -354.718756) (xy 90.495283 -354.687356)
			(xy 90.453608 -354.649413) (xy 90.417969 -354.605753) (xy 90.389138 -354.557326) (xy 90.367745 -354.505184)
			(xy 90.354253 -354.450464) (xy 90.351102 -354.422456) (xy 90.351102 -354.422202) (xy 90.349826 -354.41288)
			(xy 90.341413 -354.396066) (xy 90.327498 -354.383421) (xy 90.309957 -354.376651) (xy 90.300556 -354.376228)
			(xy 89.917778 -354.376228) (xy 89.908391 -354.376727) (xy 89.890879 -354.383496) (xy 89.876981 -354.396119)
			(xy 89.868562 -354.4129) (xy 89.867232 -354.422202) (xy 89.867232 -354.422456) (xy 89.864083 -354.450461)
			(xy 89.850594 -354.505176) (xy 89.829201 -354.557311) (xy 89.800369 -354.605731) (xy 89.764727 -354.649382)
			(xy 89.72305 -354.687313) (xy 89.676246 -354.718699) (xy 89.625333 -354.742856) (xy 89.571419 -354.75926)
			(xy 89.515679 -354.767551) (xy 89.459325 -354.767551) (xy 89.403585 -354.75926) (xy 89.349671 -354.742856)
			(xy 89.298758 -354.718699) (xy 89.251954 -354.687313) (xy 89.210277 -354.649382) (xy 89.174635 -354.605731)
			(xy 89.145803 -354.557311) (xy 89.12441 -354.505176) (xy 89.110921 -354.450461) (xy 89.107772 -354.422456)
			(xy 89.107772 -354.422202) (xy 89.10643 -354.412894) (xy 89.098031 -354.39609) (xy 89.084138 -354.383446)
			(xy 89.066619 -354.376662) (xy 89.057226 -354.376228) (xy 89.03462 -354.376228) (xy 89.024597 -354.376637)
			(xy 89.006075 -354.384305) (xy 88.991901 -354.398482) (xy 88.984235 -354.417005) (xy 88.98382 -354.427028)
			(xy 88.98382 -354.429568) (xy 88.983315 -354.45682) (xy 88.975563 -354.510768) (xy 88.960211 -354.563065)
			(xy 88.937573 -354.612644) (xy 88.90811 -354.658497) (xy 88.87242 -354.699689) (xy 88.831232 -354.735383)
			(xy 88.785383 -354.764852) (xy 88.735806 -354.787496) (xy 88.683511 -354.802853) (xy 88.629563 -354.810612)
			(xy 88.602312 -354.811076) (xy 88.572261 -354.810494) (xy 88.512904 -354.80106) (xy 88.455759 -354.78244)
			(xy 88.402239 -354.755094) (xy 88.353666 -354.719697) (xy 88.332056 -354.698808) (xy 88.325198 -354.692555)
			(xy 88.30827 -354.684991) (xy 88.299036 -354.684076) (xy 88.231472 -354.680012) (xy 88.222307 -354.67998)
			(xy 88.204866 -354.685568) (xy 88.197436 -354.690934) (xy 88.197182 -354.690934) (xy 88.176892 -354.706404)
			(xy 88.13298 -354.732385) (xy 88.086 -354.752287) (xy 88.036787 -354.765755) (xy 87.986219 -354.772551)
			(xy 87.960708 -354.772976) (xy 87.931827 -354.772419) (xy 87.874725 -354.763719) (xy 87.819589 -354.746503)
			(xy 87.767682 -354.721164) (xy 87.720192 -354.688283) (xy 87.698834 -354.668836) (xy 87.691976 -354.662486)
			(xy 87.674958 -354.655374) (xy 87.597742 -354.653088) (xy 87.588657 -354.653208) (xy 87.57147 -354.659051)
			(xy 87.564214 -354.664518) (xy 87.563706 -354.665026) (xy 87.543037 -354.68167) (xy 87.497971 -354.709691)
			(xy 87.449461 -354.731205) (xy 87.39844 -354.745799) (xy 87.345891 -354.753192) (xy 87.319358 -354.753672)
			(xy 87.292104 -354.753261) (xy 87.238152 -354.745498) (xy 87.185853 -354.730136) (xy 87.136274 -354.707487)
			(xy 87.090422 -354.678013) (xy 87.049231 -354.642314) (xy 87.01354 -354.601116) (xy 86.984076 -354.555258)
			(xy 86.961437 -354.505673) (xy 86.946085 -354.453372) (xy 86.938333 -354.399418) (xy 86.93785 -354.372164)
			(xy 63.826136 -354.372164) (xy 63.494412 -354.703888) (xy 63.476315 -354.721142) (xy 63.434769 -354.748947)
			(xy 63.388598 -354.768118) (xy 63.339576 -354.77792) (xy 63.31458 -354.778564) (xy 47.646336 -354.778564)
			(xy 47.636272 -354.779) (xy 47.617691 -354.786738) (xy 47.610268 -354.79355) (xy 46.019466 -356.384098)
			(xy 46.001357 -356.401321) (xy 45.959797 -356.429064) (xy 45.913627 -356.448174) (xy 45.864618 -356.45792)
			(xy 45.839634 -356.45852) (xy 41.131998 -356.45852) (xy 41.121928 -356.458944) (xy 41.103326 -356.466661)
			(xy 41.09593 -356.473506) (xy 40.011858 -357.557832) (xy 40.00501 -357.56523) (xy 39.997278 -357.583828)
			(xy 39.996872 -357.5939) (xy 39.996872 -357.965248) (xy 39.996235 -357.990244) (xy 39.986437 -358.039269)
			(xy 39.967264 -358.085441) (xy 39.939454 -358.126986) (xy 39.922196 -358.14508) (xy 39.518082 -358.549194)
			(xy 40.988234 -358.549194) (xy 40.988686 -358.523273) (xy 40.995718 -358.471911) (xy 41.009638 -358.421973)
			(xy 41.030189 -358.374379) (xy 41.056993 -358.330005) (xy 41.089557 -358.289667) (xy 41.108122 -358.271572)
			(xy 41.11498 -358.264968) (xy 41.123108 -358.24795) (xy 41.129712 -358.16032) (xy 41.124124 -358.142286)
			(xy 41.118028 -358.134666) (xy 41.102545 -358.114386) (xy 41.076567 -358.070471) (xy 41.056669 -358.023487)
			(xy 41.043203 -357.974273) (xy 41.03641 -357.923704) (xy 41.035986 -357.898192) (xy 41.036451 -357.870822)
			(xy 41.044269 -357.816643) (xy 41.059759 -357.76414) (xy 41.082601 -357.714393) (xy 41.112325 -357.668426)
			(xy 41.129966 -357.647494) (xy 41.13022 -357.64724) (xy 41.135798 -357.640148) (xy 41.142049 -357.623235)
			(xy 41.142412 -357.61422) (xy 41.142412 -357.547164) (xy 41.14207 -357.538146) (xy 41.135812 -357.521229)
			(xy 41.13022 -357.514144) (xy 41.129966 -357.514144) (xy 41.129966 -357.51389) (xy 41.112303 -357.492977)
			(xy 41.082596 -357.446998) (xy 41.059765 -357.397246) (xy 41.04428 -357.344741) (xy 41.036457 -357.290562)
			(xy 41.035986 -357.263192) (xy 41.036472 -357.235941) (xy 41.044228 -357.181993) (xy 41.059583 -357.129698)
			(xy 41.082225 -357.080121) (xy 41.111691 -357.034271) (xy 41.147382 -356.99308) (xy 41.188573 -356.957389)
			(xy 41.234423 -356.927923) (xy 41.284 -356.905281) (xy 41.336295 -356.889926) (xy 41.390243 -356.88217)
			(xy 41.444745 -356.88217) (xy 41.498693 -356.889926) (xy 41.550988 -356.905281) (xy 41.600565 -356.927923)
			(xy 41.646415 -356.957389) (xy 41.687606 -356.99308) (xy 41.723297 -357.034271) (xy 41.752763 -357.080121)
			(xy 41.775405 -357.129698) (xy 41.79076 -357.181993) (xy 41.798516 -357.235941) (xy 41.799002 -357.263192)
			(xy 41.798531 -357.290562) (xy 41.790714 -357.344741) (xy 41.775226 -357.397244) (xy 41.752386 -357.446991)
			(xy 41.722663 -357.492958) (xy 41.705022 -357.51389) (xy 41.704768 -357.514144) (xy 41.699195 -357.52124)
			(xy 41.692941 -357.53815) (xy 41.692576 -357.547164) (xy 41.692576 -357.61422) (xy 41.692928 -357.623237)
			(xy 41.69918 -357.640154) (xy 41.704768 -357.64724) (xy 41.705022 -357.64724) (xy 41.705022 -357.647494)
			(xy 41.722675 -357.668415) (xy 41.752384 -357.714391) (xy 41.775217 -357.764141) (xy 41.790705 -357.816644)
			(xy 41.79853 -357.870822) (xy 41.799002 -357.898192) (xy 41.798529 -357.924112) (xy 41.7915 -357.975473)
			(xy 41.777584 -358.02541) (xy 41.757036 -358.073004) (xy 41.730236 -358.117379) (xy 41.697676 -358.157718)
			(xy 41.679114 -358.175814) (xy 41.672256 -358.182418) (xy 41.664128 -358.199436) (xy 41.657524 -358.287066)
			(xy 41.663112 -358.3051) (xy 41.669208 -358.31272) (xy 41.684676 -358.333012) (xy 41.710657 -358.376923)
			(xy 41.73056 -358.423903) (xy 41.744029 -358.473115) (xy 41.749099 -358.51084) (xy 43.554396 -358.51084)
			(xy 43.554825 -358.484919) (xy 43.561863 -358.433556) (xy 43.575788 -358.383618) (xy 43.596343 -358.336024)
			(xy 43.623151 -358.29165) (xy 43.655718 -358.251313) (xy 43.674284 -358.233218) (xy 43.681142 -358.226614)
			(xy 43.68927 -358.209596) (xy 43.695874 -358.121966) (xy 43.690286 -358.103932) (xy 43.68419 -358.096312)
			(xy 43.668737 -358.07601) (xy 43.642753 -358.032102) (xy 43.622847 -357.985124) (xy 43.609375 -357.935914)
			(xy 43.602575 -357.885348) (xy 43.602148 -357.859838) (xy 43.602625 -357.832468) (xy 43.610438 -357.778289)
			(xy 43.625924 -357.725785) (xy 43.648764 -357.676038) (xy 43.678487 -357.630072) (xy 43.696128 -357.60914)
			(xy 43.696382 -357.608886) (xy 43.701978 -357.601806) (xy 43.708219 -357.584884) (xy 43.708574 -357.575866)
			(xy 43.708574 -357.50881) (xy 43.708218 -357.499793) (xy 43.70197 -357.482876) (xy 43.696382 -357.47579)
			(xy 43.696128 -357.47579) (xy 43.696128 -357.475536) (xy 43.678497 -357.454598) (xy 43.648783 -357.408627)
			(xy 43.625945 -357.358881) (xy 43.610452 -357.306382) (xy 43.602623 -357.252207) (xy 43.602148 -357.224838)
			(xy 43.602634 -357.197587) (xy 43.61039 -357.143639) (xy 43.625745 -357.091344) (xy 43.648387 -357.041767)
			(xy 43.677853 -356.995917) (xy 43.713544 -356.954726) (xy 43.754735 -356.919035) (xy 43.800585 -356.889569)
			(xy 43.850162 -356.866927) (xy 43.902457 -356.851572) (xy 43.956405 -356.843816) (xy 44.010907 -356.843816)
			(xy 44.064855 -356.851572) (xy 44.11715 -356.866927) (xy 44.166727 -356.889569) (xy 44.212577 -356.919035)
			(xy 44.253768 -356.954726) (xy 44.289459 -356.995917) (xy 44.318925 -357.041767) (xy 44.341567 -357.091344)
			(xy 44.356922 -357.143639) (xy 44.364678 -357.197587) (xy 44.365164 -357.224838) (xy 44.36467 -357.252207)
			(xy 44.356861 -357.306386) (xy 44.341378 -357.358889) (xy 44.318543 -357.408636) (xy 44.288823 -357.454604)
			(xy 44.271184 -357.475536) (xy 44.27093 -357.47579) (xy 44.265333 -357.482869) (xy 44.259095 -357.499792)
			(xy 44.258738 -357.50881) (xy 44.258738 -357.575866) (xy 44.259103 -357.584882) (xy 44.265344 -357.6018)
			(xy 44.27093 -357.608886) (xy 44.271184 -357.608886) (xy 44.271184 -357.60914) (xy 44.288806 -357.630086)
			(xy 44.318521 -357.676055) (xy 44.34136 -357.725799) (xy 44.356855 -357.778296) (xy 44.364688 -357.83247)
			(xy 44.365164 -357.859838) (xy 44.364733 -357.885759) (xy 44.357697 -357.937123) (xy 44.343774 -357.987061)
			(xy 44.323218 -358.034655) (xy 44.29641 -358.079029) (xy 44.272612 -358.108504) (xy 47.49927 -358.108504)
			(xy 47.499749 -358.082584) (xy 47.506778 -358.031224) (xy 47.520694 -357.981287) (xy 47.54124 -357.933694)
			(xy 47.568039 -357.889318) (xy 47.600597 -357.848979) (xy 47.619158 -357.830882) (xy 47.626016 -357.824278)
			(xy 47.634144 -357.80726) (xy 47.640748 -357.71963) (xy 47.63516 -357.701596) (xy 47.629064 -357.693976)
			(xy 47.613591 -357.673689) (xy 47.587611 -357.629776) (xy 47.567709 -357.582795) (xy 47.554241 -357.533581)
			(xy 47.547447 -357.483013) (xy 47.547022 -357.457502) (xy 47.547484 -357.430132) (xy 47.555302 -357.375952)
			(xy 47.570792 -357.323449) (xy 47.593634 -357.273702) (xy 47.62336 -357.227735) (xy 47.641002 -357.206804)
			(xy 47.641256 -357.20655) (xy 47.646834 -357.199458) (xy 47.653085 -357.182545) (xy 47.653448 -357.17353)
			(xy 47.653448 -357.106474) (xy 47.653115 -357.097454) (xy 47.646852 -357.080537) (xy 47.641256 -357.073454)
			(xy 47.641002 -357.073454) (xy 47.641002 -357.0732) (xy 47.62335 -357.052279) (xy 47.59364 -357.006303)
			(xy 47.570806 -356.956553) (xy 47.555318 -356.90405) (xy 47.547494 -356.849872) (xy 47.547022 -356.822502)
			(xy 47.547457 -356.795248) (xy 47.555215 -356.741294) (xy 47.570572 -356.688994) (xy 47.593217 -356.639412)
			(xy 47.622687 -356.593557) (xy 47.658384 -356.552364) (xy 47.69958 -356.51667) (xy 47.745437 -356.487203)
			(xy 47.79502 -356.464562) (xy 47.847322 -356.449209) (xy 47.901276 -356.441455) (xy 47.92853 -356.440994)
			(xy 47.957165 -356.441498) (xy 48.01379 -356.450062) (xy 48.0685 -356.466994) (xy 48.120064 -356.491913)
			(xy 48.167324 -356.52426) (xy 48.209219 -356.563306) (xy 48.244806 -356.608177) (xy 48.259492 -356.632764)
			(xy 48.264243 -356.640338) (xy 48.277941 -356.651811) (xy 48.294752 -356.657867) (xy 48.303688 -356.658164)
			(xy 48.391572 -356.658164) (xy 48.4005 -356.657828) (xy 48.417292 -356.651761) (xy 48.430994 -356.640315)
			(xy 48.435768 -356.632764) (xy 48.450459 -356.608179) (xy 48.486042 -356.563306) (xy 48.527934 -356.524256)
			(xy 48.575194 -356.491909) (xy 48.626758 -356.466992) (xy 48.681469 -356.450064) (xy 48.738095 -356.441506)
			(xy 48.76673 -356.440994) (xy 48.794101 -356.441444) (xy 48.848281 -356.449266) (xy 48.900784 -356.464759)
			(xy 48.95053 -356.487604) (xy 48.996497 -356.517332) (xy 49.017428 -356.534974) (xy 49.017682 -356.535228)
			(xy 49.024767 -356.540816) (xy 49.041685 -356.547061) (xy 49.050702 -356.54742) (xy 49.117758 -356.54742)
			(xy 49.126772 -356.547039) (xy 49.143689 -356.540808) (xy 49.150778 -356.535228) (xy 49.150778 -356.534974)
			(xy 49.151032 -356.534974) (xy 49.171965 -356.517333) (xy 49.217933 -356.487609) (xy 49.267679 -356.464763)
			(xy 49.320181 -356.449267) (xy 49.374359 -356.441438) (xy 49.429101 -356.441438) (xy 49.483279 -356.449267)
			(xy 49.535781 -356.464763) (xy 49.585527 -356.487609) (xy 49.631495 -356.517333) (xy 49.652428 -356.534974)
			(xy 49.652682 -356.535228) (xy 49.659767 -356.540816) (xy 49.676685 -356.547061) (xy 49.685702 -356.54742)
			(xy 49.752758 -356.54742) (xy 49.761772 -356.547039) (xy 49.778689 -356.540808) (xy 49.785778 -356.535228)
			(xy 49.785778 -356.534974) (xy 49.786032 -356.534974) (xy 49.806965 -356.517333) (xy 49.852933 -356.487609)
			(xy 49.902679 -356.464763) (xy 49.955181 -356.449267) (xy 50.009359 -356.441438) (xy 50.064101 -356.441438)
			(xy 50.118279 -356.449267) (xy 50.170781 -356.464763) (xy 50.220527 -356.487609) (xy 50.266495 -356.517333)
			(xy 50.287428 -356.534974) (xy 50.287682 -356.535228) (xy 50.294767 -356.540816) (xy 50.311685 -356.547061)
			(xy 50.320702 -356.54742) (xy 50.387758 -356.54742) (xy 50.396772 -356.547039) (xy 50.413689 -356.540808)
			(xy 50.420778 -356.535228) (xy 50.420778 -356.534974) (xy 50.421032 -356.534974) (xy 50.441976 -356.517349)
			(xy 50.487946 -356.487636) (xy 50.53769 -356.464798) (xy 50.590188 -356.449303) (xy 50.644362 -356.441471)
			(xy 50.67173 -356.440994) (xy 50.698982 -356.44145) (xy 50.752931 -356.449211) (xy 50.805226 -356.46457)
			(xy 50.854804 -356.487214) (xy 50.900654 -356.516684) (xy 50.941844 -356.552379) (xy 50.977535 -356.593571)
			(xy 51.007001 -356.639424) (xy 51.029642 -356.689004) (xy 51.044996 -356.7413) (xy 51.052752 -356.79525)
			(xy 51.053238 -356.822502) (xy 51.052788 -356.849873) (xy 51.044969 -356.904053) (xy 51.029477 -356.956557)
			(xy 51.006631 -357.006304) (xy 50.976902 -357.052269) (xy 50.959258 -357.0732) (xy 50.959004 -357.073454)
			(xy 50.953431 -357.08055) (xy 50.947176 -357.097459) (xy 50.946812 -357.106474) (xy 50.946812 -357.17353)
			(xy 50.947152 -357.182549) (xy 50.953411 -357.199466) (xy 50.959004 -357.20655) (xy 50.959258 -357.20655)
			(xy 50.959258 -357.206804) (xy 50.976906 -357.227729) (xy 51.006618 -357.273703) (xy 51.029453 -357.323452)
			(xy 51.044942 -357.375955) (xy 51.052766 -357.430132) (xy 51.053238 -357.457502) (xy 51.052761 -357.483422)
			(xy 51.045731 -357.534782) (xy 51.031815 -357.584719) (xy 51.011268 -357.632312) (xy 50.984469 -357.676687)
			(xy 50.951911 -357.717027) (xy 50.93335 -357.735124) (xy 50.926492 -357.741728) (xy 50.918364 -357.758746)
			(xy 50.91176 -357.846376) (xy 50.917348 -357.86441) (xy 50.923444 -357.87203) (xy 50.938921 -357.892314)
			(xy 50.964901 -357.936228) (xy 50.984801 -357.98321) (xy 50.998268 -358.032424) (xy 51.005062 -358.082993)
			(xy 51.005486 -358.108504) (xy 51.005048 -358.135758) (xy 50.99729 -358.189711) (xy 50.981933 -358.242011)
			(xy 50.959288 -358.291592) (xy 50.929818 -358.337446) (xy 50.894121 -358.37864) (xy 50.852926 -358.414333)
			(xy 50.807069 -358.4438) (xy 50.757486 -358.466442) (xy 50.705185 -358.481796) (xy 50.651232 -358.48955)
			(xy 50.623978 -358.490012) (xy 50.596607 -358.489556) (xy 50.542428 -358.481735) (xy 50.489925 -358.466244)
			(xy 50.440178 -358.4434) (xy 50.394212 -358.413674) (xy 50.37328 -358.396032) (xy 50.373026 -358.395778)
			(xy 50.365938 -358.390194) (xy 50.349022 -358.383946) (xy 50.340006 -358.383586) (xy 50.27295 -358.383586)
			(xy 50.263936 -358.38397) (xy 50.247019 -358.390199) (xy 50.23993 -358.395778) (xy 50.23993 -358.396032)
			(xy 50.239676 -358.396032) (xy 50.218743 -358.413673) (xy 50.172775 -358.443397) (xy 50.123029 -358.466243)
			(xy 50.070527 -358.481739) (xy 50.016349 -358.489568) (xy 49.961607 -358.489568) (xy 49.907429 -358.481739)
			(xy 49.854927 -358.466243) (xy 49.805181 -358.443397) (xy 49.759213 -358.413673) (xy 49.73828 -358.396032)
			(xy 49.738026 -358.395778) (xy 49.730938 -358.390194) (xy 49.714022 -358.383946) (xy 49.705006 -358.383586)
			(xy 49.63795 -358.383586) (xy 49.628936 -358.38397) (xy 49.612019 -358.390199) (xy 49.60493 -358.395778)
			(xy 49.60493 -358.396032) (xy 49.604676 -358.396032) (xy 49.583743 -358.413673) (xy 49.537775 -358.443397)
			(xy 49.488029 -358.466243) (xy 49.435527 -358.481739) (xy 49.381349 -358.489568) (xy 49.326607 -358.489568)
			(xy 49.272429 -358.481739) (xy 49.219927 -358.466243) (xy 49.170181 -358.443397) (xy 49.124213 -358.413673)
			(xy 49.10328 -358.396032) (xy 49.103026 -358.395778) (xy 49.095938 -358.390194) (xy 49.079022 -358.383946)
			(xy 49.070006 -358.383586) (xy 49.00295 -358.383586) (xy 48.993936 -358.38397) (xy 48.977019 -358.390199)
			(xy 48.96993 -358.395778) (xy 48.96993 -358.396032) (xy 48.969676 -358.396032) (xy 48.94873 -358.413654)
			(xy 48.902761 -358.443367) (xy 48.853017 -358.466206) (xy 48.800519 -358.481701) (xy 48.746346 -358.489535)
			(xy 48.718978 -358.490012) (xy 48.690344 -358.489499) (xy 48.633719 -358.480936) (xy 48.57901 -358.464005)
			(xy 48.527446 -358.439088) (xy 48.480185 -358.406743) (xy 48.43829 -358.367697) (xy 48.402702 -358.322829)
			(xy 48.388016 -358.298242) (xy 48.383258 -358.290673) (xy 48.369563 -358.279199) (xy 48.352755 -358.273141)
			(xy 48.34382 -358.272842) (xy 48.255936 -358.272842) (xy 48.247008 -358.273181) (xy 48.230216 -358.279246)
			(xy 48.216514 -358.290691) (xy 48.21174 -358.298242) (xy 48.197046 -358.322824) (xy 48.161463 -358.367698)
			(xy 48.119571 -358.406747) (xy 48.072312 -358.439094) (xy 48.020748 -358.464012) (xy 47.966039 -358.480941)
			(xy 47.909413 -358.4895) (xy 47.880778 -358.490012) (xy 47.853526 -358.489543) (xy 47.799578 -358.481783)
			(xy 47.747283 -358.466426) (xy 47.697706 -358.443782) (xy 47.651856 -358.414314) (xy 47.610666 -358.378621)
			(xy 47.574975 -358.337429) (xy 47.545509 -358.291578) (xy 47.522868 -358.242) (xy 47.507513 -358.189704)
			(xy 47.499756 -358.135756) (xy 47.49927 -358.108504) (xy 44.272612 -358.108504) (xy 44.263842 -358.119366)
			(xy 44.245276 -358.13746) (xy 44.238418 -358.144064) (xy 44.23029 -358.161082) (xy 44.223686 -358.248712)
			(xy 44.229274 -358.266746) (xy 44.23537 -358.274366) (xy 44.250822 -358.294669) (xy 44.276804 -358.338578)
			(xy 44.296709 -358.385555) (xy 44.310182 -358.434765) (xy 44.316984 -358.48533) (xy 44.317412 -358.51084)
			(xy 44.316847 -358.539303) (xy 44.308379 -358.595597) (xy 44.291638 -358.650006) (xy 44.266995 -358.701322)
			(xy 44.234998 -358.748406) (xy 44.216066 -358.769666) (xy 44.208954 -358.77754) (xy 44.202096 -358.797352)
			(xy 44.209716 -358.893618) (xy 44.219622 -358.91216) (xy 44.228258 -358.918764) (xy 44.250665 -358.936951)
			(xy 44.290263 -358.978928) (xy 44.323086 -359.026392) (xy 44.348384 -359.078259) (xy 44.36558 -359.133345)
			(xy 44.374282 -359.190392) (xy 44.374816 -359.219246) (xy 44.37433 -359.246497) (xy 44.366574 -359.300445)
			(xy 44.351219 -359.35274) (xy 44.328577 -359.402317) (xy 44.299111 -359.448167) (xy 44.26342 -359.489358)
			(xy 44.222229 -359.525049) (xy 44.176379 -359.554515) (xy 44.126802 -359.577157) (xy 44.074507 -359.592512)
			(xy 44.020559 -359.600268) (xy 43.966057 -359.600268) (xy 43.912109 -359.592512) (xy 43.859814 -359.577157)
			(xy 43.810237 -359.554515) (xy 43.764387 -359.525049) (xy 43.723196 -359.489358) (xy 43.687505 -359.448167)
			(xy 43.658039 -359.402317) (xy 43.635397 -359.35274) (xy 43.620042 -359.300445) (xy 43.612286 -359.246497)
			(xy 43.6118 -359.219246) (xy 43.612354 -359.190782) (xy 43.620824 -359.134488) (xy 43.637567 -359.080079)
			(xy 43.662213 -359.028763) (xy 43.694212 -358.98168) (xy 43.713146 -358.96042) (xy 43.720258 -358.952546)
			(xy 43.727116 -358.932734) (xy 43.719496 -358.836468) (xy 43.70959 -358.817926) (xy 43.700954 -358.811322)
			(xy 43.678543 -358.79314) (xy 43.638944 -358.751162) (xy 43.606122 -358.703697) (xy 43.580824 -358.65183)
			(xy 43.563629 -358.596743) (xy 43.554929 -358.539694) (xy 43.554396 -358.51084) (xy 41.749099 -358.51084)
			(xy 41.750825 -358.523683) (xy 41.75125 -358.549194) (xy 41.750733 -358.577659) (xy 41.742256 -358.633955)
			(xy 41.725505 -358.688366) (xy 41.700851 -358.739682) (xy 41.668842 -358.786762) (xy 41.649904 -358.80802)
			(xy 41.642792 -358.815894) (xy 41.635934 -358.835706) (xy 41.643554 -358.931972) (xy 41.65346 -358.950514)
			(xy 41.662096 -358.957118) (xy 41.684516 -358.97529) (xy 41.724116 -359.017269) (xy 41.756939 -359.064735)
			(xy 41.782236 -359.116605) (xy 41.799428 -359.171694) (xy 41.808123 -359.228745) (xy 41.808654 -359.2576)
			(xy 41.808168 -359.284851) (xy 41.800412 -359.338799) (xy 41.785057 -359.391094) (xy 41.762415 -359.440671)
			(xy 41.732949 -359.486521) (xy 41.697258 -359.527712) (xy 41.656067 -359.563403) (xy 41.610217 -359.592869)
			(xy 41.56064 -359.615511) (xy 41.508345 -359.630866) (xy 41.454397 -359.638622) (xy 41.399895 -359.638622)
			(xy 41.345947 -359.630866) (xy 41.293652 -359.615511) (xy 41.244075 -359.592869) (xy 41.198225 -359.563403)
			(xy 41.157034 -359.527712) (xy 41.121343 -359.486521) (xy 41.091877 -359.440671) (xy 41.069235 -359.391094)
			(xy 41.05388 -359.338799) (xy 41.046124 -359.284851) (xy 41.045638 -359.2576) (xy 41.046154 -359.229135)
			(xy 41.054632 -359.172839) (xy 41.071384 -359.118428) (xy 41.096038 -359.067113) (xy 41.128046 -359.020032)
			(xy 41.146984 -358.998774) (xy 41.154096 -358.9909) (xy 41.160954 -358.971088) (xy 41.153334 -358.874822)
			(xy 41.143428 -358.85628) (xy 41.134792 -358.849676) (xy 41.112367 -358.831511) (xy 41.072767 -358.78953)
			(xy 41.039945 -358.742062) (xy 41.01465 -358.690191) (xy 40.997459 -358.635101) (xy 40.988764 -358.578049)
			(xy 40.988234 -358.549194) (xy 39.518082 -358.549194) (xy 36.72967 -361.337606) (xy 36.711561 -361.354829)
			(xy 36.670001 -361.382571) (xy 36.623831 -361.401682) (xy 36.574822 -361.411428) (xy 36.549838 -361.412028)
			(xy 34.206434 -361.412028) (xy 34.19641 -361.412442) (xy 34.177887 -361.420107) (xy 34.163711 -361.434282)
			(xy 34.156043 -361.452804) (xy 34.155634 -361.462828) (xy 34.155634 -362.077) (xy 37.946582 -362.077)
			(xy 37.950653 -362.021378) (xy 37.962779 -361.966941) (xy 37.982702 -361.91485) (xy 38.009998 -361.866215)
			(xy 38.044084 -361.822072) (xy 38.084233 -361.783363) (xy 38.129591 -361.750912) (xy 38.179191 -361.725411)
			(xy 38.231975 -361.707404) (xy 38.286818 -361.697274) (xy 38.342552 -361.695237) (xy 38.397989 -361.701337)
			(xy 38.451946 -361.715443) (xy 38.503275 -361.737255) (xy 38.550881 -361.766309) (xy 38.593749 -361.801984)
			(xy 38.630966 -361.843521) (xy 38.661739 -361.890034) (xy 38.685411 -361.940531) (xy 38.701479 -361.993938)
			(xy 38.709599 -362.049114) (xy 38.710108 -362.077) (xy 38.709599 -362.104886) (xy 38.701479 -362.160062)
			(xy 38.685411 -362.213469) (xy 38.661739 -362.263966) (xy 38.630966 -362.310479) (xy 38.593749 -362.352016)
			(xy 38.550881 -362.387691) (xy 38.503275 -362.416745) (xy 38.451946 -362.438557) (xy 38.397989 -362.452663)
			(xy 38.342552 -362.458763) (xy 38.286818 -362.456726) (xy 38.231975 -362.446596) (xy 38.179191 -362.428589)
			(xy 38.129591 -362.403088) (xy 38.084233 -362.370637) (xy 38.044084 -362.331928) (xy 38.009998 -362.287785)
			(xy 37.982702 -362.23915) (xy 37.962779 -362.187059) (xy 37.950653 -362.132622) (xy 37.946582 -362.077)
			(xy 34.155634 -362.077) (xy 34.155634 -363.093) (xy 35.558982 -363.093) (xy 35.563053 -363.037378)
			(xy 35.575179 -362.982941) (xy 35.595102 -362.93085) (xy 35.622398 -362.882215) (xy 35.656484 -362.838072)
			(xy 35.696633 -362.799363) (xy 35.741991 -362.766912) (xy 35.791591 -362.741411) (xy 35.844375 -362.723404)
			(xy 35.899218 -362.713274) (xy 35.954952 -362.711237) (xy 36.010389 -362.717337) (xy 36.064346 -362.731443)
			(xy 36.115675 -362.753255) (xy 36.163281 -362.782309) (xy 36.206149 -362.817984) (xy 36.243366 -362.859521)
			(xy 36.274139 -362.906034) (xy 36.297811 -362.956531) (xy 36.313879 -363.009938) (xy 36.321999 -363.065114)
			(xy 36.322508 -363.093) (xy 36.321999 -363.120886) (xy 36.313879 -363.176062) (xy 36.297811 -363.229469)
			(xy 36.274139 -363.279966) (xy 36.243366 -363.326479) (xy 36.206149 -363.368016) (xy 36.163281 -363.403691)
			(xy 36.115675 -363.432745) (xy 36.064346 -363.454557) (xy 36.010389 -363.468663) (xy 35.954952 -363.474763)
			(xy 35.899218 -363.472726) (xy 35.844375 -363.462596) (xy 35.791591 -363.444589) (xy 35.741991 -363.419088)
			(xy 35.696633 -363.386637) (xy 35.656484 -363.347928) (xy 35.622398 -363.303785) (xy 35.595102 -363.25515)
			(xy 35.575179 -363.203059) (xy 35.563053 -363.148622) (xy 35.558982 -363.093) (xy 34.155634 -363.093)
			(xy 34.155634 -363.339126) (xy 34.155979 -363.348502) (xy 34.162712 -363.366) (xy 34.175327 -363.379869)
			(xy 34.183574 -363.384338) (xy 34.2773 -363.431836) (xy 34.305748 -363.42955) (xy 34.317432 -363.420914)
			(xy 34.342173 -363.403408) (xy 34.396032 -363.37562) (xy 34.453604 -363.356689) (xy 34.513444 -363.34709)
			(xy 34.543746 -363.346492) (xy 34.544 -363.346492) (xy 34.571251 -363.346978) (xy 34.625199 -363.354734)
			(xy 34.677494 -363.370089) (xy 34.727071 -363.392731) (xy 34.772921 -363.422197) (xy 34.814112 -363.457888)
			(xy 34.849803 -363.499079) (xy 34.879269 -363.544929) (xy 34.901911 -363.594506) (xy 34.917266 -363.646801)
			(xy 34.925022 -363.700749) (xy 34.925022 -363.755251) (xy 34.917266 -363.809199) (xy 34.901911 -363.861494)
			(xy 34.879269 -363.911071) (xy 34.849803 -363.956921) (xy 34.814112 -363.998112) (xy 34.772921 -364.033803)
			(xy 34.727071 -364.063269) (xy 34.677494 -364.085911) (xy 34.625199 -364.101266) (xy 34.571404 -364.109)
			(xy 35.559492 -364.109) (xy 35.559978 -364.081749) (xy 35.567734 -364.027801) (xy 35.583089 -363.975506)
			(xy 35.605731 -363.925929) (xy 35.635197 -363.880079) (xy 35.670888 -363.838888) (xy 35.712079 -363.803197)
			(xy 35.757929 -363.773731) (xy 35.807506 -363.751089) (xy 35.859801 -363.735734) (xy 35.913749 -363.727978)
			(xy 35.968251 -363.727978) (xy 36.022199 -363.735734) (xy 36.074494 -363.751089) (xy 36.124071 -363.773731)
			(xy 36.169921 -363.803197) (xy 36.211112 -363.838888) (xy 36.246803 -363.880079) (xy 36.276269 -363.925929)
			(xy 36.298911 -363.975506) (xy 36.314266 -364.027801) (xy 36.322022 -364.081749) (xy 36.322508 -364.109)
			(xy 36.322005 -364.137749) (xy 36.313352 -364.194592) (xy 36.296272 -364.249494) (xy 36.271152 -364.301214)
			(xy 36.238559 -364.348581) (xy 36.199231 -364.390525) (xy 36.176966 -364.40872) (xy 36.176712 -364.40872)
			(xy 36.168019 -364.416374) (xy 36.158097 -364.437277) (xy 36.157662 -364.448852) (xy 36.157916 -364.529116)
			(xy 36.158472 -364.540686) (xy 36.168676 -364.561457) (xy 36.177474 -364.568994) (xy 36.177728 -364.568994)
			(xy 36.2004 -364.587168) (xy 36.203652 -364.590584) (xy 39.286178 -364.590584) (xy 39.290249 -364.534962)
			(xy 39.302375 -364.480525) (xy 39.322298 -364.428434) (xy 39.349594 -364.379799) (xy 39.38368 -364.335656)
			(xy 39.423829 -364.296947) (xy 39.469187 -364.264496) (xy 39.518787 -364.238995) (xy 39.571571 -364.220988)
			(xy 39.626414 -364.210858) (xy 39.682148 -364.208821) (xy 39.737585 -364.214921) (xy 39.791542 -364.229027)
			(xy 39.842871 -364.250839) (xy 39.890477 -364.279893) (xy 39.933345 -364.315568) (xy 39.970562 -364.357105)
			(xy 40.001335 -364.403618) (xy 40.025007 -364.454115) (xy 40.041075 -364.507522) (xy 40.049195 -364.562698)
			(xy 40.049704 -364.590584) (xy 40.049195 -364.61847) (xy 40.041075 -364.673646) (xy 40.025007 -364.727053)
			(xy 40.001335 -364.77755) (xy 39.970562 -364.824063) (xy 39.933345 -364.8656) (xy 39.890477 -364.901275)
			(xy 39.842871 -364.930329) (xy 39.791542 -364.952141) (xy 39.737585 -364.966247) (xy 39.682148 -364.972347)
			(xy 39.626414 -364.97031) (xy 39.571571 -364.96018) (xy 39.518787 -364.942173) (xy 39.469187 -364.916672)
			(xy 39.423829 -364.884221) (xy 39.38368 -364.845512) (xy 39.349594 -364.801369) (xy 39.322298 -364.752734)
			(xy 39.302375 -364.700643) (xy 39.290249 -364.646206) (xy 39.286178 -364.590584) (xy 36.203652 -364.590584)
			(xy 36.240465 -364.629252) (xy 36.273688 -364.676923) (xy 36.299301 -364.729078) (xy 36.316712 -364.784513)
			(xy 36.32552 -364.841947) (xy 36.326064 -364.871) (xy 36.325578 -364.898251) (xy 36.317822 -364.952199)
			(xy 36.302467 -365.004494) (xy 36.279825 -365.054071) (xy 36.250359 -365.099921) (xy 36.214668 -365.141112)
			(xy 36.173477 -365.176803) (xy 36.127627 -365.206269) (xy 36.07805 -365.228911) (xy 36.025755 -365.244266)
			(xy 35.971807 -365.252022) (xy 35.917305 -365.252022) (xy 35.863357 -365.244266) (xy 35.811062 -365.228911)
			(xy 35.761485 -365.206269) (xy 35.715635 -365.176803) (xy 35.674444 -365.141112) (xy 35.638753 -365.099921)
			(xy 35.609287 -365.054071) (xy 35.586645 -365.004494) (xy 35.57129 -364.952199) (xy 35.563534 -364.898251)
			(xy 35.563048 -364.871) (xy 35.56353 -364.84225) (xy 35.572184 -364.785405) (xy 35.589267 -364.730502)
			(xy 35.614391 -364.678781) (xy 35.646989 -364.631415) (xy 35.686323 -364.589473) (xy 35.70859 -364.57128)
			(xy 35.708844 -364.57128) (xy 35.717546 -364.563635) (xy 35.727461 -364.542724) (xy 35.727894 -364.531148)
			(xy 35.72764 -364.450884) (xy 35.7271 -364.439312) (xy 35.716886 -364.41854) (xy 35.708082 -364.411006)
			(xy 35.707828 -364.411006) (xy 35.685147 -364.392843) (xy 35.645085 -364.350755) (xy 35.611864 -364.303082)
			(xy 35.586253 -364.250925) (xy 35.568843 -364.195488) (xy 35.560036 -364.138053) (xy 35.559492 -364.109)
			(xy 34.571404 -364.109) (xy 34.571251 -364.109022) (xy 34.544 -364.109508) (xy 34.543746 -364.109508)
			(xy 34.513442 -364.108927) (xy 34.453597 -364.099342) (xy 34.396023 -364.080406) (xy 34.342172 -364.052596)
			(xy 34.317432 -364.035086) (xy 34.305748 -364.02645) (xy 34.2773 -364.024164) (xy 34.183574 -364.071662)
			(xy 34.175441 -364.076271) (xy 34.162917 -364.090128) (xy 34.156152 -364.107538) (xy 34.155634 -364.116874)
			(xy 34.155634 -364.856268) (xy 34.15607 -364.866332) (xy 34.163806 -364.884915) (xy 34.17062 -364.892336)
			(xy 34.828226 -365.549942) (xy 34.861246 -365.554768) (xy 34.875978 -365.546894) (xy 34.903707 -365.532824)
			(xy 34.962606 -365.512902) (xy 35.023959 -365.502819) (xy 35.055048 -365.50219) (xy 35.055302 -365.50219)
			(xy 35.082553 -365.502676) (xy 35.136501 -365.510433) (xy 35.188795 -365.525788) (xy 35.238373 -365.548429)
			(xy 35.284223 -365.577895) (xy 35.325413 -365.613587) (xy 35.361105 -365.654777) (xy 35.390571 -365.700627)
			(xy 35.413212 -365.750205) (xy 35.428567 -365.802499) (xy 35.436324 -365.856447) (xy 35.43681 -365.883698)
			(xy 35.43681 -365.883952) (xy 35.436174 -365.915038) (xy 35.426062 -365.976385) (xy 35.406162 -366.035288)
			(xy 35.392106 -366.063022) (xy 35.391834 -366.06353) (xy 38.846504 -366.06353) (xy 38.850575 -366.007908)
			(xy 38.862701 -365.953471) (xy 38.882624 -365.90138) (xy 38.90992 -365.852745) (xy 38.944006 -365.808602)
			(xy 38.984155 -365.769893) (xy 39.029513 -365.737442) (xy 39.079113 -365.711941) (xy 39.131897 -365.693934)
			(xy 39.18674 -365.683804) (xy 39.242474 -365.681767) (xy 39.297911 -365.687867) (xy 39.351868 -365.701973)
			(xy 39.403197 -365.723785) (xy 39.450803 -365.752839) (xy 39.493671 -365.788514) (xy 39.530888 -365.830051)
			(xy 39.561661 -365.876564) (xy 39.585333 -365.927061) (xy 39.601401 -365.980468) (xy 39.609521 -366.035644)
			(xy 39.61003 -366.06353) (xy 39.609521 -366.091416) (xy 39.601401 -366.146592) (xy 39.585333 -366.199999)
			(xy 39.561661 -366.250496) (xy 39.530888 -366.297009) (xy 39.493671 -366.338546) (xy 39.450803 -366.374221)
			(xy 39.403197 -366.403275) (xy 39.351868 -366.425087) (xy 39.297911 -366.439193) (xy 39.242474 -366.445293)
			(xy 39.18674 -366.443256) (xy 39.131897 -366.433126) (xy 39.079113 -366.415119) (xy 39.029513 -366.389618)
			(xy 38.984155 -366.357167) (xy 38.944006 -366.318458) (xy 38.90992 -366.274315) (xy 38.882624 -366.22568)
			(xy 38.862701 -366.173589) (xy 38.850575 -366.119152) (xy 38.846504 -366.06353) (xy 35.391834 -366.06353)
			(xy 35.384232 -366.077754) (xy 35.389058 -366.110774) (xy 36.025328 -366.747044) (xy 36.032725 -366.753892)
			(xy 36.051324 -366.761625) (xy 36.061396 -366.76203)
		)
		(stroke
			(width 0)
			(type solid)
		)
		(fill yes)
		(layer "In6.Cu")
		(net "GND")
	)
	(gr_poly
		(pts
			(xy 302.813212 -366.633252) (xy 302.822183 -366.632803) (xy 302.838958 -366.626412) (xy 302.845978 -366.620806)
			(xy 302.853598 -366.612678) (xy 302.901604 -366.548162) (xy 302.907153 -366.539859) (xy 302.911996 -366.520506)
			(xy 302.911002 -366.51057) (xy 302.909986 -366.50295) (xy 302.90897 -366.499648) (xy 302.90221 -366.47421)
			(xy 302.894943 -366.422079) (xy 302.894492 -366.395762) (xy 302.894492 -366.395) (xy 302.894978 -366.367749)
			(xy 302.902734 -366.313801) (xy 302.918089 -366.261506) (xy 302.940731 -366.211929) (xy 302.970197 -366.166079)
			(xy 303.005888 -366.124888) (xy 303.047079 -366.089197) (xy 303.092929 -366.059731) (xy 303.142506 -366.037089)
			(xy 303.194801 -366.021734) (xy 303.248749 -366.013978) (xy 303.303251 -366.013978) (xy 303.357199 -366.021734)
			(xy 303.409494 -366.037089) (xy 303.459071 -366.059731) (xy 303.504921 -366.089197) (xy 303.546112 -366.124888)
			(xy 303.581803 -366.166079) (xy 303.611269 -366.211929) (xy 303.633911 -366.261506) (xy 303.649266 -366.313801)
			(xy 303.657022 -366.367749) (xy 303.657508 -366.395) (xy 303.657508 -366.395762) (xy 303.65705 -366.422079)
			(xy 303.64979 -366.47421) (xy 303.64303 -366.499648) (xy 303.642014 -366.50295) (xy 303.640998 -366.51057)
			(xy 303.640035 -366.520504) (xy 303.644876 -366.539846) (xy 303.650396 -366.548162) (xy 303.698402 -366.612678)
			(xy 303.706022 -366.620806) (xy 303.713033 -366.626422) (xy 303.729816 -366.632799) (xy 303.738788 -366.633252)
			(xy 303.739296 -366.633252) (xy 310.543702 -366.633252) (xy 310.5531 -366.632236) (xy 310.560413 -366.63064)
			(xy 310.573722 -366.623806) (xy 310.579262 -366.618774) (xy 312.455306 -364.74273) (xy 312.462141 -364.735327)
			(xy 312.469849 -364.716729) (xy 312.470292 -364.706662) (xy 312.470292 -357.958644) (xy 312.469788 -357.94822)
			(xy 312.461527 -357.929079) (xy 312.45429 -357.92156) (xy 312.431938 -357.900478) (xy 312.424616 -357.894098)
			(xy 312.406589 -357.886923) (xy 312.396886 -357.886508) (xy 307.599334 -357.886508) (xy 307.574339 -357.885869)
			(xy 307.525318 -357.876066) (xy 307.479152 -357.856887) (xy 307.437614 -357.829071) (xy 307.419502 -357.811832)
			(xy 303.655984 -354.048314) (xy 303.648872 -354.040948) (xy 303.630076 -354.033328) (xy 301.295308 -354.033328)
			(xy 301.285238 -354.03375) (xy 301.266634 -354.041466) (xy 301.25924 -354.048314) (xy 300.878494 -354.42906)
			(xy 300.860398 -354.446314) (xy 300.818851 -354.47412) (xy 300.77268 -354.49329) (xy 300.723658 -354.503089)
			(xy 300.698662 -354.503736) (xy 275.648928 -354.503736) (xy 275.623933 -354.503097) (xy 275.574912 -354.493293)
			(xy 275.528745 -354.474115) (xy 275.487206 -354.446301) (xy 275.469096 -354.42906) (xy 272.756376 -351.71634)
			(xy 272.739156 -351.698229) (xy 272.711421 -351.656668) (xy 272.692317 -351.610498) (xy 272.682578 -351.561491)
			(xy 272.681954 -351.536508) (xy 272.681954 -350.877632) (xy 272.682562 -350.852647) (xy 272.692298 -350.803636)
			(xy 272.711403 -350.757463) (xy 272.739144 -350.715901) (xy 272.756376 -350.6978) (xy 272.970498 -350.483932)
			(xy 273.097498 -350.356932) (xy 273.106004 -350.348577) (xy 273.124322 -350.333311) (xy 273.134074 -350.326452)
			(xy 273.137705 -350.323917) (xy 273.144094 -350.317785) (xy 273.146774 -350.31426) (xy 273.162197 -350.293517)
			(xy 273.197738 -350.255984) (xy 273.238021 -350.223594) (xy 273.282308 -350.196938) (xy 273.329789 -350.176505)
			(xy 273.379593 -350.16267) (xy 273.430809 -350.155685) (xy 273.456654 -350.155256) (xy 273.48391 -350.155716)
			(xy 273.537868 -350.163467) (xy 273.590173 -350.178819) (xy 273.639762 -350.201458) (xy 273.685623 -350.230924)
			(xy 273.726824 -350.266618) (xy 273.762526 -350.307811) (xy 273.792002 -350.353666) (xy 273.814652 -350.40325)
			(xy 273.830015 -350.455552) (xy 273.837778 -350.509508) (xy 273.838162 -350.536764) (xy 273.837681 -350.564226)
			(xy 273.829805 -350.618582) (xy 273.814225 -350.67125) (xy 273.811556 -350.67705) (xy 274.079972 -350.67705)
			(xy 274.079972 -350.62255) (xy 274.087728 -350.568604) (xy 274.103081 -350.516311) (xy 274.125721 -350.466735)
			(xy 274.155185 -350.420885) (xy 274.190874 -350.379695) (xy 274.232061 -350.344003) (xy 274.277908 -350.314535)
			(xy 274.327482 -350.291892) (xy 274.379774 -350.276534) (xy 274.43372 -350.268774) (xy 274.46097 -350.268286)
			(xy 274.486206 -350.268654) (xy 274.536241 -350.275281) (xy 274.584962 -350.288463) (xy 274.631512 -350.307967)
			(xy 274.653502 -350.320356) (xy 274.663154 -350.326198) (xy 274.685252 -350.32823) (xy 274.77974 -350.294702)
			(xy 274.795742 -350.279208) (xy 274.799806 -350.268794) (xy 274.810477 -350.242007) (xy 274.838768 -350.191764)
			(xy 274.874301 -350.146354) (xy 274.916266 -350.106811) (xy 274.963707 -350.074039) (xy 275.015542 -350.048783)
			(xy 275.070589 -350.03162) (xy 275.127592 -350.022941) (xy 275.156422 -350.022414) (xy 275.183675 -350.022857)
			(xy 275.237625 -350.030617) (xy 275.289922 -350.045977) (xy 275.339501 -350.068622) (xy 275.385352 -350.098092)
			(xy 275.426543 -350.133788) (xy 275.462234 -350.174983) (xy 275.491699 -350.220838) (xy 275.514339 -350.270419)
			(xy 275.52706 -350.313752) (xy 277.667974 -350.313752) (xy 277.668485 -350.286179) (xy 277.676429 -350.231609)
			(xy 277.692146 -350.17875) (xy 277.715308 -350.128704) (xy 277.745432 -350.082513) (xy 277.781891 -350.04114)
			(xy 277.802594 -350.022922) (xy 277.810697 -350.015306) (xy 277.82006 -349.995165) (xy 277.820628 -349.98406)
			(xy 277.820628 -349.906844) (xy 277.820075 -349.895732) (xy 277.810728 -349.875572) (xy 277.802594 -349.867982)
			(xy 277.78187 -349.849785) (xy 277.745401 -349.808413) (xy 277.71527 -349.76222) (xy 277.692107 -349.71217)
			(xy 277.676393 -349.659304) (xy 277.668457 -349.604728) (xy 277.667974 -349.577152) (xy 277.668433 -349.5499)
			(xy 277.676196 -349.495953) (xy 277.691556 -349.443659) (xy 277.714201 -349.394082) (xy 277.743671 -349.348233)
			(xy 277.779365 -349.307044) (xy 277.820557 -349.271353) (xy 277.866409 -349.241887) (xy 277.915987 -349.219245)
			(xy 277.968282 -349.203889) (xy 278.02223 -349.196131) (xy 278.049482 -349.195644) (xy 278.083772 -349.197168)
			(xy 278.093932 -349.198184) (xy 278.113236 -349.192088) (xy 278.183848 -349.132906) (xy 278.193246 -349.114872)
			(xy 278.194262 -349.104712) (xy 278.197203 -349.076538) (xy 278.210381 -349.021447) (xy 278.231563 -348.968911)
			(xy 278.260283 -348.920087) (xy 278.295909 -348.876047) (xy 278.337657 -348.837761) (xy 278.384609 -348.806072)
			(xy 278.435731 -348.781676) (xy 278.4899 -348.76511) (xy 278.545923 -348.756738) (xy 278.574246 -348.756224)
			(xy 278.592265 -348.756444) (xy 278.62814 -348.759879) (xy 278.645874 -348.763082) (xy 278.655272 -348.76486)
			(xy 278.674322 -348.76105) (xy 278.749506 -348.713298) (xy 278.760936 -348.69755) (xy 278.763222 -348.688152)
			(xy 278.770612 -348.661106) (xy 278.792243 -348.609379) (xy 278.821208 -348.561373) (xy 278.856884 -348.518122)
			(xy 278.898505 -348.480555) (xy 278.945173 -348.449481) (xy 278.995885 -348.425569) (xy 279.04955 -348.409333)
			(xy 279.105013 -348.401122) (xy 279.133046 -348.400624) (xy 279.1603 -348.401035) (xy 279.214252 -348.408799)
			(xy 279.26655 -348.424161) (xy 279.31613 -348.44681) (xy 279.361981 -348.476284) (xy 279.403172 -348.511983)
			(xy 279.438863 -348.553181) (xy 279.468327 -348.599039) (xy 279.490966 -348.648623) (xy 279.506318 -348.700924)
			(xy 279.51407 -348.754878) (xy 279.514554 -348.782132) (xy 279.514058 -348.809706) (xy 279.506114 -348.864278)
			(xy 279.490396 -348.917138) (xy 279.467232 -348.967184) (xy 279.437104 -349.013375) (xy 279.40064 -349.054746)
			(xy 279.379934 -349.072962) (xy 279.371827 -349.080574) (xy 279.362469 -349.100719) (xy 279.3619 -349.111824)
			(xy 279.3619 -349.18904) (xy 279.36243 -349.200154) (xy 279.371796 -349.220313) (xy 279.379934 -349.227902)
			(xy 279.40067 -349.246084) (xy 279.43713 -349.287461) (xy 279.467254 -349.333656) (xy 279.490413 -349.383707)
			(xy 279.506124 -349.436571) (xy 279.514061 -349.491146) (xy 279.514058 -349.546295) (xy 279.506115 -349.60087)
			(xy 279.505539 -349.602806) (xy 280.59583 -349.602806) (xy 280.599901 -349.547184) (xy 280.612027 -349.492747)
			(xy 280.63195 -349.440656) (xy 280.659246 -349.392021) (xy 280.693332 -349.347878) (xy 280.733481 -349.309169)
			(xy 280.778839 -349.276718) (xy 280.828439 -349.251217) (xy 280.881223 -349.23321) (xy 280.936066 -349.22308)
			(xy 280.9918 -349.221043) (xy 281.047237 -349.227143) (xy 281.101194 -349.241249) (xy 281.152523 -349.263061)
			(xy 281.200129 -349.292115) (xy 281.242997 -349.32779) (xy 281.280214 -349.369327) (xy 281.310987 -349.41584)
			(xy 281.334659 -349.466337) (xy 281.350727 -349.519744) (xy 281.358847 -349.57492) (xy 281.359356 -349.602806)
			(xy 281.358847 -349.630692) (xy 281.350727 -349.685868) (xy 281.334659 -349.739275) (xy 281.310987 -349.789772)
			(xy 281.280214 -349.836285) (xy 281.242997 -349.877822) (xy 281.200129 -349.913497) (xy 281.152523 -349.942551)
			(xy 281.101194 -349.964363) (xy 281.047237 -349.978469) (xy 280.9918 -349.984569) (xy 280.936066 -349.982532)
			(xy 280.881223 -349.972402) (xy 280.828439 -349.954395) (xy 280.778839 -349.928894) (xy 280.733481 -349.896443)
			(xy 280.693332 -349.857734) (xy 280.659246 -349.813591) (xy 280.63195 -349.764956) (xy 280.612027 -349.712865)
			(xy 280.599901 -349.658428) (xy 280.59583 -349.602806) (xy 279.505539 -349.602806) (xy 279.490398 -349.653732)
			(xy 279.467234 -349.70378) (xy 279.437105 -349.749972) (xy 279.40064 -349.791345) (xy 279.379934 -349.809562)
			(xy 279.371827 -349.817174) (xy 279.362469 -349.837319) (xy 279.3619 -349.848424) (xy 279.3619 -349.92564)
			(xy 279.36243 -349.936754) (xy 279.371796 -349.956913) (xy 279.379934 -349.964502) (xy 279.400656 -349.982701)
			(xy 279.437124 -350.024073) (xy 279.467254 -350.070266) (xy 279.490418 -350.120316) (xy 279.506132 -350.17318)
			(xy 279.51407 -350.227757) (xy 279.514554 -350.255332) (xy 279.514052 -350.282582) (xy 279.506292 -350.336527)
			(xy 279.490936 -350.388818) (xy 279.468294 -350.438393) (xy 279.438829 -350.484241) (xy 279.426771 -350.498156)
			(xy 280.01671 -350.498156) (xy 280.020781 -350.442534) (xy 280.032907 -350.388097) (xy 280.05283 -350.336006)
			(xy 280.080126 -350.287371) (xy 280.114212 -350.243228) (xy 280.154361 -350.204519) (xy 280.199719 -350.172068)
			(xy 280.249319 -350.146567) (xy 280.302103 -350.12856) (xy 280.356946 -350.11843) (xy 280.41268 -350.116393)
			(xy 280.468117 -350.122493) (xy 280.522074 -350.136599) (xy 280.573403 -350.158411) (xy 280.621009 -350.187465)
			(xy 280.663877 -350.22314) (xy 280.701094 -350.264677) (xy 280.731867 -350.31119) (xy 280.755539 -350.361687)
			(xy 280.771607 -350.415094) (xy 280.779727 -350.47027) (xy 280.780236 -350.498156) (xy 280.779727 -350.526042)
			(xy 280.771607 -350.581218) (xy 280.755539 -350.634625) (xy 280.731867 -350.685122) (xy 280.701094 -350.731635)
			(xy 280.663877 -350.773172) (xy 280.621009 -350.808847) (xy 280.573403 -350.837901) (xy 280.522074 -350.859713)
			(xy 280.468117 -350.873819) (xy 280.41268 -350.879919) (xy 280.356946 -350.877882) (xy 280.302103 -350.867752)
			(xy 280.249319 -350.849745) (xy 280.199719 -350.824244) (xy 280.154361 -350.791793) (xy 280.114212 -350.753084)
			(xy 280.080126 -350.708941) (xy 280.05283 -350.660306) (xy 280.032907 -350.608215) (xy 280.020781 -350.553778)
			(xy 280.01671 -350.498156) (xy 279.426771 -350.498156) (xy 279.403139 -350.525429) (xy 279.361952 -350.56112)
			(xy 279.316105 -350.590587) (xy 279.266531 -350.613231) (xy 279.21424 -350.628589) (xy 279.160296 -350.636351)
			(xy 279.133046 -350.63684) (xy 279.105193 -350.636246) (xy 279.050082 -350.62813) (xy 278.996735 -350.612092)
			(xy 278.946285 -350.588474) (xy 278.899801 -350.557776) (xy 278.858271 -350.52065) (xy 278.822576 -350.477884)
			(xy 278.793473 -350.430385) (xy 278.771581 -350.379161) (xy 278.763984 -350.35236) (xy 278.761698 -350.34347)
			(xy 278.75103 -350.32823) (xy 278.679148 -350.280478) (xy 278.661114 -350.276414) (xy 278.65197 -350.277684)
			(xy 278.638954 -350.279354) (xy 278.612769 -350.281133) (xy 278.599646 -350.28124) (xy 278.585497 -350.281141)
			(xy 278.557274 -350.27911) (xy 278.543258 -350.277176) (xy 278.533098 -350.275652) (xy 278.51354 -350.280478)
			(xy 278.439118 -350.336358) (xy 278.428958 -350.353884) (xy 278.427688 -350.364044) (xy 278.423627 -350.391202)
			(xy 278.408653 -350.444035) (xy 278.386259 -350.494175) (xy 278.356909 -350.540587) (xy 278.321209 -350.582312)
			(xy 278.279895 -350.618488) (xy 278.233823 -350.648368) (xy 278.183943 -350.671335) (xy 278.131286 -350.686914)
			(xy 278.076939 -350.694784) (xy 278.049482 -350.69526) (xy 278.022226 -350.694862) (xy 277.968271 -350.687101)
			(xy 277.915969 -350.67174) (xy 277.866385 -350.649092) (xy 277.82053 -350.619618) (xy 277.779336 -350.583917)
			(xy 277.743643 -350.542717) (xy 277.714176 -350.496857) (xy 277.691537 -350.447269) (xy 277.676185 -350.394965)
			(xy 277.668434 -350.341008) (xy 277.667974 -350.313752) (xy 275.52706 -350.313752) (xy 275.529692 -350.322718)
			(xy 275.537446 -350.376669) (xy 275.53793 -350.403922) (xy 275.53726 -350.435484) (xy 275.526876 -350.497749)
			(xy 275.506395 -350.557459) (xy 275.491956 -350.585532) (xy 275.48713 -350.594422) (xy 275.485098 -350.61398)
			(xy 275.510752 -350.702118) (xy 275.523198 -350.717612) (xy 275.532088 -350.722692) (xy 275.557211 -350.737205)
			(xy 275.603094 -350.772714) (xy 275.643068 -350.814763) (xy 275.676212 -350.862383) (xy 275.701759 -350.914474)
			(xy 275.71912 -350.969834) (xy 275.727895 -351.027185) (xy 275.72843 -351.056194) (xy 275.727944 -351.083445)
			(xy 275.720188 -351.137393) (xy 275.704833 -351.189688) (xy 275.682191 -351.239265) (xy 275.652725 -351.285115)
			(xy 275.617034 -351.326306) (xy 275.575843 -351.361997) (xy 275.529993 -351.391463) (xy 275.480416 -351.414105)
			(xy 275.428121 -351.42946) (xy 275.374173 -351.437216) (xy 275.319671 -351.437216) (xy 275.265723 -351.42946)
			(xy 275.213428 -351.414105) (xy 275.163851 -351.391463) (xy 275.118001 -351.361997) (xy 275.07681 -351.326306)
			(xy 275.041119 -351.285115) (xy 275.011653 -351.239265) (xy 274.989011 -351.189688) (xy 274.973656 -351.137393)
			(xy 274.9659 -351.083445) (xy 274.965414 -351.056194) (xy 274.966085 -351.024632) (xy 274.976467 -350.962367)
			(xy 274.996949 -350.902657) (xy 275.011388 -350.874584) (xy 275.016214 -350.865694) (xy 275.018246 -350.846136)
			(xy 274.992592 -350.757998) (xy 274.980146 -350.742504) (xy 274.971256 -350.737424) (xy 274.96389 -350.73336)
			(xy 274.954238 -350.727518) (xy 274.93214 -350.725486) (xy 274.837652 -350.759014) (xy 274.82165 -350.774508)
			(xy 274.817586 -350.784922) (xy 274.80693 -350.811715) (xy 274.778637 -350.861958) (xy 274.743101 -350.907368)
			(xy 274.701133 -350.94691) (xy 274.65369 -350.979681) (xy 274.601854 -351.004936) (xy 274.546805 -351.022098)
			(xy 274.489801 -351.030775) (xy 274.46097 -351.031302) (xy 274.43372 -351.030826) (xy 274.379774 -351.023066)
			(xy 274.327482 -351.007708) (xy 274.277908 -350.985065) (xy 274.232061 -350.955597) (xy 274.190874 -350.919905)
			(xy 274.155185 -350.878715) (xy 274.125721 -350.832865) (xy 274.103081 -350.783289) (xy 274.087728 -350.730996)
			(xy 274.079972 -350.67705) (xy 273.811556 -350.67705) (xy 273.791261 -350.721144) (xy 273.761388 -350.767233)
			(xy 273.743674 -350.788224) (xy 273.737324 -350.795336) (xy 273.730974 -350.812354) (xy 273.730974 -350.898206)
			(xy 273.737324 -350.915224) (xy 273.743674 -350.922336) (xy 273.761403 -350.943315) (xy 273.79128 -350.989404)
			(xy 273.814242 -351.0393) (xy 273.829814 -351.091972) (xy 273.837674 -351.146333) (xy 273.838162 -351.173796)
			(xy 273.837623 -351.203425) (xy 273.828494 -351.261975) (xy 273.81041 -351.318405) (xy 273.783806 -351.371355)
			(xy 273.767042 -351.395792) (xy 273.76247 -351.401888) (xy 273.757136 -351.418398) (xy 273.754477 -351.427447)
			(xy 273.755327 -351.446276) (xy 273.762954 -351.463512) (xy 273.769328 -351.470468) (xy 275.897594 -353.598734)
			(xy 275.904989 -353.605589) (xy 275.923588 -353.613336) (xy 275.933662 -353.61372) (xy 300.413928 -353.61372)
			(xy 300.423805 -353.613259) (xy 300.442103 -353.605815) (xy 300.449488 -353.599242) (xy 300.449742 -353.598988)
			(xy 300.830742 -353.217988) (xy 300.848838 -353.200732) (xy 300.890384 -353.172922) (xy 300.936554 -353.153744)
			(xy 300.985577 -353.143935) (xy 301.010574 -353.143312) (xy 303.90465 -353.143312) (xy 303.929647 -353.143949)
			(xy 303.978671 -353.153747) (xy 304.024843 -353.172919) (xy 304.06639 -353.200728) (xy 304.084482 -353.217988)
			(xy 307.848 -356.981506) (xy 307.855399 -356.988352) (xy 307.873997 -356.996085) (xy 307.884068 -356.996492)
			(xy 309.765192 -356.996492) (xy 309.775214 -356.996074) (xy 309.793732 -356.988405) (xy 309.807905 -356.974232)
			(xy 309.815574 -356.955714) (xy 309.815992 -356.945692) (xy 309.815992 -356.565708) (xy 309.815574 -356.555686)
			(xy 309.807905 -356.537168) (xy 309.793732 -356.522995) (xy 309.775214 -356.515326) (xy 309.765192 -356.514908)
			(xy 308.070758 -356.514908) (xy 308.045762 -356.514272) (xy 307.996739 -356.504472) (xy 307.950569 -356.485296)
			(xy 307.909027 -356.457482) (xy 307.890926 -356.440232) (xy 304.195988 -352.745294) (xy 304.188876 -352.737928)
			(xy 304.17008 -352.730308) (xy 300.91888 -352.730308) (xy 300.908812 -352.730735) (xy 300.890213 -352.738455)
			(xy 300.882812 -352.745294) (xy 300.312074 -353.316032) (xy 300.293978 -353.333286) (xy 300.252432 -353.361091)
			(xy 300.20626 -353.38026) (xy 300.157237 -353.390056) (xy 300.132242 -353.390708) (xy 282.1178 -353.390708)
			(xy 282.092798 -353.390116) (xy 282.043763 -353.380321) (xy 281.99758 -353.361148) (xy 281.956026 -353.333333)
			(xy 281.937968 -353.316032) (xy 280.8478 -352.225864) (xy 280.830577 -352.207755) (xy 280.802835 -352.166195)
			(xy 280.783725 -352.120025) (xy 280.77398 -352.071016) (xy 280.773378 -352.046032) (xy 280.773378 -351.066608)
			(xy 280.773988 -351.041624) (xy 280.783729 -350.992616) (xy 280.802839 -350.946448) (xy 280.830583 -350.904891)
			(xy 280.8478 -350.886776) (xy 281.18054 -350.55429) (xy 281.377898 -350.356932) (xy 281.386404 -350.348577)
			(xy 281.404722 -350.333311) (xy 281.414474 -350.326452) (xy 281.418105 -350.323917) (xy 281.424494 -350.317785)
			(xy 281.427174 -350.31426) (xy 281.442597 -350.293517) (xy 281.478138 -350.255984) (xy 281.518421 -350.223594)
			(xy 281.562708 -350.196938) (xy 281.610189 -350.176505) (xy 281.659993 -350.16267) (xy 281.711209 -350.155685)
			(xy 281.737054 -350.155256) (xy 281.76431 -350.155716) (xy 281.818268 -350.163467) (xy 281.870573 -350.178819)
			(xy 281.920162 -350.201458) (xy 281.966023 -350.230924) (xy 282.007224 -350.266618) (xy 282.042926 -350.307811)
			(xy 282.072402 -350.353666) (xy 282.095052 -350.40325) (xy 282.110415 -350.455552) (xy 282.118178 -350.509508)
			(xy 282.118562 -350.536764) (xy 282.118081 -350.564226) (xy 282.110205 -350.618582) (xy 282.094625 -350.67125)
			(xy 282.091956 -350.67705) (xy 282.360372 -350.67705) (xy 282.360372 -350.62255) (xy 282.368128 -350.568604)
			(xy 282.383481 -350.516311) (xy 282.406121 -350.466735) (xy 282.435585 -350.420885) (xy 282.471274 -350.379695)
			(xy 282.512461 -350.344003) (xy 282.558308 -350.314535) (xy 282.607882 -350.291892) (xy 282.660174 -350.276534)
			(xy 282.71412 -350.268774) (xy 282.74137 -350.268286) (xy 282.766606 -350.268654) (xy 282.816641 -350.275281)
			(xy 282.865362 -350.288463) (xy 282.911912 -350.307967) (xy 282.933902 -350.320356) (xy 282.943554 -350.326198)
			(xy 282.965652 -350.32823) (xy 283.06014 -350.294702) (xy 283.076142 -350.279208) (xy 283.080206 -350.268794)
			(xy 283.090877 -350.242007) (xy 283.119168 -350.191764) (xy 283.154701 -350.146354) (xy 283.196666 -350.106811)
			(xy 283.244107 -350.074039) (xy 283.295942 -350.048783) (xy 283.350989 -350.03162) (xy 283.407992 -350.022941)
			(xy 283.436822 -350.022414) (xy 283.464075 -350.022857) (xy 283.518025 -350.030617) (xy 283.570322 -350.045977)
			(xy 283.619901 -350.068622) (xy 283.665752 -350.098092) (xy 283.706943 -350.133788) (xy 283.742634 -350.174983)
			(xy 283.772099 -350.220838) (xy 283.794739 -350.270419) (xy 283.80746 -350.313752) (xy 285.948374 -350.313752)
			(xy 285.948885 -350.286179) (xy 285.956829 -350.231609) (xy 285.972546 -350.17875) (xy 285.995708 -350.128704)
			(xy 286.025832 -350.082513) (xy 286.062291 -350.04114) (xy 286.082994 -350.022922) (xy 286.091097 -350.015306)
			(xy 286.10046 -349.995165) (xy 286.101028 -349.98406) (xy 286.101028 -349.906844) (xy 286.100475 -349.895732)
			(xy 286.091128 -349.875572) (xy 286.082994 -349.867982) (xy 286.06227 -349.849785) (xy 286.025801 -349.808413)
			(xy 285.99567 -349.76222) (xy 285.972507 -349.71217) (xy 285.956793 -349.659304) (xy 285.948857 -349.604728)
			(xy 285.948374 -349.577152) (xy 285.948833 -349.5499) (xy 285.956596 -349.495953) (xy 285.971956 -349.443659)
			(xy 285.994601 -349.394082) (xy 286.024071 -349.348233) (xy 286.059765 -349.307044) (xy 286.100957 -349.271353)
			(xy 286.146809 -349.241887) (xy 286.196387 -349.219245) (xy 286.248682 -349.203889) (xy 286.30263 -349.196131)
			(xy 286.329882 -349.195644) (xy 286.364172 -349.197168) (xy 286.374332 -349.198184) (xy 286.393636 -349.192088)
			(xy 286.464248 -349.132906) (xy 286.473646 -349.114872) (xy 286.474662 -349.104712) (xy 286.477603 -349.076538)
			(xy 286.490781 -349.021447) (xy 286.511963 -348.968911) (xy 286.540683 -348.920087) (xy 286.576309 -348.876047)
			(xy 286.618057 -348.837761) (xy 286.665009 -348.806072) (xy 286.716131 -348.781676) (xy 286.7703 -348.76511)
			(xy 286.826323 -348.756738) (xy 286.854646 -348.756224) (xy 286.872665 -348.756444) (xy 286.90854 -348.759879)
			(xy 286.926274 -348.763082) (xy 286.935672 -348.76486) (xy 286.954722 -348.76105) (xy 287.029906 -348.713298)
			(xy 287.041336 -348.69755) (xy 287.043622 -348.688152) (xy 287.051012 -348.661106) (xy 287.072643 -348.609379)
			(xy 287.101608 -348.561373) (xy 287.137284 -348.518122) (xy 287.178905 -348.480555) (xy 287.225573 -348.449481)
			(xy 287.276285 -348.425569) (xy 287.32995 -348.409333) (xy 287.385413 -348.401122) (xy 287.413446 -348.400624)
			(xy 287.4407 -348.401035) (xy 287.494652 -348.408799) (xy 287.54695 -348.424161) (xy 287.59653 -348.44681)
			(xy 287.642381 -348.476284) (xy 287.683572 -348.511983) (xy 287.719263 -348.553181) (xy 287.748727 -348.599039)
			(xy 287.771366 -348.648623) (xy 287.786718 -348.700924) (xy 287.79447 -348.754878) (xy 287.794954 -348.782132)
			(xy 287.794458 -348.809706) (xy 287.786514 -348.864278) (xy 287.770796 -348.917138) (xy 287.747632 -348.967184)
			(xy 287.717504 -349.013375) (xy 287.68104 -349.054746) (xy 287.660334 -349.072962) (xy 287.652227 -349.080574)
			(xy 287.642869 -349.100719) (xy 287.6423 -349.111824) (xy 287.6423 -349.18904) (xy 287.64283 -349.200154)
			(xy 287.652196 -349.220313) (xy 287.660334 -349.227902) (xy 287.68107 -349.246084) (xy 287.71753 -349.287461)
			(xy 287.747654 -349.333656) (xy 287.770813 -349.383707) (xy 287.786524 -349.436571) (xy 287.794461 -349.491146)
			(xy 287.794458 -349.546295) (xy 287.786515 -349.60087) (xy 287.785939 -349.602806) (xy 288.90163 -349.602806)
			(xy 288.905701 -349.547184) (xy 288.917827 -349.492747) (xy 288.93775 -349.440656) (xy 288.965046 -349.392021)
			(xy 288.999132 -349.347878) (xy 289.039281 -349.309169) (xy 289.084639 -349.276718) (xy 289.134239 -349.251217)
			(xy 289.187023 -349.23321) (xy 289.241866 -349.22308) (xy 289.2976 -349.221043) (xy 289.353037 -349.227143)
			(xy 289.406994 -349.241249) (xy 289.458323 -349.263061) (xy 289.505929 -349.292115) (xy 289.548797 -349.32779)
			(xy 289.586014 -349.369327) (xy 289.616787 -349.41584) (xy 289.640459 -349.466337) (xy 289.656527 -349.519744)
			(xy 289.664647 -349.57492) (xy 289.665156 -349.602806) (xy 289.664647 -349.630692) (xy 289.656527 -349.685868)
			(xy 289.640459 -349.739275) (xy 289.616787 -349.789772) (xy 289.586014 -349.836285) (xy 289.548797 -349.877822)
			(xy 289.505929 -349.913497) (xy 289.458323 -349.942551) (xy 289.406994 -349.964363) (xy 289.353037 -349.978469)
			(xy 289.2976 -349.984569) (xy 289.241866 -349.982532) (xy 289.187023 -349.972402) (xy 289.134239 -349.954395)
			(xy 289.084639 -349.928894) (xy 289.039281 -349.896443) (xy 288.999132 -349.857734) (xy 288.965046 -349.813591)
			(xy 288.93775 -349.764956) (xy 288.917827 -349.712865) (xy 288.905701 -349.658428) (xy 288.90163 -349.602806)
			(xy 287.785939 -349.602806) (xy 287.770798 -349.653732) (xy 287.747634 -349.70378) (xy 287.717505 -349.749972)
			(xy 287.68104 -349.791345) (xy 287.660334 -349.809562) (xy 287.652227 -349.817174) (xy 287.642869 -349.837319)
			(xy 287.6423 -349.848424) (xy 287.6423 -349.92564) (xy 287.64283 -349.936754) (xy 287.652196 -349.956913)
			(xy 287.660334 -349.964502) (xy 287.681056 -349.982701) (xy 287.717524 -350.024073) (xy 287.747654 -350.070266)
			(xy 287.770818 -350.120316) (xy 287.786532 -350.17318) (xy 287.79447 -350.227757) (xy 287.794954 -350.255332)
			(xy 287.794452 -350.282582) (xy 287.786692 -350.336527) (xy 287.771336 -350.388818) (xy 287.748694 -350.438393)
			(xy 287.719229 -350.484241) (xy 287.707171 -350.498156) (xy 288.32251 -350.498156) (xy 288.326581 -350.442534)
			(xy 288.338707 -350.388097) (xy 288.35863 -350.336006) (xy 288.385926 -350.287371) (xy 288.420012 -350.243228)
			(xy 288.460161 -350.204519) (xy 288.505519 -350.172068) (xy 288.555119 -350.146567) (xy 288.607903 -350.12856)
			(xy 288.662746 -350.11843) (xy 288.71848 -350.116393) (xy 288.773917 -350.122493) (xy 288.827874 -350.136599)
			(xy 288.879203 -350.158411) (xy 288.926809 -350.187465) (xy 288.969677 -350.22314) (xy 289.006894 -350.264677)
			(xy 289.037667 -350.31119) (xy 289.061339 -350.361687) (xy 289.077407 -350.415094) (xy 289.085527 -350.47027)
			(xy 289.086036 -350.498156) (xy 289.085527 -350.526042) (xy 289.077407 -350.581218) (xy 289.061339 -350.634625)
			(xy 289.037667 -350.685122) (xy 289.006894 -350.731635) (xy 288.969677 -350.773172) (xy 288.926809 -350.808847)
			(xy 288.879203 -350.837901) (xy 288.827874 -350.859713) (xy 288.773917 -350.873819) (xy 288.71848 -350.879919)
			(xy 288.662746 -350.877882) (xy 288.607903 -350.867752) (xy 288.555119 -350.849745) (xy 288.505519 -350.824244)
			(xy 288.460161 -350.791793) (xy 288.420012 -350.753084) (xy 288.385926 -350.708941) (xy 288.35863 -350.660306)
			(xy 288.338707 -350.608215) (xy 288.326581 -350.553778) (xy 288.32251 -350.498156) (xy 287.707171 -350.498156)
			(xy 287.683539 -350.525429) (xy 287.642352 -350.56112) (xy 287.596505 -350.590587) (xy 287.546931 -350.613231)
			(xy 287.49464 -350.628589) (xy 287.440696 -350.636351) (xy 287.413446 -350.63684) (xy 287.385593 -350.636246)
			(xy 287.330482 -350.62813) (xy 287.277135 -350.612092) (xy 287.226685 -350.588474) (xy 287.180201 -350.557776)
			(xy 287.138671 -350.52065) (xy 287.102976 -350.477884) (xy 287.073873 -350.430385) (xy 287.051981 -350.379161)
			(xy 287.044384 -350.35236) (xy 287.042098 -350.34347) (xy 287.03143 -350.32823) (xy 286.959548 -350.280478)
			(xy 286.941514 -350.276414) (xy 286.93237 -350.277684) (xy 286.919354 -350.279354) (xy 286.893169 -350.281133)
			(xy 286.880046 -350.28124) (xy 286.865897 -350.281141) (xy 286.837674 -350.27911) (xy 286.823658 -350.277176)
			(xy 286.813498 -350.275652) (xy 286.79394 -350.280478) (xy 286.719518 -350.336358) (xy 286.709358 -350.353884)
			(xy 286.708088 -350.364044) (xy 286.704027 -350.391202) (xy 286.689053 -350.444035) (xy 286.666659 -350.494175)
			(xy 286.637309 -350.540587) (xy 286.601609 -350.582312) (xy 286.560295 -350.618488) (xy 286.514223 -350.648368)
			(xy 286.464343 -350.671335) (xy 286.411686 -350.686914) (xy 286.357339 -350.694784) (xy 286.329882 -350.69526)
			(xy 286.302626 -350.694862) (xy 286.248671 -350.687101) (xy 286.196369 -350.67174) (xy 286.146785 -350.649092)
			(xy 286.10093 -350.619618) (xy 286.059736 -350.583917) (xy 286.024043 -350.542717) (xy 285.994576 -350.496857)
			(xy 285.971937 -350.447269) (xy 285.956585 -350.394965) (xy 285.948834 -350.341008) (xy 285.948374 -350.313752)
			(xy 283.80746 -350.313752) (xy 283.810092 -350.322718) (xy 283.817846 -350.376669) (xy 283.81833 -350.403922)
			(xy 283.81766 -350.435484) (xy 283.807276 -350.497749) (xy 283.786795 -350.557459) (xy 283.772356 -350.585532)
			(xy 283.76753 -350.594422) (xy 283.765498 -350.61398) (xy 283.791152 -350.702118) (xy 283.803598 -350.717612)
			(xy 283.812488 -350.722692) (xy 283.837611 -350.737205) (xy 283.883494 -350.772714) (xy 283.923468 -350.814763)
			(xy 283.956612 -350.862383) (xy 283.982159 -350.914474) (xy 283.99952 -350.969834) (xy 284.008295 -351.027185)
			(xy 284.00883 -351.056194) (xy 284.008344 -351.083445) (xy 284.000588 -351.137393) (xy 283.989899 -351.173796)
			(xy 289.661346 -351.173796) (xy 289.661819 -351.146321) (xy 289.669712 -351.09194) (xy 289.685335 -351.039257)
			(xy 289.708363 -350.989365) (xy 289.738318 -350.943297) (xy 289.756088 -350.922336) (xy 289.762184 -350.915224)
			(xy 289.768534 -350.898206) (xy 289.768534 -350.812354) (xy 289.762184 -350.795336) (xy 289.756088 -350.788224)
			(xy 289.738352 -350.767239) (xy 289.708424 -350.721163) (xy 289.685406 -350.671275) (xy 289.669773 -350.618603)
			(xy 289.661849 -350.564235) (xy 289.661346 -350.536764) (xy 289.661832 -350.509513) (xy 289.669588 -350.455565)
			(xy 289.684943 -350.40327) (xy 289.707585 -350.353693) (xy 289.737051 -350.307843) (xy 289.772742 -350.266652)
			(xy 289.813933 -350.230961) (xy 289.859783 -350.201495) (xy 289.90936 -350.178853) (xy 289.961655 -350.163498)
			(xy 290.015603 -350.155742) (xy 290.070105 -350.155742) (xy 290.124053 -350.163498) (xy 290.176348 -350.178853)
			(xy 290.225925 -350.201495) (xy 290.271775 -350.230961) (xy 290.312966 -350.266652) (xy 290.348657 -350.307843)
			(xy 290.378123 -350.353693) (xy 290.400765 -350.40327) (xy 290.41612 -350.455565) (xy 290.423876 -350.509513)
			(xy 290.424362 -350.536764) (xy 290.423864 -350.564238) (xy 290.415976 -350.618618) (xy 290.400359 -350.6713)
			(xy 290.397706 -350.67705) (xy 290.666172 -350.67705) (xy 290.666172 -350.62255) (xy 290.673928 -350.568604)
			(xy 290.689281 -350.516311) (xy 290.711921 -350.466735) (xy 290.741385 -350.420885) (xy 290.777074 -350.379695)
			(xy 290.818261 -350.344003) (xy 290.864108 -350.314535) (xy 290.913682 -350.291892) (xy 290.965974 -350.276534)
			(xy 291.01992 -350.268774) (xy 291.04717 -350.268286) (xy 291.072406 -350.268654) (xy 291.122441 -350.275281)
			(xy 291.171162 -350.288463) (xy 291.217712 -350.307967) (xy 291.239702 -350.320356) (xy 291.249354 -350.326198)
			(xy 291.271452 -350.32823) (xy 291.36594 -350.294702) (xy 291.381942 -350.279208) (xy 291.386006 -350.268794)
			(xy 291.396677 -350.242007) (xy 291.424968 -350.191764) (xy 291.460501 -350.146354) (xy 291.502466 -350.106811)
			(xy 291.549907 -350.074039) (xy 291.601742 -350.048783) (xy 291.656789 -350.03162) (xy 291.713792 -350.022941)
			(xy 291.742622 -350.022414) (xy 291.769875 -350.022857) (xy 291.823825 -350.030617) (xy 291.876122 -350.045977)
			(xy 291.925701 -350.068622) (xy 291.971552 -350.098092) (xy 292.012743 -350.133788) (xy 292.048434 -350.174983)
			(xy 292.077899 -350.220838) (xy 292.100539 -350.270419) (xy 292.11326 -350.313752) (xy 294.254174 -350.313752)
			(xy 294.254685 -350.286179) (xy 294.262629 -350.231609) (xy 294.278346 -350.17875) (xy 294.301508 -350.128704)
			(xy 294.331632 -350.082513) (xy 294.368091 -350.04114) (xy 294.388794 -350.022922) (xy 294.396897 -350.015306)
			(xy 294.40626 -349.995165) (xy 294.406828 -349.98406) (xy 294.406828 -349.906844) (xy 294.406275 -349.895732)
			(xy 294.396928 -349.875572) (xy 294.388794 -349.867982) (xy 294.36807 -349.849785) (xy 294.331601 -349.808413)
			(xy 294.30147 -349.76222) (xy 294.278307 -349.71217) (xy 294.262593 -349.659304) (xy 294.254657 -349.604728)
			(xy 294.254174 -349.577152) (xy 294.254633 -349.5499) (xy 294.262396 -349.495953) (xy 294.277756 -349.443659)
			(xy 294.300401 -349.394082) (xy 294.329871 -349.348233) (xy 294.365565 -349.307044) (xy 294.406757 -349.271353)
			(xy 294.452609 -349.241887) (xy 294.502187 -349.219245) (xy 294.554482 -349.203889) (xy 294.60843 -349.196131)
			(xy 294.635682 -349.195644) (xy 294.669972 -349.197168) (xy 294.680132 -349.198184) (xy 294.699436 -349.192088)
			(xy 294.770048 -349.132906) (xy 294.779446 -349.114872) (xy 294.780462 -349.104712) (xy 294.783403 -349.076538)
			(xy 294.796581 -349.021447) (xy 294.817763 -348.968911) (xy 294.846483 -348.920087) (xy 294.882109 -348.876047)
			(xy 294.923857 -348.837761) (xy 294.970809 -348.806072) (xy 295.021931 -348.781676) (xy 295.0761 -348.76511)
			(xy 295.132123 -348.756738) (xy 295.160446 -348.756224) (xy 295.178465 -348.756444) (xy 295.21434 -348.759879)
			(xy 295.232074 -348.763082) (xy 295.241472 -348.76486) (xy 295.260522 -348.76105) (xy 295.335706 -348.713298)
			(xy 295.347136 -348.69755) (xy 295.349422 -348.688152) (xy 295.356812 -348.661106) (xy 295.378443 -348.609379)
			(xy 295.407408 -348.561373) (xy 295.443084 -348.518122) (xy 295.484705 -348.480555) (xy 295.531373 -348.449481)
			(xy 295.582085 -348.425569) (xy 295.63575 -348.409333) (xy 295.691213 -348.401122) (xy 295.719246 -348.400624)
			(xy 295.7465 -348.401035) (xy 295.800452 -348.408799) (xy 295.85275 -348.424161) (xy 295.90233 -348.44681)
			(xy 295.948181 -348.476284) (xy 295.989372 -348.511983) (xy 296.025063 -348.553181) (xy 296.054527 -348.599039)
			(xy 296.077166 -348.648623) (xy 296.092518 -348.700924) (xy 296.10027 -348.754878) (xy 296.100754 -348.782132)
			(xy 296.100258 -348.809706) (xy 296.092314 -348.864278) (xy 296.076596 -348.917138) (xy 296.053432 -348.967184)
			(xy 296.023304 -349.013375) (xy 295.98684 -349.054746) (xy 295.966134 -349.072962) (xy 295.958027 -349.080574)
			(xy 295.948669 -349.100719) (xy 295.9481 -349.111824) (xy 295.9481 -349.18904) (xy 295.94863 -349.200154)
			(xy 295.957996 -349.220313) (xy 295.966134 -349.227902) (xy 295.98687 -349.246084) (xy 296.02333 -349.287461)
			(xy 296.053454 -349.333656) (xy 296.076613 -349.383707) (xy 296.092324 -349.436571) (xy 296.100261 -349.491146)
			(xy 296.100258 -349.546295) (xy 296.092315 -349.60087) (xy 296.091739 -349.602806) (xy 297.25823 -349.602806)
			(xy 297.262301 -349.547184) (xy 297.274427 -349.492747) (xy 297.29435 -349.440656) (xy 297.321646 -349.392021)
			(xy 297.355732 -349.347878) (xy 297.395881 -349.309169) (xy 297.441239 -349.276718) (xy 297.490839 -349.251217)
			(xy 297.543623 -349.23321) (xy 297.598466 -349.22308) (xy 297.6542 -349.221043) (xy 297.709637 -349.227143)
			(xy 297.763594 -349.241249) (xy 297.814923 -349.263061) (xy 297.862529 -349.292115) (xy 297.905397 -349.32779)
			(xy 297.942614 -349.369327) (xy 297.973387 -349.41584) (xy 297.997059 -349.466337) (xy 298.013127 -349.519744)
			(xy 298.021247 -349.57492) (xy 298.021756 -349.602806) (xy 298.021247 -349.630692) (xy 298.013127 -349.685868)
			(xy 297.997059 -349.739275) (xy 297.973387 -349.789772) (xy 297.942614 -349.836285) (xy 297.905397 -349.877822)
			(xy 297.862529 -349.913497) (xy 297.814923 -349.942551) (xy 297.763594 -349.964363) (xy 297.709637 -349.978469)
			(xy 297.6542 -349.984569) (xy 297.598466 -349.982532) (xy 297.543623 -349.972402) (xy 297.490839 -349.954395)
			(xy 297.441239 -349.928894) (xy 297.395881 -349.896443) (xy 297.355732 -349.857734) (xy 297.321646 -349.813591)
			(xy 297.29435 -349.764956) (xy 297.274427 -349.712865) (xy 297.262301 -349.658428) (xy 297.25823 -349.602806)
			(xy 296.091739 -349.602806) (xy 296.076598 -349.653732) (xy 296.053434 -349.70378) (xy 296.023305 -349.749972)
			(xy 295.98684 -349.791345) (xy 295.966134 -349.809562) (xy 295.958027 -349.817174) (xy 295.948669 -349.837319)
			(xy 295.9481 -349.848424) (xy 295.9481 -349.92564) (xy 295.94863 -349.936754) (xy 295.957996 -349.956913)
			(xy 295.966134 -349.964502) (xy 295.986856 -349.982701) (xy 296.023324 -350.024073) (xy 296.053454 -350.070266)
			(xy 296.076618 -350.120316) (xy 296.092332 -350.17318) (xy 296.10027 -350.227757) (xy 296.100754 -350.255332)
			(xy 296.100252 -350.282582) (xy 296.092492 -350.336527) (xy 296.077136 -350.388818) (xy 296.054494 -350.438393)
			(xy 296.025029 -350.484241) (xy 296.012971 -350.498156) (xy 296.67911 -350.498156) (xy 296.683181 -350.442534)
			(xy 296.695307 -350.388097) (xy 296.71523 -350.336006) (xy 296.742526 -350.287371) (xy 296.776612 -350.243228)
			(xy 296.816761 -350.204519) (xy 296.862119 -350.172068) (xy 296.911719 -350.146567) (xy 296.964503 -350.12856)
			(xy 297.019346 -350.11843) (xy 297.07508 -350.116393) (xy 297.130517 -350.122493) (xy 297.184474 -350.136599)
			(xy 297.235803 -350.158411) (xy 297.283409 -350.187465) (xy 297.326277 -350.22314) (xy 297.363494 -350.264677)
			(xy 297.394267 -350.31119) (xy 297.417939 -350.361687) (xy 297.434007 -350.415094) (xy 297.442127 -350.47027)
			(xy 297.442636 -350.498156) (xy 297.442127 -350.526042) (xy 297.434007 -350.581218) (xy 297.417939 -350.634625)
			(xy 297.394267 -350.685122) (xy 297.363494 -350.731635) (xy 297.326277 -350.773172) (xy 297.283409 -350.808847)
			(xy 297.235803 -350.837901) (xy 297.184474 -350.859713) (xy 297.130517 -350.873819) (xy 297.07508 -350.879919)
			(xy 297.019346 -350.877882) (xy 296.964503 -350.867752) (xy 296.911719 -350.849745) (xy 296.862119 -350.824244)
			(xy 296.816761 -350.791793) (xy 296.776612 -350.753084) (xy 296.742526 -350.708941) (xy 296.71523 -350.660306)
			(xy 296.695307 -350.608215) (xy 296.683181 -350.553778) (xy 296.67911 -350.498156) (xy 296.012971 -350.498156)
			(xy 295.989339 -350.525429) (xy 295.948152 -350.56112) (xy 295.902305 -350.590587) (xy 295.852731 -350.613231)
			(xy 295.80044 -350.628589) (xy 295.746496 -350.636351) (xy 295.719246 -350.63684) (xy 295.691393 -350.636246)
			(xy 295.636282 -350.62813) (xy 295.582935 -350.612092) (xy 295.532485 -350.588474) (xy 295.486001 -350.557776)
			(xy 295.444471 -350.52065) (xy 295.408776 -350.477884) (xy 295.379673 -350.430385) (xy 295.357781 -350.379161)
			(xy 295.350184 -350.35236) (xy 295.347898 -350.34347) (xy 295.33723 -350.32823) (xy 295.265348 -350.280478)
			(xy 295.247314 -350.276414) (xy 295.23817 -350.277684) (xy 295.225154 -350.279354) (xy 295.198969 -350.281133)
			(xy 295.185846 -350.28124) (xy 295.171697 -350.281141) (xy 295.143474 -350.27911) (xy 295.129458 -350.277176)
			(xy 295.119298 -350.275652) (xy 295.09974 -350.280478) (xy 295.025318 -350.336358) (xy 295.015158 -350.353884)
			(xy 295.013888 -350.364044) (xy 295.009827 -350.391202) (xy 294.994853 -350.444035) (xy 294.972459 -350.494175)
			(xy 294.943109 -350.540587) (xy 294.907409 -350.582312) (xy 294.866095 -350.618488) (xy 294.820023 -350.648368)
			(xy 294.770143 -350.671335) (xy 294.717486 -350.686914) (xy 294.663139 -350.694784) (xy 294.635682 -350.69526)
			(xy 294.608426 -350.694862) (xy 294.554471 -350.687101) (xy 294.502169 -350.67174) (xy 294.452585 -350.649092)
			(xy 294.40673 -350.619618) (xy 294.365536 -350.583917) (xy 294.329843 -350.542717) (xy 294.300376 -350.496857)
			(xy 294.277737 -350.447269) (xy 294.262385 -350.394965) (xy 294.254634 -350.341008) (xy 294.254174 -350.313752)
			(xy 292.11326 -350.313752) (xy 292.115892 -350.322718) (xy 292.123646 -350.376669) (xy 292.12413 -350.403922)
			(xy 292.12346 -350.435484) (xy 292.113076 -350.497749) (xy 292.092595 -350.557459) (xy 292.078156 -350.585532)
			(xy 292.07333 -350.594422) (xy 292.071298 -350.61398) (xy 292.096952 -350.702118) (xy 292.109398 -350.717612)
			(xy 292.118288 -350.722692) (xy 292.143411 -350.737205) (xy 292.189294 -350.772714) (xy 292.229268 -350.814763)
			(xy 292.262412 -350.862383) (xy 292.287959 -350.914474) (xy 292.30532 -350.969834) (xy 292.314095 -351.027185)
			(xy 292.31463 -351.056194) (xy 292.314144 -351.083445) (xy 292.306388 -351.137393) (xy 292.295699 -351.173796)
			(xy 298.017946 -351.173796) (xy 298.018419 -351.146321) (xy 298.026312 -351.09194) (xy 298.041935 -351.039257)
			(xy 298.064963 -350.989365) (xy 298.094918 -350.943297) (xy 298.112688 -350.922336) (xy 298.118784 -350.915224)
			(xy 298.125134 -350.898206) (xy 298.125134 -350.812354) (xy 298.118784 -350.795336) (xy 298.112688 -350.788224)
			(xy 298.094952 -350.767239) (xy 298.065024 -350.721163) (xy 298.042006 -350.671275) (xy 298.026373 -350.618603)
			(xy 298.018449 -350.564235) (xy 298.017946 -350.536764) (xy 298.018432 -350.509513) (xy 298.026188 -350.455565)
			(xy 298.041543 -350.40327) (xy 298.064185 -350.353693) (xy 298.093651 -350.307843) (xy 298.129342 -350.266652)
			(xy 298.170533 -350.230961) (xy 298.216383 -350.201495) (xy 298.26596 -350.178853) (xy 298.318255 -350.163498)
			(xy 298.372203 -350.155742) (xy 298.426705 -350.155742) (xy 298.480653 -350.163498) (xy 298.532948 -350.178853)
			(xy 298.582525 -350.201495) (xy 298.628375 -350.230961) (xy 298.669566 -350.266652) (xy 298.705257 -350.307843)
			(xy 298.734723 -350.353693) (xy 298.757365 -350.40327) (xy 298.77272 -350.455565) (xy 298.780476 -350.509513)
			(xy 298.780962 -350.536764) (xy 298.780464 -350.564238) (xy 298.772576 -350.618618) (xy 298.756959 -350.6713)
			(xy 298.754306 -350.67705) (xy 299.022772 -350.67705) (xy 299.022772 -350.62255) (xy 299.030528 -350.568604)
			(xy 299.045881 -350.516311) (xy 299.068521 -350.466735) (xy 299.097985 -350.420885) (xy 299.133674 -350.379695)
			(xy 299.174861 -350.344003) (xy 299.220708 -350.314535) (xy 299.270282 -350.291892) (xy 299.322574 -350.276534)
			(xy 299.37652 -350.268774) (xy 299.40377 -350.268286) (xy 299.429006 -350.268654) (xy 299.479041 -350.275281)
			(xy 299.527762 -350.288463) (xy 299.574312 -350.307967) (xy 299.596302 -350.320356) (xy 299.605954 -350.326198)
			(xy 299.628052 -350.32823) (xy 299.72254 -350.294702) (xy 299.738542 -350.279208) (xy 299.742606 -350.268794)
			(xy 299.753277 -350.242007) (xy 299.781568 -350.191764) (xy 299.817101 -350.146354) (xy 299.859066 -350.106811)
			(xy 299.906507 -350.074039) (xy 299.958342 -350.048783) (xy 300.013389 -350.03162) (xy 300.070392 -350.022941)
			(xy 300.099222 -350.022414) (xy 300.126475 -350.022857) (xy 300.180425 -350.030617) (xy 300.232722 -350.045977)
			(xy 300.282301 -350.068622) (xy 300.328152 -350.098092) (xy 300.369343 -350.133788) (xy 300.405034 -350.174983)
			(xy 300.434499 -350.220838) (xy 300.457139 -350.270419) (xy 300.46986 -350.313752) (xy 302.610774 -350.313752)
			(xy 302.611285 -350.286179) (xy 302.619229 -350.231609) (xy 302.634946 -350.17875) (xy 302.658108 -350.128704)
			(xy 302.688232 -350.082513) (xy 302.724691 -350.04114) (xy 302.745394 -350.022922) (xy 302.753497 -350.015306)
			(xy 302.76286 -349.995165) (xy 302.763428 -349.98406) (xy 302.763428 -349.906844) (xy 302.762875 -349.895732)
			(xy 302.753528 -349.875572) (xy 302.745394 -349.867982) (xy 302.72467 -349.849785) (xy 302.688201 -349.808413)
			(xy 302.65807 -349.76222) (xy 302.634907 -349.71217) (xy 302.619193 -349.659304) (xy 302.611257 -349.604728)
			(xy 302.610774 -349.577152) (xy 302.611233 -349.5499) (xy 302.618996 -349.495953) (xy 302.634356 -349.443659)
			(xy 302.657001 -349.394082) (xy 302.686471 -349.348233) (xy 302.722165 -349.307044) (xy 302.763357 -349.271353)
			(xy 302.809209 -349.241887) (xy 302.858787 -349.219245) (xy 302.911082 -349.203889) (xy 302.96503 -349.196131)
			(xy 302.992282 -349.195644) (xy 303.026572 -349.197168) (xy 303.036732 -349.198184) (xy 303.056036 -349.192088)
			(xy 303.126648 -349.132906) (xy 303.136046 -349.114872) (xy 303.137062 -349.104712) (xy 303.140003 -349.076538)
			(xy 303.153181 -349.021447) (xy 303.174363 -348.968911) (xy 303.203083 -348.920087) (xy 303.238709 -348.876047)
			(xy 303.280457 -348.837761) (xy 303.327409 -348.806072) (xy 303.378531 -348.781676) (xy 303.4327 -348.76511)
			(xy 303.488723 -348.756738) (xy 303.517046 -348.756224) (xy 303.535065 -348.756444) (xy 303.57094 -348.759879)
			(xy 303.588674 -348.763082) (xy 303.598072 -348.76486) (xy 303.617122 -348.76105) (xy 303.692306 -348.713298)
			(xy 303.703736 -348.69755) (xy 303.706022 -348.688152) (xy 303.713412 -348.661106) (xy 303.735043 -348.609379)
			(xy 303.764008 -348.561373) (xy 303.799684 -348.518122) (xy 303.841305 -348.480555) (xy 303.887973 -348.449481)
			(xy 303.938685 -348.425569) (xy 303.99235 -348.409333) (xy 304.047813 -348.401122) (xy 304.075846 -348.400624)
			(xy 304.1031 -348.401035) (xy 304.157052 -348.408799) (xy 304.20935 -348.424161) (xy 304.25893 -348.44681)
			(xy 304.304781 -348.476284) (xy 304.345972 -348.511983) (xy 304.381663 -348.553181) (xy 304.411127 -348.599039)
			(xy 304.433766 -348.648623) (xy 304.449118 -348.700924) (xy 304.45687 -348.754878) (xy 304.457354 -348.782132)
			(xy 304.456858 -348.809706) (xy 304.448914 -348.864278) (xy 304.433196 -348.917138) (xy 304.410032 -348.967184)
			(xy 304.379904 -349.013375) (xy 304.34344 -349.054746) (xy 304.322734 -349.072962) (xy 304.314627 -349.080574)
			(xy 304.305269 -349.100719) (xy 304.3047 -349.111824) (xy 304.3047 -349.18904) (xy 304.30523 -349.200154)
			(xy 304.314596 -349.220313) (xy 304.322734 -349.227902) (xy 304.34347 -349.246084) (xy 304.37993 -349.287461)
			(xy 304.410054 -349.333656) (xy 304.433213 -349.383707) (xy 304.448924 -349.436571) (xy 304.456861 -349.491146)
			(xy 304.456858 -349.546295) (xy 304.448915 -349.60087) (xy 304.448339 -349.602806) (xy 305.58943 -349.602806)
			(xy 305.593501 -349.547184) (xy 305.605627 -349.492747) (xy 305.62555 -349.440656) (xy 305.652846 -349.392021)
			(xy 305.686932 -349.347878) (xy 305.727081 -349.309169) (xy 305.772439 -349.276718) (xy 305.822039 -349.251217)
			(xy 305.874823 -349.23321) (xy 305.929666 -349.22308) (xy 305.9854 -349.221043) (xy 306.040837 -349.227143)
			(xy 306.094794 -349.241249) (xy 306.146123 -349.263061) (xy 306.193729 -349.292115) (xy 306.236597 -349.32779)
			(xy 306.273814 -349.369327) (xy 306.304587 -349.41584) (xy 306.328259 -349.466337) (xy 306.344327 -349.519744)
			(xy 306.352447 -349.57492) (xy 306.352956 -349.602806) (xy 306.352447 -349.630692) (xy 306.344327 -349.685868)
			(xy 306.328259 -349.739275) (xy 306.304587 -349.789772) (xy 306.273814 -349.836285) (xy 306.236597 -349.877822)
			(xy 306.193729 -349.913497) (xy 306.146123 -349.942551) (xy 306.094794 -349.964363) (xy 306.040837 -349.978469)
			(xy 305.9854 -349.984569) (xy 305.929666 -349.982532) (xy 305.874823 -349.972402) (xy 305.822039 -349.954395)
			(xy 305.772439 -349.928894) (xy 305.727081 -349.896443) (xy 305.686932 -349.857734) (xy 305.652846 -349.813591)
			(xy 305.62555 -349.764956) (xy 305.605627 -349.712865) (xy 305.593501 -349.658428) (xy 305.58943 -349.602806)
			(xy 304.448339 -349.602806) (xy 304.433198 -349.653732) (xy 304.410034 -349.70378) (xy 304.379905 -349.749972)
			(xy 304.34344 -349.791345) (xy 304.322734 -349.809562) (xy 304.314627 -349.817174) (xy 304.305269 -349.837319)
			(xy 304.3047 -349.848424) (xy 304.3047 -349.92564) (xy 304.30523 -349.936754) (xy 304.314596 -349.956913)
			(xy 304.322734 -349.964502) (xy 304.343456 -349.982701) (xy 304.379924 -350.024073) (xy 304.410054 -350.070266)
			(xy 304.433218 -350.120316) (xy 304.448932 -350.17318) (xy 304.45687 -350.227757) (xy 304.457354 -350.255332)
			(xy 304.456852 -350.282582) (xy 304.449092 -350.336527) (xy 304.433736 -350.388818) (xy 304.411094 -350.438393)
			(xy 304.381629 -350.484241) (xy 304.369571 -350.498156) (xy 305.01031 -350.498156) (xy 305.014381 -350.442534)
			(xy 305.026507 -350.388097) (xy 305.04643 -350.336006) (xy 305.073726 -350.287371) (xy 305.107812 -350.243228)
			(xy 305.147961 -350.204519) (xy 305.193319 -350.172068) (xy 305.242919 -350.146567) (xy 305.295703 -350.12856)
			(xy 305.350546 -350.11843) (xy 305.40628 -350.116393) (xy 305.461717 -350.122493) (xy 305.515674 -350.136599)
			(xy 305.567003 -350.158411) (xy 305.614609 -350.187465) (xy 305.657477 -350.22314) (xy 305.694694 -350.264677)
			(xy 305.725467 -350.31119) (xy 305.749139 -350.361687) (xy 305.765207 -350.415094) (xy 305.773327 -350.47027)
			(xy 305.773836 -350.498156) (xy 305.773327 -350.526042) (xy 305.765207 -350.581218) (xy 305.749139 -350.634625)
			(xy 305.725467 -350.685122) (xy 305.694694 -350.731635) (xy 305.657477 -350.773172) (xy 305.614609 -350.808847)
			(xy 305.567003 -350.837901) (xy 305.515674 -350.859713) (xy 305.461717 -350.873819) (xy 305.40628 -350.879919)
			(xy 305.350546 -350.877882) (xy 305.295703 -350.867752) (xy 305.242919 -350.849745) (xy 305.193319 -350.824244)
			(xy 305.147961 -350.791793) (xy 305.107812 -350.753084) (xy 305.073726 -350.708941) (xy 305.04643 -350.660306)
			(xy 305.026507 -350.608215) (xy 305.014381 -350.553778) (xy 305.01031 -350.498156) (xy 304.369571 -350.498156)
			(xy 304.345939 -350.525429) (xy 304.304752 -350.56112) (xy 304.258905 -350.590587) (xy 304.209331 -350.613231)
			(xy 304.15704 -350.628589) (xy 304.103096 -350.636351) (xy 304.075846 -350.63684) (xy 304.047993 -350.636246)
			(xy 303.992882 -350.62813) (xy 303.939535 -350.612092) (xy 303.889085 -350.588474) (xy 303.842601 -350.557776)
			(xy 303.801071 -350.52065) (xy 303.765376 -350.477884) (xy 303.736273 -350.430385) (xy 303.714381 -350.379161)
			(xy 303.706784 -350.35236) (xy 303.704498 -350.34347) (xy 303.69383 -350.32823) (xy 303.621948 -350.280478)
			(xy 303.603914 -350.276414) (xy 303.59477 -350.277684) (xy 303.581754 -350.279354) (xy 303.555569 -350.281133)
			(xy 303.542446 -350.28124) (xy 303.528297 -350.281141) (xy 303.500074 -350.27911) (xy 303.486058 -350.277176)
			(xy 303.475898 -350.275652) (xy 303.45634 -350.280478) (xy 303.381918 -350.336358) (xy 303.371758 -350.353884)
			(xy 303.370488 -350.364044) (xy 303.366427 -350.391202) (xy 303.351453 -350.444035) (xy 303.329059 -350.494175)
			(xy 303.299709 -350.540587) (xy 303.264009 -350.582312) (xy 303.222695 -350.618488) (xy 303.176623 -350.648368)
			(xy 303.126743 -350.671335) (xy 303.074086 -350.686914) (xy 303.019739 -350.694784) (xy 302.992282 -350.69526)
			(xy 302.965026 -350.694862) (xy 302.911071 -350.687101) (xy 302.858769 -350.67174) (xy 302.809185 -350.649092)
			(xy 302.76333 -350.619618) (xy 302.722136 -350.583917) (xy 302.686443 -350.542717) (xy 302.656976 -350.496857)
			(xy 302.634337 -350.447269) (xy 302.618985 -350.394965) (xy 302.611234 -350.341008) (xy 302.610774 -350.313752)
			(xy 300.46986 -350.313752) (xy 300.472492 -350.322718) (xy 300.480246 -350.376669) (xy 300.48073 -350.403922)
			(xy 300.48006 -350.435484) (xy 300.469676 -350.497749) (xy 300.449195 -350.557459) (xy 300.434756 -350.585532)
			(xy 300.42993 -350.594422) (xy 300.427898 -350.61398) (xy 300.453552 -350.702118) (xy 300.465998 -350.717612)
			(xy 300.474888 -350.722692) (xy 300.500011 -350.737205) (xy 300.545894 -350.772714) (xy 300.585868 -350.814763)
			(xy 300.619012 -350.862383) (xy 300.644559 -350.914474) (xy 300.66192 -350.969834) (xy 300.670695 -351.027185)
			(xy 300.67123 -351.056194) (xy 300.670744 -351.083445) (xy 300.662988 -351.137393) (xy 300.652299 -351.173796)
			(xy 306.349146 -351.173796) (xy 306.349619 -351.146321) (xy 306.357512 -351.09194) (xy 306.373135 -351.039257)
			(xy 306.396163 -350.989365) (xy 306.426118 -350.943297) (xy 306.443888 -350.922336) (xy 306.449984 -350.915224)
			(xy 306.456334 -350.898206) (xy 306.456334 -350.812354) (xy 306.449984 -350.795336) (xy 306.443888 -350.788224)
			(xy 306.426152 -350.767239) (xy 306.396224 -350.721163) (xy 306.373206 -350.671275) (xy 306.357573 -350.618603)
			(xy 306.349649 -350.564235) (xy 306.349146 -350.536764) (xy 306.349632 -350.509513) (xy 306.357388 -350.455565)
			(xy 306.372743 -350.40327) (xy 306.395385 -350.353693) (xy 306.424851 -350.307843) (xy 306.460542 -350.266652)
			(xy 306.501733 -350.230961) (xy 306.547583 -350.201495) (xy 306.59716 -350.178853) (xy 306.649455 -350.163498)
			(xy 306.703403 -350.155742) (xy 306.757905 -350.155742) (xy 306.811853 -350.163498) (xy 306.864148 -350.178853)
			(xy 306.913725 -350.201495) (xy 306.959575 -350.230961) (xy 307.000766 -350.266652) (xy 307.036457 -350.307843)
			(xy 307.065923 -350.353693) (xy 307.088565 -350.40327) (xy 307.10392 -350.455565) (xy 307.111676 -350.509513)
			(xy 307.112162 -350.536764) (xy 307.111664 -350.564238) (xy 307.103776 -350.618618) (xy 307.088159 -350.6713)
			(xy 307.085506 -350.67705) (xy 307.353972 -350.67705) (xy 307.353972 -350.62255) (xy 307.361728 -350.568604)
			(xy 307.377081 -350.516311) (xy 307.399721 -350.466735) (xy 307.429185 -350.420885) (xy 307.464874 -350.379695)
			(xy 307.506061 -350.344003) (xy 307.551908 -350.314535) (xy 307.601482 -350.291892) (xy 307.653774 -350.276534)
			(xy 307.70772 -350.268774) (xy 307.73497 -350.268286) (xy 307.760206 -350.268654) (xy 307.810241 -350.275281)
			(xy 307.858962 -350.288463) (xy 307.905512 -350.307967) (xy 307.927502 -350.320356) (xy 307.937154 -350.326198)
			(xy 307.959252 -350.32823) (xy 308.05374 -350.294702) (xy 308.069742 -350.279208) (xy 308.073806 -350.268794)
			(xy 308.084477 -350.242007) (xy 308.112768 -350.191764) (xy 308.148301 -350.146354) (xy 308.190266 -350.106811)
			(xy 308.237707 -350.074039) (xy 308.289542 -350.048783) (xy 308.344589 -350.03162) (xy 308.401592 -350.022941)
			(xy 308.430422 -350.022414) (xy 308.457675 -350.022857) (xy 308.511625 -350.030617) (xy 308.563922 -350.045977)
			(xy 308.613501 -350.068622) (xy 308.659352 -350.098092) (xy 308.700543 -350.133788) (xy 308.736234 -350.174983)
			(xy 308.765699 -350.220838) (xy 308.788339 -350.270419) (xy 308.80106 -350.313752) (xy 310.941974 -350.313752)
			(xy 310.942485 -350.286179) (xy 310.950429 -350.231609) (xy 310.966146 -350.17875) (xy 310.989308 -350.128704)
			(xy 311.019432 -350.082513) (xy 311.055891 -350.04114) (xy 311.076594 -350.022922) (xy 311.084697 -350.015306)
			(xy 311.09406 -349.995165) (xy 311.094628 -349.98406) (xy 311.094628 -349.906844) (xy 311.094075 -349.895732)
			(xy 311.084728 -349.875572) (xy 311.076594 -349.867982) (xy 311.05587 -349.849785) (xy 311.019401 -349.808413)
			(xy 310.98927 -349.76222) (xy 310.966107 -349.71217) (xy 310.950393 -349.659304) (xy 310.942457 -349.604728)
			(xy 310.941974 -349.577152) (xy 310.942433 -349.5499) (xy 310.950196 -349.495953) (xy 310.965556 -349.443659)
			(xy 310.988201 -349.394082) (xy 311.017671 -349.348233) (xy 311.053365 -349.307044) (xy 311.094557 -349.271353)
			(xy 311.140409 -349.241887) (xy 311.189987 -349.219245) (xy 311.242282 -349.203889) (xy 311.29623 -349.196131)
			(xy 311.323482 -349.195644) (xy 311.357772 -349.197168) (xy 311.367932 -349.198184) (xy 311.387236 -349.192088)
			(xy 311.457848 -349.132906) (xy 311.467246 -349.114872) (xy 311.468262 -349.104712) (xy 311.471203 -349.076538)
			(xy 311.484381 -349.021447) (xy 311.505563 -348.968911) (xy 311.534283 -348.920087) (xy 311.569909 -348.876047)
			(xy 311.611657 -348.837761) (xy 311.658609 -348.806072) (xy 311.709731 -348.781676) (xy 311.7639 -348.76511)
			(xy 311.819923 -348.756738) (xy 311.848246 -348.756224) (xy 311.866265 -348.756444) (xy 311.90214 -348.759879)
			(xy 311.919874 -348.763082) (xy 311.929272 -348.76486) (xy 311.948322 -348.76105) (xy 312.023506 -348.713298)
			(xy 312.034936 -348.69755) (xy 312.037222 -348.688152) (xy 312.044612 -348.661106) (xy 312.066243 -348.609379)
			(xy 312.095208 -348.561373) (xy 312.130884 -348.518122) (xy 312.172505 -348.480555) (xy 312.219173 -348.449481)
			(xy 312.269885 -348.425569) (xy 312.32355 -348.409333) (xy 312.379013 -348.401122) (xy 312.407046 -348.400624)
			(xy 312.4343 -348.401035) (xy 312.488252 -348.408799) (xy 312.54055 -348.424161) (xy 312.59013 -348.44681)
			(xy 312.635981 -348.476284) (xy 312.677172 -348.511983) (xy 312.712863 -348.553181) (xy 312.742327 -348.599039)
			(xy 312.764966 -348.648623) (xy 312.780318 -348.700924) (xy 312.78807 -348.754878) (xy 312.788554 -348.782132)
			(xy 312.788058 -348.809706) (xy 312.780114 -348.864278) (xy 312.764396 -348.917138) (xy 312.741232 -348.967184)
			(xy 312.711104 -349.013375) (xy 312.67464 -349.054746) (xy 312.653934 -349.072962) (xy 312.645827 -349.080574)
			(xy 312.636469 -349.100719) (xy 312.6359 -349.111824) (xy 312.6359 -349.18904) (xy 312.63643 -349.200154)
			(xy 312.645796 -349.220313) (xy 312.653934 -349.227902) (xy 312.67467 -349.246084) (xy 312.71113 -349.287461)
			(xy 312.741254 -349.333656) (xy 312.764413 -349.383707) (xy 312.780124 -349.436571) (xy 312.788061 -349.491146)
			(xy 312.788058 -349.546295) (xy 312.780115 -349.60087) (xy 312.764398 -349.653732) (xy 312.741234 -349.70378)
			(xy 312.711105 -349.749972) (xy 312.67464 -349.791345) (xy 312.653934 -349.809562) (xy 312.645827 -349.817174)
			(xy 312.636469 -349.837319) (xy 312.6359 -349.848424) (xy 312.6359 -349.92564) (xy 312.63643 -349.936754)
			(xy 312.645796 -349.956913) (xy 312.653934 -349.964502) (xy 312.674656 -349.982701) (xy 312.711124 -350.024073)
			(xy 312.741254 -350.070266) (xy 312.764418 -350.120316) (xy 312.780132 -350.17318) (xy 312.78807 -350.227757)
			(xy 312.788554 -350.255332) (xy 312.788052 -350.282582) (xy 312.780292 -350.336527) (xy 312.764936 -350.388818)
			(xy 312.742294 -350.438393) (xy 312.712829 -350.484241) (xy 312.677139 -350.525429) (xy 312.635952 -350.56112)
			(xy 312.590105 -350.590587) (xy 312.540531 -350.613231) (xy 312.48824 -350.628589) (xy 312.434296 -350.636351)
			(xy 312.407046 -350.63684) (xy 312.379193 -350.636246) (xy 312.324082 -350.62813) (xy 312.270735 -350.612092)
			(xy 312.220285 -350.588474) (xy 312.173801 -350.557776) (xy 312.132271 -350.52065) (xy 312.096576 -350.477884)
			(xy 312.067473 -350.430385) (xy 312.045581 -350.379161) (xy 312.037984 -350.35236) (xy 312.035698 -350.34347)
			(xy 312.02503 -350.32823) (xy 311.953148 -350.280478) (xy 311.935114 -350.276414) (xy 311.92597 -350.277684)
			(xy 311.912954 -350.279354) (xy 311.886769 -350.281133) (xy 311.873646 -350.28124) (xy 311.859497 -350.281141)
			(xy 311.831274 -350.27911) (xy 311.817258 -350.277176) (xy 311.807098 -350.275652) (xy 311.78754 -350.280478)
			(xy 311.713118 -350.336358) (xy 311.702958 -350.353884) (xy 311.701688 -350.364044) (xy 311.697627 -350.391202)
			(xy 311.682653 -350.444035) (xy 311.660259 -350.494175) (xy 311.630909 -350.540587) (xy 311.595209 -350.582312)
			(xy 311.553895 -350.618488) (xy 311.507823 -350.648368) (xy 311.457943 -350.671335) (xy 311.405286 -350.686914)
			(xy 311.350939 -350.694784) (xy 311.323482 -350.69526) (xy 311.296226 -350.694862) (xy 311.242271 -350.687101)
			(xy 311.189969 -350.67174) (xy 311.140385 -350.649092) (xy 311.09453 -350.619618) (xy 311.053336 -350.583917)
			(xy 311.017643 -350.542717) (xy 310.988176 -350.496857) (xy 310.965537 -350.447269) (xy 310.950185 -350.394965)
			(xy 310.942434 -350.341008) (xy 310.941974 -350.313752) (xy 308.80106 -350.313752) (xy 308.803692 -350.322718)
			(xy 308.811446 -350.376669) (xy 308.81193 -350.403922) (xy 308.81126 -350.435484) (xy 308.800876 -350.497749)
			(xy 308.780395 -350.557459) (xy 308.765956 -350.585532) (xy 308.76113 -350.594422) (xy 308.759098 -350.61398)
			(xy 308.784752 -350.702118) (xy 308.797198 -350.717612) (xy 308.806088 -350.722692) (xy 308.831211 -350.737205)
			(xy 308.877094 -350.772714) (xy 308.917068 -350.814763) (xy 308.950212 -350.862383) (xy 308.975759 -350.914474)
			(xy 308.99312 -350.969834) (xy 309.001895 -351.027185) (xy 309.00243 -351.056194) (xy 309.001944 -351.083445)
			(xy 308.994188 -351.137393) (xy 308.978833 -351.189688) (xy 308.956191 -351.239265) (xy 308.926725 -351.285115)
			(xy 308.891034 -351.326306) (xy 308.849843 -351.361997) (xy 308.803993 -351.391463) (xy 308.754416 -351.414105)
			(xy 308.702121 -351.42946) (xy 308.648173 -351.437216) (xy 308.593671 -351.437216) (xy 308.539723 -351.42946)
			(xy 308.487428 -351.414105) (xy 308.437851 -351.391463) (xy 308.392001 -351.361997) (xy 308.35081 -351.326306)
			(xy 308.315119 -351.285115) (xy 308.285653 -351.239265) (xy 308.263011 -351.189688) (xy 308.247656 -351.137393)
			(xy 308.2399 -351.083445) (xy 308.239414 -351.056194) (xy 308.240085 -351.024632) (xy 308.250467 -350.962367)
			(xy 308.270949 -350.902657) (xy 308.285388 -350.874584) (xy 308.290214 -350.865694) (xy 308.292246 -350.846136)
			(xy 308.266592 -350.757998) (xy 308.254146 -350.742504) (xy 308.245256 -350.737424) (xy 308.23789 -350.73336)
			(xy 308.228238 -350.727518) (xy 308.20614 -350.725486) (xy 308.111652 -350.759014) (xy 308.09565 -350.774508)
			(xy 308.091586 -350.784922) (xy 308.08093 -350.811715) (xy 308.052637 -350.861958) (xy 308.017101 -350.907368)
			(xy 307.975133 -350.94691) (xy 307.92769 -350.979681) (xy 307.875854 -351.004936) (xy 307.820805 -351.022098)
			(xy 307.763801 -351.030775) (xy 307.73497 -351.031302) (xy 307.70772 -351.030826) (xy 307.653774 -351.023066)
			(xy 307.601482 -351.007708) (xy 307.551908 -350.985065) (xy 307.506061 -350.955597) (xy 307.464874 -350.919905)
			(xy 307.429185 -350.878715) (xy 307.399721 -350.832865) (xy 307.377081 -350.783289) (xy 307.361728 -350.730996)
			(xy 307.353972 -350.67705) (xy 307.085506 -350.67705) (xy 307.065137 -350.721193) (xy 307.035187 -350.767262)
			(xy 307.01742 -350.788224) (xy 307.011324 -350.795336) (xy 307.004974 -350.812354) (xy 307.004974 -350.898206)
			(xy 307.011324 -350.915224) (xy 307.01742 -350.922336) (xy 307.035185 -350.943297) (xy 307.065109 -350.98938)
			(xy 307.088121 -351.039274) (xy 307.103747 -351.091951) (xy 307.111663 -351.146324) (xy 307.112162 -351.173796)
			(xy 307.111676 -351.201047) (xy 307.10392 -351.254995) (xy 307.088565 -351.30729) (xy 307.065923 -351.356867)
			(xy 307.036457 -351.402717) (xy 307.000766 -351.443908) (xy 306.959575 -351.479599) (xy 306.913725 -351.509065)
			(xy 306.864148 -351.531707) (xy 306.811853 -351.547062) (xy 306.757905 -351.554818) (xy 306.703403 -351.554818)
			(xy 306.649455 -351.547062) (xy 306.59716 -351.531707) (xy 306.547583 -351.509065) (xy 306.501733 -351.479599)
			(xy 306.460542 -351.443908) (xy 306.424851 -351.402717) (xy 306.395385 -351.356867) (xy 306.372743 -351.30729)
			(xy 306.357388 -351.254995) (xy 306.349632 -351.201047) (xy 306.349146 -351.173796) (xy 300.652299 -351.173796)
			(xy 300.647633 -351.189688) (xy 300.624991 -351.239265) (xy 300.595525 -351.285115) (xy 300.559834 -351.326306)
			(xy 300.518643 -351.361997) (xy 300.472793 -351.391463) (xy 300.423216 -351.414105) (xy 300.370921 -351.42946)
			(xy 300.316973 -351.437216) (xy 300.262471 -351.437216) (xy 300.208523 -351.42946) (xy 300.156228 -351.414105)
			(xy 300.106651 -351.391463) (xy 300.060801 -351.361997) (xy 300.01961 -351.326306) (xy 299.983919 -351.285115)
			(xy 299.954453 -351.239265) (xy 299.931811 -351.189688) (xy 299.916456 -351.137393) (xy 299.9087 -351.083445)
			(xy 299.908214 -351.056194) (xy 299.908885 -351.024632) (xy 299.919267 -350.962367) (xy 299.939749 -350.902657)
			(xy 299.954188 -350.874584) (xy 299.959014 -350.865694) (xy 299.961046 -350.846136) (xy 299.935392 -350.757998)
			(xy 299.922946 -350.742504) (xy 299.914056 -350.737424) (xy 299.90669 -350.73336) (xy 299.897038 -350.727518)
			(xy 299.87494 -350.725486) (xy 299.780452 -350.759014) (xy 299.76445 -350.774508) (xy 299.760386 -350.784922)
			(xy 299.74973 -350.811715) (xy 299.721437 -350.861958) (xy 299.685901 -350.907368) (xy 299.643933 -350.94691)
			(xy 299.59649 -350.979681) (xy 299.544654 -351.004936) (xy 299.489605 -351.022098) (xy 299.432601 -351.030775)
			(xy 299.40377 -351.031302) (xy 299.37652 -351.030826) (xy 299.322574 -351.023066) (xy 299.270282 -351.007708)
			(xy 299.220708 -350.985065) (xy 299.174861 -350.955597) (xy 299.133674 -350.919905) (xy 299.097985 -350.878715)
			(xy 299.068521 -350.832865) (xy 299.045881 -350.783289) (xy 299.030528 -350.730996) (xy 299.022772 -350.67705)
			(xy 298.754306 -350.67705) (xy 298.733937 -350.721193) (xy 298.703987 -350.767262) (xy 298.68622 -350.788224)
			(xy 298.680124 -350.795336) (xy 298.673774 -350.812354) (xy 298.673774 -350.898206) (xy 298.680124 -350.915224)
			(xy 298.68622 -350.922336) (xy 298.703985 -350.943297) (xy 298.733909 -350.98938) (xy 298.756921 -351.039274)
			(xy 298.772547 -351.091951) (xy 298.780463 -351.146324) (xy 298.780962 -351.173796) (xy 298.780476 -351.201047)
			(xy 298.77272 -351.254995) (xy 298.757365 -351.30729) (xy 298.734723 -351.356867) (xy 298.705257 -351.402717)
			(xy 298.669566 -351.443908) (xy 298.628375 -351.479599) (xy 298.582525 -351.509065) (xy 298.532948 -351.531707)
			(xy 298.480653 -351.547062) (xy 298.426705 -351.554818) (xy 298.372203 -351.554818) (xy 298.318255 -351.547062)
			(xy 298.26596 -351.531707) (xy 298.216383 -351.509065) (xy 298.170533 -351.479599) (xy 298.129342 -351.443908)
			(xy 298.093651 -351.402717) (xy 298.064185 -351.356867) (xy 298.041543 -351.30729) (xy 298.026188 -351.254995)
			(xy 298.018432 -351.201047) (xy 298.017946 -351.173796) (xy 292.295699 -351.173796) (xy 292.291033 -351.189688)
			(xy 292.268391 -351.239265) (xy 292.238925 -351.285115) (xy 292.203234 -351.326306) (xy 292.162043 -351.361997)
			(xy 292.116193 -351.391463) (xy 292.066616 -351.414105) (xy 292.014321 -351.42946) (xy 291.960373 -351.437216)
			(xy 291.905871 -351.437216) (xy 291.851923 -351.42946) (xy 291.799628 -351.414105) (xy 291.750051 -351.391463)
			(xy 291.704201 -351.361997) (xy 291.66301 -351.326306) (xy 291.627319 -351.285115) (xy 291.597853 -351.239265)
			(xy 291.575211 -351.189688) (xy 291.559856 -351.137393) (xy 291.5521 -351.083445) (xy 291.551614 -351.056194)
			(xy 291.552285 -351.024632) (xy 291.562667 -350.962367) (xy 291.583149 -350.902657) (xy 291.597588 -350.874584)
			(xy 291.602414 -350.865694) (xy 291.604446 -350.846136) (xy 291.578792 -350.757998) (xy 291.566346 -350.742504)
			(xy 291.557456 -350.737424) (xy 291.55009 -350.73336) (xy 291.540438 -350.727518) (xy 291.51834 -350.725486)
			(xy 291.423852 -350.759014) (xy 291.40785 -350.774508) (xy 291.403786 -350.784922) (xy 291.39313 -350.811715)
			(xy 291.364837 -350.861958) (xy 291.329301 -350.907368) (xy 291.287333 -350.94691) (xy 291.23989 -350.979681)
			(xy 291.188054 -351.004936) (xy 291.133005 -351.022098) (xy 291.076001 -351.030775) (xy 291.04717 -351.031302)
			(xy 291.01992 -351.030826) (xy 290.965974 -351.023066) (xy 290.913682 -351.007708) (xy 290.864108 -350.985065)
			(xy 290.818261 -350.955597) (xy 290.777074 -350.919905) (xy 290.741385 -350.878715) (xy 290.711921 -350.832865)
			(xy 290.689281 -350.783289) (xy 290.673928 -350.730996) (xy 290.666172 -350.67705) (xy 290.397706 -350.67705)
			(xy 290.377337 -350.721193) (xy 290.347387 -350.767262) (xy 290.32962 -350.788224) (xy 290.323524 -350.795336)
			(xy 290.317174 -350.812354) (xy 290.317174 -350.898206) (xy 290.323524 -350.915224) (xy 290.32962 -350.922336)
			(xy 290.347385 -350.943297) (xy 290.377309 -350.98938) (xy 290.400321 -351.039274) (xy 290.415947 -351.091951)
			(xy 290.423863 -351.146324) (xy 290.424362 -351.173796) (xy 290.423876 -351.201047) (xy 290.41612 -351.254995)
			(xy 290.400765 -351.30729) (xy 290.378123 -351.356867) (xy 290.348657 -351.402717) (xy 290.312966 -351.443908)
			(xy 290.271775 -351.479599) (xy 290.225925 -351.509065) (xy 290.176348 -351.531707) (xy 290.124053 -351.547062)
			(xy 290.070105 -351.554818) (xy 290.015603 -351.554818) (xy 289.961655 -351.547062) (xy 289.90936 -351.531707)
			(xy 289.859783 -351.509065) (xy 289.813933 -351.479599) (xy 289.772742 -351.443908) (xy 289.737051 -351.402717)
			(xy 289.707585 -351.356867) (xy 289.684943 -351.30729) (xy 289.669588 -351.254995) (xy 289.661832 -351.201047)
			(xy 289.661346 -351.173796) (xy 283.989899 -351.173796) (xy 283.985233 -351.189688) (xy 283.962591 -351.239265)
			(xy 283.933125 -351.285115) (xy 283.897434 -351.326306) (xy 283.856243 -351.361997) (xy 283.810393 -351.391463)
			(xy 283.760816 -351.414105) (xy 283.708521 -351.42946) (xy 283.654573 -351.437216) (xy 283.600071 -351.437216)
			(xy 283.546123 -351.42946) (xy 283.493828 -351.414105) (xy 283.444251 -351.391463) (xy 283.398401 -351.361997)
			(xy 283.35721 -351.326306) (xy 283.321519 -351.285115) (xy 283.292053 -351.239265) (xy 283.269411 -351.189688)
			(xy 283.254056 -351.137393) (xy 283.2463 -351.083445) (xy 283.245814 -351.056194) (xy 283.246485 -351.024632)
			(xy 283.256867 -350.962367) (xy 283.277349 -350.902657) (xy 283.291788 -350.874584) (xy 283.296614 -350.865694)
			(xy 283.298646 -350.846136) (xy 283.272992 -350.757998) (xy 283.260546 -350.742504) (xy 283.251656 -350.737424)
			(xy 283.24429 -350.73336) (xy 283.234638 -350.727518) (xy 283.21254 -350.725486) (xy 283.118052 -350.759014)
			(xy 283.10205 -350.774508) (xy 283.097986 -350.784922) (xy 283.08733 -350.811715) (xy 283.059037 -350.861958)
			(xy 283.023501 -350.907368) (xy 282.981533 -350.94691) (xy 282.93409 -350.979681) (xy 282.882254 -351.004936)
			(xy 282.827205 -351.022098) (xy 282.770201 -351.030775) (xy 282.74137 -351.031302) (xy 282.71412 -351.030826)
			(xy 282.660174 -351.023066) (xy 282.607882 -351.007708) (xy 282.558308 -350.985065) (xy 282.512461 -350.955597)
			(xy 282.471274 -350.919905) (xy 282.435585 -350.878715) (xy 282.406121 -350.832865) (xy 282.383481 -350.783289)
			(xy 282.368128 -350.730996) (xy 282.360372 -350.67705) (xy 282.091956 -350.67705) (xy 282.071661 -350.721144)
			(xy 282.041788 -350.767233) (xy 282.024074 -350.788224) (xy 282.017724 -350.795336) (xy 282.011374 -350.812354)
			(xy 282.011374 -350.898206) (xy 282.017724 -350.915224) (xy 282.024074 -350.922336) (xy 282.041803 -350.943315)
			(xy 282.07168 -350.989404) (xy 282.094642 -351.0393) (xy 282.110214 -351.091972) (xy 282.118074 -351.146333)
			(xy 282.118562 -351.173796) (xy 282.118097 -351.201071) (xy 282.110327 -351.255065) (xy 282.094946 -351.307401)
			(xy 282.072265 -351.357012) (xy 282.04275 -351.402887) (xy 282.007 -351.44409) (xy 281.965746 -351.47978)
			(xy 281.919829 -351.509229) (xy 281.870185 -351.531838) (xy 281.817826 -351.547144) (xy 281.763822 -351.554836)
			(xy 281.736546 -351.555304) (xy 281.736292 -351.555304) (xy 281.726305 -351.555843) (xy 281.707876 -351.563559)
			(xy 281.700478 -351.57029) (xy 281.676348 -351.594166) (xy 281.670829 -351.600699) (xy 281.664076 -351.6164)
			(xy 281.66314 -351.6249) (xy 281.66314 -351.741994) (xy 281.663563 -351.752064) (xy 281.671281 -351.770666)
			(xy 281.678126 -351.778062) (xy 281.9146 -352.014536) (xy 282.386024 -352.485706) (xy 282.393424 -352.492548)
			(xy 282.412022 -352.500273) (xy 282.422092 -352.500692) (xy 299.847508 -352.500692) (xy 299.856906 -352.499676)
			(xy 299.864217 -352.498077) (xy 299.877519 -352.491236) (xy 299.883068 -352.486214) (xy 300.454314 -351.914968)
			(xy 300.47241 -351.897713) (xy 300.513956 -351.869906) (xy 300.560127 -351.850735) (xy 300.60915 -351.840937)
			(xy 300.634146 -351.840292) (xy 304.444654 -351.840292) (xy 304.46965 -351.840929) (xy 304.518672 -351.850731)
			(xy 304.56484 -351.869908) (xy 304.60638 -351.897724) (xy 304.624486 -351.914968) (xy 307.067458 -354.35794)
			(xy 307.074217 -354.364201) (xy 307.090974 -354.371824) (xy 307.109347 -354.37298) (xy 307.118258 -354.37064)
			(xy 307.190394 -354.348796) (xy 307.196892 -354.346588) (xy 307.208486 -354.339254) (xy 307.213254 -354.334318)
			(xy 307.234082 -354.311458) (xy 307.240178 -354.300028) (xy 307.241702 -354.293678) (xy 307.247818 -354.269271)
			(xy 307.265613 -354.222207) (xy 307.28945 -354.177896) (xy 307.318914 -354.137109) (xy 307.353492 -354.100557)
			(xy 307.372766 -354.084382) (xy 307.377338 -354.080826) (xy 307.383942 -354.07219) (xy 307.40096 -354.037646)
			(xy 307.400706 -354.0252) (xy 307.399182 -353.953064) (xy 307.398003 -353.941336) (xy 307.386484 -353.920805)
			(xy 307.377084 -353.913694) (xy 307.355673 -353.898344) (xy 307.316879 -353.862699) (xy 307.283354 -353.82206)
			(xy 307.255735 -353.777197) (xy 307.234547 -353.728962) (xy 307.220191 -353.678273) (xy 307.212941 -353.626091)
			(xy 307.212492 -353.59975) (xy 307.212978 -353.572499) (xy 307.220734 -353.518551) (xy 307.236089 -353.466256)
			(xy 307.258731 -353.416679) (xy 307.288197 -353.370829) (xy 307.323888 -353.329638) (xy 307.365079 -353.293947)
			(xy 307.410929 -353.264481) (xy 307.460506 -353.241839) (xy 307.512801 -353.226484) (xy 307.566749 -353.218728)
			(xy 307.621251 -353.218728) (xy 307.675199 -353.226484) (xy 307.727494 -353.241839) (xy 307.777071 -353.264481)
			(xy 307.822921 -353.293947) (xy 307.864112 -353.329638) (xy 307.899803 -353.370829) (xy 307.929269 -353.416679)
			(xy 307.951911 -353.466256) (xy 307.967266 -353.518551) (xy 307.975022 -353.572499) (xy 307.975508 -353.59975)
			(xy 307.975762 -353.59975) (xy 307.975221 -353.628087) (xy 307.966797 -353.684131) (xy 307.950187 -353.738317)
			(xy 307.925755 -353.789454) (xy 307.894036 -353.836421) (xy 307.855727 -353.878188) (xy 307.83403 -353.896422)
			(xy 307.829712 -353.899978) (xy 307.822854 -353.908614) (xy 307.80609 -353.942904) (xy 307.806344 -353.95535)
			(xy 307.807868 -354.025962) (xy 307.808122 -354.030534) (xy 307.809392 -354.04171) (xy 307.820568 -354.060506)
			(xy 307.829712 -354.066856) (xy 307.851174 -354.082229) (xy 307.890055 -354.11794) (xy 307.923645 -354.158667)
			(xy 307.951302 -354.203635) (xy 307.972498 -354.251985) (xy 307.98683 -354.302794) (xy 307.994024 -354.355094)
			(xy 307.993942 -354.407886) (xy 307.986587 -354.460163) (xy 307.972098 -354.510928) (xy 307.961792 -354.535232)
			(xy 307.950819 -354.558898) (xy 307.923392 -354.60327) (xy 307.89018 -354.643496) (xy 307.851803 -354.678828)
			(xy 307.808974 -354.708608) (xy 307.762491 -354.732282) (xy 307.713218 -354.749409) (xy 307.687726 -354.754942)
			(xy 307.673756 -354.757736) (xy 307.653182 -354.776532) (xy 307.649118 -354.789994) (xy 307.649118 -354.790502)
			(xy 307.62321 -354.875592) (xy 307.620934 -354.884502) (xy 307.622154 -354.902839) (xy 307.629724 -354.919585)
			(xy 307.63591 -354.926392) (xy 308.319424 -355.609906) (xy 308.326824 -355.616748) (xy 308.345422 -355.624473)
			(xy 308.355492 -355.624892) (xy 309.314596 -355.624892) (xy 309.323084 -355.624586) (xy 309.339126 -355.619036)
			(xy 309.352449 -355.608517) (xy 309.357268 -355.601524) (xy 309.410608 -355.51872) (xy 309.412386 -355.492812)
			(xy 309.406798 -355.480874) (xy 309.395655 -355.45564) (xy 309.379936 -355.402766) (xy 309.371994 -355.34818)
			(xy 309.371492 -355.3206) (xy 309.371986 -355.292582) (xy 309.380183 -355.237148) (xy 309.396401 -355.183509)
			(xy 309.42029 -355.13282) (xy 309.451338 -355.086171) (xy 309.488876 -355.044565) (xy 309.532095 -355.008898)
			(xy 309.580068 -354.979937) (xy 309.631761 -354.958305) (xy 309.686062 -354.944467) (xy 309.713884 -354.941124)
			(xy 309.723028 -354.940108) (xy 309.747412 -354.928424) (xy 309.751672 -354.926221) (xy 309.759347 -354.92047)
			(xy 309.762652 -354.916994) (xy 309.802784 -354.873306) (xy 309.808911 -354.866027) (xy 309.81571 -354.848272)
			(xy 309.815992 -354.838762) (xy 309.815992 -354.032312) (xy 309.815556 -354.022616) (xy 309.808366 -354.004606)
			(xy 309.802022 -353.99726) (xy 309.787544 -353.98202) (xy 309.780686 -353.976178) (xy 309.77332 -353.971606)
			(xy 309.750714 -353.960176) (xy 309.742078 -353.95916) (xy 309.714855 -353.955122) (xy 309.661871 -353.940239)
			(xy 309.611573 -353.917905) (xy 309.565001 -353.888582) (xy 309.523122 -353.852877) (xy 309.486801 -353.81153)
			(xy 309.456792 -353.765397) (xy 309.433717 -353.715434) (xy 309.418052 -353.662677) (xy 309.410124 -353.608217)
			(xy 309.409592 -353.5807) (xy 309.410057 -353.553424) (xy 309.417827 -353.499428) (xy 309.433209 -353.44709)
			(xy 309.455888 -353.397476) (xy 309.485404 -353.351599) (xy 309.521152 -353.310393) (xy 309.562406 -353.274699)
			(xy 309.608323 -353.245245) (xy 309.657967 -353.222631) (xy 309.710326 -353.207319) (xy 309.764331 -353.199621)
			(xy 309.791608 -353.199192) (xy 309.791862 -353.199192) (xy 309.801852 -353.198661) (xy 309.820294 -353.190957)
			(xy 309.827676 -353.184206) (xy 311.706514 -351.305368) (xy 311.72461 -351.288113) (xy 311.766156 -351.260306)
			(xy 311.812327 -351.241135) (xy 311.86135 -351.231337) (xy 311.886346 -351.230692) (xy 312.522108 -351.230692)
			(xy 312.532177 -351.230267) (xy 312.550779 -351.22255) (xy 312.558176 -351.215706) (xy 313.489848 -350.284288)
			(xy 313.496619 -350.276861) (xy 313.504201 -350.258264) (xy 313.50458 -350.24822) (xy 313.50458 -342.871044)
			(xy 313.505218 -342.846048) (xy 313.515019 -342.797026) (xy 313.534196 -342.750858) (xy 313.562011 -342.709317)
			(xy 313.579256 -342.691212) (xy 315.60135 -340.669118) (xy 315.608189 -340.661718) (xy 315.615902 -340.643119)
			(xy 315.616336 -340.63305) (xy 315.616336 -339.146134) (xy 315.616944 -339.121149) (xy 315.626679 -339.072137)
			(xy 315.645783 -339.025963) (xy 315.673522 -338.9844) (xy 315.690758 -338.966302) (xy 316.021212 -338.635848)
			(xy 316.029718 -338.627493) (xy 316.048036 -338.612227) (xy 316.057788 -338.605368) (xy 316.061419 -338.602833)
			(xy 316.067808 -338.596701) (xy 316.070488 -338.593176) (xy 316.085914 -338.572437) (xy 316.121459 -338.534914)
			(xy 316.161744 -338.502532) (xy 316.206031 -338.475884) (xy 316.25351 -338.455458) (xy 316.303312 -338.441628)
			(xy 316.354525 -338.434647) (xy 316.380368 -338.434172) (xy 316.407623 -338.434633) (xy 316.461578 -338.442386)
			(xy 316.513881 -338.457739) (xy 316.563467 -338.480379) (xy 316.609325 -338.509846) (xy 316.650524 -338.54554)
			(xy 316.686223 -338.586733) (xy 316.715696 -338.632588) (xy 316.738343 -338.68217) (xy 316.753703 -338.734471)
			(xy 316.761464 -338.788425) (xy 316.761876 -338.81568) (xy 316.761372 -338.843151) (xy 316.753446 -338.897518)
			(xy 316.737813 -338.950189) (xy 316.735155 -338.95595) (xy 317.003688 -338.95595) (xy 317.003688 -338.90145)
			(xy 317.011444 -338.847505) (xy 317.026798 -338.795213) (xy 317.049437 -338.745639) (xy 317.078901 -338.69979)
			(xy 317.11459 -338.658601) (xy 317.155777 -338.622911) (xy 317.201624 -338.593445) (xy 317.251198 -338.570804)
			(xy 317.30349 -338.555447) (xy 317.357434 -338.547689) (xy 317.384684 -338.547202) (xy 317.409921 -338.547562)
			(xy 317.459956 -338.554191) (xy 317.508676 -338.567375) (xy 317.555227 -338.586882) (xy 317.577216 -338.599272)
			(xy 317.586868 -338.605114) (xy 317.608966 -338.607146) (xy 317.703454 -338.573618) (xy 317.719456 -338.558124)
			(xy 317.72352 -338.54771) (xy 317.734188 -338.520921) (xy 317.762478 -338.470677) (xy 317.798011 -338.425266)
			(xy 317.839977 -338.385723) (xy 317.887418 -338.352951) (xy 317.939254 -338.327695) (xy 317.994301 -338.310533)
			(xy 318.051306 -338.301856) (xy 318.080136 -338.30133) (xy 318.107392 -338.301722) (xy 318.161347 -338.309484)
			(xy 318.213649 -338.324847) (xy 318.263231 -338.347496) (xy 318.309086 -338.376972) (xy 318.35028 -338.412673)
			(xy 318.385973 -338.453873) (xy 318.415439 -338.499734) (xy 318.438079 -338.549321) (xy 318.450802 -338.592668)
			(xy 320.591688 -338.592668) (xy 320.592205 -338.565095) (xy 320.600147 -338.510525) (xy 320.615863 -338.457666)
			(xy 320.639023 -338.40762) (xy 320.669146 -338.361429) (xy 320.705605 -338.320056) (xy 320.726308 -338.301838)
			(xy 320.734406 -338.294217) (xy 320.743771 -338.27408) (xy 320.744342 -338.262976) (xy 320.744342 -338.18576)
			(xy 320.743831 -338.174643) (xy 320.734454 -338.154484) (xy 320.726308 -338.146898) (xy 320.705594 -338.12869)
			(xy 320.669124 -338.08732) (xy 320.638992 -338.04113) (xy 320.615826 -337.991082) (xy 320.600111 -337.938218)
			(xy 320.592172 -337.883643) (xy 320.591688 -337.856068) (xy 320.592148 -337.828816) (xy 320.599909 -337.774868)
			(xy 320.615268 -337.722573) (xy 320.637912 -337.672996) (xy 320.667382 -337.627146) (xy 320.703076 -337.585956)
			(xy 320.744268 -337.550265) (xy 320.79012 -337.520799) (xy 320.839699 -337.498158) (xy 320.891995 -337.482803)
			(xy 320.945944 -337.475046) (xy 320.973196 -337.47456) (xy 321.007486 -337.476084) (xy 321.017646 -337.4771)
			(xy 321.03695 -337.471004) (xy 321.107562 -337.411822) (xy 321.11696 -337.393788) (xy 321.117976 -337.383628)
			(xy 321.120916 -337.355454) (xy 321.134093 -337.300362) (xy 321.155274 -337.247825) (xy 321.183994 -337.199)
			(xy 321.21962 -337.154959) (xy 321.261368 -337.116673) (xy 321.30832 -337.084984) (xy 321.359444 -337.060588)
			(xy 321.413613 -337.044023) (xy 321.469637 -337.035653) (xy 321.49796 -337.03514) (xy 321.515979 -337.035357)
			(xy 321.551854 -337.038794) (xy 321.569588 -337.041998) (xy 321.578986 -337.043776) (xy 321.598036 -337.039966)
			(xy 321.67322 -336.992214) (xy 321.68465 -336.976466) (xy 321.686936 -336.967068) (xy 321.694324 -336.940021)
			(xy 321.715954 -336.888293) (xy 321.744918 -336.840287) (xy 321.780595 -336.797034) (xy 321.822215 -336.759467)
			(xy 321.868884 -336.728393) (xy 321.919597 -336.704481) (xy 321.973263 -336.688246) (xy 322.028726 -336.680037)
			(xy 322.05676 -336.67954) (xy 322.084014 -336.679993) (xy 322.137968 -336.687745) (xy 322.190269 -336.703099)
			(xy 322.239852 -336.72574) (xy 322.285708 -336.755208) (xy 322.326902 -336.790904) (xy 322.362596 -336.832099)
			(xy 322.392064 -336.877955) (xy 322.414704 -336.927539) (xy 322.430056 -336.97984) (xy 322.437808 -337.033794)
			(xy 322.438268 -337.061048) (xy 322.437778 -337.088622) (xy 322.429832 -337.143194) (xy 322.414112 -337.196054)
			(xy 322.390947 -337.2461) (xy 322.360818 -337.29229) (xy 322.324354 -337.333662) (xy 322.303648 -337.351878)
			(xy 322.295536 -337.359486) (xy 322.28618 -337.379634) (xy 322.285614 -337.39074) (xy 322.285614 -337.467956)
			(xy 322.286186 -337.479066) (xy 322.295521 -337.499225) (xy 322.303648 -337.506818) (xy 322.324404 -337.52498)
			(xy 322.360872 -337.566356) (xy 322.391002 -337.612553) (xy 322.414166 -337.662607) (xy 322.42988 -337.715475)
			(xy 322.437818 -337.770054) (xy 322.437813 -337.825208) (xy 322.430621 -337.87461) (xy 323.594728 -337.87461)
			(xy 323.598799 -337.818988) (xy 323.610925 -337.764551) (xy 323.630848 -337.71246) (xy 323.658144 -337.663825)
			(xy 323.69223 -337.619682) (xy 323.732379 -337.580973) (xy 323.777737 -337.548522) (xy 323.827337 -337.523021)
			(xy 323.880121 -337.505014) (xy 323.934964 -337.494884) (xy 323.990698 -337.492847) (xy 324.046135 -337.498947)
			(xy 324.100092 -337.513053) (xy 324.151421 -337.534865) (xy 324.199027 -337.563919) (xy 324.241895 -337.599594)
			(xy 324.279112 -337.641131) (xy 324.309885 -337.687644) (xy 324.333557 -337.738141) (xy 324.349625 -337.791548)
			(xy 324.357745 -337.846724) (xy 324.358254 -337.87461) (xy 324.357745 -337.902496) (xy 324.349625 -337.957672)
			(xy 324.333557 -338.011079) (xy 324.309885 -338.061576) (xy 324.279112 -338.108089) (xy 324.241895 -338.149626)
			(xy 324.199027 -338.185301) (xy 324.151421 -338.214355) (xy 324.100092 -338.236167) (xy 324.046135 -338.250273)
			(xy 323.990698 -338.256373) (xy 323.934964 -338.254336) (xy 323.880121 -338.244206) (xy 323.827337 -338.226199)
			(xy 323.777737 -338.200698) (xy 323.732379 -338.168247) (xy 323.69223 -338.129538) (xy 323.658144 -338.085395)
			(xy 323.630848 -338.03676) (xy 323.610925 -337.984669) (xy 323.598799 -337.930232) (xy 323.594728 -337.87461)
			(xy 322.430621 -337.87461) (xy 322.429867 -337.879786) (xy 322.414144 -337.932651) (xy 322.390972 -337.982701)
			(xy 322.360834 -338.028893) (xy 322.324359 -338.070264) (xy 322.303648 -338.088478) (xy 322.295536 -338.096086)
			(xy 322.28618 -338.116234) (xy 322.285614 -338.12734) (xy 322.285614 -338.204556) (xy 322.286186 -338.215666)
			(xy 322.295521 -338.235825) (xy 322.303648 -338.243418) (xy 322.324381 -338.261605) (xy 322.360847 -338.30298)
			(xy 322.390975 -338.349176) (xy 322.414137 -338.399228) (xy 322.429849 -338.452094) (xy 322.437785 -338.506672)
			(xy 322.438268 -338.534248) (xy 322.437867 -338.561502) (xy 322.430103 -338.615455) (xy 322.414739 -338.667754)
			(xy 322.39209 -338.717334) (xy 322.362615 -338.763186) (xy 322.356744 -338.76996) (xy 323.015608 -338.76996)
			(xy 323.019679 -338.714338) (xy 323.031805 -338.659901) (xy 323.051728 -338.60781) (xy 323.079024 -338.559175)
			(xy 323.11311 -338.515032) (xy 323.153259 -338.476323) (xy 323.198617 -338.443872) (xy 323.248217 -338.418371)
			(xy 323.301001 -338.400364) (xy 323.355844 -338.390234) (xy 323.411578 -338.388197) (xy 323.467015 -338.394297)
			(xy 323.520972 -338.408403) (xy 323.572301 -338.430215) (xy 323.619907 -338.459269) (xy 323.662775 -338.494944)
			(xy 323.699992 -338.536481) (xy 323.730765 -338.582994) (xy 323.754437 -338.633491) (xy 323.770505 -338.686898)
			(xy 323.778625 -338.742074) (xy 323.779134 -338.76996) (xy 323.778625 -338.797846) (xy 323.770505 -338.853022)
			(xy 323.754437 -338.906429) (xy 323.730765 -338.956926) (xy 323.699992 -339.003439) (xy 323.662775 -339.044976)
			(xy 323.619907 -339.080651) (xy 323.572301 -339.109705) (xy 323.520972 -339.131517) (xy 323.467015 -339.145623)
			(xy 323.411578 -339.151723) (xy 323.355844 -339.149686) (xy 323.301001 -339.139556) (xy 323.248217 -339.121549)
			(xy 323.198617 -339.096048) (xy 323.153259 -339.063597) (xy 323.11311 -339.024888) (xy 323.079024 -338.980745)
			(xy 323.051728 -338.93211) (xy 323.031805 -338.880019) (xy 323.019679 -338.825582) (xy 323.015608 -338.76996)
			(xy 322.356744 -338.76996) (xy 322.326914 -338.804377) (xy 322.285715 -338.840068) (xy 322.239857 -338.869532)
			(xy 322.190271 -338.89217) (xy 322.137969 -338.907521) (xy 322.084014 -338.915273) (xy 322.05676 -338.915756)
			(xy 322.028902 -338.915302) (xy 321.973782 -338.907171) (xy 321.920428 -338.891118) (xy 321.869973 -338.867483)
			(xy 321.823488 -338.836768) (xy 321.781959 -338.799624) (xy 321.746268 -338.75684) (xy 321.717172 -338.709324)
			(xy 321.695289 -338.658085) (xy 321.687698 -338.631276) (xy 321.685412 -338.622386) (xy 321.674744 -338.607146)
			(xy 321.602862 -338.559394) (xy 321.584828 -338.55533) (xy 321.575684 -338.5566) (xy 321.562667 -338.558269)
			(xy 321.536483 -338.560049) (xy 321.52336 -338.560156) (xy 321.509211 -338.560066) (xy 321.480988 -338.558029)
			(xy 321.466972 -338.556092) (xy 321.456812 -338.554568) (xy 321.437254 -338.559394) (xy 321.362832 -338.615274)
			(xy 321.352672 -338.6328) (xy 321.351402 -338.64296) (xy 321.34734 -338.670118) (xy 321.332364 -338.72295)
			(xy 321.30997 -338.773089) (xy 321.280619 -338.8195) (xy 321.244919 -338.861224) (xy 321.203606 -338.8974)
			(xy 321.157534 -338.92728) (xy 321.107655 -338.950248) (xy 321.054999 -338.965828) (xy 321.000653 -338.973699)
			(xy 320.973196 -338.974176) (xy 320.945942 -338.973748) (xy 320.891988 -338.96599) (xy 320.839687 -338.950632)
			(xy 320.790105 -338.927986) (xy 320.74425 -338.898515) (xy 320.703057 -338.862818) (xy 320.667363 -338.821621)
			(xy 320.637896 -338.775763) (xy 320.615256 -338.726179) (xy 320.599902 -338.673877) (xy 320.592149 -338.619922)
			(xy 320.591688 -338.592668) (xy 318.450802 -338.592668) (xy 318.453431 -338.601625) (xy 318.461184 -338.655582)
			(xy 318.461644 -338.682838) (xy 318.460991 -338.714401) (xy 318.450602 -338.776667) (xy 318.430113 -338.836376)
			(xy 318.41567 -338.864448) (xy 318.410844 -338.873338) (xy 318.408812 -338.892896) (xy 318.434466 -338.981034)
			(xy 318.446912 -338.996528) (xy 318.455802 -339.001608) (xy 318.480891 -339.016175) (xy 318.526773 -339.051676)
			(xy 318.566749 -339.093717) (xy 318.599895 -339.141327) (xy 318.625448 -339.193409) (xy 318.642817 -339.24876)
			(xy 318.651603 -339.306104) (xy 318.652144 -339.33511) (xy 318.651658 -339.362361) (xy 318.643902 -339.416309)
			(xy 318.628547 -339.468604) (xy 318.605905 -339.518181) (xy 318.576439 -339.564031) (xy 318.540748 -339.605222)
			(xy 318.499557 -339.640913) (xy 318.453707 -339.670379) (xy 318.40413 -339.693021) (xy 318.351835 -339.708376)
			(xy 318.297887 -339.716132) (xy 318.243385 -339.716132) (xy 318.189437 -339.708376) (xy 318.137142 -339.693021)
			(xy 318.087565 -339.670379) (xy 318.041715 -339.640913) (xy 318.000524 -339.605222) (xy 317.964833 -339.564031)
			(xy 317.935367 -339.518181) (xy 317.912725 -339.468604) (xy 317.89737 -339.416309) (xy 317.889614 -339.362361)
			(xy 317.889128 -339.33511) (xy 317.889764 -339.303546) (xy 317.900161 -339.24128) (xy 317.920656 -339.181572)
			(xy 317.935102 -339.1535) (xy 317.939928 -339.14461) (xy 317.94196 -339.125052) (xy 317.916306 -339.036914)
			(xy 317.90386 -339.02142) (xy 317.89497 -339.01634) (xy 317.887604 -339.012276) (xy 317.877952 -339.006434)
			(xy 317.855854 -339.004402) (xy 317.761366 -339.03793) (xy 317.745364 -339.053424) (xy 317.7413 -339.063838)
			(xy 317.730641 -339.09063) (xy 317.702347 -339.140872) (xy 317.666811 -339.186281) (xy 317.624844 -339.225822)
			(xy 317.577401 -339.258593) (xy 317.525566 -339.283849) (xy 317.470518 -339.301011) (xy 317.413514 -339.30969)
			(xy 317.384684 -339.310218) (xy 317.357434 -339.309711) (xy 317.30349 -339.301953) (xy 317.251198 -339.286596)
			(xy 317.201624 -339.263955) (xy 317.155777 -339.234489) (xy 317.11459 -339.198799) (xy 317.078901 -339.15761)
			(xy 317.049437 -339.111761) (xy 317.026798 -339.062187) (xy 317.011444 -339.009895) (xy 317.003688 -338.95595)
			(xy 316.735155 -338.95595) (xy 316.714794 -339.000077) (xy 316.684865 -339.046152) (xy 316.667134 -339.06714)
			(xy 316.661038 -339.074252) (xy 316.654688 -339.09127) (xy 316.654688 -339.177122) (xy 316.661038 -339.19414)
			(xy 316.667134 -339.201252) (xy 316.684902 -339.222214) (xy 316.714854 -339.268282) (xy 316.737878 -339.318175)
			(xy 316.753498 -339.370858) (xy 316.761389 -339.425237) (xy 316.761876 -339.452712) (xy 316.761425 -339.479446)
			(xy 316.753953 -339.532391) (xy 316.739157 -339.583772) (xy 316.717328 -339.632582) (xy 316.688893 -339.677863)
			(xy 316.654411 -339.718727) (xy 316.614558 -339.754373) (xy 316.570115 -339.784102) (xy 316.54623 -339.79612)
			(xy 316.533022 -339.802724) (xy 316.517528 -339.827108) (xy 316.517528 -340.905846) (xy 316.516922 -340.930831)
			(xy 316.507189 -340.979845) (xy 316.488085 -341.02602) (xy 316.460345 -341.067583) (xy 316.443106 -341.085678)
			(xy 314.409328 -343.119456) (xy 314.40254 -343.126877) (xy 314.394926 -343.145474) (xy 314.394596 -343.155524)
			(xy 314.394596 -350.100646) (xy 314.395079 -350.11061) (xy 314.402661 -350.12904) (xy 314.409328 -350.13646)
			(xy 314.410852 -350.137984) (xy 314.410852 -350.600772) (xy 314.410414 -350.610835) (xy 314.402676 -350.629416)
			(xy 314.395866 -350.63684) (xy 312.986674 -352.046032) (xy 312.968578 -352.063286) (xy 312.927032 -352.091091)
			(xy 312.88086 -352.11026) (xy 312.831837 -352.120056) (xy 312.806842 -352.120708) (xy 312.190892 -352.120708)
			(xy 312.180823 -352.121133) (xy 312.162221 -352.12885) (xy 312.154824 -352.135694) (xy 311.825894 -352.464624)
			(xy 311.819157 -352.471993) (xy 311.811401 -352.49037) (xy 311.811181 -352.510315) (xy 311.814464 -352.519742)
			(xy 311.814718 -352.519742) (xy 311.818912 -352.528903) (xy 311.833077 -352.543208) (xy 311.851644 -352.550993)
			(xy 311.861708 -352.551492) (xy 312.518552 -352.551492) (xy 312.526042 -352.551797) (xy 312.540371 -352.556184)
			(xy 312.546746 -352.560128) (xy 312.667904 -352.642424) (xy 312.677974 -352.648591) (xy 312.701335 -352.651827)
			(xy 312.723672 -352.644261) (xy 312.73242 -352.636328) (xy 314.266326 -351.102168) (xy 314.284422 -351.084914)
			(xy 314.325968 -351.057109) (xy 314.37214 -351.03794) (xy 314.421163 -351.028144) (xy 314.446158 -351.027492)
			(xy 317.08852 -351.027492) (xy 317.098588 -351.027065) (xy 317.117187 -351.019345) (xy 317.124588 -351.012506)
			(xy 321.65417 -346.482924) (xy 321.661008 -346.475523) (xy 321.668719 -346.456924) (xy 321.669156 -346.446856)
			(xy 321.669156 -343.272618) (xy 321.669796 -343.247623) (xy 321.679601 -343.198603) (xy 321.69878 -343.152437)
			(xy 321.726595 -343.110899) (xy 321.743832 -343.092786) (xy 323.65823 -341.178388) (xy 323.665082 -341.170992)
			(xy 323.672823 -341.152393) (xy 323.673216 -341.14232) (xy 323.673216 -339.437472) (xy 323.673851 -339.412475)
			(xy 323.683646 -339.363448) (xy 323.702815 -339.317273) (xy 323.730623 -339.275724) (xy 323.747892 -339.25764)
			(xy 324.376796 -338.628736) (xy 324.385308 -338.620445) (xy 324.403627 -338.605309) (xy 324.413372 -338.59851)
			(xy 324.417005 -338.595902) (xy 324.423396 -338.589647) (xy 324.426072 -338.586064) (xy 324.441495 -338.56532)
			(xy 324.477036 -338.527787) (xy 324.517319 -338.495396) (xy 324.561606 -338.46874) (xy 324.609086 -338.448307)
			(xy 324.658891 -338.434471) (xy 324.710107 -338.427486) (xy 324.735952 -338.42706) (xy 324.763208 -338.42752)
			(xy 324.817166 -338.435271) (xy 324.869471 -338.450622) (xy 324.91906 -338.473262) (xy 324.964921 -338.502728)
			(xy 325.006122 -338.538421) (xy 325.041824 -338.579615) (xy 325.0713 -338.62547) (xy 325.09395 -338.675054)
			(xy 325.109312 -338.727356) (xy 325.117075 -338.781312) (xy 325.11746 -338.808568) (xy 325.116979 -338.83603)
			(xy 325.109102 -338.890386) (xy 325.093522 -338.943054) (xy 325.090854 -338.94885) (xy 325.359276 -338.94885)
			(xy 325.359276 -338.89435) (xy 325.367031 -338.840405) (xy 325.382385 -338.788112) (xy 325.405024 -338.738537)
			(xy 325.434487 -338.692688) (xy 325.470176 -338.651498) (xy 325.511362 -338.615807) (xy 325.557209 -338.586339)
			(xy 325.606782 -338.563696) (xy 325.659074 -338.548338) (xy 325.713018 -338.540578) (xy 325.740268 -338.54009)
			(xy 325.765504 -338.540458) (xy 325.815539 -338.547085) (xy 325.86426 -338.560267) (xy 325.91081 -338.579771)
			(xy 325.9328 -338.59216) (xy 325.942452 -338.598002) (xy 325.96455 -338.600034) (xy 326.059038 -338.566506)
			(xy 326.07504 -338.551012) (xy 326.079104 -338.540598) (xy 326.089779 -338.513812) (xy 326.118069 -338.46357)
			(xy 326.153601 -338.418159) (xy 326.195566 -338.378617) (xy 326.243007 -338.345844) (xy 326.294841 -338.320588)
			(xy 326.349887 -338.303424) (xy 326.40689 -338.294745) (xy 326.43572 -338.294218) (xy 326.462975 -338.294636)
			(xy 326.516928 -338.302397) (xy 326.569229 -338.317757) (xy 326.618811 -338.340403) (xy 326.664665 -338.369876)
			(xy 326.705858 -338.405574) (xy 326.741552 -338.446772) (xy 326.771019 -338.49263) (xy 326.793659 -338.542214)
			(xy 326.806382 -338.585556) (xy 328.947272 -338.585556) (xy 328.947786 -338.557983) (xy 328.95573 -338.503413)
			(xy 328.971446 -338.450554) (xy 328.994607 -338.400509) (xy 329.024731 -338.354318) (xy 329.061189 -338.312944)
			(xy 329.081892 -338.294726) (xy 329.089993 -338.287108) (xy 329.099357 -338.266968) (xy 329.099926 -338.255864)
			(xy 329.099926 -338.178648) (xy 329.099371 -338.167536) (xy 329.090026 -338.147376) (xy 329.081892 -338.139786)
			(xy 329.061169 -338.121587) (xy 329.0247 -338.080216) (xy 328.99457 -338.034023) (xy 328.971406 -337.983973)
			(xy 328.955692 -337.931108) (xy 328.947756 -337.876531) (xy 328.947272 -337.848956) (xy 328.947737 -337.821705)
			(xy 328.955499 -337.767757) (xy 328.970859 -337.715463) (xy 328.993503 -337.665887) (xy 329.022972 -337.620038)
			(xy 329.058666 -337.578849) (xy 329.099857 -337.543158) (xy 329.145708 -337.513692) (xy 329.195286 -337.49105)
			(xy 329.247581 -337.475694) (xy 329.301529 -337.467935) (xy 329.32878 -337.467448) (xy 329.36307 -337.468972)
			(xy 329.37323 -337.469988) (xy 329.392534 -337.463892) (xy 329.463146 -337.40471) (xy 329.472544 -337.386676)
			(xy 329.47356 -337.376516) (xy 329.476506 -337.348343) (xy 329.489684 -337.293252) (xy 329.510865 -337.240716)
			(xy 329.539585 -337.191892) (xy 329.57521 -337.147852) (xy 329.616957 -337.109566) (xy 329.663909 -337.077877)
			(xy 329.715031 -337.05348) (xy 329.769199 -337.036914) (xy 329.825221 -337.028542) (xy 329.853544 -337.028028)
			(xy 329.871563 -337.028248) (xy 329.907438 -337.031683) (xy 329.925172 -337.034886) (xy 329.93457 -337.036664)
			(xy 329.95362 -337.032854) (xy 330.028804 -336.985102) (xy 330.040234 -336.969354) (xy 330.04252 -336.959956)
			(xy 330.049915 -336.932911) (xy 330.071545 -336.881184) (xy 330.100509 -336.833179) (xy 330.136185 -336.789927)
			(xy 330.177804 -336.75236) (xy 330.224472 -336.721286) (xy 330.275184 -336.697373) (xy 330.328848 -336.681137)
			(xy 330.384311 -336.672927) (xy 330.412344 -336.672428) (xy 330.439598 -336.672837) (xy 330.49355 -336.6806)
			(xy 330.545849 -336.695963) (xy 330.595428 -336.718612) (xy 330.64128 -336.748086) (xy 330.682471 -336.783786)
			(xy 330.718162 -336.824984) (xy 330.747627 -336.870842) (xy 330.770265 -336.920426) (xy 330.785617 -336.972728)
			(xy 330.793369 -337.026682) (xy 330.793852 -337.053936) (xy 330.793359 -337.08151) (xy 330.785414 -337.136082)
			(xy 330.769696 -337.188942) (xy 330.746531 -337.238989) (xy 330.716403 -337.285179) (xy 330.679938 -337.32655)
			(xy 330.659232 -337.344766) (xy 330.651122 -337.352376) (xy 330.641766 -337.372522) (xy 330.641198 -337.383628)
			(xy 330.641198 -337.460844) (xy 330.641782 -337.471952) (xy 330.651109 -337.492111) (xy 330.659232 -337.499706)
			(xy 330.679972 -337.517883) (xy 330.716433 -337.559261) (xy 330.746556 -337.605457) (xy 330.769715 -337.655508)
			(xy 330.785426 -337.708373) (xy 330.793363 -337.762948) (xy 330.79336 -337.818098) (xy 330.787241 -337.860132)
			(xy 331.952344 -337.860132) (xy 331.956415 -337.80451) (xy 331.968541 -337.750073) (xy 331.988464 -337.697982)
			(xy 332.01576 -337.649347) (xy 332.049846 -337.605204) (xy 332.089995 -337.566495) (xy 332.135353 -337.534044)
			(xy 332.184953 -337.508543) (xy 332.237737 -337.490536) (xy 332.29258 -337.480406) (xy 332.348314 -337.478369)
			(xy 332.403751 -337.484469) (xy 332.457708 -337.498575) (xy 332.509037 -337.520387) (xy 332.556643 -337.549441)
			(xy 332.599511 -337.585116) (xy 332.636728 -337.626653) (xy 332.667501 -337.673166) (xy 332.691173 -337.723663)
			(xy 332.707241 -337.77707) (xy 332.715361 -337.832246) (xy 332.71587 -337.860132) (xy 332.715361 -337.888018)
			(xy 332.707241 -337.943194) (xy 332.691173 -337.996601) (xy 332.667501 -338.047098) (xy 332.636728 -338.093611)
			(xy 332.599511 -338.135148) (xy 332.556643 -338.170823) (xy 332.509037 -338.199877) (xy 332.457708 -338.221689)
			(xy 332.403751 -338.235795) (xy 332.348314 -338.241895) (xy 332.29258 -338.239858) (xy 332.237737 -338.229728)
			(xy 332.184953 -338.211721) (xy 332.135353 -338.18622) (xy 332.089995 -338.153769) (xy 332.049846 -338.11506)
			(xy 332.01576 -338.070917) (xy 331.988464 -338.022282) (xy 331.968541 -337.970191) (xy 331.956415 -337.915754)
			(xy 331.952344 -337.860132) (xy 330.787241 -337.860132) (xy 330.785416 -337.872673) (xy 330.769699 -337.925535)
			(xy 330.746534 -337.975584) (xy 330.716404 -338.021776) (xy 330.679939 -338.06315) (xy 330.659232 -338.081366)
			(xy 330.651122 -338.088976) (xy 330.641766 -338.109122) (xy 330.641198 -338.120228) (xy 330.641198 -338.197444)
			(xy 330.641782 -338.208552) (xy 330.651109 -338.228711) (xy 330.659232 -338.236306) (xy 330.679956 -338.254503)
			(xy 330.716424 -338.295876) (xy 330.746553 -338.342069) (xy 330.769717 -338.392119) (xy 330.785431 -338.444984)
			(xy 330.793368 -338.499561) (xy 330.793852 -338.527136) (xy 330.793356 -338.554386) (xy 330.785596 -338.608331)
			(xy 330.770238 -338.660623) (xy 330.747596 -338.710197) (xy 330.718492 -338.755482) (xy 331.373224 -338.755482)
			(xy 331.377295 -338.69986) (xy 331.389421 -338.645423) (xy 331.409344 -338.593332) (xy 331.43664 -338.544697)
			(xy 331.470726 -338.500554) (xy 331.510875 -338.461845) (xy 331.556233 -338.429394) (xy 331.605833 -338.403893)
			(xy 331.658617 -338.385886) (xy 331.71346 -338.375756) (xy 331.769194 -338.373719) (xy 331.824631 -338.379819)
			(xy 331.878588 -338.393925) (xy 331.929917 -338.415737) (xy 331.977523 -338.444791) (xy 332.020391 -338.480466)
			(xy 332.057608 -338.522003) (xy 332.088381 -338.568516) (xy 332.112053 -338.619013) (xy 332.128121 -338.67242)
			(xy 332.136241 -338.727596) (xy 332.13675 -338.755482) (xy 332.136241 -338.783368) (xy 332.128121 -338.838544)
			(xy 332.112053 -338.891951) (xy 332.088381 -338.942448) (xy 332.057608 -338.988961) (xy 332.020391 -339.030498)
			(xy 331.977523 -339.066173) (xy 331.929917 -339.095227) (xy 331.878588 -339.117039) (xy 331.824631 -339.131145)
			(xy 331.769194 -339.137245) (xy 331.71346 -339.135208) (xy 331.658617 -339.125078) (xy 331.605833 -339.107071)
			(xy 331.556233 -339.08157) (xy 331.510875 -339.049119) (xy 331.470726 -339.01041) (xy 331.43664 -338.966267)
			(xy 331.409344 -338.917632) (xy 331.389421 -338.865541) (xy 331.377295 -338.811104) (xy 331.373224 -338.755482)
			(xy 330.718492 -338.755482) (xy 330.71813 -338.756046) (xy 330.68244 -338.797234) (xy 330.641252 -338.832925)
			(xy 330.595405 -338.862392) (xy 330.545831 -338.885035) (xy 330.493539 -338.900394) (xy 330.439594 -338.908155)
			(xy 330.412344 -338.908644) (xy 330.384492 -338.908049) (xy 330.329381 -338.899932) (xy 330.276034 -338.883895)
			(xy 330.225583 -338.860277) (xy 330.1791 -338.829579) (xy 330.13757 -338.792453) (xy 330.101875 -338.749687)
			(xy 330.072772 -338.702188) (xy 330.050879 -338.650965) (xy 330.043282 -338.624164) (xy 330.040996 -338.615274)
			(xy 330.030328 -338.600034) (xy 329.958446 -338.552282) (xy 329.940412 -338.548218) (xy 329.931268 -338.549488)
			(xy 329.918252 -338.551158) (xy 329.892067 -338.552937) (xy 329.878944 -338.553044) (xy 329.864795 -338.552945)
			(xy 329.836572 -338.550914) (xy 329.822556 -338.54898) (xy 329.812396 -338.547456) (xy 329.792838 -338.552282)
			(xy 329.718416 -338.608162) (xy 329.708256 -338.625688) (xy 329.706986 -338.635848) (xy 329.70293 -338.663007)
			(xy 329.687955 -338.71584) (xy 329.665561 -338.76598) (xy 329.63621 -338.812392) (xy 329.600509 -338.854117)
			(xy 329.559195 -338.890293) (xy 329.513122 -338.920173) (xy 329.463242 -338.94314) (xy 329.410584 -338.958719)
			(xy 329.356237 -338.966588) (xy 329.32878 -338.967064) (xy 329.301525 -338.966664) (xy 329.247569 -338.958903)
			(xy 329.195267 -338.943542) (xy 329.145684 -338.920894) (xy 329.099829 -338.89142) (xy 329.058635 -338.855719)
			(xy 329.022942 -338.81452) (xy 328.993475 -338.76866) (xy 328.970836 -338.719073) (xy 328.955484 -338.666768)
			(xy 328.947732 -338.612811) (xy 328.947272 -338.585556) (xy 326.806382 -338.585556) (xy 326.809013 -338.594517)
			(xy 326.816767 -338.648471) (xy 326.817228 -338.675726) (xy 326.81656 -338.707288) (xy 326.806176 -338.769553)
			(xy 326.785693 -338.829263) (xy 326.771254 -338.857336) (xy 326.766428 -338.866226) (xy 326.764396 -338.885784)
			(xy 326.79005 -338.973922) (xy 326.802496 -338.989416) (xy 326.811386 -338.994496) (xy 326.83651 -339.009007)
			(xy 326.882393 -339.044516) (xy 326.922368 -339.086566) (xy 326.955511 -339.134186) (xy 326.981058 -339.186277)
			(xy 326.998419 -339.241637) (xy 327.007193 -339.298989) (xy 327.007728 -339.327998) (xy 327.007242 -339.355249)
			(xy 326.999486 -339.409197) (xy 326.984131 -339.461492) (xy 326.961489 -339.511069) (xy 326.932023 -339.556919)
			(xy 326.896332 -339.59811) (xy 326.855141 -339.633801) (xy 326.809291 -339.663267) (xy 326.759714 -339.685909)
			(xy 326.707419 -339.701264) (xy 326.653471 -339.70902) (xy 326.598969 -339.70902) (xy 326.545021 -339.701264)
			(xy 326.492726 -339.685909) (xy 326.443149 -339.663267) (xy 326.397299 -339.633801) (xy 326.356108 -339.59811)
			(xy 326.320417 -339.556919) (xy 326.290951 -339.511069) (xy 326.268309 -339.461492) (xy 326.252954 -339.409197)
			(xy 326.245198 -339.355249) (xy 326.244712 -339.327998) (xy 326.245385 -339.296436) (xy 326.255766 -339.234171)
			(xy 326.276247 -339.174461) (xy 326.290686 -339.146388) (xy 326.295512 -339.137498) (xy 326.297544 -339.11794)
			(xy 326.27189 -339.029802) (xy 326.259444 -339.014308) (xy 326.250554 -339.009228) (xy 326.243188 -339.005164)
			(xy 326.233536 -338.999322) (xy 326.211438 -338.99729) (xy 326.11695 -339.030818) (xy 326.100948 -339.046312)
			(xy 326.096884 -339.056726) (xy 326.086232 -339.083521) (xy 326.057938 -339.133764) (xy 326.022402 -339.179173)
			(xy 325.980433 -339.218715) (xy 325.93299 -339.251486) (xy 325.881153 -339.276741) (xy 325.826104 -339.293902)
			(xy 325.769099 -339.30258) (xy 325.740268 -339.303106) (xy 325.713018 -339.302622) (xy 325.659074 -339.294862)
			(xy 325.606782 -339.279504) (xy 325.557209 -339.256861) (xy 325.511362 -339.227393) (xy 325.470176 -339.191702)
			(xy 325.434487 -339.150512) (xy 325.405024 -339.104663) (xy 325.382385 -339.055088) (xy 325.367031 -339.002795)
			(xy 325.359276 -338.94885) (xy 325.090854 -338.94885) (xy 325.070558 -338.992946) (xy 325.040684 -339.039036)
			(xy 325.022972 -339.060028) (xy 325.016622 -339.06714) (xy 325.010272 -339.084158) (xy 325.010272 -339.17001)
			(xy 325.016622 -339.187028) (xy 325.022972 -339.19414) (xy 325.040701 -339.215119) (xy 325.070578 -339.261208)
			(xy 325.093539 -339.311104) (xy 325.109111 -339.363777) (xy 325.11697 -339.418137) (xy 325.11746 -339.4456)
			(xy 325.116995 -339.472875) (xy 325.109225 -339.526868) (xy 325.093842 -339.579203) (xy 325.071162 -339.628814)
			(xy 325.041646 -339.674688) (xy 325.005897 -339.71589) (xy 324.964643 -339.75158) (xy 324.918726 -339.781029)
			(xy 324.869082 -339.803637) (xy 324.816724 -339.818943) (xy 324.762719 -339.826634) (xy 324.735444 -339.827108)
			(xy 324.73519 -339.827108) (xy 324.725204 -339.827648) (xy 324.706775 -339.835364) (xy 324.699376 -339.842094)
			(xy 324.578218 -339.963252) (xy 324.571413 -339.970599) (xy 324.563697 -339.989062) (xy 324.563232 -339.999066)
			(xy 324.563232 -341.427054) (xy 324.562595 -341.45205) (xy 324.552794 -341.501073) (xy 324.533618 -341.547242)
			(xy 324.505804 -341.588783) (xy 324.488556 -341.606886) (xy 322.574158 -343.521284) (xy 322.566792 -343.528396)
			(xy 322.559172 -343.547192) (xy 322.559172 -346.73159) (xy 322.558531 -346.756585) (xy 322.548726 -346.805605)
			(xy 322.529548 -346.851771) (xy 322.501734 -346.89331) (xy 322.484496 -346.911422) (xy 317.553086 -351.842832)
			(xy 317.53499 -351.860087) (xy 317.493444 -351.887894) (xy 317.447273 -351.907065) (xy 317.39825 -351.916863)
			(xy 317.373254 -351.917508) (xy 314.730892 -351.917508) (xy 314.720823 -351.917933) (xy 314.702221 -351.92565)
			(xy 314.694824 -351.932494) (xy 314.390532 -352.236786) (xy 314.383758 -352.244145) (xy 314.376103 -352.262607)
			(xy 314.376103 -352.282593) (xy 314.383758 -352.301055) (xy 314.390532 -352.308414) (xy 314.668408 -352.58629)
			(xy 314.674824 -352.592181) (xy 314.690568 -352.599605) (xy 314.707892 -352.601294) (xy 314.716414 -352.599498)
			(xy 314.72886 -352.59645) (xy 314.734194 -352.593656) (xy 314.761208 -352.580357) (xy 314.818391 -352.561505)
			(xy 314.877827 -352.551883) (xy 314.90793 -352.551238) (xy 314.919868 -352.551746) (xy 314.948021 -352.553046)
			(xy 315.003511 -352.562902) (xy 315.056948 -352.58081) (xy 315.107171 -352.606381) (xy 315.153088 -352.639059)
			(xy 315.193701 -352.678133) (xy 315.228127 -352.722754) (xy 315.255618 -352.771952) (xy 315.26607 -352.798126)
			(xy 315.271658 -352.813112) (xy 315.297566 -352.830892) (xy 317.64732 -352.830892) (xy 317.656718 -352.829876)
			(xy 317.664028 -352.828276) (xy 317.677328 -352.821432) (xy 317.68288 -352.816414) (xy 323.45249 -347.046804)
			(xy 323.459338 -347.039406) (xy 323.467076 -347.020808) (xy 323.467476 -347.010736) (xy 323.467476 -344.938858)
			(xy 323.468112 -344.913862) (xy 323.477912 -344.864838) (xy 323.497086 -344.818668) (xy 323.524899 -344.777125)
			(xy 323.542152 -344.759026) (xy 327.146158 -341.15502) (xy 327.164254 -341.137763) (xy 327.205799 -341.109952)
			(xy 327.25197 -341.090775) (xy 327.300993 -341.080968) (xy 327.32599 -341.080344) (xy 331.571092 -341.080344)
			(xy 331.581162 -341.079921) (xy 331.599763 -341.072202) (xy 331.60716 -341.065358) (xy 332.285594 -340.386924)
			(xy 332.292429 -340.379522) (xy 332.300137 -340.360923) (xy 332.30058 -340.350856) (xy 332.30058 -339.192616)
			(xy 332.30122 -339.167621) (xy 332.311027 -339.118602) (xy 332.330207 -339.072438) (xy 332.358024 -339.030901)
			(xy 332.375256 -339.012784) (xy 332.741524 -338.646516) (xy 332.745334 -338.63788) (xy 332.757002 -338.613066)
			(xy 332.786399 -338.566779) (xy 332.822118 -338.525175) (xy 332.863422 -338.48911) (xy 332.909462 -338.459327)
			(xy 332.95929 -338.436439) (xy 333.011881 -338.420917) (xy 333.066151 -338.41308) (xy 333.093568 -338.412582)
			(xy 333.120823 -338.413043) (xy 333.174778 -338.420796) (xy 333.22708 -338.436149) (xy 333.276665 -338.45879)
			(xy 333.322523 -338.488257) (xy 333.36372 -338.52395) (xy 333.399418 -338.565144) (xy 333.42889 -338.610998)
			(xy 333.451536 -338.660581) (xy 333.466895 -338.712881) (xy 333.474654 -338.766835) (xy 333.475076 -338.79409)
			(xy 333.4746 -338.821554) (xy 333.466734 -338.875916) (xy 333.451162 -338.92859) (xy 333.448513 -338.934349)
			(xy 333.716898 -338.934349) (xy 333.716898 -338.879851) (xy 333.724654 -338.825908) (xy 333.740007 -338.773617)
			(xy 333.762646 -338.724043) (xy 333.792109 -338.678196) (xy 333.827797 -338.637009) (xy 333.868983 -338.601319)
			(xy 333.914829 -338.571854) (xy 333.964402 -338.549213) (xy 334.016692 -338.533857) (xy 334.070635 -338.526099)
			(xy 334.097884 -338.525612) (xy 334.123121 -338.52597) (xy 334.173156 -338.5326) (xy 334.221876 -338.545784)
			(xy 334.268427 -338.565292) (xy 334.290416 -338.577682) (xy 334.300068 -338.583524) (xy 334.322166 -338.585556)
			(xy 334.416654 -338.552028) (xy 334.432656 -338.536534) (xy 334.43672 -338.52612) (xy 334.447394 -338.499334)
			(xy 334.475682 -338.449089) (xy 334.511214 -338.403678) (xy 334.553179 -338.364135) (xy 334.60062 -338.331361)
			(xy 334.652455 -338.306106) (xy 334.707502 -338.288944) (xy 334.764506 -338.280266) (xy 334.793336 -338.27974)
			(xy 334.820592 -338.280122) (xy 334.874548 -338.287885) (xy 334.926851 -338.303248) (xy 334.976434 -338.325898)
			(xy 335.02229 -338.355374) (xy 335.063483 -338.391076) (xy 335.099176 -338.432278) (xy 335.128642 -338.47814)
			(xy 335.151282 -338.527728) (xy 335.164005 -338.571078) (xy 337.304888 -338.571078) (xy 337.305412 -338.543506)
			(xy 337.313353 -338.488935) (xy 337.329067 -338.436077) (xy 337.352226 -338.386031) (xy 337.382348 -338.33984)
			(xy 337.418806 -338.298466) (xy 337.439508 -338.280248) (xy 337.447602 -338.272623) (xy 337.456969 -338.252489)
			(xy 337.457542 -338.241386) (xy 337.457542 -338.16417) (xy 337.457025 -338.153053) (xy 337.447652 -338.132894)
			(xy 337.439508 -338.125308) (xy 337.418799 -338.107094) (xy 337.382328 -338.065726) (xy 337.352196 -338.019537)
			(xy 337.329029 -337.969489) (xy 337.313313 -337.916627) (xy 337.305373 -337.862053) (xy 337.304888 -337.834478)
			(xy 337.305357 -337.807226) (xy 337.313117 -337.753278) (xy 337.328474 -337.700983) (xy 337.351118 -337.651406)
			(xy 337.380586 -337.605556) (xy 337.416279 -337.564366) (xy 337.457471 -337.528675) (xy 337.503322 -337.499209)
			(xy 337.5529 -337.476568) (xy 337.605196 -337.461213) (xy 337.659144 -337.453456) (xy 337.686396 -337.45297)
			(xy 337.720686 -337.454494) (xy 337.730846 -337.45551) (xy 337.75015 -337.449414) (xy 337.820762 -337.390232)
			(xy 337.83016 -337.372198) (xy 337.831176 -337.362038) (xy 337.834125 -337.333865) (xy 337.8473 -337.278773)
			(xy 337.86848 -337.226236) (xy 337.897198 -337.177411) (xy 337.932823 -337.13337) (xy 337.974571 -337.095084)
			(xy 338.021522 -337.063394) (xy 338.072645 -337.038998) (xy 338.126814 -337.022433) (xy 338.182837 -337.014063)
			(xy 338.21116 -337.01355) (xy 338.229179 -337.013767) (xy 338.265054 -337.017204) (xy 338.282788 -337.020408)
			(xy 338.292186 -337.022186) (xy 338.311236 -337.018376) (xy 338.38642 -336.970624) (xy 338.39785 -336.954876)
			(xy 338.400136 -336.945478) (xy 338.407531 -336.918433) (xy 338.429159 -336.866705) (xy 338.458122 -336.818698)
			(xy 338.493798 -336.775445) (xy 338.535417 -336.737878) (xy 338.582086 -336.706803) (xy 338.632798 -336.682891)
			(xy 338.686463 -336.666656) (xy 338.741926 -336.658447) (xy 338.76996 -336.65795) (xy 338.797208 -336.658515)
			(xy 338.851151 -336.666265) (xy 338.903442 -336.681613) (xy 338.953016 -336.704247) (xy 338.998864 -336.733705)
			(xy 339.040054 -336.769388) (xy 339.075746 -336.81057) (xy 339.105214 -336.856412) (xy 339.127858 -336.905981)
			(xy 339.143217 -336.958269) (xy 339.150979 -337.01221) (xy 339.151468 -337.039458) (xy 339.150985 -337.067032)
			(xy 339.143037 -337.121605) (xy 339.127316 -337.174465) (xy 339.10415 -337.224511) (xy 339.07402 -337.270701)
			(xy 339.037554 -337.312072) (xy 339.016848 -337.330288) (xy 339.008731 -337.337892) (xy 338.999378 -337.358043)
			(xy 338.998814 -337.36915) (xy 338.998814 -337.446366) (xy 338.999381 -337.457476) (xy 339.00872 -337.477635)
			(xy 339.016848 -337.485228) (xy 339.037514 -337.503488) (xy 339.073982 -337.544852) (xy 339.104114 -337.591035)
			(xy 339.127281 -337.641077) (xy 339.143001 -337.693932) (xy 339.150945 -337.748501) (xy 339.150949 -337.803645)
			(xy 339.143012 -337.858215) (xy 339.127342 -337.910932) (xy 340.283544 -337.910932) (xy 340.287615 -337.85531)
			(xy 340.299741 -337.800873) (xy 340.319664 -337.748782) (xy 340.34696 -337.700147) (xy 340.381046 -337.656004)
			(xy 340.421195 -337.617295) (xy 340.466553 -337.584844) (xy 340.516153 -337.559343) (xy 340.568937 -337.541336)
			(xy 340.62378 -337.531206) (xy 340.679514 -337.529169) (xy 340.734951 -337.535269) (xy 340.788908 -337.549375)
			(xy 340.840237 -337.571187) (xy 340.887843 -337.600241) (xy 340.930711 -337.635916) (xy 340.967928 -337.677453)
			(xy 340.998701 -337.723966) (xy 341.022373 -337.774463) (xy 341.038441 -337.82787) (xy 341.046561 -337.883046)
			(xy 341.04707 -337.910932) (xy 341.046561 -337.938818) (xy 341.038441 -337.993994) (xy 341.022373 -338.047401)
			(xy 340.998701 -338.097898) (xy 340.967928 -338.144411) (xy 340.930711 -338.185948) (xy 340.887843 -338.221623)
			(xy 340.840237 -338.250677) (xy 340.788908 -338.272489) (xy 340.734951 -338.286595) (xy 340.679514 -338.292695)
			(xy 340.62378 -338.290658) (xy 340.568937 -338.280528) (xy 340.516153 -338.262521) (xy 340.466553 -338.23702)
			(xy 340.421195 -338.204569) (xy 340.381046 -338.16586) (xy 340.34696 -338.121717) (xy 340.319664 -338.073082)
			(xy 340.299741 -338.020991) (xy 340.287615 -337.966554) (xy 340.283544 -337.910932) (xy 339.127342 -337.910932)
			(xy 339.1273 -337.911073) (xy 339.10414 -337.961117) (xy 339.074015 -338.007305) (xy 339.037553 -338.048674)
			(xy 339.016848 -338.066888) (xy 339.008731 -338.074492) (xy 338.999378 -338.094643) (xy 338.998814 -338.10575)
			(xy 338.998814 -338.182966) (xy 338.999381 -338.194076) (xy 339.00872 -338.214235) (xy 339.016848 -338.221828)
			(xy 339.037586 -338.24001) (xy 339.074052 -338.281386) (xy 339.104179 -338.327583) (xy 339.12734 -338.377636)
			(xy 339.143051 -338.430503) (xy 339.150985 -338.485082) (xy 339.151468 -338.512658) (xy 339.151006 -338.539912)
			(xy 339.143253 -338.593865) (xy 339.1279 -338.646165) (xy 339.10526 -338.695748) (xy 339.075793 -338.741603)
			(xy 339.040099 -338.782797) (xy 339.012995 -338.806282) (xy 339.704424 -338.806282) (xy 339.708495 -338.75066)
			(xy 339.720621 -338.696223) (xy 339.740544 -338.644132) (xy 339.76784 -338.595497) (xy 339.801926 -338.551354)
			(xy 339.842075 -338.512645) (xy 339.887433 -338.480194) (xy 339.937033 -338.454693) (xy 339.989817 -338.436686)
			(xy 340.04466 -338.426556) (xy 340.100394 -338.424519) (xy 340.155831 -338.430619) (xy 340.209788 -338.444725)
			(xy 340.261117 -338.466537) (xy 340.308723 -338.495591) (xy 340.351591 -338.531266) (xy 340.388808 -338.572803)
			(xy 340.419581 -338.619316) (xy 340.443253 -338.669813) (xy 340.459321 -338.72322) (xy 340.467441 -338.778396)
			(xy 340.46795 -338.806282) (xy 340.467441 -338.834168) (xy 340.459321 -338.889344) (xy 340.443253 -338.942751)
			(xy 340.419581 -338.993248) (xy 340.388808 -339.039761) (xy 340.351591 -339.081298) (xy 340.308723 -339.116973)
			(xy 340.261117 -339.146027) (xy 340.209788 -339.167839) (xy 340.155831 -339.181945) (xy 340.100394 -339.188045)
			(xy 340.04466 -339.186008) (xy 339.989817 -339.175878) (xy 339.937033 -339.157871) (xy 339.887433 -339.13237)
			(xy 339.842075 -339.099919) (xy 339.801926 -339.06121) (xy 339.76784 -339.017067) (xy 339.740544 -338.968432)
			(xy 339.720621 -338.916341) (xy 339.708495 -338.861904) (xy 339.704424 -338.806282) (xy 339.012995 -338.806282)
			(xy 338.998905 -338.818491) (xy 338.953049 -338.847959) (xy 338.903467 -338.8706) (xy 338.851167 -338.885953)
			(xy 338.797214 -338.893705) (xy 338.76996 -338.894166) (xy 338.742102 -338.893704) (xy 338.686983 -338.885574)
			(xy 338.63363 -338.869521) (xy 338.583175 -338.845887) (xy 338.53669 -338.815173) (xy 338.495161 -338.77803)
			(xy 338.45947 -338.735247) (xy 338.430373 -338.687732) (xy 338.40849 -338.636494) (xy 338.400898 -338.609686)
			(xy 338.398612 -338.600796) (xy 338.387944 -338.585556) (xy 338.316062 -338.537804) (xy 338.298028 -338.53374)
			(xy 338.288884 -338.53501) (xy 338.275867 -338.536679) (xy 338.249683 -338.538459) (xy 338.23656 -338.538566)
			(xy 338.222411 -338.538477) (xy 338.194188 -338.53644) (xy 338.180172 -338.534502) (xy 338.170012 -338.532978)
			(xy 338.150454 -338.537804) (xy 338.076032 -338.593684) (xy 338.065872 -338.61121) (xy 338.064602 -338.62137)
			(xy 338.060548 -338.648529) (xy 338.045571 -338.701361) (xy 338.023175 -338.7515) (xy 337.993824 -338.797911)
			(xy 337.958122 -338.839635) (xy 337.916809 -338.875811) (xy 337.870736 -338.905691) (xy 337.820856 -338.928658)
			(xy 337.768199 -338.944238) (xy 337.713853 -338.952109) (xy 337.686396 -338.952586) (xy 337.659142 -338.952148)
			(xy 337.605189 -338.94439) (xy 337.552889 -338.929033) (xy 337.503308 -338.906388) (xy 337.457454 -338.876918)
			(xy 337.41626 -338.841221) (xy 337.380567 -338.800026) (xy 337.3511 -338.754169) (xy 337.328458 -338.704586)
			(xy 337.313104 -338.652285) (xy 337.30535 -338.598332) (xy 337.304888 -338.571078) (xy 335.164005 -338.571078)
			(xy 335.166633 -338.580034) (xy 335.174384 -338.633992) (xy 335.174844 -338.661248) (xy 335.174195 -338.692811)
			(xy 335.163804 -338.755077) (xy 335.143314 -338.814786) (xy 335.12887 -338.842858) (xy 335.124044 -338.851748)
			(xy 335.122012 -338.871306) (xy 335.147666 -338.959444) (xy 335.160112 -338.974938) (xy 335.169002 -338.980018)
			(xy 335.194096 -338.994578) (xy 335.239978 -339.03008) (xy 335.279953 -339.072122) (xy 335.313099 -339.119734)
			(xy 335.338651 -339.171817) (xy 335.356019 -339.227169) (xy 335.364803 -339.284513) (xy 335.365344 -339.31352)
			(xy 335.364858 -339.340771) (xy 335.357102 -339.394719) (xy 335.341747 -339.447014) (xy 335.325804 -339.481922)
			(xy 341.04326 -339.481922) (xy 341.043769 -339.454448) (xy 341.051657 -339.40007) (xy 341.067272 -339.347388)
			(xy 341.090292 -339.297495) (xy 341.120237 -339.251425) (xy 341.138002 -339.230462) (xy 341.144098 -339.22335)
			(xy 341.150448 -339.206332) (xy 341.150448 -339.12048) (xy 341.144098 -339.103462) (xy 341.138002 -339.09635)
			(xy 341.120234 -339.075391) (xy 341.09031 -339.029309) (xy 341.067298 -338.979413) (xy 341.051673 -338.926736)
			(xy 341.043758 -338.872363) (xy 341.04326 -338.84489) (xy 341.043746 -338.817639) (xy 341.051502 -338.763691)
			(xy 341.066857 -338.711396) (xy 341.089499 -338.661819) (xy 341.118965 -338.615969) (xy 341.154656 -338.574778)
			(xy 341.195847 -338.539087) (xy 341.241697 -338.509621) (xy 341.291274 -338.486979) (xy 341.343569 -338.471624)
			(xy 341.397517 -338.463868) (xy 341.452019 -338.463868) (xy 341.505967 -338.471624) (xy 341.558262 -338.486979)
			(xy 341.607839 -338.509621) (xy 341.653689 -338.539087) (xy 341.69488 -338.574778) (xy 341.730571 -338.615969)
			(xy 341.760037 -338.661819) (xy 341.782679 -338.711396) (xy 341.798034 -338.763691) (xy 341.80579 -338.817639)
			(xy 341.806276 -338.84489) (xy 341.80579 -338.872365) (xy 341.797899 -338.926745) (xy 341.782279 -338.979427)
			(xy 341.779638 -338.985149) (xy 342.048098 -338.985149) (xy 342.048098 -338.930651) (xy 342.055854 -338.876708)
			(xy 342.071207 -338.824417) (xy 342.093846 -338.774843) (xy 342.123309 -338.728996) (xy 342.158997 -338.687809)
			(xy 342.200183 -338.652119) (xy 342.246029 -338.622654) (xy 342.295602 -338.600013) (xy 342.347892 -338.584657)
			(xy 342.401835 -338.576899) (xy 342.429084 -338.576412) (xy 342.454321 -338.57677) (xy 342.504356 -338.5834)
			(xy 342.553076 -338.596584) (xy 342.599627 -338.616092) (xy 342.621616 -338.628482) (xy 342.631268 -338.634324)
			(xy 342.653366 -338.636356) (xy 342.747854 -338.602828) (xy 342.763856 -338.587334) (xy 342.76792 -338.57692)
			(xy 342.778594 -338.550134) (xy 342.806882 -338.499889) (xy 342.842414 -338.454478) (xy 342.884379 -338.414935)
			(xy 342.93182 -338.382161) (xy 342.983655 -338.356906) (xy 343.038702 -338.339744) (xy 343.095706 -338.331066)
			(xy 343.124536 -338.33054) (xy 343.151792 -338.330922) (xy 343.205748 -338.338685) (xy 343.258051 -338.354048)
			(xy 343.307634 -338.376698) (xy 343.35349 -338.406174) (xy 343.394683 -338.441876) (xy 343.430376 -338.483078)
			(xy 343.459842 -338.52894) (xy 343.482482 -338.578528) (xy 343.497833 -338.630834) (xy 343.505584 -338.684792)
			(xy 343.506044 -338.712048) (xy 343.505395 -338.743611) (xy 343.495004 -338.805877) (xy 343.474514 -338.865586)
			(xy 343.46007 -338.893658) (xy 343.455244 -338.902548) (xy 343.453212 -338.922106) (xy 343.478866 -339.010244)
			(xy 343.491312 -339.025738) (xy 343.500202 -339.030818) (xy 343.525296 -339.045378) (xy 343.571178 -339.08088)
			(xy 343.611153 -339.122922) (xy 343.644299 -339.170534) (xy 343.669851 -339.222617) (xy 343.687219 -339.277969)
			(xy 343.696003 -339.335313) (xy 343.696435 -339.358478) (xy 345.636088 -339.358478) (xy 345.636612 -339.330906)
			(xy 345.644553 -339.276335) (xy 345.660267 -339.223477) (xy 345.683426 -339.173431) (xy 345.713548 -339.12724)
			(xy 345.750006 -339.085866) (xy 345.770708 -339.067648) (xy 345.778802 -339.060023) (xy 345.788169 -339.039889)
			(xy 345.788742 -339.028786) (xy 345.788742 -338.95157) (xy 345.788225 -338.940453) (xy 345.778852 -338.920294)
			(xy 345.770708 -338.912708) (xy 345.74998 -338.894516) (xy 345.713516 -338.853142) (xy 345.683389 -338.806949)
			(xy 345.660227 -338.756899) (xy 345.644513 -338.704036) (xy 345.636575 -338.649461) (xy 345.636577 -338.594311)
			(xy 345.644519 -338.539737) (xy 345.660237 -338.486874) (xy 345.683403 -338.436826) (xy 345.713533 -338.390635)
			(xy 345.750001 -338.349264) (xy 345.770708 -338.331048) (xy 345.778802 -338.323423) (xy 345.788169 -338.303289)
			(xy 345.788742 -338.292186) (xy 345.788742 -338.21497) (xy 345.788225 -338.203853) (xy 345.778852 -338.183694)
			(xy 345.770708 -338.176108) (xy 345.749999 -338.157894) (xy 345.713528 -338.116526) (xy 345.683396 -338.070337)
			(xy 345.660229 -338.020289) (xy 345.644513 -337.967427) (xy 345.636573 -337.912853) (xy 345.636088 -337.885278)
			(xy 345.636557 -337.858026) (xy 345.644317 -337.804078) (xy 345.659674 -337.751783) (xy 345.682318 -337.702206)
			(xy 345.711786 -337.656356) (xy 345.747479 -337.615166) (xy 345.788671 -337.579475) (xy 345.834522 -337.550009)
			(xy 345.8841 -337.527368) (xy 345.936396 -337.512013) (xy 345.990344 -337.504256) (xy 346.017596 -337.50377)
			(xy 346.051886 -337.505294) (xy 346.062046 -337.50631) (xy 346.08135 -337.500214) (xy 346.151962 -337.441032)
			(xy 346.16136 -337.422998) (xy 346.162376 -337.412838) (xy 346.165325 -337.384665) (xy 346.1785 -337.329573)
			(xy 346.19968 -337.277036) (xy 346.228398 -337.228211) (xy 346.264023 -337.18417) (xy 346.305771 -337.145884)
			(xy 346.352722 -337.114194) (xy 346.403845 -337.089798) (xy 346.458014 -337.073233) (xy 346.514037 -337.064863)
			(xy 346.54236 -337.06435) (xy 346.569608 -337.064915) (xy 346.623551 -337.072665) (xy 346.675842 -337.088013)
			(xy 346.725416 -337.110647) (xy 346.771264 -337.140105) (xy 346.812454 -337.175788) (xy 346.848146 -337.21697)
			(xy 346.877614 -337.262812) (xy 346.900258 -337.312381) (xy 346.915617 -337.364669) (xy 346.923379 -337.41861)
			(xy 346.923868 -337.445858) (xy 346.923337 -337.473719) (xy 346.915242 -337.528849) (xy 346.899218 -337.582216)
			(xy 346.875606 -337.632687) (xy 346.844907 -337.679189) (xy 346.807773 -337.720733) (xy 346.786708 -337.738974)
			(xy 346.777564 -337.746594) (xy 346.767912 -337.767676) (xy 346.771468 -337.871562) (xy 346.78239 -337.892136)
			(xy 346.792042 -337.899248) (xy 346.8126 -337.914661) (xy 346.849734 -337.950174) (xy 346.881765 -337.990351)
			(xy 346.908113 -338.034465) (xy 346.9283 -338.081715) (xy 346.941963 -338.131248) (xy 346.948852 -338.182167)
			(xy 346.949268 -338.207858) (xy 346.948732 -338.236774) (xy 346.940008 -338.293945) (xy 346.922755 -338.349144)
			(xy 346.897366 -338.401106) (xy 346.864425 -338.448641) (xy 346.824687 -338.490658) (xy 346.802202 -338.508848)
			(xy 346.793423 -338.516394) (xy 346.783249 -338.537165) (xy 346.782644 -338.548726) (xy 346.782644 -338.62899)
			(xy 346.783205 -338.64056) (xy 346.793405 -338.661331) (xy 346.802202 -338.668868) (xy 346.822945 -338.68567)
			(xy 346.860078 -338.724016) (xy 346.891503 -338.767164) (xy 346.916606 -338.814272) (xy 346.934896 -338.864419)
			(xy 346.946016 -338.916626) (xy 346.94975 -338.969874) (xy 346.946024 -339.023123) (xy 346.93491 -339.075332)
			(xy 346.916627 -339.125481) (xy 346.891531 -339.172592) (xy 346.860112 -339.215745) (xy 346.822984 -339.254096)
			(xy 346.802202 -339.270848) (xy 346.793423 -339.278394) (xy 346.783249 -339.299165) (xy 346.782644 -339.310726)
			(xy 346.782644 -339.39099) (xy 346.783205 -339.40256) (xy 346.793405 -339.423331) (xy 346.802202 -339.430868)
			(xy 346.824671 -339.449077) (xy 346.864407 -339.491093) (xy 346.897347 -339.538624) (xy 346.922738 -339.590582)
			(xy 346.939998 -339.645776) (xy 346.948731 -339.702943) (xy 346.949268 -339.731858) (xy 346.948806 -339.759112)
			(xy 346.941053 -339.813065) (xy 346.9257 -339.865365) (xy 346.90306 -339.914948) (xy 346.873593 -339.960803)
			(xy 346.837899 -340.001997) (xy 346.796705 -340.037691) (xy 346.750849 -340.067159) (xy 346.701267 -340.0898)
			(xy 346.648967 -340.105153) (xy 346.595014 -340.112905) (xy 346.56776 -340.113366) (xy 346.539022 -340.112852)
			(xy 346.482198 -340.104211) (xy 346.427313 -340.087145) (xy 346.375608 -340.06204) (xy 346.328253 -340.029464)
			(xy 346.28632 -339.990155) (xy 346.250757 -339.945001) (xy 346.222368 -339.895024) (xy 346.201796 -339.841355)
			(xy 346.195142 -339.813392) (xy 346.192856 -339.80374) (xy 346.182188 -339.787738) (xy 346.10802 -339.737446)
			(xy 346.089224 -339.733382) (xy 346.079318 -339.734906) (xy 346.063998 -339.737279) (xy 346.033098 -339.739824)
			(xy 346.017596 -339.739986) (xy 345.990342 -339.739548) (xy 345.936389 -339.73179) (xy 345.884089 -339.716433)
			(xy 345.834508 -339.693788) (xy 345.788654 -339.664318) (xy 345.74746 -339.628621) (xy 345.711767 -339.587426)
			(xy 345.6823 -339.541569) (xy 345.659658 -339.491986) (xy 345.644304 -339.439685) (xy 345.63655 -339.385732)
			(xy 345.636088 -339.358478) (xy 343.696435 -339.358478) (xy 343.696544 -339.36432) (xy 343.696058 -339.391571)
			(xy 343.688302 -339.445519) (xy 343.672947 -339.497814) (xy 343.650305 -339.547391) (xy 343.620839 -339.593241)
			(xy 343.585148 -339.634432) (xy 343.543957 -339.670123) (xy 343.498107 -339.699589) (xy 343.44853 -339.722231)
			(xy 343.396235 -339.737586) (xy 343.342287 -339.745342) (xy 343.287785 -339.745342) (xy 343.233837 -339.737586)
			(xy 343.181542 -339.722231) (xy 343.131965 -339.699589) (xy 343.086115 -339.670123) (xy 343.044924 -339.634432)
			(xy 343.009233 -339.593241) (xy 342.979767 -339.547391) (xy 342.957125 -339.497814) (xy 342.94177 -339.445519)
			(xy 342.934014 -339.391571) (xy 342.933528 -339.36432) (xy 342.934168 -339.332756) (xy 342.944563 -339.27049)
			(xy 342.965057 -339.210782) (xy 342.979502 -339.18271) (xy 342.984328 -339.17382) (xy 342.98636 -339.154262)
			(xy 342.960706 -339.066124) (xy 342.94826 -339.05063) (xy 342.93937 -339.04555) (xy 342.932004 -339.041486)
			(xy 342.922352 -339.035644) (xy 342.900254 -339.033612) (xy 342.805766 -339.06714) (xy 342.789764 -339.082634)
			(xy 342.7857 -339.093048) (xy 342.775046 -339.119842) (xy 342.746751 -339.170084) (xy 342.711214 -339.215492)
			(xy 342.669246 -339.255033) (xy 342.621803 -339.287804) (xy 342.569967 -339.313059) (xy 342.514919 -339.330221)
			(xy 342.457915 -339.3389) (xy 342.429084 -339.339428) (xy 342.401835 -339.338901) (xy 342.347892 -339.331143)
			(xy 342.295602 -339.315787) (xy 342.246029 -339.293146) (xy 342.200183 -339.263681) (xy 342.158997 -339.227991)
			(xy 342.123309 -339.186804) (xy 342.093846 -339.140957) (xy 342.071207 -339.091383) (xy 342.055854 -339.039092)
			(xy 342.048098 -338.985149) (xy 341.779638 -338.985149) (xy 341.759254 -339.02932) (xy 341.729302 -339.075388)
			(xy 341.711534 -339.09635) (xy 341.705438 -339.103462) (xy 341.699088 -339.12048) (xy 341.699088 -339.206332)
			(xy 341.705438 -339.22335) (xy 341.711534 -339.230462) (xy 341.729266 -339.25145) (xy 341.759195 -339.297525)
			(xy 341.782213 -339.347413) (xy 341.797846 -339.400084) (xy 341.805772 -339.454451) (xy 341.806276 -339.481922)
			(xy 341.80579 -339.509173) (xy 341.798034 -339.563121) (xy 341.782679 -339.615416) (xy 341.760037 -339.664993)
			(xy 341.730571 -339.710843) (xy 341.69488 -339.752034) (xy 341.653689 -339.787725) (xy 341.607839 -339.817191)
			(xy 341.558262 -339.839833) (xy 341.505967 -339.855188) (xy 341.452019 -339.862944) (xy 341.397517 -339.862944)
			(xy 341.343569 -339.855188) (xy 341.291274 -339.839833) (xy 341.241697 -339.817191) (xy 341.195847 -339.787725)
			(xy 341.154656 -339.752034) (xy 341.118965 -339.710843) (xy 341.089499 -339.664993) (xy 341.066857 -339.615416)
			(xy 341.051502 -339.563121) (xy 341.043746 -339.509173) (xy 341.04326 -339.481922) (xy 335.325804 -339.481922)
			(xy 335.319105 -339.496591) (xy 335.289639 -339.542441) (xy 335.253948 -339.583632) (xy 335.212757 -339.619323)
			(xy 335.166907 -339.648789) (xy 335.11733 -339.671431) (xy 335.065035 -339.686786) (xy 335.011087 -339.694542)
			(xy 334.956585 -339.694542) (xy 334.902637 -339.686786) (xy 334.850342 -339.671431) (xy 334.800765 -339.648789)
			(xy 334.754915 -339.619323) (xy 334.713724 -339.583632) (xy 334.678033 -339.542441) (xy 334.648567 -339.496591)
			(xy 334.625925 -339.447014) (xy 334.61057 -339.394719) (xy 334.602814 -339.340771) (xy 334.602328 -339.31352)
			(xy 334.602968 -339.281956) (xy 334.613363 -339.21969) (xy 334.633857 -339.159982) (xy 334.648302 -339.13191)
			(xy 334.653128 -339.12302) (xy 334.65516 -339.103462) (xy 334.629506 -339.015324) (xy 334.61706 -338.99983)
			(xy 334.60817 -338.99475) (xy 334.600804 -338.990686) (xy 334.591152 -338.984844) (xy 334.569054 -338.982812)
			(xy 334.474566 -339.01634) (xy 334.458564 -339.031834) (xy 334.4545 -339.042248) (xy 334.443846 -339.069042)
			(xy 334.415551 -339.119284) (xy 334.380014 -339.164692) (xy 334.338046 -339.204233) (xy 334.290603 -339.237004)
			(xy 334.238767 -339.262259) (xy 334.183719 -339.279421) (xy 334.126715 -339.2881) (xy 334.097884 -339.288628)
			(xy 334.070635 -339.288101) (xy 334.016692 -339.280343) (xy 333.964402 -339.264987) (xy 333.914829 -339.242346)
			(xy 333.868983 -339.212881) (xy 333.827797 -339.177191) (xy 333.792109 -339.136004) (xy 333.762646 -339.090157)
			(xy 333.740007 -339.040583) (xy 333.724654 -338.988292) (xy 333.716898 -338.934349) (xy 333.448513 -338.934349)
			(xy 333.428206 -338.978491) (xy 333.398339 -339.024589) (xy 333.380588 -339.04555) (xy 333.374238 -339.052662)
			(xy 333.367888 -339.06968) (xy 333.367888 -339.155532) (xy 333.374238 -339.17255) (xy 333.380588 -339.179662)
			(xy 333.398319 -339.20064) (xy 333.4282 -339.246728) (xy 333.451163 -339.296624) (xy 333.466736 -339.349297)
			(xy 333.474594 -339.403658) (xy 333.475076 -339.431122) (xy 333.474521 -339.461141) (xy 333.465127 -339.520438)
			(xy 333.446558 -339.577532) (xy 333.419272 -339.63101) (xy 333.383945 -339.679553) (xy 333.363062 -339.701124)
			(xy 333.355696 -339.70849) (xy 333.348076 -339.727032) (xy 333.348076 -340.47811) (xy 333.347443 -340.503108)
			(xy 333.33765 -340.552137) (xy 333.318483 -340.598313) (xy 333.290676 -340.639865) (xy 333.2734 -340.657942)
			(xy 332.035658 -341.895684) (xy 332.017563 -341.912942) (xy 331.976018 -341.940755) (xy 331.929847 -341.959935)
			(xy 331.880823 -341.969745) (xy 331.855826 -341.97036) (xy 327.610724 -341.97036) (xy 327.600661 -341.970799)
			(xy 327.582083 -341.978539) (xy 327.574656 -341.985346) (xy 326.738996 -342.821006) (xy 348.559372 -342.821006)
			(xy 348.563443 -342.765384) (xy 348.575569 -342.710947) (xy 348.595492 -342.658856) (xy 348.622788 -342.610221)
			(xy 348.656874 -342.566078) (xy 348.697023 -342.527369) (xy 348.742381 -342.494918) (xy 348.791981 -342.469417)
			(xy 348.844765 -342.45141) (xy 348.899608 -342.44128) (xy 348.955342 -342.439243) (xy 349.010779 -342.445343)
			(xy 349.064736 -342.459449) (xy 349.116065 -342.481261) (xy 349.163671 -342.510315) (xy 349.206539 -342.54599)
			(xy 349.243756 -342.587527) (xy 349.274529 -342.63404) (xy 349.298201 -342.684537) (xy 349.314269 -342.737944)
			(xy 349.322389 -342.79312) (xy 349.322898 -342.821006) (xy 349.322389 -342.848892) (xy 349.314269 -342.904068)
			(xy 349.298201 -342.957475) (xy 349.274529 -343.007972) (xy 349.243756 -343.054485) (xy 349.206539 -343.096022)
			(xy 349.163671 -343.131697) (xy 349.116065 -343.160751) (xy 349.064736 -343.182563) (xy 349.010779 -343.196669)
			(xy 348.955342 -343.202769) (xy 348.899608 -343.200732) (xy 348.844765 -343.190602) (xy 348.791981 -343.172595)
			(xy 348.742381 -343.147094) (xy 348.697023 -343.114643) (xy 348.656874 -343.075934) (xy 348.622788 -343.031791)
			(xy 348.595492 -342.983156) (xy 348.575569 -342.931065) (xy 348.563443 -342.876628) (xy 348.559372 -342.821006)
			(xy 326.738996 -342.821006) (xy 325.843646 -343.716356) (xy 347.980252 -343.716356) (xy 347.984323 -343.660734)
			(xy 347.996449 -343.606297) (xy 348.016372 -343.554206) (xy 348.043668 -343.505571) (xy 348.077754 -343.461428)
			(xy 348.117903 -343.422719) (xy 348.163261 -343.390268) (xy 348.212861 -343.364767) (xy 348.265645 -343.34676)
			(xy 348.320488 -343.33663) (xy 348.376222 -343.334593) (xy 348.431659 -343.340693) (xy 348.485616 -343.354799)
			(xy 348.536945 -343.376611) (xy 348.584551 -343.405665) (xy 348.627419 -343.44134) (xy 348.664636 -343.482877)
			(xy 348.695409 -343.52939) (xy 348.719081 -343.579887) (xy 348.735149 -343.633294) (xy 348.743269 -343.68847)
			(xy 348.743778 -343.716356) (xy 348.743269 -343.744242) (xy 348.735149 -343.799418) (xy 348.719081 -343.852825)
			(xy 348.695409 -343.903322) (xy 348.664636 -343.949835) (xy 348.627419 -343.991372) (xy 348.584551 -344.027047)
			(xy 348.536945 -344.056101) (xy 348.485616 -344.077913) (xy 348.431659 -344.092019) (xy 348.376222 -344.098119)
			(xy 348.320488 -344.096082) (xy 348.265645 -344.085952) (xy 348.212861 -344.067945) (xy 348.163261 -344.042444)
			(xy 348.117903 -344.009993) (xy 348.077754 -343.971284) (xy 348.043668 -343.927141) (xy 348.016372 -343.878506)
			(xy 347.996449 -343.826415) (xy 347.984323 -343.771978) (xy 347.980252 -343.716356) (xy 325.843646 -343.716356)
			(xy 325.168006 -344.391996) (xy 349.319088 -344.391996) (xy 349.319575 -344.364521) (xy 349.327467 -344.310142)
			(xy 349.343087 -344.25746) (xy 349.366112 -344.207567) (xy 349.396063 -344.161498) (xy 349.41383 -344.140536)
			(xy 349.419926 -344.133424) (xy 349.426276 -344.116406) (xy 349.426276 -344.030554) (xy 349.419926 -344.013536)
			(xy 349.41383 -344.006424) (xy 349.396085 -343.985446) (xy 349.36616 -343.939368) (xy 349.343145 -343.889477)
			(xy 349.327514 -343.836804) (xy 349.319591 -343.782435) (xy 349.319088 -343.754964) (xy 349.319574 -343.727713)
			(xy 349.32733 -343.673765) (xy 349.342685 -343.62147) (xy 349.365327 -343.571893) (xy 349.394793 -343.526043)
			(xy 349.430484 -343.484852) (xy 349.471675 -343.449161) (xy 349.517525 -343.419695) (xy 349.567102 -343.397053)
			(xy 349.619397 -343.381698) (xy 349.673345 -343.373942) (xy 349.727847 -343.373942) (xy 349.781795 -343.381698)
			(xy 349.83409 -343.397053) (xy 349.883667 -343.419695) (xy 349.929517 -343.449161) (xy 349.970708 -343.484852)
			(xy 350.006399 -343.526043) (xy 350.035865 -343.571893) (xy 350.058507 -343.62147) (xy 350.073862 -343.673765)
			(xy 350.081618 -343.727713) (xy 350.082104 -343.754964) (xy 350.081596 -343.782438) (xy 350.073709 -343.836816)
			(xy 350.058094 -343.889498) (xy 350.055438 -343.895254) (xy 350.323849 -343.895254) (xy 350.323849 -343.840746)
			(xy 350.331607 -343.786793) (xy 350.346964 -343.734494) (xy 350.369607 -343.684912) (xy 350.399077 -343.639058)
			(xy 350.434772 -343.597864) (xy 350.475967 -343.56217) (xy 350.521823 -343.532702) (xy 350.571405 -343.510059)
			(xy 350.623705 -343.494704) (xy 350.677658 -343.486949) (xy 350.704912 -343.486486) (xy 350.730147 -343.48688)
			(xy 350.780181 -343.493499) (xy 350.828902 -343.506673) (xy 350.875454 -343.526171) (xy 350.897444 -343.538556)
			(xy 350.907096 -343.544398) (xy 350.929194 -343.54643) (xy 351.023682 -343.512902) (xy 351.039684 -343.497408)
			(xy 351.043748 -343.486994) (xy 351.054468 -343.460228) (xy 351.082752 -343.409987) (xy 351.118279 -343.364577)
			(xy 351.160237 -343.325035) (xy 351.207671 -343.29226) (xy 351.259499 -343.267) (xy 351.314539 -343.249831)
			(xy 351.371536 -343.241145) (xy 351.400364 -343.240614) (xy 351.427617 -343.241089) (xy 351.481569 -343.248842)
			(xy 351.533868 -343.264194) (xy 351.583449 -343.286834) (xy 351.629303 -343.3163) (xy 351.670497 -343.351993)
			(xy 351.706191 -343.393185) (xy 351.735659 -343.439039) (xy 351.758301 -343.488619) (xy 351.771024 -343.531952)
			(xy 353.911916 -343.531952) (xy 353.912412 -343.504378) (xy 353.920357 -343.449807) (xy 353.936076 -343.396947)
			(xy 353.95924 -343.346901) (xy 353.989368 -343.300711) (xy 354.025831 -343.259338) (xy 354.046536 -343.241122)
			(xy 354.054646 -343.233512) (xy 354.064004 -343.213366) (xy 354.06457 -343.20226) (xy 354.06457 -343.125044)
			(xy 354.064003 -343.113934) (xy 354.054665 -343.093775) (xy 354.046536 -343.086182) (xy 354.02582 -343.067976)
			(xy 353.989349 -343.026607) (xy 353.959216 -342.980416) (xy 353.936051 -342.930367) (xy 353.920336 -342.877503)
			(xy 353.912399 -342.822927) (xy 353.911916 -342.795352) (xy 353.912333 -342.768098) (xy 353.920097 -342.714147)
			(xy 353.935459 -342.66185) (xy 353.958108 -342.612271) (xy 353.987581 -342.566419) (xy 354.02328 -342.525229)
			(xy 354.064477 -342.489538) (xy 354.110334 -342.460073) (xy 354.159917 -342.437434) (xy 354.212217 -342.422082)
			(xy 354.26617 -342.414328) (xy 354.293424 -342.413844) (xy 354.327714 -342.415368) (xy 354.337874 -342.416384)
			(xy 354.357178 -342.410288) (xy 354.42779 -342.351106) (xy 354.437188 -342.333072) (xy 354.438204 -342.322912)
			(xy 354.441103 -342.294733) (xy 354.454284 -342.239638) (xy 354.475469 -342.1871) (xy 354.504193 -342.138273)
			(xy 354.539824 -342.094232) (xy 354.581577 -342.055946) (xy 354.628534 -342.024258) (xy 354.679662 -341.999864)
			(xy 354.733836 -341.983302) (xy 354.789863 -341.974935) (xy 354.818188 -341.974424) (xy 354.836208 -341.974638)
			(xy 354.872082 -341.978077) (xy 354.889816 -341.981282) (xy 354.899214 -341.98306) (xy 354.918264 -341.97925)
			(xy 354.993448 -341.931498) (xy 355.004878 -341.91575) (xy 355.007164 -341.906352) (xy 355.014516 -341.879294)
			(xy 355.03615 -341.827565) (xy 355.065119 -341.779558) (xy 355.1008 -341.736305) (xy 355.142425 -341.698739)
			(xy 355.189099 -341.667666) (xy 355.239816 -341.643757) (xy 355.293486 -341.627525) (xy 355.348953 -341.619319)
			(xy 355.376988 -341.618824) (xy 355.404242 -341.619267) (xy 355.458195 -341.627023) (xy 355.510496 -341.642379)
			(xy 355.560078 -341.665022) (xy 355.605932 -341.694492) (xy 355.647126 -341.730188) (xy 355.68282 -341.771384)
			(xy 355.712287 -341.81724) (xy 355.734928 -341.866823) (xy 355.750282 -341.919124) (xy 355.758035 -341.973078)
			(xy 355.758496 -342.000332) (xy 355.757985 -342.027905) (xy 355.750042 -342.082476) (xy 355.734326 -342.135335)
			(xy 355.711164 -342.185381) (xy 355.68104 -342.231572) (xy 355.64458 -342.272945) (xy 355.623876 -342.291162)
			(xy 355.615776 -342.298781) (xy 355.606412 -342.31892) (xy 355.605842 -342.330024) (xy 355.605842 -342.40724)
			(xy 355.606358 -342.418356) (xy 355.615732 -342.438515) (xy 355.623876 -342.446102) (xy 355.644614 -342.464282)
			(xy 355.68108 -342.505657) (xy 355.711208 -342.551852) (xy 355.734371 -342.601903) (xy 355.750085 -342.654768)
			(xy 355.758023 -342.709345) (xy 355.75802 -342.764496) (xy 355.750076 -342.819072) (xy 355.734356 -342.871935)
			(xy 355.711188 -342.921984) (xy 355.681055 -342.968176) (xy 355.644585 -343.009547) (xy 355.623876 -343.027762)
			(xy 355.615776 -343.035381) (xy 355.606412 -343.05552) (xy 355.605842 -343.066624) (xy 355.605842 -343.14384)
			(xy 355.606358 -343.154956) (xy 355.615732 -343.175115) (xy 355.623876 -343.182702) (xy 355.644587 -343.200914)
			(xy 355.681058 -343.242282) (xy 355.711191 -343.288471) (xy 355.734357 -343.338519) (xy 355.750073 -343.391382)
			(xy 355.758012 -343.445957) (xy 355.758496 -343.473532) (xy 355.758052 -343.500785) (xy 355.750291 -343.554734)
			(xy 355.734931 -343.607031) (xy 355.712285 -343.656609) (xy 355.682814 -343.70246) (xy 355.647119 -343.74365)
			(xy 355.605924 -343.779341) (xy 355.56007 -343.808806) (xy 355.510489 -343.831446) (xy 355.458191 -343.8468)
			(xy 355.404241 -343.854555) (xy 355.376988 -343.85504) (xy 355.349134 -343.854498) (xy 355.29402 -343.846374)
			(xy 355.240672 -343.830329) (xy 355.190221 -343.806703) (xy 355.143738 -343.775999) (xy 355.102208 -343.738867)
			(xy 355.066514 -343.696095) (xy 355.037413 -343.648591) (xy 355.015522 -343.597363) (xy 355.007926 -343.57056)
			(xy 355.00564 -343.56167) (xy 354.994972 -343.54643) (xy 354.92309 -343.498678) (xy 354.905056 -343.494614)
			(xy 354.895912 -343.495884) (xy 354.882895 -343.49755) (xy 354.856711 -343.499332) (xy 354.843588 -343.49944)
			(xy 354.829439 -343.499347) (xy 354.801216 -343.497312) (xy 354.7872 -343.495376) (xy 354.77704 -343.493852)
			(xy 354.757482 -343.498678) (xy 354.68306 -343.554558) (xy 354.6729 -343.572084) (xy 354.67163 -343.582244)
			(xy 354.667529 -343.609395) (xy 354.652557 -343.662224) (xy 354.630166 -343.712362) (xy 354.60082 -343.758772)
			(xy 354.565124 -343.800496) (xy 354.523816 -343.836673) (xy 354.477749 -343.866554) (xy 354.427874 -343.889524)
			(xy 354.375221 -343.905107) (xy 354.320879 -343.912981) (xy 354.293424 -343.91346) (xy 354.26617 -343.913022)
			(xy 354.212215 -343.905267) (xy 354.159914 -343.889912) (xy 354.110331 -343.867269) (xy 354.064475 -343.837799)
			(xy 354.023281 -343.802102) (xy 353.987587 -343.760906) (xy 353.95812 -343.715048) (xy 353.93548 -343.665464)
			(xy 353.920128 -343.613161) (xy 353.912376 -343.559206) (xy 353.911916 -343.531952) (xy 351.771024 -343.531952)
			(xy 351.773656 -343.540918) (xy 351.78141 -343.594869) (xy 351.781872 -343.622122) (xy 351.781209 -343.653685)
			(xy 351.770824 -343.71595) (xy 351.750339 -343.775659) (xy 351.735898 -343.803732) (xy 351.731072 -343.812622)
			(xy 351.72904 -343.83218) (xy 351.754694 -343.920318) (xy 351.76714 -343.935812) (xy 351.77603 -343.940892)
			(xy 351.801163 -343.955389) (xy 351.847044 -343.990902) (xy 351.887016 -344.032955) (xy 351.920157 -344.080578)
			(xy 351.945703 -344.132671) (xy 351.963063 -344.188032) (xy 351.971837 -344.245384) (xy 351.972372 -344.274394)
			(xy 351.971886 -344.301645) (xy 351.96413 -344.355593) (xy 351.948775 -344.407888) (xy 351.926133 -344.457465)
			(xy 351.896667 -344.503315) (xy 351.860976 -344.544506) (xy 351.819785 -344.580197) (xy 351.773935 -344.609663)
			(xy 351.724358 -344.632305) (xy 351.672063 -344.64766) (xy 351.618115 -344.655416) (xy 351.563613 -344.655416)
			(xy 351.509665 -344.64766) (xy 351.45737 -344.632305) (xy 351.407793 -344.609663) (xy 351.361943 -344.580197)
			(xy 351.320752 -344.544506) (xy 351.285061 -344.503315) (xy 351.255595 -344.457465) (xy 351.232953 -344.407888)
			(xy 351.217598 -344.355593) (xy 351.209842 -344.301645) (xy 351.209356 -344.274394) (xy 351.210022 -344.242831)
			(xy 351.220406 -344.180566) (xy 351.240889 -344.120857) (xy 351.25533 -344.092784) (xy 351.260156 -344.083894)
			(xy 351.262188 -344.064336) (xy 351.236534 -343.976198) (xy 351.224088 -343.960704) (xy 351.215198 -343.955624)
			(xy 351.207832 -343.95156) (xy 351.19818 -343.945718) (xy 351.176082 -343.943686) (xy 351.081594 -343.977214)
			(xy 351.065592 -343.992708) (xy 351.061528 -344.003122) (xy 351.050837 -344.0299) (xy 351.022548 -344.080142)
			(xy 350.987017 -344.125551) (xy 350.945054 -344.165093) (xy 350.897616 -344.197866) (xy 350.845785 -344.223124)
			(xy 350.790741 -344.24029) (xy 350.733741 -344.248972) (xy 350.704912 -344.249502) (xy 350.677658 -344.249051)
			(xy 350.623705 -344.241296) (xy 350.571405 -344.225941) (xy 350.521823 -344.203298) (xy 350.475967 -344.17383)
			(xy 350.434772 -344.138136) (xy 350.399077 -344.096942) (xy 350.369607 -344.051088) (xy 350.346964 -344.001506)
			(xy 350.331607 -343.949207) (xy 350.323849 -343.895254) (xy 350.055438 -343.895254) (xy 350.035074 -343.939392)
			(xy 350.005127 -343.985461) (xy 349.987362 -344.006424) (xy 349.981266 -344.013536) (xy 349.974916 -344.030554)
			(xy 349.974916 -344.116406) (xy 349.981266 -344.133424) (xy 349.987362 -344.140536) (xy 350.005133 -344.161492)
			(xy 350.035055 -344.207576) (xy 350.058065 -344.257472) (xy 350.07369 -344.31015) (xy 350.081605 -344.364523)
			(xy 350.082104 -344.391996) (xy 350.081618 -344.419247) (xy 350.073862 -344.473195) (xy 350.058507 -344.52549)
			(xy 350.035865 -344.575067) (xy 350.006399 -344.620917) (xy 349.970708 -344.662108) (xy 349.929517 -344.697799)
			(xy 349.883667 -344.727265) (xy 349.83409 -344.749907) (xy 349.781795 -344.765262) (xy 349.727847 -344.773018)
			(xy 349.673345 -344.773018) (xy 349.619397 -344.765262) (xy 349.567102 -344.749907) (xy 349.517525 -344.727265)
			(xy 349.471675 -344.697799) (xy 349.430484 -344.662108) (xy 349.394793 -344.620917) (xy 349.365327 -344.575067)
			(xy 349.342685 -344.52549) (xy 349.32733 -344.473195) (xy 349.319574 -344.419247) (xy 349.319088 -344.391996)
			(xy 325.168006 -344.391996) (xy 324.372478 -345.187524) (xy 324.365112 -345.194636) (xy 324.357492 -345.213432)
			(xy 324.357492 -347.29547) (xy 324.356853 -347.320466) (xy 324.347052 -347.369488) (xy 324.327877 -347.415658)
			(xy 324.300067 -347.457202) (xy 324.282816 -347.475302) (xy 322.28416 -349.473958) (xy 327.06208 -349.473958)
			(xy 327.06208 -349.389262) (xy 327.070131 -349.304948) (xy 327.08616 -349.221782) (xy 327.110021 -349.140515)
			(xy 327.1415 -349.061885) (xy 327.180311 -348.986604) (xy 327.226101 -348.915352) (xy 327.278457 -348.848776)
			(xy 327.336905 -348.787478) (xy 327.400915 -348.732013) (xy 327.469907 -348.682884) (xy 327.543257 -348.640535)
			(xy 327.6203 -348.605351) (xy 327.700339 -348.577649) (xy 327.782648 -348.557681) (xy 327.866483 -348.545628)
			(xy 327.951084 -348.541598) (xy 328.035685 -348.545628) (xy 328.11952 -348.557681) (xy 328.201829 -348.577649)
			(xy 328.281868 -348.605351) (xy 328.358911 -348.640535) (xy 328.432261 -348.682884) (xy 328.501253 -348.732013)
			(xy 328.565263 -348.787478) (xy 328.623711 -348.848776) (xy 328.676067 -348.915352) (xy 328.721857 -348.986604)
			(xy 328.760668 -349.061885) (xy 328.792147 -349.140515) (xy 328.816008 -349.221782) (xy 328.832037 -349.304948)
			(xy 328.840088 -349.389262) (xy 328.840592 -349.43161) (xy 328.840088 -349.473958) (xy 334.52206 -349.473958)
			(xy 334.52206 -349.389262) (xy 334.530111 -349.304948) (xy 334.54614 -349.221782) (xy 334.570001 -349.140515)
			(xy 334.60148 -349.061885) (xy 334.640291 -348.986604) (xy 334.686081 -348.915352) (xy 334.738437 -348.848776)
			(xy 334.796885 -348.787478) (xy 334.860895 -348.732013) (xy 334.929887 -348.682884) (xy 335.003237 -348.640535)
			(xy 335.08028 -348.605351) (xy 335.160319 -348.577649) (xy 335.242628 -348.557681) (xy 335.326463 -348.545628)
			(xy 335.411064 -348.541598) (xy 335.495665 -348.545628) (xy 335.5795 -348.557681) (xy 335.661809 -348.577649)
			(xy 335.741848 -348.605351) (xy 335.818891 -348.640535) (xy 335.892241 -348.682884) (xy 335.961233 -348.732013)
			(xy 336.025243 -348.787478) (xy 336.083691 -348.848776) (xy 336.136047 -348.915352) (xy 336.181837 -348.986604)
			(xy 336.220648 -349.061885) (xy 336.252127 -349.140515) (xy 336.275988 -349.221782) (xy 336.292017 -349.304948)
			(xy 336.300068 -349.389262) (xy 336.300572 -349.43161) (xy 336.300068 -349.473958) (xy 336.292017 -349.558272)
			(xy 336.275988 -349.641438) (xy 336.252127 -349.722705) (xy 336.220648 -349.801335) (xy 336.181837 -349.876616)
			(xy 336.136047 -349.947868) (xy 336.083691 -350.014444) (xy 336.025243 -350.075742) (xy 335.961233 -350.131207)
			(xy 335.892241 -350.180336) (xy 335.818891 -350.222685) (xy 335.741848 -350.257869) (xy 335.661809 -350.285571)
			(xy 335.5795 -350.305539) (xy 335.495665 -350.317592) (xy 335.411064 -350.321623) (xy 335.326463 -350.317592)
			(xy 335.242628 -350.305539) (xy 335.160319 -350.285571) (xy 335.08028 -350.257869) (xy 335.003237 -350.222685)
			(xy 334.929887 -350.180336) (xy 334.860895 -350.131207) (xy 334.796885 -350.075742) (xy 334.738437 -350.014444)
			(xy 334.686081 -349.947868) (xy 334.640291 -349.876616) (xy 334.60148 -349.801335) (xy 334.570001 -349.722705)
			(xy 334.54614 -349.641438) (xy 334.530111 -349.558272) (xy 334.52206 -349.473958) (xy 328.840088 -349.473958)
			(xy 328.832037 -349.558272) (xy 328.816008 -349.641438) (xy 328.792147 -349.722705) (xy 328.760668 -349.801335)
			(xy 328.721857 -349.876616) (xy 328.676067 -349.947868) (xy 328.623711 -350.014444) (xy 328.565263 -350.075742)
			(xy 328.501253 -350.131207) (xy 328.432261 -350.180336) (xy 328.358911 -350.222685) (xy 328.281868 -350.257869)
			(xy 328.201829 -350.285571) (xy 328.11952 -350.305539) (xy 328.035685 -350.317592) (xy 327.951084 -350.321623)
			(xy 327.866483 -350.317592) (xy 327.782648 -350.305539) (xy 327.700339 -350.285571) (xy 327.6203 -350.257869)
			(xy 327.543257 -350.222685) (xy 327.469907 -350.180336) (xy 327.400915 -350.131207) (xy 327.336905 -350.075742)
			(xy 327.278457 -350.014444) (xy 327.226101 -349.947868) (xy 327.180311 -349.876616) (xy 327.1415 -349.801335)
			(xy 327.110021 -349.722705) (xy 327.08616 -349.641438) (xy 327.070131 -349.558272) (xy 327.06208 -349.473958)
			(xy 322.28416 -349.473958) (xy 319.784038 -351.97408) (xy 327.06208 -351.97408) (xy 327.06208 -351.889384)
			(xy 327.070131 -351.80507) (xy 327.08616 -351.721904) (xy 327.110021 -351.640637) (xy 327.1415 -351.562007)
			(xy 327.180311 -351.486726) (xy 327.226101 -351.415474) (xy 327.278457 -351.348898) (xy 327.336905 -351.2876)
			(xy 327.400915 -351.232135) (xy 327.469907 -351.183006) (xy 327.543257 -351.140657) (xy 327.6203 -351.105473)
			(xy 327.700339 -351.077771) (xy 327.782648 -351.057803) (xy 327.866483 -351.04575) (xy 327.951084 -351.04172)
			(xy 328.035685 -351.04575) (xy 328.11952 -351.057803) (xy 328.201829 -351.077771) (xy 328.281868 -351.105473)
			(xy 328.358911 -351.140657) (xy 328.432261 -351.183006) (xy 328.501253 -351.232135) (xy 328.565263 -351.2876)
			(xy 328.623711 -351.348898) (xy 328.676067 -351.415474) (xy 328.721857 -351.486726) (xy 328.760668 -351.562007)
			(xy 328.792147 -351.640637) (xy 328.816008 -351.721904) (xy 328.832037 -351.80507) (xy 328.840088 -351.889384)
			(xy 328.840592 -351.931732) (xy 328.840088 -351.97408) (xy 334.52206 -351.97408) (xy 334.52206 -351.889384)
			(xy 334.530111 -351.80507) (xy 334.54614 -351.721904) (xy 334.570001 -351.640637) (xy 334.60148 -351.562007)
			(xy 334.640291 -351.486726) (xy 334.686081 -351.415474) (xy 334.738437 -351.348898) (xy 334.796885 -351.2876)
			(xy 334.860895 -351.232135) (xy 334.929887 -351.183006) (xy 335.003237 -351.140657) (xy 335.08028 -351.105473)
			(xy 335.160319 -351.077771) (xy 335.242628 -351.057803) (xy 335.326463 -351.04575) (xy 335.411064 -351.04172)
			(xy 335.495665 -351.04575) (xy 335.5795 -351.057803) (xy 335.661809 -351.077771) (xy 335.741848 -351.105473)
			(xy 335.818891 -351.140657) (xy 335.892241 -351.183006) (xy 335.961233 -351.232135) (xy 336.025243 -351.2876)
			(xy 336.083691 -351.348898) (xy 336.136047 -351.415474) (xy 336.181837 -351.486726) (xy 336.220648 -351.562007)
			(xy 336.252127 -351.640637) (xy 336.275988 -351.721904) (xy 336.292017 -351.80507) (xy 336.300068 -351.889384)
			(xy 336.300572 -351.931732) (xy 336.300068 -351.97408) (xy 336.292017 -352.058394) (xy 336.275988 -352.14156)
			(xy 336.252127 -352.222827) (xy 336.220648 -352.301457) (xy 336.181837 -352.376738) (xy 336.136047 -352.44799)
			(xy 336.083691 -352.514566) (xy 336.025243 -352.575864) (xy 335.961233 -352.631329) (xy 335.892241 -352.680458)
			(xy 335.818891 -352.722807) (xy 335.741848 -352.757991) (xy 335.661809 -352.785693) (xy 335.5795 -352.805661)
			(xy 335.495665 -352.817714) (xy 335.411064 -352.821745) (xy 335.326463 -352.817714) (xy 335.242628 -352.805661)
			(xy 335.160319 -352.785693) (xy 335.08028 -352.757991) (xy 335.003237 -352.722807) (xy 334.929887 -352.680458)
			(xy 334.860895 -352.631329) (xy 334.796885 -352.575864) (xy 334.738437 -352.514566) (xy 334.686081 -352.44799)
			(xy 334.640291 -352.376738) (xy 334.60148 -352.301457) (xy 334.570001 -352.222827) (xy 334.54614 -352.14156)
			(xy 334.530111 -352.058394) (xy 334.52206 -351.97408) (xy 328.840088 -351.97408) (xy 328.832037 -352.058394)
			(xy 328.816008 -352.14156) (xy 328.792147 -352.222827) (xy 328.760668 -352.301457) (xy 328.721857 -352.376738)
			(xy 328.676067 -352.44799) (xy 328.623711 -352.514566) (xy 328.565263 -352.575864) (xy 328.501253 -352.631329)
			(xy 328.432261 -352.680458) (xy 328.358911 -352.722807) (xy 328.281868 -352.757991) (xy 328.201829 -352.785693)
			(xy 328.11952 -352.805661) (xy 328.035685 -352.817714) (xy 327.951084 -352.821745) (xy 327.866483 -352.817714)
			(xy 327.782648 -352.805661) (xy 327.700339 -352.785693) (xy 327.6203 -352.757991) (xy 327.543257 -352.722807)
			(xy 327.469907 -352.680458) (xy 327.400915 -352.631329) (xy 327.336905 -352.575864) (xy 327.278457 -352.514566)
			(xy 327.226101 -352.44799) (xy 327.180311 -352.376738) (xy 327.1415 -352.301457) (xy 327.110021 -352.222827)
			(xy 327.08616 -352.14156) (xy 327.070131 -352.058394) (xy 327.06208 -351.97408) (xy 319.784038 -351.97408)
			(xy 318.784986 -352.973132) (xy 339.357462 -352.973132) (xy 339.357989 -352.944427) (xy 339.366594 -352.887665)
			(xy 339.3836 -352.832831) (xy 339.408623 -352.781161) (xy 339.4411 -352.73382) (xy 339.480298 -352.691874)
			(xy 339.502496 -352.673666) (xy 339.511894 -352.6663) (xy 339.5218 -352.645726) (xy 339.5218 -352.542348)
			(xy 339.511894 -352.521774) (xy 339.502496 -352.514408) (xy 339.480306 -352.496237) (xy 339.441174 -352.454308)
			(xy 339.408755 -352.406996) (xy 339.383781 -352.355366) (xy 339.366812 -352.30058) (xy 339.358231 -352.243873)
			(xy 339.357716 -352.215196) (xy 339.358226 -352.186279) (xy 339.366956 -352.129107) (xy 339.384215 -352.073908)
			(xy 339.409608 -352.021946) (xy 339.442553 -351.974412) (xy 339.482296 -351.932396) (xy 339.504782 -351.914206)
			(xy 339.513551 -351.906651) (xy 339.523727 -351.885887) (xy 339.52434 -351.874328) (xy 339.52434 -351.794064)
			(xy 339.523754 -351.782498) (xy 339.513572 -351.761725) (xy 339.504782 -351.754186) (xy 339.482288 -351.736007)
			(xy 339.442554 -351.693985) (xy 339.409617 -351.646447) (xy 339.384231 -351.594483) (xy 339.366977 -351.539284)
			(xy 339.35825 -351.482113) (xy 339.357716 -351.453196) (xy 339.358152 -351.425942) (xy 339.36591 -351.371989)
			(xy 339.381268 -351.319689) (xy 339.403912 -351.270107) (xy 339.433383 -351.224253) (xy 339.46908 -351.18306)
			(xy 339.510275 -351.147366) (xy 339.556132 -351.117899) (xy 339.605715 -351.095258) (xy 339.658016 -351.079904)
			(xy 339.71197 -351.07215) (xy 339.739224 -351.071688) (xy 339.768141 -351.072228) (xy 339.825312 -351.080948)
			(xy 339.880512 -351.098199) (xy 339.932475 -351.123587) (xy 339.980009 -351.156528) (xy 340.022025 -351.196269)
			(xy 340.040214 -351.218754) (xy 340.047765 -351.227527) (xy 340.068532 -351.237702) (xy 340.080092 -351.238312)
			(xy 340.160356 -351.238312) (xy 340.17192 -351.237712) (xy 340.192691 -351.227538) (xy 340.200234 -351.218754)
			(xy 340.216987 -351.197971) (xy 340.255341 -351.160841) (xy 340.298495 -351.129419) (xy 340.345609 -351.10432)
			(xy 340.395761 -351.086034) (xy 340.447972 -351.074917) (xy 340.501224 -351.071187) (xy 340.554476 -351.074917)
			(xy 340.606687 -351.086034) (xy 340.656839 -351.10432) (xy 340.703953 -351.129419) (xy 340.747107 -351.160841)
			(xy 340.785461 -351.197971) (xy 340.802214 -351.218754) (xy 340.809765 -351.227527) (xy 340.830532 -351.237702)
			(xy 340.842092 -351.238312) (xy 340.922356 -351.238312) (xy 340.93392 -351.237712) (xy 340.954691 -351.227538)
			(xy 340.962234 -351.218754) (xy 340.978987 -351.197971) (xy 341.017341 -351.160841) (xy 341.060495 -351.129419)
			(xy 341.107609 -351.10432) (xy 341.157761 -351.086034) (xy 341.209972 -351.074917) (xy 341.263224 -351.071187)
			(xy 341.316476 -351.074917) (xy 341.368687 -351.086034) (xy 341.418839 -351.10432) (xy 341.465953 -351.129419)
			(xy 341.509107 -351.160841) (xy 341.547461 -351.197971) (xy 341.564214 -351.218754) (xy 341.571765 -351.227527)
			(xy 341.592532 -351.237702) (xy 341.604092 -351.238312) (xy 341.684356 -351.238312) (xy 341.69592 -351.237712)
			(xy 341.716691 -351.227538) (xy 341.724234 -351.218754) (xy 341.740987 -351.197971) (xy 341.779341 -351.160841)
			(xy 341.822495 -351.129419) (xy 341.869609 -351.10432) (xy 341.919761 -351.086034) (xy 341.971972 -351.074917)
			(xy 342.025224 -351.071187) (xy 342.078476 -351.074917) (xy 342.130687 -351.086034) (xy 342.180839 -351.10432)
			(xy 342.227953 -351.129419) (xy 342.271107 -351.160841) (xy 342.309461 -351.197971) (xy 342.326214 -351.218754)
			(xy 342.333765 -351.227527) (xy 342.354532 -351.237702) (xy 342.366092 -351.238312) (xy 342.446356 -351.238312)
			(xy 342.45792 -351.237712) (xy 342.478691 -351.227538) (xy 342.486234 -351.218754) (xy 342.504394 -351.196245)
			(xy 342.546422 -351.156513) (xy 342.593963 -351.123579) (xy 342.645931 -351.098195) (xy 342.701133 -351.080944)
			(xy 342.758306 -351.07222) (xy 342.787224 -351.071688) (xy 342.813553 -351.072133) (xy 342.865711 -351.07936)
			(xy 342.916378 -351.093701) (xy 342.964587 -351.114883) (xy 343.009419 -351.142502) (xy 343.050021 -351.176032)
			(xy 343.068148 -351.195132) (xy 343.075006 -351.202752) (xy 343.09304 -351.211134) (xy 343.184734 -351.215452)
			(xy 343.203276 -351.208848) (xy 343.210896 -351.20199) (xy 343.231996 -351.183769) (xy 343.278502 -351.153026)
			(xy 343.328986 -351.129378) (xy 343.382374 -351.113327) (xy 343.43753 -351.105215) (xy 343.465404 -351.104708)
			(xy 343.492658 -351.105152) (xy 343.54661 -351.11291) (xy 343.598909 -351.128267) (xy 343.648491 -351.150911)
			(xy 343.694344 -351.180381) (xy 343.735537 -351.216077) (xy 343.771231 -351.257272) (xy 343.800699 -351.303127)
			(xy 343.82334 -351.352709) (xy 343.838695 -351.405009) (xy 343.84645 -351.458962) (xy 343.846912 -351.486216)
			(xy 343.846367 -351.515132) (xy 343.837648 -351.572304) (xy 343.820398 -351.627503) (xy 343.795011 -351.679466)
			(xy 343.762071 -351.727) (xy 343.722331 -351.769016) (xy 343.699846 -351.787206) (xy 343.691077 -351.79476)
			(xy 343.680899 -351.815525) (xy 343.680288 -351.827084) (xy 343.680288 -351.907348) (xy 343.680892 -351.918911)
			(xy 343.691063 -351.939683) (xy 343.699846 -351.947226) (xy 343.722352 -351.965391) (xy 343.762083 -352.007417)
			(xy 343.795018 -352.054958) (xy 343.820402 -352.106924) (xy 343.837654 -352.162126) (xy 343.846379 -352.219299)
			(xy 343.846912 -352.248216) (xy 343.846392 -352.276921) (xy 343.837781 -352.333682) (xy 343.820772 -352.388515)
			(xy 343.795747 -352.440184) (xy 343.763271 -352.487526) (xy 343.724074 -352.529473) (xy 343.701878 -352.547682)
			(xy 343.69248 -352.555048) (xy 343.682574 -352.575622) (xy 343.682574 -352.679) (xy 343.69248 -352.699574)
			(xy 343.701878 -352.70694) (xy 343.724038 -352.725146) (xy 343.763173 -352.767067) (xy 343.795596 -352.814372)
			(xy 343.820576 -352.865995) (xy 343.837551 -352.920775) (xy 343.846139 -352.977477) (xy 343.846658 -353.006152)
			(xy 343.846172 -353.033403) (xy 343.838416 -353.087351) (xy 343.823061 -353.139646) (xy 343.800419 -353.189223)
			(xy 343.770953 -353.235073) (xy 343.735262 -353.276264) (xy 343.694071 -353.311955) (xy 343.648221 -353.341421)
			(xy 343.598644 -353.364063) (xy 343.546349 -353.379418) (xy 343.492401 -353.387174) (xy 343.437899 -353.387174)
			(xy 343.383951 -353.379418) (xy 343.331656 -353.364063) (xy 343.282079 -353.341421) (xy 343.236229 -353.311955)
			(xy 343.195038 -353.276264) (xy 343.159347 -353.235073) (xy 343.129881 -353.189223) (xy 343.107239 -353.139646)
			(xy 343.091884 -353.087351) (xy 343.084128 -353.033403) (xy 343.083642 -353.006152) (xy 343.08419 -352.977448)
			(xy 343.092792 -352.920687) (xy 343.109794 -352.865854) (xy 343.134813 -352.814184) (xy 343.167286 -352.766842)
			(xy 343.20648 -352.724895) (xy 343.228676 -352.706686) (xy 343.238074 -352.69932) (xy 343.24798 -352.678746)
			(xy 343.24798 -352.575368) (xy 343.238074 -352.554794) (xy 343.228676 -352.547428) (xy 343.216925 -352.537922)
			(xy 343.194803 -352.517321) (xy 343.18448 -352.50628) (xy 343.177622 -352.49866) (xy 343.159588 -352.490278)
			(xy 343.067894 -352.48596) (xy 343.049352 -352.492564) (xy 343.041732 -352.499422) (xy 343.020373 -352.517836)
			(xy 342.973249 -352.548808) (xy 342.92208 -352.572511) (xy 342.895174 -352.580956) (xy 342.882474 -352.584766)
			(xy 342.864186 -352.603562) (xy 342.834722 -352.713036) (xy 342.841072 -352.738436) (xy 342.850216 -352.748342)
			(xy 342.869675 -352.769691) (xy 342.902554 -352.817185) (xy 342.927894 -352.869094) (xy 342.945115 -352.924231)
			(xy 342.953825 -352.981334) (xy 342.954356 -353.010216) (xy 342.953837 -353.037465) (xy 342.94608 -353.09141)
			(xy 342.930725 -353.143701) (xy 342.908086 -353.193275) (xy 342.878622 -353.239123) (xy 342.842934 -353.280312)
			(xy 342.801748 -353.316003) (xy 342.755903 -353.34547) (xy 342.706331 -353.368114) (xy 342.654041 -353.383473)
			(xy 342.600097 -353.391235) (xy 342.572848 -353.391724) (xy 342.545478 -353.391248) (xy 342.491298 -353.383436)
			(xy 342.438795 -353.36795) (xy 342.389048 -353.34511) (xy 342.343081 -353.315386) (xy 342.32215 -353.297744)
			(xy 342.315038 -353.291648) (xy 342.29802 -353.285298) (xy 342.212676 -353.285298) (xy 342.195658 -353.291648)
			(xy 342.188546 -353.297744) (xy 342.167613 -353.315385) (xy 342.121645 -353.345109) (xy 342.071899 -353.367955)
			(xy 342.019397 -353.383451) (xy 341.965219 -353.39128) (xy 341.910477 -353.39128) (xy 341.856299 -353.383451)
			(xy 341.803797 -353.367955) (xy 341.754051 -353.345109) (xy 341.708083 -353.315385) (xy 341.68715 -353.297744)
			(xy 341.680038 -353.291648) (xy 341.66302 -353.285298) (xy 341.577676 -353.285298) (xy 341.560658 -353.291648)
			(xy 341.553546 -353.297744) (xy 341.532613 -353.315385) (xy 341.486645 -353.345109) (xy 341.436899 -353.367955)
			(xy 341.384397 -353.383451) (xy 341.330219 -353.39128) (xy 341.275477 -353.39128) (xy 341.221299 -353.383451)
			(xy 341.168797 -353.367955) (xy 341.119051 -353.345109) (xy 341.073083 -353.315385) (xy 341.05215 -353.297744)
			(xy 341.045038 -353.291648) (xy 341.02802 -353.285298) (xy 340.942676 -353.285298) (xy 340.925658 -353.291648)
			(xy 340.918546 -353.297744) (xy 340.897613 -353.315382) (xy 340.85164 -353.345093) (xy 340.801893 -353.367928)
			(xy 340.749392 -353.38342) (xy 340.695217 -353.391249) (xy 340.667848 -353.391724) (xy 340.640597 -353.3912)
			(xy 340.586649 -353.38345) (xy 340.534353 -353.368101) (xy 340.484774 -353.345465) (xy 340.438922 -353.316004)
			(xy 340.397729 -353.280316) (xy 340.362035 -353.239129) (xy 340.332566 -353.193282) (xy 340.309921 -353.143707)
			(xy 340.294564 -353.091413) (xy 340.286804 -353.037467) (xy 340.28634 -353.010216) (xy 340.286927 -352.979985)
			(xy 340.296473 -352.920281) (xy 340.315313 -352.86283) (xy 340.342975 -352.809067) (xy 340.378769 -352.760338)
			(xy 340.399878 -352.73869) (xy 340.409022 -352.729546) (xy 340.416642 -352.704908) (xy 340.393782 -352.595688)
			(xy 340.377018 -352.57613) (xy 340.364826 -352.571558) (xy 340.340772 -352.561862) (xy 340.295307 -352.536913)
			(xy 340.253633 -352.506045) (xy 340.216515 -352.469825) (xy 340.200234 -352.449638) (xy 340.192664 -352.440885)
			(xy 340.171911 -352.430699) (xy 340.160356 -352.43008) (xy 340.080092 -352.43008) (xy 340.068525 -352.430653)
			(xy 340.047754 -352.440847) (xy 340.040214 -352.449638) (xy 340.025838 -352.467546) (xy 339.993492 -352.500146)
			(xy 339.975698 -352.514662) (xy 339.9663 -352.522028) (xy 339.956394 -352.542602) (xy 339.956394 -352.64598)
			(xy 339.9663 -352.666554) (xy 339.975698 -352.67392) (xy 339.997852 -352.692132) (xy 340.036987 -352.734053)
			(xy 340.06941 -352.781356) (xy 340.094391 -352.832978) (xy 340.111367 -352.887756) (xy 340.119957 -352.944458)
			(xy 340.120478 -352.973132) (xy 340.119992 -353.000383) (xy 340.112236 -353.054331) (xy 340.096881 -353.106626)
			(xy 340.074239 -353.156203) (xy 340.044773 -353.202053) (xy 340.009082 -353.243244) (xy 339.967891 -353.278935)
			(xy 339.922041 -353.308401) (xy 339.872464 -353.331043) (xy 339.820169 -353.346398) (xy 339.766221 -353.354154)
			(xy 339.711719 -353.354154) (xy 339.657771 -353.346398) (xy 339.605476 -353.331043) (xy 339.555899 -353.308401)
			(xy 339.510049 -353.278935) (xy 339.468858 -353.243244) (xy 339.433167 -353.202053) (xy 339.403701 -353.156203)
			(xy 339.381059 -353.106626) (xy 339.365704 -353.054331) (xy 339.357948 -353.000383) (xy 339.357462 -352.973132)
			(xy 318.784986 -352.973132) (xy 318.111886 -353.646232) (xy 318.09379 -353.663487) (xy 318.052244 -353.691294)
			(xy 318.006073 -353.710465) (xy 317.95705 -353.720263) (xy 317.932054 -353.720908) (xy 316.548008 -353.720908)
			(xy 316.537986 -353.721326) (xy 316.519468 -353.728995) (xy 316.505295 -353.743168) (xy 316.497626 -353.761686)
			(xy 316.497208 -353.771708) (xy 316.497208 -356.014528) (xy 316.496676 -356.038404) (xy 316.489107 -356.085556)
			(xy 316.474298 -356.130957) (xy 316.452609 -356.173504) (xy 316.424569 -356.21216) (xy 316.408054 -356.229412)
			(xy 316.407292 -356.230174) (xy 316.405768 -356.231952) (xy 316.40096 -356.237567) (xy 316.394515 -356.250864)
			(xy 316.393068 -356.258114) (xy 316.389004 -356.283768) (xy 316.388314 -356.28878) (xy 316.3887 -356.298888)
			(xy 316.389766 -356.303834) (xy 316.393068 -356.31755) (xy 316.395354 -356.322376) (xy 316.407445 -356.348472)
			(xy 316.424526 -356.403388) (xy 316.433187 -356.460244) (xy 316.433363 -356.46995) (xy 317.016382 -356.46995)
			(xy 317.020453 -356.414328) (xy 317.032579 -356.359891) (xy 317.052502 -356.3078) (xy 317.079798 -356.259165)
			(xy 317.113884 -356.215022) (xy 317.154033 -356.176313) (xy 317.199391 -356.143862) (xy 317.248991 -356.118361)
			(xy 317.301775 -356.100354) (xy 317.356618 -356.090224) (xy 317.412352 -356.088187) (xy 317.467789 -356.094287)
			(xy 317.521746 -356.108393) (xy 317.573075 -356.130205) (xy 317.620681 -356.159259) (xy 317.663549 -356.194934)
			(xy 317.700766 -356.236471) (xy 317.731539 -356.282984) (xy 317.755211 -356.333481) (xy 317.771279 -356.386888)
			(xy 317.779399 -356.442064) (xy 317.779908 -356.46995) (xy 317.779399 -356.497836) (xy 317.771279 -356.553012)
			(xy 317.755211 -356.606419) (xy 317.731539 -356.656916) (xy 317.700766 -356.703429) (xy 317.663549 -356.744966)
			(xy 317.620681 -356.780641) (xy 317.573075 -356.809695) (xy 317.521746 -356.831507) (xy 317.467789 -356.845613)
			(xy 317.412352 -356.851713) (xy 317.356618 -356.849676) (xy 317.301775 -356.839546) (xy 317.248991 -356.821539)
			(xy 317.199391 -356.796038) (xy 317.154033 -356.763587) (xy 317.113884 -356.724878) (xy 317.079798 -356.680735)
			(xy 317.052502 -356.6321) (xy 317.032579 -356.580009) (xy 317.020453 -356.525572) (xy 317.016382 -356.46995)
			(xy 316.433363 -356.46995) (xy 316.433708 -356.489) (xy 316.43319 -356.517757) (xy 316.424553 -356.574619)
			(xy 316.407462 -356.629535) (xy 316.395354 -356.655624) (xy 316.393068 -356.66045) (xy 316.389766 -356.674166)
			(xy 316.388691 -356.679111) (xy 316.388303 -356.689221) (xy 316.389004 -356.694232) (xy 316.393068 -356.719886)
			(xy 316.394497 -356.727142) (xy 316.400943 -356.740444) (xy 316.405768 -356.746048) (xy 316.407292 -356.747826)
			(xy 316.408054 -356.748588) (xy 316.424612 -356.765807) (xy 316.452697 -356.804447) (xy 316.474405 -356.846998)
			(xy 316.489203 -356.892417) (xy 316.496727 -356.939588) (xy 316.497208 -356.963472) (xy 316.497208 -359.029)
			(xy 317.905382 -359.029) (xy 317.909453 -358.973378) (xy 317.921579 -358.918941) (xy 317.941502 -358.86685)
			(xy 317.968798 -358.818215) (xy 318.002884 -358.774072) (xy 318.043033 -358.735363) (xy 318.088391 -358.702912)
			(xy 318.137991 -358.677411) (xy 318.190775 -358.659404) (xy 318.245618 -358.649274) (xy 318.301352 -358.647237)
			(xy 318.356789 -358.653337) (xy 318.410746 -358.667443) (xy 318.462075 -358.689255) (xy 318.509681 -358.718309)
			(xy 318.552549 -358.753984) (xy 318.589766 -358.795521) (xy 318.620539 -358.842034) (xy 318.644211 -358.892531)
			(xy 318.660279 -358.945938) (xy 318.668399 -359.001114) (xy 318.668908 -359.029) (xy 318.668399 -359.056886)
			(xy 318.661737 -359.102152) (xy 335.533238 -359.102152) (xy 335.533763 -359.074042) (xy 335.542002 -359.018429)
			(xy 335.558308 -358.964625) (xy 335.582329 -358.913795) (xy 335.613546 -358.867038) (xy 335.632044 -358.845866)
			(xy 335.638648 -358.838754) (xy 335.645252 -358.82199) (xy 335.646522 -358.736138) (xy 335.640426 -358.71912)
			(xy 335.63433 -358.711754) (xy 335.61724 -358.690976) (xy 335.58848 -358.645509) (xy 335.566395 -358.596451)
			(xy 335.551422 -358.544777) (xy 335.54386 -358.491512) (xy 335.543398 -358.464612) (xy 335.543867 -358.437359)
			(xy 335.551622 -358.383408) (xy 335.566977 -358.33111) (xy 335.589618 -358.28153) (xy 335.619086 -358.235676)
			(xy 335.654779 -358.194483) (xy 335.695971 -358.158789) (xy 335.741824 -358.129321) (xy 335.791404 -358.106679)
			(xy 335.843702 -358.091323) (xy 335.897653 -358.083567) (xy 335.924906 -358.083104) (xy 335.953823 -358.083617)
			(xy 336.010995 -358.092347) (xy 336.066194 -358.109606) (xy 336.118155 -358.134998) (xy 336.165689 -358.167943)
			(xy 336.207706 -358.207684) (xy 336.225896 -358.23017) (xy 336.233452 -358.238937) (xy 336.254216 -358.249115)
			(xy 336.265774 -358.249728) (xy 336.346038 -358.249728) (xy 336.357605 -358.249147) (xy 336.378378 -358.238962)
			(xy 336.385916 -358.23017) (xy 336.402669 -358.209387) (xy 336.441023 -358.172257) (xy 336.484177 -358.140835)
			(xy 336.531291 -358.115736) (xy 336.581443 -358.09745) (xy 336.633654 -358.086333) (xy 336.686906 -358.082603)
			(xy 336.740158 -358.086333) (xy 336.792369 -358.09745) (xy 336.842521 -358.115736) (xy 336.889635 -358.140835)
			(xy 336.932789 -358.172257) (xy 336.971143 -358.209387) (xy 336.987896 -358.23017) (xy 336.995452 -358.238937)
			(xy 337.016216 -358.249115) (xy 337.027774 -358.249728) (xy 337.108038 -358.249728) (xy 337.119605 -358.249147)
			(xy 337.140378 -358.238962) (xy 337.147916 -358.23017) (xy 337.16609 -358.207673) (xy 337.208115 -358.16794)
			(xy 337.255653 -358.135003) (xy 337.307618 -358.109617) (xy 337.362818 -358.092364) (xy 337.419989 -358.083638)
			(xy 337.448906 -358.083104) (xy 337.477834 -358.083626) (xy 337.535025 -358.092383) (xy 337.590236 -358.109678)
			(xy 337.642201 -358.135116) (xy 337.689727 -358.168113) (xy 337.731722 -358.207911) (xy 337.749896 -358.230424)
			(xy 337.757262 -358.239568) (xy 337.777582 -358.249728) (xy 337.880452 -358.251252) (xy 337.90128 -358.2416)
			(xy 337.908646 -358.232456) (xy 337.915758 -358.224074) (xy 337.921854 -358.216962) (xy 337.928204 -358.199944)
			(xy 337.928204 -358.1146) (xy 337.921854 -358.097582) (xy 337.915758 -358.09047) (xy 337.898131 -358.069528)
			(xy 337.868419 -358.023557) (xy 337.845581 -357.973812) (xy 337.830087 -357.921314) (xy 337.822254 -357.86714)
			(xy 337.821778 -357.839772) (xy 337.822252 -357.812521) (xy 337.830012 -357.758573) (xy 337.84537 -357.706279)
			(xy 337.868013 -357.656703) (xy 337.897481 -357.610853) (xy 337.933174 -357.569664) (xy 337.974364 -357.533973)
			(xy 338.020215 -357.504506) (xy 338.069792 -357.481865) (xy 338.122087 -357.466509) (xy 338.176035 -357.458751)
			(xy 338.203286 -357.458264) (xy 338.232204 -357.458768) (xy 338.289377 -357.467497) (xy 338.344577 -357.484756)
			(xy 338.396539 -357.51015) (xy 338.444072 -357.543097) (xy 338.486087 -357.582842) (xy 338.504276 -357.60533)
			(xy 338.511847 -357.614082) (xy 338.532599 -357.62427) (xy 338.544154 -357.624888) (xy 338.624418 -357.624888)
			(xy 338.635988 -357.624332) (xy 338.656759 -357.614128) (xy 338.664296 -357.60533) (xy 338.681049 -357.584547)
			(xy 338.719403 -357.547417) (xy 338.762557 -357.515995) (xy 338.809671 -357.490896) (xy 338.859823 -357.47261)
			(xy 338.912034 -357.461493) (xy 338.965286 -357.457763) (xy 339.018538 -357.461493) (xy 339.070749 -357.47261)
			(xy 339.120901 -357.490896) (xy 339.168015 -357.515995) (xy 339.211169 -357.547417) (xy 339.249523 -357.584547)
			(xy 339.266276 -357.60533) (xy 339.273847 -357.614082) (xy 339.294599 -357.62427) (xy 339.306154 -357.624888)
			(xy 339.386418 -357.624888) (xy 339.397988 -357.624332) (xy 339.418759 -357.614128) (xy 339.426296 -357.60533)
			(xy 339.444497 -357.582855) (xy 339.486514 -357.543118) (xy 339.534046 -357.510177) (xy 339.586006 -357.484787)
			(xy 339.641202 -357.467529) (xy 339.69837 -357.458799) (xy 339.727286 -357.458264) (xy 339.754536 -357.458791)
			(xy 339.80848 -357.466545) (xy 339.860773 -357.481897) (xy 339.910348 -357.504534) (xy 339.956197 -357.533997)
			(xy 339.997386 -357.569684) (xy 340.033078 -357.610869) (xy 340.062545 -357.656715) (xy 340.085188 -357.706288)
			(xy 340.100546 -357.758579) (xy 340.108306 -357.812522) (xy 340.108794 -357.839772) (xy 340.108313 -357.867142)
			(xy 340.100499 -357.92132) (xy 340.085013 -357.973823) (xy 340.062175 -358.02357) (xy 340.032454 -358.069538)
			(xy 340.030165 -358.072254) (xy 340.314959 -358.072254) (xy 340.314959 -358.017746) (xy 340.322717 -357.963791)
			(xy 340.338075 -357.911491) (xy 340.360721 -357.861908) (xy 340.390192 -357.816054) (xy 340.42589 -357.77486)
			(xy 340.467087 -357.739167) (xy 340.512945 -357.709701) (xy 340.56253 -357.687061) (xy 340.614833 -357.671708)
			(xy 340.668787 -357.663956) (xy 340.696042 -357.663496) (xy 340.723411 -357.663997) (xy 340.777589 -357.671807)
			(xy 340.830091 -357.687288) (xy 340.879839 -357.710121) (xy 340.925807 -357.739838) (xy 340.94674 -357.757476)
			(xy 340.953852 -357.763572) (xy 340.97087 -357.769922) (xy 341.056214 -357.769922) (xy 341.073232 -357.763572)
			(xy 341.080344 -357.757476) (xy 341.101277 -357.739835) (xy 341.147245 -357.710111) (xy 341.196991 -357.687265)
			(xy 341.249493 -357.671769) (xy 341.303671 -357.66394) (xy 341.358413 -357.66394) (xy 341.412591 -357.671769)
			(xy 341.465093 -357.687265) (xy 341.514839 -357.710111) (xy 341.560807 -357.739835) (xy 341.58174 -357.757476)
			(xy 341.588852 -357.763572) (xy 341.60587 -357.769922) (xy 341.691214 -357.769922) (xy 341.708232 -357.763572)
			(xy 341.715344 -357.757476) (xy 341.736277 -357.739835) (xy 341.782245 -357.710111) (xy 341.831991 -357.687265)
			(xy 341.884493 -357.671769) (xy 341.938671 -357.66394) (xy 341.993413 -357.66394) (xy 342.047591 -357.671769)
			(xy 342.100093 -357.687265) (xy 342.149839 -357.710111) (xy 342.195807 -357.739835) (xy 342.21674 -357.757476)
			(xy 342.223852 -357.763572) (xy 342.24087 -357.769922) (xy 342.326214 -357.769922) (xy 342.343232 -357.763572)
			(xy 342.350344 -357.757476) (xy 342.371283 -357.739846) (xy 342.417254 -357.710134) (xy 342.467 -357.687296)
			(xy 342.519499 -357.671803) (xy 342.573673 -357.663972) (xy 342.601042 -357.663496) (xy 342.628292 -357.663977)
			(xy 342.682235 -357.671738) (xy 342.734526 -357.687097) (xy 342.784098 -357.709741) (xy 342.829944 -357.739209)
			(xy 342.871129 -357.7749) (xy 342.906817 -357.81609) (xy 342.936279 -357.861939) (xy 342.958918 -357.911514)
			(xy 342.974271 -357.963806) (xy 342.982026 -358.01775) (xy 342.982026 -358.07225) (xy 342.974271 -358.126194)
			(xy 342.958918 -358.178486) (xy 342.936279 -358.228061) (xy 342.906817 -358.27391) (xy 342.871129 -358.3151)
			(xy 342.829944 -358.350791) (xy 342.784098 -358.380259) (xy 342.734526 -358.402903) (xy 342.682235 -358.418262)
			(xy 342.628292 -358.426023) (xy 342.601042 -358.426512) (xy 342.573673 -358.426018) (xy 342.519495 -358.418207)
			(xy 342.466992 -358.402724) (xy 342.417245 -358.379888) (xy 342.371277 -358.35017) (xy 342.350344 -358.332532)
			(xy 342.343232 -358.326436) (xy 342.326214 -358.320086) (xy 342.24087 -358.320086) (xy 342.223852 -358.326436)
			(xy 342.21674 -358.332532) (xy 342.195807 -358.350173) (xy 342.149839 -358.379897) (xy 342.100093 -358.402743)
			(xy 342.047591 -358.418239) (xy 341.993413 -358.426068) (xy 341.938671 -358.426068) (xy 341.884493 -358.418239)
			(xy 341.831991 -358.402743) (xy 341.782245 -358.379897) (xy 341.736277 -358.350173) (xy 341.715344 -358.332532)
			(xy 341.708232 -358.326436) (xy 341.691214 -358.320086) (xy 341.60587 -358.320086) (xy 341.588852 -358.326436)
			(xy 341.58174 -358.332532) (xy 341.560807 -358.350173) (xy 341.514839 -358.379897) (xy 341.465093 -358.402743)
			(xy 341.412591 -358.418239) (xy 341.358413 -358.426068) (xy 341.303671 -358.426068) (xy 341.249493 -358.418239)
			(xy 341.196991 -358.402743) (xy 341.147245 -358.379897) (xy 341.101277 -358.350173) (xy 341.080344 -358.332532)
			(xy 341.073232 -358.326436) (xy 341.056214 -358.320086) (xy 340.97087 -358.320086) (xy 340.953852 -358.326436)
			(xy 340.94674 -358.332532) (xy 340.925808 -358.350171) (xy 340.879835 -358.379882) (xy 340.830087 -358.402717)
			(xy 340.777587 -358.418208) (xy 340.723411 -358.426037) (xy 340.696042 -358.426512) (xy 340.668787 -358.426044)
			(xy 340.614833 -358.418292) (xy 340.56253 -358.402939) (xy 340.512945 -358.380299) (xy 340.467087 -358.350833)
			(xy 340.42589 -358.31514) (xy 340.390192 -358.273946) (xy 340.360721 -358.228092) (xy 340.338075 -358.178509)
			(xy 340.322717 -358.126209) (xy 340.314959 -358.072254) (xy 340.030165 -358.072254) (xy 340.014814 -358.09047)
			(xy 340.008718 -358.097582) (xy 340.002368 -358.1146) (xy 340.002368 -358.199944) (xy 340.008718 -358.216962)
			(xy 340.014814 -358.224074) (xy 340.032457 -358.245003) (xy 340.062167 -358.290977) (xy 340.085002 -358.340725)
			(xy 340.100493 -358.393227) (xy 340.10832 -358.447403) (xy 340.108794 -358.474772) (xy 340.1083 -358.502884)
			(xy 340.100057 -358.558499) (xy 340.083744 -358.612304) (xy 340.059716 -358.663133) (xy 340.02849 -358.709888)
			(xy 340.009988 -358.731058) (xy 340.003384 -358.73817) (xy 339.99678 -358.754934) (xy 339.99551 -358.840786)
			(xy 340.001606 -358.857804) (xy 340.007702 -358.86517) (xy 340.024793 -358.885948) (xy 340.053555 -358.931414)
			(xy 340.075641 -358.980471) (xy 340.090613 -359.032146) (xy 340.098173 -359.085412) (xy 340.098634 -359.112312)
			(xy 340.098109 -359.141265) (xy 340.089351 -359.198505) (xy 340.072036 -359.253762) (xy 340.046565 -359.305765)
			(xy 340.013522 -359.353319) (xy 339.993986 -359.374694) (xy 339.987128 -359.38206) (xy 339.980016 -359.400348)
			(xy 339.981286 -359.491534) (xy 339.988906 -359.509568) (xy 339.996018 -359.51668) (xy 340.004582 -359.525305)
			(xy 340.020722 -359.543481) (xy 340.028276 -359.553002) (xy 340.035852 -359.561749) (xy 340.0566 -359.57194)
			(xy 340.068154 -359.57256) (xy 340.148418 -359.57256) (xy 340.159989 -359.572014) (xy 340.180761 -359.561803)
			(xy 340.188296 -359.553002) (xy 340.206705 -359.530327) (xy 340.249229 -359.490296) (xy 340.29736 -359.457215)
			(xy 340.323424 -359.444036) (xy 340.332822 -359.439464) (xy 340.346284 -359.423716) (xy 340.37524 -359.3338)
			(xy 340.373462 -359.313226) (xy 340.368382 -359.304082) (xy 340.353844 -359.27595) (xy 340.333234 -359.216076)
			(xy 340.322781 -359.153624) (xy 340.322154 -359.121964) (xy 340.322644 -359.094714) (xy 340.330405 -359.040768)
			(xy 340.345762 -358.988476) (xy 340.368405 -358.938901) (xy 340.397871 -358.893052) (xy 340.433562 -358.851864)
			(xy 340.474751 -358.816173) (xy 340.520599 -358.786706) (xy 340.570174 -358.764063) (xy 340.622466 -358.748705)
			(xy 340.676412 -358.740944) (xy 340.703662 -358.740456) (xy 340.731032 -358.740931) (xy 340.785211 -358.748744)
			(xy 340.837715 -358.764231) (xy 340.887462 -358.787071) (xy 340.933429 -358.816795) (xy 340.95436 -358.834436)
			(xy 340.961472 -358.840532) (xy 340.97849 -358.846882) (xy 341.063834 -358.846882) (xy 341.080852 -358.840532)
			(xy 341.087964 -358.834436) (xy 341.108897 -358.816795) (xy 341.154865 -358.787071) (xy 341.204611 -358.764225)
			(xy 341.257113 -358.748729) (xy 341.311291 -358.7409) (xy 341.366033 -358.7409) (xy 341.420211 -358.748729)
			(xy 341.472713 -358.764225) (xy 341.522459 -358.787071) (xy 341.568427 -358.816795) (xy 341.58936 -358.834436)
			(xy 341.596472 -358.840532) (xy 341.61349 -358.846882) (xy 341.698834 -358.846882) (xy 341.715852 -358.840532)
			(xy 341.722964 -358.834436) (xy 341.743897 -358.816795) (xy 341.789865 -358.787071) (xy 341.839611 -358.764225)
			(xy 341.892113 -358.748729) (xy 341.946291 -358.7409) (xy 342.001033 -358.7409) (xy 342.055211 -358.748729)
			(xy 342.107713 -358.764225) (xy 342.157459 -358.787071) (xy 342.203427 -358.816795) (xy 342.22436 -358.834436)
			(xy 342.231472 -358.840532) (xy 342.24849 -358.846882) (xy 342.333834 -358.846882) (xy 342.350852 -358.840532)
			(xy 342.357964 -358.834436) (xy 342.378903 -358.816806) (xy 342.424874 -358.787091) (xy 342.474619 -358.764253)
			(xy 342.527118 -358.74876) (xy 342.581293 -358.740931) (xy 342.608662 -358.740456) (xy 342.635912 -358.740991)
			(xy 342.689859 -358.748741) (xy 342.742153 -358.764091) (xy 342.791731 -358.786726) (xy 342.837582 -358.816187)
			(xy 342.878774 -358.851873) (xy 342.914469 -358.893058) (xy 342.943938 -358.938904) (xy 342.966583 -358.988477)
			(xy 342.981943 -359.040769) (xy 342.989704 -359.094714) (xy 342.99017 -359.121964) (xy 342.989735 -359.147938)
			(xy 342.982694 -359.199406) (xy 342.968738 -359.249444) (xy 342.948123 -359.297126) (xy 342.935052 -359.319576)
			(xy 342.929718 -359.328212) (xy 342.92667 -359.348278) (xy 342.949276 -359.43794) (xy 342.961214 -359.454196)
			(xy 342.970104 -359.45953) (xy 342.990317 -359.47195) (xy 343.027799 -359.501031) (xy 343.061396 -359.534525)
			(xy 343.076276 -359.553002) (xy 343.083852 -359.561749) (xy 343.1046 -359.57194) (xy 343.116154 -359.57256)
			(xy 343.196418 -359.57256) (xy 343.207989 -359.572014) (xy 343.228761 -359.561803) (xy 343.236296 -359.553002)
			(xy 343.243109 -359.544383) (xy 343.257596 -359.527862) (xy 343.265252 -359.519982) (xy 343.272364 -359.512616)
			(xy 343.279984 -359.494328) (xy 343.279984 -359.402888) (xy 343.272364 -359.3846) (xy 343.265252 -359.377234)
			(xy 343.244854 -359.3557) (xy 343.210314 -359.307482) (xy 343.183653 -359.254498) (xy 343.165516 -359.198027)
			(xy 343.156339 -359.139428) (xy 343.155778 -359.109772) (xy 343.156209 -359.0824) (xy 343.164032 -359.028219)
			(xy 343.179528 -358.975715) (xy 343.202379 -358.925968) (xy 343.232112 -358.880004) (xy 343.249758 -358.859074)
			(xy 343.255854 -358.851962) (xy 343.262204 -358.834944) (xy 343.262204 -358.7496) (xy 343.255854 -358.732582)
			(xy 343.249758 -358.72547) (xy 343.232089 -358.70456) (xy 343.202363 -358.658589) (xy 343.179517 -358.608839)
			(xy 343.164022 -358.556333) (xy 343.156195 -358.502151) (xy 343.156198 -358.447407) (xy 343.164031 -358.393225)
			(xy 343.179532 -358.340721) (xy 343.202383 -358.290974) (xy 343.232114 -358.245006) (xy 343.249758 -358.224074)
			(xy 343.255854 -358.216962) (xy 343.262204 -358.199944) (xy 343.262204 -358.1146) (xy 343.255854 -358.097582)
			(xy 343.249758 -358.09047) (xy 343.232131 -358.069528) (xy 343.202419 -358.023557) (xy 343.179581 -357.973812)
			(xy 343.164087 -357.921314) (xy 343.156254 -357.86714) (xy 343.155778 -357.839772) (xy 343.156252 -357.812521)
			(xy 343.164012 -357.758573) (xy 343.17937 -357.706279) (xy 343.202013 -357.656703) (xy 343.231481 -357.610853)
			(xy 343.267174 -357.569664) (xy 343.308364 -357.533973) (xy 343.354215 -357.504506) (xy 343.403792 -357.481865)
			(xy 343.456087 -357.466509) (xy 343.510035 -357.458751) (xy 343.537286 -357.458264) (xy 343.566204 -357.458768)
			(xy 343.623377 -357.467497) (xy 343.678577 -357.484756) (xy 343.730539 -357.51015) (xy 343.778072 -357.543097)
			(xy 343.820087 -357.582842) (xy 343.838276 -357.60533) (xy 343.845847 -357.614082) (xy 343.866599 -357.62427)
			(xy 343.878154 -357.624888) (xy 343.958418 -357.624888) (xy 343.969988 -357.624332) (xy 343.990759 -357.614128)
			(xy 343.998296 -357.60533) (xy 344.015049 -357.584547) (xy 344.053403 -357.547417) (xy 344.096557 -357.515995)
			(xy 344.143671 -357.490896) (xy 344.193823 -357.47261) (xy 344.246034 -357.461493) (xy 344.299286 -357.457763)
			(xy 344.352538 -357.461493) (xy 344.404749 -357.47261) (xy 344.454901 -357.490896) (xy 344.502015 -357.515995)
			(xy 344.545169 -357.547417) (xy 344.583523 -357.584547) (xy 344.600276 -357.60533) (xy 344.607847 -357.614082)
			(xy 344.628599 -357.62427) (xy 344.640154 -357.624888) (xy 344.720418 -357.624888) (xy 344.731988 -357.624332)
			(xy 344.752759 -357.614128) (xy 344.760296 -357.60533) (xy 344.778497 -357.582855) (xy 344.820514 -357.543118)
			(xy 344.868046 -357.510177) (xy 344.920006 -357.484787) (xy 344.975202 -357.467529) (xy 345.03237 -357.458799)
			(xy 345.061286 -357.458264) (xy 345.088536 -357.458791) (xy 345.14248 -357.466545) (xy 345.194773 -357.481897)
			(xy 345.244348 -357.504534) (xy 345.290197 -357.533997) (xy 345.331386 -357.569684) (xy 345.367078 -357.610869)
			(xy 345.396545 -357.656715) (xy 345.419188 -357.706288) (xy 345.434546 -357.758579) (xy 345.442306 -357.812522)
			(xy 345.442794 -357.839772) (xy 345.442313 -357.867142) (xy 345.434499 -357.92132) (xy 345.419013 -357.973823)
			(xy 345.396175 -358.02357) (xy 345.366454 -358.069538) (xy 345.348814 -358.09047) (xy 345.342718 -358.097582)
			(xy 345.336368 -358.1146) (xy 345.336368 -358.199944) (xy 345.342718 -358.216962) (xy 345.348814 -358.224074)
			(xy 345.366426 -358.24503) (xy 345.396148 -358.290995) (xy 345.418993 -358.340737) (xy 345.43449 -358.393235)
			(xy 345.44232 -358.44741) (xy 345.442323 -358.502148) (xy 345.434499 -358.556323) (xy 345.419008 -358.608823)
			(xy 345.396169 -358.658568) (xy 345.366451 -358.704536) (xy 345.348814 -358.72547) (xy 345.342718 -358.732582)
			(xy 345.336368 -358.7496) (xy 345.336368 -358.834944) (xy 345.342718 -358.851962) (xy 345.348814 -358.859074)
			(xy 345.366457 -358.880003) (xy 345.396167 -358.925977) (xy 345.419002 -358.975725) (xy 345.434493 -359.028227)
			(xy 345.44232 -359.082403) (xy 345.442794 -359.109772) (xy 345.442239 -359.139428) (xy 345.433051 -359.198023)
			(xy 345.414908 -359.254492) (xy 345.388247 -359.307474) (xy 345.35371 -359.355693) (xy 345.33332 -359.377234)
			(xy 345.326208 -359.3846) (xy 345.318588 -359.402888) (xy 345.318588 -359.494328) (xy 345.326208 -359.512616)
			(xy 345.33332 -359.519982) (xy 345.353721 -359.541514) (xy 345.388262 -359.589732) (xy 345.414922 -359.642716)
			(xy 345.433059 -359.699188) (xy 345.442234 -359.757787) (xy 345.442794 -359.787444) (xy 345.442363 -359.814697)
			(xy 345.4346 -359.868647) (xy 345.419239 -359.920944) (xy 345.396592 -359.970522) (xy 345.367119 -360.016373)
			(xy 345.331422 -360.057563) (xy 345.290227 -360.093254) (xy 345.244371 -360.122719) (xy 345.19479 -360.145359)
			(xy 345.142491 -360.160713) (xy 345.088539 -360.168467) (xy 345.061286 -360.168952) (xy 345.03237 -360.16839)
			(xy 344.975201 -360.159673) (xy 344.920002 -360.142424) (xy 344.86804 -360.117041) (xy 344.820505 -360.084104)
			(xy 344.778487 -360.044369) (xy 344.760296 -360.021886) (xy 344.752734 -360.013125) (xy 344.731975 -360.002942)
			(xy 344.720418 -360.002328) (xy 344.640154 -360.002328) (xy 344.628589 -360.00292) (xy 344.607817 -360.013098)
			(xy 344.600276 -360.021886) (xy 344.588084 -360.036618) (xy 344.581988 -360.04373) (xy 344.575638 -360.061256)
			(xy 344.576908 -360.147616) (xy 344.583766 -360.164888) (xy 344.59037 -360.171746) (xy 344.609168 -360.19302)
			(xy 344.640975 -360.240039) (xy 344.665456 -360.291255) (xy 344.682071 -360.345536) (xy 344.690451 -360.40168)
			(xy 344.690954 -360.430064) (xy 344.690388 -360.457312) (xy 344.682638 -360.511255) (xy 344.66729 -360.563545)
			(xy 344.644656 -360.613119) (xy 344.615198 -360.658967) (xy 344.579515 -360.700157) (xy 344.538333 -360.735849)
			(xy 344.492491 -360.765317) (xy 344.442922 -360.787961) (xy 344.390635 -360.803321) (xy 344.336694 -360.811083)
			(xy 344.309446 -360.811572) (xy 344.28053 -360.811031) (xy 344.223359 -360.802308) (xy 344.16816 -360.785056)
			(xy 344.116198 -360.759668) (xy 344.068664 -360.726728) (xy 344.026646 -360.68699) (xy 344.008456 -360.664506)
			(xy 344.000908 -360.65573) (xy 343.980139 -360.645554) (xy 343.968578 -360.644948) (xy 343.888314 -360.644948)
			(xy 343.876745 -360.64551) (xy 343.855973 -360.655709) (xy 343.848436 -360.664506) (xy 343.836244 -360.679492)
			(xy 343.830148 -360.68635) (xy 343.823798 -360.703876) (xy 343.824814 -360.789728) (xy 343.831418 -360.807)
			(xy 343.837768 -360.814112) (xy 343.856251 -360.835263) (xy 343.887441 -360.881978) (xy 343.911455 -360.932756)
			(xy 343.927775 -360.986503) (xy 343.936051 -361.04206) (xy 343.936574 -361.070144) (xy 343.936163 -361.097398)
			(xy 343.9284 -361.15135) (xy 343.913037 -361.203648) (xy 343.890388 -361.253228) (xy 343.860914 -361.29908)
			(xy 343.825215 -361.34027) (xy 343.784017 -361.375961) (xy 343.738159 -361.405426) (xy 343.688575 -361.428064)
			(xy 343.636274 -361.443416) (xy 343.58232 -361.451169) (xy 343.555066 -361.451652) (xy 343.52615 -361.451104)
			(xy 343.468979 -361.442384) (xy 343.41378 -361.425133) (xy 343.361818 -361.399747) (xy 343.314284 -361.366807)
			(xy 343.272267 -361.32707) (xy 343.254076 -361.304586) (xy 343.246522 -361.295816) (xy 343.225757 -361.285637)
			(xy 343.214198 -361.285028) (xy 343.133934 -361.285028) (xy 343.122367 -361.285608) (xy 343.101596 -361.295795)
			(xy 343.094056 -361.304586) (xy 343.077303 -361.325369) (xy 343.038949 -361.362499) (xy 342.995795 -361.393921)
			(xy 342.948681 -361.41902) (xy 342.898529 -361.437306) (xy 342.846318 -361.448423) (xy 342.793066 -361.452153)
			(xy 342.739814 -361.448423) (xy 342.687603 -361.437306) (xy 342.637451 -361.41902) (xy 342.590337 -361.393921)
			(xy 342.547183 -361.362499) (xy 342.508829 -361.325369) (xy 342.492076 -361.304586) (xy 342.484522 -361.295816)
			(xy 342.463757 -361.285637) (xy 342.452198 -361.285028) (xy 342.371934 -361.285028) (xy 342.360367 -361.285608)
			(xy 342.339596 -361.295795) (xy 342.332056 -361.304586) (xy 342.315303 -361.325369) (xy 342.276949 -361.362499)
			(xy 342.233795 -361.393921) (xy 342.186681 -361.41902) (xy 342.136529 -361.437306) (xy 342.084318 -361.448423)
			(xy 342.031066 -361.452153) (xy 341.977814 -361.448423) (xy 341.925603 -361.437306) (xy 341.875451 -361.41902)
			(xy 341.828337 -361.393921) (xy 341.785183 -361.362499) (xy 341.746829 -361.325369) (xy 341.730076 -361.304586)
			(xy 341.722522 -361.295816) (xy 341.701757 -361.285637) (xy 341.690198 -361.285028) (xy 341.609934 -361.285028)
			(xy 341.598367 -361.285608) (xy 341.577596 -361.295795) (xy 341.570056 -361.304586) (xy 341.553303 -361.325369)
			(xy 341.514949 -361.362499) (xy 341.471795 -361.393921) (xy 341.424681 -361.41902) (xy 341.374529 -361.437306)
			(xy 341.322318 -361.448423) (xy 341.269066 -361.452153) (xy 341.215814 -361.448423) (xy 341.163603 -361.437306)
			(xy 341.113451 -361.41902) (xy 341.066337 -361.393921) (xy 341.023183 -361.362499) (xy 340.984829 -361.325369)
			(xy 340.968076 -361.304586) (xy 340.960522 -361.295816) (xy 340.939757 -361.285637) (xy 340.928198 -361.285028)
			(xy 340.847934 -361.285028) (xy 340.836367 -361.285608) (xy 340.815596 -361.295795) (xy 340.808056 -361.304586)
			(xy 340.791303 -361.325369) (xy 340.752949 -361.362499) (xy 340.709795 -361.393921) (xy 340.662681 -361.41902)
			(xy 340.612529 -361.437306) (xy 340.560318 -361.448423) (xy 340.507066 -361.452153) (xy 340.453814 -361.448423)
			(xy 340.401603 -361.437306) (xy 340.351451 -361.41902) (xy 340.304337 -361.393921) (xy 340.261183 -361.362499)
			(xy 340.222829 -361.325369) (xy 340.206076 -361.304586) (xy 340.198522 -361.295816) (xy 340.177757 -361.285637)
			(xy 340.166198 -361.285028) (xy 340.085934 -361.285028) (xy 340.074367 -361.285608) (xy 340.053596 -361.295795)
			(xy 340.046056 -361.304586) (xy 340.029303 -361.325369) (xy 339.990949 -361.362499) (xy 339.947795 -361.393921)
			(xy 339.900681 -361.41902) (xy 339.850529 -361.437306) (xy 339.798318 -361.448423) (xy 339.745066 -361.452153)
			(xy 339.691814 -361.448423) (xy 339.639603 -361.437306) (xy 339.589451 -361.41902) (xy 339.542337 -361.393921)
			(xy 339.499183 -361.362499) (xy 339.460829 -361.325369) (xy 339.444076 -361.304586) (xy 339.436522 -361.295816)
			(xy 339.415757 -361.285637) (xy 339.404198 -361.285028) (xy 339.323934 -361.285028) (xy 339.312367 -361.285608)
			(xy 339.291596 -361.295795) (xy 339.284056 -361.304586) (xy 339.267303 -361.325369) (xy 339.228949 -361.362499)
			(xy 339.185795 -361.393921) (xy 339.138681 -361.41902) (xy 339.088529 -361.437306) (xy 339.036318 -361.448423)
			(xy 338.983066 -361.452153) (xy 338.929814 -361.448423) (xy 338.877603 -361.437306) (xy 338.827451 -361.41902)
			(xy 338.780337 -361.393921) (xy 338.737183 -361.362499) (xy 338.698829 -361.325369) (xy 338.682076 -361.304586)
			(xy 338.674522 -361.295816) (xy 338.653757 -361.285637) (xy 338.642198 -361.285028) (xy 338.561934 -361.285028)
			(xy 338.550367 -361.285608) (xy 338.529596 -361.295795) (xy 338.522056 -361.304586) (xy 338.503886 -361.327088)
			(xy 338.461863 -361.366822) (xy 338.414323 -361.39976) (xy 338.362358 -361.425145) (xy 338.307156 -361.442397)
			(xy 338.249983 -361.45112) (xy 338.221066 -361.451652) (xy 338.192139 -361.451095) (xy 338.134949 -361.442348)
			(xy 338.079737 -361.425061) (xy 338.027772 -361.399629) (xy 337.980246 -361.366638) (xy 337.93825 -361.326844)
			(xy 337.920076 -361.304332) (xy 337.91271 -361.295188) (xy 337.89239 -361.285028) (xy 337.78952 -361.283504)
			(xy 337.768692 -361.293156) (xy 337.761326 -361.3023) (xy 337.743109 -361.323664) (xy 337.701484 -361.361338)
			(xy 337.654786 -361.392503) (xy 337.604023 -361.416485) (xy 337.550294 -361.432766) (xy 337.494757 -361.440995)
			(xy 337.466686 -361.441492) (xy 337.437771 -361.440915) (xy 337.380603 -361.432199) (xy 337.325405 -361.414953)
			(xy 337.273443 -361.389572) (xy 337.225907 -361.356639) (xy 337.183888 -361.316907) (xy 337.165696 -361.294426)
			(xy 337.158144 -361.285654) (xy 337.137377 -361.275479) (xy 337.125818 -361.274868) (xy 337.045554 -361.274868)
			(xy 337.033987 -361.275446) (xy 337.013214 -361.285633) (xy 337.005676 -361.294426) (xy 336.988923 -361.315209)
			(xy 336.950569 -361.352339) (xy 336.907415 -361.383761) (xy 336.860301 -361.40886) (xy 336.810149 -361.427146)
			(xy 336.757938 -361.438263) (xy 336.704686 -361.441993) (xy 336.651434 -361.438263) (xy 336.599223 -361.427146)
			(xy 336.549071 -361.40886) (xy 336.501957 -361.383761) (xy 336.458803 -361.352339) (xy 336.420449 -361.315209)
			(xy 336.403696 -361.294426) (xy 336.396144 -361.285654) (xy 336.375377 -361.275479) (xy 336.363818 -361.274868)
			(xy 336.283554 -361.274868) (xy 336.271987 -361.275446) (xy 336.251214 -361.285633) (xy 336.243676 -361.294426)
			(xy 336.225505 -361.316926) (xy 336.18348 -361.356659) (xy 336.135941 -361.389596) (xy 336.083976 -361.414981)
			(xy 336.028775 -361.432234) (xy 335.971603 -361.440959) (xy 335.942686 -361.441492) (xy 335.915432 -361.441058)
			(xy 335.861479 -361.433299) (xy 335.80918 -361.41794) (xy 335.759598 -361.395295) (xy 335.713745 -361.365824)
			(xy 335.672552 -361.330127) (xy 335.636858 -361.288931) (xy 335.607391 -361.243075) (xy 335.584749 -361.193492)
			(xy 335.569395 -361.141191) (xy 335.56164 -361.087238) (xy 335.561178 -361.059984) (xy 335.561627 -361.032788)
			(xy 335.569312 -360.978943) (xy 335.584579 -360.926739) (xy 335.607118 -360.877238) (xy 335.63647 -360.831447)
			(xy 335.653888 -360.810556) (xy 335.659984 -360.803698) (xy 335.666334 -360.786172) (xy 335.665318 -360.70032)
			(xy 335.658714 -360.683048) (xy 335.652364 -360.675936) (xy 335.633861 -360.654801) (xy 335.602673 -360.608082)
			(xy 335.578663 -360.5573) (xy 335.562347 -360.50355) (xy 335.554077 -360.44799) (xy 335.553558 -360.419904)
			(xy 335.554016 -360.392735) (xy 335.561743 -360.338949) (xy 335.577025 -360.286804) (xy 335.599554 -360.237356)
			(xy 335.628874 -360.191607) (xy 335.646268 -360.17073) (xy 335.652364 -360.163618) (xy 335.658714 -360.146092)
			(xy 335.657444 -360.059732) (xy 335.650586 -360.04246) (xy 335.643982 -360.035602) (xy 335.625151 -360.014356)
			(xy 335.593351 -359.967329) (xy 335.568877 -359.916105) (xy 335.552269 -359.861819) (xy 335.543897 -359.805669)
			(xy 335.543398 -359.777284) (xy 335.543939 -359.748332) (xy 335.552696 -359.691093) (xy 335.570008 -359.635837)
			(xy 335.595475 -359.583834) (xy 335.628512 -359.536279) (xy 335.648046 -359.514902) (xy 335.654904 -359.507536)
			(xy 335.662016 -359.489248) (xy 335.660746 -359.398062) (xy 335.653126 -359.380028) (xy 335.646014 -359.372916)
			(xy 335.625019 -359.351305) (xy 335.589452 -359.302673) (xy 335.561974 -359.249053) (xy 335.54327 -359.191779)
			(xy 335.533803 -359.132277) (xy 335.533238 -359.102152) (xy 318.661737 -359.102152) (xy 318.660279 -359.112062)
			(xy 318.644211 -359.165469) (xy 318.620539 -359.215966) (xy 318.589766 -359.262479) (xy 318.552549 -359.304016)
			(xy 318.509681 -359.339691) (xy 318.462075 -359.368745) (xy 318.410746 -359.390557) (xy 318.356789 -359.404663)
			(xy 318.301352 -359.410763) (xy 318.245618 -359.408726) (xy 318.190775 -359.398596) (xy 318.137991 -359.380589)
			(xy 318.088391 -359.355088) (xy 318.043033 -359.322637) (xy 318.002884 -359.283928) (xy 317.968798 -359.239785)
			(xy 317.941502 -359.19115) (xy 317.921579 -359.139059) (xy 317.909453 -359.084622) (xy 317.905382 -359.029)
			(xy 316.497208 -359.029) (xy 316.497208 -359.650284) (xy 316.496695 -359.675583) (xy 316.488315 -359.725483)
			(xy 316.471815 -359.773316) (xy 316.447647 -359.81777) (xy 316.416475 -359.857627) (xy 316.398148 -359.875074)
			(xy 316.387319 -359.885572) (xy 316.370485 -359.910589) (xy 316.367735 -359.918) (xy 319.046858 -359.918)
			(xy 319.050929 -359.862378) (xy 319.063055 -359.807941) (xy 319.082978 -359.75585) (xy 319.110274 -359.707215)
			(xy 319.14436 -359.663072) (xy 319.184509 -359.624363) (xy 319.229867 -359.591912) (xy 319.279467 -359.566411)
			(xy 319.332251 -359.548404) (xy 319.387094 -359.538274) (xy 319.442828 -359.536237) (xy 319.498265 -359.542337)
			(xy 319.552222 -359.556443) (xy 319.603551 -359.578255) (xy 319.651157 -359.607309) (xy 319.694025 -359.642984)
			(xy 319.731242 -359.684521) (xy 319.762015 -359.731034) (xy 319.785687 -359.781531) (xy 319.801755 -359.834938)
			(xy 319.809875 -359.890114) (xy 319.810384 -359.918) (xy 319.809875 -359.945886) (xy 319.801755 -360.001062)
			(xy 319.785687 -360.054469) (xy 319.762015 -360.104966) (xy 319.731242 -360.151479) (xy 319.694025 -360.193016)
			(xy 319.651157 -360.228691) (xy 319.603551 -360.257745) (xy 319.552222 -360.279557) (xy 319.498265 -360.293663)
			(xy 319.442828 -360.299763) (xy 319.387094 -360.297726) (xy 319.332251 -360.287596) (xy 319.279467 -360.269589)
			(xy 319.229867 -360.244088) (xy 319.184509 -360.211637) (xy 319.14436 -360.172928) (xy 319.110274 -360.128785)
			(xy 319.082978 -360.08015) (xy 319.063055 -360.028059) (xy 319.050929 -359.973622) (xy 319.046858 -359.918)
			(xy 316.367735 -359.918) (xy 316.359994 -359.938858) (xy 316.35643 -359.9688) (xy 316.359994 -359.998742)
			(xy 316.370485 -360.027011) (xy 316.387319 -360.052028) (xy 316.398148 -360.062526) (xy 316.416459 -360.079986)
			(xy 316.447608 -360.119852) (xy 316.471764 -360.164305) (xy 316.488266 -360.21213) (xy 316.496663 -360.262021)
			(xy 316.497208 -360.287316) (xy 316.497208 -360.361992) (xy 322.46265 -360.361992) (xy 322.466721 -360.30637)
			(xy 322.478847 -360.251933) (xy 322.49877 -360.199842) (xy 322.526066 -360.151207) (xy 322.560152 -360.107064)
			(xy 322.600301 -360.068355) (xy 322.645659 -360.035904) (xy 322.695259 -360.010403) (xy 322.748043 -359.992396)
			(xy 322.802886 -359.982266) (xy 322.85862 -359.980229) (xy 322.914057 -359.986329) (xy 322.968014 -360.000435)
			(xy 323.019343 -360.022247) (xy 323.066949 -360.051301) (xy 323.109817 -360.086976) (xy 323.147034 -360.128513)
			(xy 323.177807 -360.175026) (xy 323.201479 -360.225523) (xy 323.217547 -360.27893) (xy 323.225667 -360.334106)
			(xy 323.226176 -360.361992) (xy 323.225667 -360.389878) (xy 323.217547 -360.445054) (xy 323.201479 -360.498461)
			(xy 323.177807 -360.548958) (xy 323.147034 -360.595471) (xy 323.109817 -360.637008) (xy 323.066949 -360.672683)
			(xy 323.019343 -360.701737) (xy 322.968014 -360.723549) (xy 322.914057 -360.737655) (xy 322.85862 -360.743755)
			(xy 322.802886 -360.741718) (xy 322.748043 -360.731588) (xy 322.695259 -360.713581) (xy 322.645659 -360.68808)
			(xy 322.600301 -360.655629) (xy 322.560152 -360.61692) (xy 322.526066 -360.572777) (xy 322.49877 -360.524142)
			(xy 322.478847 -360.472051) (xy 322.466721 -360.417614) (xy 322.46265 -360.361992) (xy 316.497208 -360.361992)
			(xy 316.497208 -361.598718) (xy 321.434966 -361.598718) (xy 321.439037 -361.543096) (xy 321.451163 -361.488659)
			(xy 321.471086 -361.436568) (xy 321.498382 -361.387933) (xy 321.532468 -361.34379) (xy 321.572617 -361.305081)
			(xy 321.617975 -361.27263) (xy 321.667575 -361.247129) (xy 321.720359 -361.229122) (xy 321.775202 -361.218992)
			(xy 321.830936 -361.216955) (xy 321.886373 -361.223055) (xy 321.94033 -361.237161) (xy 321.991659 -361.258973)
			(xy 322.039265 -361.288027) (xy 322.082133 -361.323702) (xy 322.11935 -361.365239) (xy 322.150123 -361.411752)
			(xy 322.173795 -361.462249) (xy 322.175345 -361.4674) (xy 326.668382 -361.4674) (xy 326.672453 -361.411778)
			(xy 326.684579 -361.357341) (xy 326.704502 -361.30525) (xy 326.731798 -361.256615) (xy 326.765884 -361.212472)
			(xy 326.806033 -361.173763) (xy 326.851391 -361.141312) (xy 326.900991 -361.115811) (xy 326.953775 -361.097804)
			(xy 327.008618 -361.087674) (xy 327.064352 -361.085637) (xy 327.119789 -361.091737) (xy 327.173746 -361.105843)
			(xy 327.225075 -361.127655) (xy 327.240715 -361.1372) (xy 328.725782 -361.1372) (xy 328.729853 -361.081578)
			(xy 328.741979 -361.027141) (xy 328.761902 -360.97505) (xy 328.789198 -360.926415) (xy 328.823284 -360.882272)
			(xy 328.863433 -360.843563) (xy 328.908791 -360.811112) (xy 328.958391 -360.785611) (xy 329.011175 -360.767604)
			(xy 329.066018 -360.757474) (xy 329.121752 -360.755437) (xy 329.177189 -360.761537) (xy 329.231146 -360.775643)
			(xy 329.282475 -360.797455) (xy 329.330081 -360.826509) (xy 329.372949 -360.862184) (xy 329.410166 -360.903721)
			(xy 329.440939 -360.950234) (xy 329.464611 -361.000731) (xy 329.480679 -361.054138) (xy 329.488799 -361.109314)
			(xy 329.489308 -361.1372) (xy 330.021182 -361.1372) (xy 330.025253 -361.081578) (xy 330.037379 -361.027141)
			(xy 330.057302 -360.97505) (xy 330.084598 -360.926415) (xy 330.118684 -360.882272) (xy 330.158833 -360.843563)
			(xy 330.204191 -360.811112) (xy 330.253791 -360.785611) (xy 330.306575 -360.767604) (xy 330.361418 -360.757474)
			(xy 330.417152 -360.755437) (xy 330.472589 -360.761537) (xy 330.526546 -360.775643) (xy 330.577875 -360.797455)
			(xy 330.625481 -360.826509) (xy 330.668349 -360.862184) (xy 330.705566 -360.903721) (xy 330.736339 -360.950234)
			(xy 330.760011 -361.000731) (xy 330.776079 -361.054138) (xy 330.784199 -361.109314) (xy 330.784708 -361.1372)
			(xy 330.784199 -361.165086) (xy 330.776079 -361.220262) (xy 330.760011 -361.273669) (xy 330.736339 -361.324166)
			(xy 330.705566 -361.370679) (xy 330.668349 -361.412216) (xy 330.625481 -361.447891) (xy 330.577875 -361.476945)
			(xy 330.526546 -361.498757) (xy 330.472589 -361.512863) (xy 330.417152 -361.518963) (xy 330.361418 -361.516926)
			(xy 330.306575 -361.506796) (xy 330.253791 -361.488789) (xy 330.204191 -361.463288) (xy 330.158833 -361.430837)
			(xy 330.118684 -361.392128) (xy 330.084598 -361.347985) (xy 330.057302 -361.29935) (xy 330.037379 -361.247259)
			(xy 330.025253 -361.192822) (xy 330.021182 -361.1372) (xy 329.489308 -361.1372) (xy 329.488799 -361.165086)
			(xy 329.480679 -361.220262) (xy 329.464611 -361.273669) (xy 329.440939 -361.324166) (xy 329.410166 -361.370679)
			(xy 329.372949 -361.412216) (xy 329.330081 -361.447891) (xy 329.282475 -361.476945) (xy 329.231146 -361.498757)
			(xy 329.177189 -361.512863) (xy 329.121752 -361.518963) (xy 329.066018 -361.516926) (xy 329.011175 -361.506796)
			(xy 328.958391 -361.488789) (xy 328.908791 -361.463288) (xy 328.863433 -361.430837) (xy 328.823284 -361.392128)
			(xy 328.789198 -361.347985) (xy 328.761902 -361.29935) (xy 328.741979 -361.247259) (xy 328.729853 -361.192822)
			(xy 328.725782 -361.1372) (xy 327.240715 -361.1372) (xy 327.272681 -361.156709) (xy 327.315549 -361.192384)
			(xy 327.352766 -361.233921) (xy 327.383539 -361.280434) (xy 327.407211 -361.330931) (xy 327.423279 -361.384338)
			(xy 327.431399 -361.439514) (xy 327.431908 -361.4674) (xy 327.431399 -361.495286) (xy 327.423279 -361.550462)
			(xy 327.407211 -361.603869) (xy 327.383539 -361.654366) (xy 327.352766 -361.700879) (xy 327.315549 -361.742416)
			(xy 327.272681 -361.778091) (xy 327.225075 -361.807145) (xy 327.173746 -361.828957) (xy 327.119789 -361.843063)
			(xy 327.064352 -361.849163) (xy 327.008618 -361.847126) (xy 326.953775 -361.836996) (xy 326.900991 -361.818989)
			(xy 326.851391 -361.793488) (xy 326.806033 -361.761037) (xy 326.765884 -361.722328) (xy 326.731798 -361.678185)
			(xy 326.704502 -361.62955) (xy 326.684579 -361.577459) (xy 326.672453 -361.523022) (xy 326.668382 -361.4674)
			(xy 322.175345 -361.4674) (xy 322.189863 -361.515656) (xy 322.197983 -361.570832) (xy 322.198492 -361.598718)
			(xy 322.197983 -361.626604) (xy 322.189863 -361.68178) (xy 322.173795 -361.735187) (xy 322.150123 -361.785684)
			(xy 322.11935 -361.832197) (xy 322.082133 -361.873734) (xy 322.039265 -361.909409) (xy 321.991659 -361.938463)
			(xy 321.94033 -361.960275) (xy 321.886373 -361.974381) (xy 321.830936 -361.980481) (xy 321.775202 -361.978444)
			(xy 321.720359 -361.968314) (xy 321.667575 -361.950307) (xy 321.617975 -361.924806) (xy 321.572617 -361.892355)
			(xy 321.532468 -361.853646) (xy 321.498382 -361.809503) (xy 321.471086 -361.760868) (xy 321.451163 -361.708777)
			(xy 321.439037 -361.65434) (xy 321.434966 -361.598718) (xy 316.497208 -361.598718) (xy 316.497208 -362.788962)
			(xy 320.244722 -362.788962) (xy 320.248793 -362.73334) (xy 320.260919 -362.678903) (xy 320.280842 -362.626812)
			(xy 320.308138 -362.578177) (xy 320.342224 -362.534034) (xy 320.382373 -362.495325) (xy 320.427731 -362.462874)
			(xy 320.477331 -362.437373) (xy 320.530115 -362.419366) (xy 320.584958 -362.409236) (xy 320.640692 -362.407199)
			(xy 320.696129 -362.413299) (xy 320.750086 -362.427405) (xy 320.801415 -362.449217) (xy 320.849021 -362.478271)
			(xy 320.891889 -362.513946) (xy 320.929106 -362.555483) (xy 320.959879 -362.601996) (xy 320.963819 -362.6104)
			(xy 326.668382 -362.6104) (xy 326.672453 -362.554778) (xy 326.684579 -362.500341) (xy 326.704502 -362.44825)
			(xy 326.731798 -362.399615) (xy 326.765884 -362.355472) (xy 326.806033 -362.316763) (xy 326.851391 -362.284312)
			(xy 326.900991 -362.258811) (xy 326.953775 -362.240804) (xy 327.008618 -362.230674) (xy 327.064352 -362.228637)
			(xy 327.119789 -362.234737) (xy 327.173746 -362.248843) (xy 327.225075 -362.270655) (xy 327.272681 -362.299709)
			(xy 327.315549 -362.335384) (xy 327.352766 -362.376921) (xy 327.383539 -362.423434) (xy 327.407211 -362.473931)
			(xy 327.423279 -362.527338) (xy 327.431399 -362.582514) (xy 327.431908 -362.6104) (xy 327.431444 -362.6358)
			(xy 328.801982 -362.6358) (xy 328.806053 -362.580178) (xy 328.818179 -362.525741) (xy 328.838102 -362.47365)
			(xy 328.865398 -362.425015) (xy 328.899484 -362.380872) (xy 328.939633 -362.342163) (xy 328.984991 -362.309712)
			(xy 329.034591 -362.284211) (xy 329.087375 -362.266204) (xy 329.142218 -362.256074) (xy 329.197952 -362.254037)
			(xy 329.253389 -362.260137) (xy 329.307346 -362.274243) (xy 329.358675 -362.296055) (xy 329.406281 -362.325109)
			(xy 329.449149 -362.360784) (xy 329.486366 -362.402321) (xy 329.517139 -362.448834) (xy 329.540811 -362.499331)
			(xy 329.556879 -362.552738) (xy 329.564999 -362.607914) (xy 329.565508 -362.6358) (xy 330.300582 -362.6358)
			(xy 330.304653 -362.580178) (xy 330.316779 -362.525741) (xy 330.336702 -362.47365) (xy 330.363998 -362.425015)
			(xy 330.398084 -362.380872) (xy 330.438233 -362.342163) (xy 330.483591 -362.309712) (xy 330.533191 -362.284211)
			(xy 330.585975 -362.266204) (xy 330.640818 -362.256074) (xy 330.696552 -362.254037) (xy 330.751989 -362.260137)
			(xy 330.805946 -362.274243) (xy 330.857275 -362.296055) (xy 330.904881 -362.325109) (xy 330.947749 -362.360784)
			(xy 330.984966 -362.402321) (xy 331.015739 -362.448834) (xy 331.039411 -362.499331) (xy 331.055479 -362.552738)
			(xy 331.063599 -362.607914) (xy 331.064108 -362.6358) (xy 331.063599 -362.663686) (xy 331.055479 -362.718862)
			(xy 331.039411 -362.772269) (xy 331.015739 -362.822766) (xy 330.984966 -362.869279) (xy 330.947749 -362.910816)
			(xy 330.904881 -362.946491) (xy 330.857275 -362.975545) (xy 330.805946 -362.997357) (xy 330.751989 -363.011463)
			(xy 330.696552 -363.017563) (xy 330.640818 -363.015526) (xy 330.585975 -363.005396) (xy 330.533191 -362.987389)
			(xy 330.483591 -362.961888) (xy 330.438233 -362.929437) (xy 330.398084 -362.890728) (xy 330.363998 -362.846585)
			(xy 330.336702 -362.79795) (xy 330.316779 -362.745859) (xy 330.304653 -362.691422) (xy 330.300582 -362.6358)
			(xy 329.565508 -362.6358) (xy 329.564999 -362.663686) (xy 329.556879 -362.718862) (xy 329.540811 -362.772269)
			(xy 329.517139 -362.822766) (xy 329.486366 -362.869279) (xy 329.449149 -362.910816) (xy 329.406281 -362.946491)
			(xy 329.358675 -362.975545) (xy 329.307346 -362.997357) (xy 329.253389 -363.011463) (xy 329.197952 -363.017563)
			(xy 329.142218 -363.015526) (xy 329.087375 -363.005396) (xy 329.034591 -362.987389) (xy 328.984991 -362.961888)
			(xy 328.939633 -362.929437) (xy 328.899484 -362.890728) (xy 328.865398 -362.846585) (xy 328.838102 -362.79795)
			(xy 328.818179 -362.745859) (xy 328.806053 -362.691422) (xy 328.801982 -362.6358) (xy 327.431444 -362.6358)
			(xy 327.431399 -362.638286) (xy 327.423279 -362.693462) (xy 327.407211 -362.746869) (xy 327.383539 -362.797366)
			(xy 327.352766 -362.843879) (xy 327.315549 -362.885416) (xy 327.272681 -362.921091) (xy 327.225075 -362.950145)
			(xy 327.173746 -362.971957) (xy 327.119789 -362.986063) (xy 327.064352 -362.992163) (xy 327.008618 -362.990126)
			(xy 326.953775 -362.979996) (xy 326.900991 -362.961989) (xy 326.851391 -362.936488) (xy 326.806033 -362.904037)
			(xy 326.765884 -362.865328) (xy 326.731798 -362.821185) (xy 326.704502 -362.77255) (xy 326.684579 -362.720459)
			(xy 326.672453 -362.666022) (xy 326.668382 -362.6104) (xy 320.963819 -362.6104) (xy 320.983551 -362.652493)
			(xy 320.999619 -362.7059) (xy 321.007739 -362.761076) (xy 321.008248 -362.788962) (xy 321.007739 -362.816848)
			(xy 320.999619 -362.872024) (xy 320.983551 -362.925431) (xy 320.959879 -362.975928) (xy 320.929106 -363.022441)
			(xy 320.891889 -363.063978) (xy 320.849021 -363.099653) (xy 320.801415 -363.128707) (xy 320.750086 -363.150519)
			(xy 320.696129 -363.164625) (xy 320.640692 -363.170725) (xy 320.584958 -363.168688) (xy 320.530115 -363.158558)
			(xy 320.477331 -363.140551) (xy 320.427731 -363.11505) (xy 320.382373 -363.082599) (xy 320.342224 -363.04389)
			(xy 320.308138 -362.999747) (xy 320.280842 -362.951112) (xy 320.260919 -362.899021) (xy 320.248793 -362.844584)
			(xy 320.244722 -362.788962) (xy 316.497208 -362.788962) (xy 316.497208 -363.23905) (xy 318.698878 -363.23905)
			(xy 318.702949 -363.183428) (xy 318.715075 -363.128991) (xy 318.734998 -363.0769) (xy 318.762294 -363.028265)
			(xy 318.79638 -362.984122) (xy 318.836529 -362.945413) (xy 318.881887 -362.912962) (xy 318.931487 -362.887461)
			(xy 318.984271 -362.869454) (xy 319.039114 -362.859324) (xy 319.094848 -362.857287) (xy 319.150285 -362.863387)
			(xy 319.204242 -362.877493) (xy 319.255571 -362.899305) (xy 319.303177 -362.928359) (xy 319.346045 -362.964034)
			(xy 319.383262 -363.005571) (xy 319.414035 -363.052084) (xy 319.437707 -363.102581) (xy 319.453775 -363.155988)
			(xy 319.461895 -363.211164) (xy 319.462404 -363.23905) (xy 319.461895 -363.266936) (xy 319.453775 -363.322112)
			(xy 319.437707 -363.375519) (xy 319.414035 -363.426016) (xy 319.383262 -363.472529) (xy 319.346045 -363.514066)
			(xy 319.303177 -363.549741) (xy 319.255571 -363.578795) (xy 319.204242 -363.600607) (xy 319.150285 -363.614713)
			(xy 319.094848 -363.620813) (xy 319.039114 -363.618776) (xy 318.984271 -363.608646) (xy 318.931487 -363.590639)
			(xy 318.881887 -363.565138) (xy 318.836529 -363.532687) (xy 318.79638 -363.493978) (xy 318.762294 -363.449835)
			(xy 318.734998 -363.4012) (xy 318.715075 -363.349109) (xy 318.702949 -363.294672) (xy 318.698878 -363.23905)
			(xy 316.497208 -363.23905) (xy 316.497208 -363.741208) (xy 316.497698 -363.751214) (xy 316.505359 -363.769702)
			(xy 316.519512 -363.78385) (xy 316.538002 -363.791506) (xy 316.548008 -363.792008) (xy 321.431158 -363.792008)
			(xy 321.441223 -363.792442) (xy 321.459812 -363.800172) (xy 321.467226 -363.806994) (xy 321.473068 -363.812836)
			(xy 323.748146 -363.812836) (xy 323.757933 -363.812389) (xy 323.776088 -363.805074) (xy 323.783452 -363.798612)
			(xy 323.841618 -363.742478) (xy 323.849492 -363.724952) (xy 323.849746 -363.714792) (xy 323.851112 -363.688174)
			(xy 323.860354 -363.635682) (xy 323.876813 -363.584987) (xy 323.900168 -363.537078) (xy 323.929965 -363.492885)
			(xy 323.965624 -363.453271) (xy 324.006449 -363.419005) (xy 324.051646 -363.390757) (xy 324.100336 -363.369074)
			(xy 324.15157 -363.35438) (xy 324.20435 -363.346961) (xy 324.231 -363.346492) (xy 324.259362 -363.347002)
			(xy 324.315464 -363.35538) (xy 324.369709 -363.371966) (xy 324.420903 -363.396394) (xy 324.467919 -363.428128)
			(xy 324.509723 -363.466469) (xy 324.527926 -363.488224) (xy 324.531482 -363.492796) (xy 324.540118 -363.4994)
			(xy 324.564502 -363.511592) (xy 324.569781 -363.513965) (xy 324.581067 -363.516523) (xy 324.586854 -363.516672)
			(xy 324.643496 -363.516672) (xy 324.649285 -363.516546) (xy 324.660573 -363.51398) (xy 324.665848 -363.511592)
			(xy 324.690232 -363.4994) (xy 324.698868 -363.492796) (xy 324.702424 -363.488224) (xy 324.720667 -363.466507)
			(xy 324.762474 -363.428181) (xy 324.809486 -363.396454) (xy 324.86067 -363.372022) (xy 324.914902 -363.355423)
			(xy 324.970992 -363.347019) (xy 324.99935 -363.346492) (xy 325.026004 -363.346932) (xy 325.078793 -363.354346)
			(xy 325.130036 -363.369036) (xy 325.178735 -363.390718) (xy 325.223942 -363.418967) (xy 325.264776 -363.453234)
			(xy 325.300442 -363.492852) (xy 325.330245 -363.53705) (xy 325.353606 -363.584966) (xy 325.370069 -363.635667)
			(xy 325.379313 -363.688167) (xy 325.380604 -363.714792) (xy 325.380858 -363.724952) (xy 325.388732 -363.742478)
			(xy 325.446898 -363.798612) (xy 325.454245 -363.805105) (xy 325.472409 -363.812442) (xy 325.482204 -363.812836)
			(xy 326.596502 -363.812836) (xy 326.607253 -363.812361) (xy 326.626867 -363.803553) (xy 326.634348 -363.795818)
			(xy 326.634602 -363.795564) (xy 326.68464 -363.738922) (xy 326.688183 -363.734705) (xy 326.693569 -363.725098)
			(xy 326.695308 -363.719872) (xy 326.698356 -363.709712) (xy 326.697086 -363.699044) (xy 326.69574 -363.68728)
			(xy 326.694343 -363.663641) (xy 326.694292 -363.6518) (xy 326.694778 -363.624549) (xy 326.702534 -363.570601)
			(xy 326.717889 -363.518306) (xy 326.740531 -363.468729) (xy 326.769997 -363.422879) (xy 326.805688 -363.381688)
			(xy 326.846879 -363.345997) (xy 326.892729 -363.316531) (xy 326.942306 -363.293889) (xy 326.994601 -363.278534)
			(xy 327.048549 -363.270778) (xy 327.103051 -363.270778) (xy 327.156999 -363.278534) (xy 327.209294 -363.293889)
			(xy 327.258871 -363.316531) (xy 327.304721 -363.345997) (xy 327.345912 -363.381688) (xy 327.381603 -363.422879)
			(xy 327.411069 -363.468729) (xy 327.433711 -363.518306) (xy 327.449066 -363.570601) (xy 327.456822 -363.624549)
			(xy 327.457308 -363.6518) (xy 327.457108 -363.668398) (xy 327.454187 -363.701466) (xy 327.451466 -363.71784)
			(xy 327.449688 -363.729016) (xy 327.455276 -363.750352) (xy 327.512426 -363.818932) (xy 327.520033 -363.827178)
			(xy 327.540336 -363.836659) (xy 327.551542 -363.83722) (xy 327.616058 -363.83722) (xy 327.627257 -363.836639)
			(xy 327.64755 -363.827155) (xy 327.655174 -363.818932) (xy 327.712324 -363.750352) (xy 327.717912 -363.729016)
			(xy 327.716134 -363.71784) (xy 327.713414 -363.701465) (xy 327.710487 -363.668398) (xy 327.710292 -363.6518)
			(xy 327.710778 -363.624549) (xy 327.718534 -363.570601) (xy 327.733889 -363.518306) (xy 327.756531 -363.468729)
			(xy 327.785997 -363.422879) (xy 327.821688 -363.381688) (xy 327.862879 -363.345997) (xy 327.908729 -363.316531)
			(xy 327.958306 -363.293889) (xy 328.010601 -363.278534) (xy 328.064549 -363.270778) (xy 328.119051 -363.270778)
			(xy 328.172999 -363.278534) (xy 328.225294 -363.293889) (xy 328.274871 -363.316531) (xy 328.320721 -363.345997)
			(xy 328.361912 -363.381688) (xy 328.397603 -363.422879) (xy 328.427069 -363.468729) (xy 328.449711 -363.518306)
			(xy 328.465066 -363.570601) (xy 328.472822 -363.624549) (xy 328.473308 -363.6518) (xy 328.473108 -363.668398)
			(xy 328.470187 -363.701466) (xy 328.467466 -363.71784) (xy 328.465688 -363.729016) (xy 328.471276 -363.750352)
			(xy 328.528426 -363.818932) (xy 328.536033 -363.827178) (xy 328.556336 -363.836659) (xy 328.567542 -363.83722)
			(xy 355.664262 -363.83722) (xy 355.67366 -363.836204) (xy 355.680968 -363.8346) (xy 355.694263 -363.827751)
			(xy 355.699822 -363.822742) (xy 362.333032 -357.189532) (xy 362.33554 -357.186955) (xy 362.339875 -357.181219)
			(xy 362.341668 -357.178102) (xy 362.427566 -357.019962) (xy 362.593409 -356.700522) (xy 362.752388 -356.377611)
			(xy 362.904429 -356.051375) (xy 363.049462 -355.721965) (xy 363.187422 -355.38953) (xy 363.253274 -355.222048)
			(xy 363.320296 -355.048864) (xy 363.447627 -354.699975) (xy 363.567233 -354.348362) (xy 363.679057 -353.994197)
			(xy 363.783045 -353.637653) (xy 363.879145 -353.278903) (xy 363.967311 -352.91812) (xy 364.007908 -352.736912)
			(xy 364.009178 -352.72599) (xy 364.009178 -339.68182) (xy 364.008416 -339.672676) (xy 363.637322 -337.609434)
			(xy 363.52988 -337.01101) (xy 363.502956 -336.987642) (xy 363.485176 -336.98688) (xy 363.458681 -336.985329)
			(xy 363.40647 -336.97581) (xy 363.356082 -336.959144) (xy 363.308491 -336.935654) (xy 363.264617 -336.905792)
			(xy 363.225307 -336.870135) (xy 363.19132 -336.829373) (xy 363.163313 -336.784292) (xy 363.141826 -336.735764)
			(xy 363.127275 -336.684725) (xy 363.119941 -336.632162) (xy 363.119416 -336.605626) (xy 363.119906 -336.577628)
			(xy 363.128089 -336.522232) (xy 363.144281 -336.468628) (xy 363.168136 -336.417966) (xy 363.19914 -336.371336)
			(xy 363.236628 -336.32974) (xy 363.279794 -336.29407) (xy 363.327711 -336.265094) (xy 363.35335 -336.253836)
			(xy 363.36986 -336.246978) (xy 363.386878 -336.215482) (xy 363.13237 -334.800956) (xy 363.13072 -334.793321)
			(xy 363.123469 -334.779495) (xy 363.118146 -334.773778) (xy 363.060996 -334.716628) (xy 363.027722 -334.711802)
			(xy 363.012736 -334.720184) (xy 362.984314 -334.735109) (xy 362.923714 -334.756277) (xy 362.860427 -334.767015)
			(xy 362.828332 -334.767682) (xy 362.801078 -334.767221) (xy 362.747125 -334.759467) (xy 362.694825 -334.744114)
			(xy 362.645243 -334.721473) (xy 362.599387 -334.692005) (xy 362.558193 -334.656311) (xy 362.522498 -334.615117)
			(xy 362.49303 -334.569263) (xy 362.470388 -334.51968) (xy 362.455034 -334.467381) (xy 362.44728 -334.413428)
			(xy 362.446824 -334.386174) (xy 362.447486 -334.354079) (xy 362.458228 -334.290793) (xy 362.479406 -334.230197)
			(xy 362.494322 -334.20177) (xy 362.502704 -334.186784) (xy 362.497878 -334.15351) (xy 357.03383 -328.689462)
			(xy 357.026431 -328.68262) (xy 357.007832 -328.674901) (xy 356.997762 -328.674476) (xy 348.75597 -328.674476)
			(xy 348.745903 -328.674047) (xy 348.727308 -328.666322) (xy 348.719902 -328.65949) (xy 347.859604 -327.799192)
			(xy 347.852205 -327.792346) (xy 347.833608 -327.784611) (xy 347.823536 -327.784206) (xy 344.776552 -327.784206)
			(xy 344.766485 -327.783775) (xy 344.747893 -327.776049) (xy 344.740484 -327.76922) (xy 314.892182 -327.76922)
			(xy 314.882114 -327.769647) (xy 314.863516 -327.777368) (xy 314.856114 -327.784206) (xy 312.029094 -330.611226)
			(xy 312.021728 -330.618338) (xy 312.014108 -330.637134) (xy 312.014108 -334.614266) (xy 312.013673 -334.624331)
			(xy 312.005943 -334.642919) (xy 311.999122 -334.650334) (xy 311.195212 -335.454244) (xy 311.187817 -335.461098)
			(xy 311.169218 -335.468846) (xy 311.159144 -335.46923) (xy 305.583082 -335.46923) (xy 305.573013 -335.468804)
			(xy 305.55441 -335.461089) (xy 305.547014 -335.454244) (xy 305.080924 -334.988154) (xy 305.074082 -334.980754)
			(xy 305.066361 -334.962156) (xy 305.065938 -334.952086) (xy 305.065938 -326.738234) (xy 305.066374 -326.72817)
			(xy 305.074109 -326.709586) (xy 305.080924 -326.702166) (xy 306.949348 -324.833742) (xy 306.956191 -324.826343)
			(xy 306.963913 -324.807744) (xy 306.964334 -324.797674) (xy 306.964334 -322.115688) (xy 306.963907 -322.10562)
			(xy 306.956182 -322.087025) (xy 306.949348 -322.07962) (xy 306.192174 -321.322446) (xy 306.184776 -321.315598)
			(xy 306.166178 -321.307866) (xy 306.156106 -321.30746) (xy 304.284634 -321.30746) (xy 304.274611 -321.307046)
			(xy 304.256089 -321.29938) (xy 304.241916 -321.285205) (xy 304.234253 -321.266683) (xy 304.233834 -321.25666)
			(xy 274.85848 -321.25666) (xy 274.848413 -321.257088) (xy 274.829819 -321.264815) (xy 274.822412 -321.271646)
			(xy 266.347194 -329.746864) (xy 266.339828 -329.753976) (xy 266.332208 -329.772772) (xy 266.332208 -331.872336)
			(xy 266.332638 -331.882403) (xy 266.340362 -331.900997) (xy 266.347194 -331.908404) (xy 266.355068 -331.916278)
			(xy 266.362469 -331.923116) (xy 266.381068 -331.930829) (xy 266.391136 -331.931264) (xy 267.551154 -331.931264)
			(xy 267.560552 -331.930248) (xy 267.567862 -331.928646) (xy 267.581162 -331.921803) (xy 267.586714 -331.916786)
			(xy 267.725144 -331.778356) (xy 267.743686 -331.759814) (xy 267.765281 -331.739023) (xy 267.813794 -331.703812)
			(xy 267.867222 -331.676633) (xy 267.924247 -331.658156) (xy 267.983462 -331.648836) (xy 268.013434 -331.648308)
			(xy 268.040666 -331.648796) (xy 268.094577 -331.656551) (xy 268.146835 -331.671898) (xy 268.196377 -331.694526)
			(xy 268.242195 -331.723973) (xy 268.283357 -331.75964) (xy 268.319025 -331.800802) (xy 268.348472 -331.84662)
			(xy 268.3711 -331.896162) (xy 268.386448 -331.948419) (xy 268.394204 -332.00233) (xy 268.394688 -332.029562)
			(xy 268.39412 -332.059531) (xy 268.384786 -332.118737) (xy 268.36631 -332.175756) (xy 268.339146 -332.229185)
			(xy 268.303963 -332.277709) (xy 268.283182 -332.29931) (xy 268.259052 -332.323186) (xy 268.080744 -332.501748)
			(xy 268.074052 -332.50916) (xy 268.066439 -332.527599) (xy 268.066428 -332.547548) (xy 268.074021 -332.565995)
			(xy 268.080744 -332.573376) (xy 268.259052 -332.751938) (xy 268.283182 -332.775814) (xy 268.303971 -332.79741)
			(xy 268.339179 -332.845923) (xy 268.366355 -332.899351) (xy 268.384828 -332.956376) (xy 268.394143 -333.01559)
			(xy 268.394688 -333.045562) (xy 268.394228 -333.072799) (xy 268.386481 -333.12672) (xy 268.371139 -333.17899)
			(xy 268.348514 -333.228544) (xy 268.319067 -333.274374) (xy 268.283397 -333.315546) (xy 268.242232 -333.351224)
			(xy 268.196407 -333.380679) (xy 268.146857 -333.403313) (xy 268.094591 -333.418665) (xy 268.040671 -333.426423)
			(xy 268.013434 -333.426816) (xy 267.983466 -333.426247) (xy 267.924261 -333.416911) (xy 267.867245 -333.398432)
			(xy 267.81382 -333.371264) (xy 267.7653 -333.336076) (xy 267.743686 -333.31531) (xy 267.717016 -333.28864)
			(xy 267.518642 -333.090266) (xy 267.51153 -333.083154) (xy 267.492734 -333.07528) (xy 266.054078 -333.07528)
			(xy 266.024095 -333.074728) (xy 265.964867 -333.065356) (xy 265.907834 -333.046831) (xy 265.854404 -333.019608)
			(xy 265.805892 -332.98436) (xy 265.78433 -332.96352) (xy 265.299952 -332.479142) (xy 265.27917 -332.457529)
			(xy 265.243927 -332.409025) (xy 265.216703 -332.355606) (xy 265.198167 -332.298588) (xy 265.188776 -332.239372)
			(xy 265.188192 -332.209394) (xy 265.188192 -329.445874) (xy 265.188745 -329.415892) (xy 265.198119 -329.356665)
			(xy 265.216647 -329.299635) (xy 265.243874 -329.246209) (xy 265.279127 -329.197702) (xy 265.299952 -329.176126)
			(xy 274.091908 -320.38417) (xy 274.098742 -320.376808) (xy 274.1065 -320.358293) (xy 274.106562 -320.33822)
			(xy 274.103084 -320.328798) (xy 274.096988 -320.314574) (xy 274.071842 -320.297556) (xy 261.584186 -320.297556)
			(xy 261.574118 -320.297983) (xy 261.555523 -320.305707) (xy 261.548118 -320.312542) (xy 260.432296 -321.428364)
			(xy 260.42546 -321.435766) (xy 260.417749 -321.454364) (xy 260.41731 -321.464432) (xy 260.41731 -324.102984)
			(xy 262.047228 -324.102984) (xy 262.04764 -324.075729) (xy 262.0554 -324.021774) (xy 262.07076 -323.969473)
			(xy 262.093407 -323.919891) (xy 262.12288 -323.874036) (xy 262.158579 -323.832842) (xy 262.199778 -323.797149)
			(xy 262.245636 -323.767682) (xy 262.295222 -323.745042) (xy 262.347525 -323.729689) (xy 262.401481 -323.721936)
			(xy 262.428736 -323.721476) (xy 262.457923 -323.722026) (xy 262.515615 -323.730929) (xy 262.57128 -323.748508)
			(xy 262.623622 -323.774352) (xy 262.671421 -323.80786) (xy 262.713565 -323.848251) (xy 262.731758 -323.871082)
			(xy 262.739886 -323.88175) (xy 262.763762 -323.892164) (xy 262.876792 -323.880226) (xy 262.898128 -323.86524)
			(xy 262.90397 -323.853048) (xy 262.915962 -323.829003) (xy 262.945644 -323.784216) (xy 262.981318 -323.744038)
			(xy 263.022276 -323.709263) (xy 263.067709 -323.680579) (xy 263.116717 -323.658554) (xy 263.168331 -323.643624)
			(xy 263.221529 -323.636083) (xy 263.248394 -323.635624) (xy 263.277413 -323.636205) (xy 263.334783 -323.644995)
			(xy 263.390159 -323.662371) (xy 263.442264 -323.687935) (xy 263.489897 -323.721095) (xy 263.531958 -323.761087)
			(xy 263.550146 -323.783706) (xy 263.55802 -323.793612) (xy 263.58088 -323.804026) (xy 263.689592 -323.797676)
			(xy 263.711182 -323.784722) (xy 263.717532 -323.774054) (xy 263.732422 -323.75023) (xy 263.768091 -323.706826)
			(xy 263.809739 -323.669121) (xy 263.856464 -323.637929) (xy 263.907257 -323.613925) (xy 263.961022 -323.597627)
			(xy 264.016594 -323.589388) (xy 264.044684 -323.588888) (xy 264.074105 -323.589449) (xy 264.132249 -323.598494)
			(xy 264.188315 -323.616358) (xy 264.240974 -323.642616) (xy 264.288978 -323.676646) (xy 264.33119 -323.717642)
			(xy 264.366608 -323.764632) (xy 264.38098 -323.79031) (xy 264.387584 -323.802502) (xy 264.410698 -323.816726)
			(xy 264.526776 -323.81952) (xy 264.550652 -323.806312) (xy 264.557764 -323.794374) (xy 264.572655 -323.770504)
			(xy 264.608307 -323.726987) (xy 264.649964 -323.689177) (xy 264.696721 -323.657895) (xy 264.747566 -323.633819)
			(xy 264.801395 -323.61747) (xy 264.857042 -323.609204) (xy 264.88517 -323.6087) (xy 264.912425 -323.609145)
			(xy 264.96638 -323.616899) (xy 265.018683 -323.632253) (xy 265.068268 -323.654894) (xy 265.114125 -323.684362)
			(xy 265.155323 -323.720056) (xy 265.19102 -323.761251) (xy 265.220492 -323.807106) (xy 265.243137 -323.856689)
			(xy 265.258495 -323.908991) (xy 265.266253 -323.962945) (xy 265.266253 -324.017455) (xy 265.258495 -324.071409)
			(xy 265.243137 -324.123711) (xy 265.220492 -324.173294) (xy 265.19102 -324.219149) (xy 265.155323 -324.260344)
			(xy 265.114125 -324.296038) (xy 265.068268 -324.325506) (xy 265.018683 -324.348147) (xy 264.96638 -324.363501)
			(xy 264.912425 -324.371255) (xy 264.88517 -324.371716) (xy 264.85575 -324.37111) (xy 264.797609 -324.362072)
			(xy 264.741544 -324.344217) (xy 264.688885 -324.317966) (xy 264.64088 -324.283943) (xy 264.598667 -324.242953)
			(xy 264.563247 -324.195969) (xy 264.548874 -324.170294) (xy 264.54227 -324.158102) (xy 264.519156 -324.143878)
			(xy 264.403078 -324.141084) (xy 264.379202 -324.154292) (xy 264.37209 -324.16623) (xy 264.355509 -324.192731)
			(xy 264.31513 -324.240447) (xy 264.267502 -324.280928) (xy 264.241026 -324.297548) (xy 264.229342 -324.30466)
			(xy 264.216388 -324.328028) (xy 264.218166 -324.443344) (xy 264.231882 -324.466458) (xy 264.24382 -324.473316)
			(xy 264.266861 -324.486704) (xy 264.309326 -324.518897) (xy 264.346909 -324.556676) (xy 264.378881 -324.599307)
			(xy 264.392156 -324.622414) (xy 264.397998 -324.633336) (xy 264.418064 -324.646798) (xy 264.523982 -324.66026)
			(xy 264.546588 -324.652132) (xy 264.555224 -324.642988) (xy 264.573309 -324.624411) (xy 264.61364 -324.591832)
			(xy 264.658014 -324.565019) (xy 264.705611 -324.544466) (xy 264.755555 -324.530551) (xy 264.806923 -324.523533)
			(xy 264.832846 -324.5231) (xy 264.860096 -324.523573) (xy 264.91404 -324.531335) (xy 264.96633 -324.546694)
			(xy 265.015902 -324.569339) (xy 265.061748 -324.598807) (xy 265.102934 -324.634499) (xy 265.138621 -324.675689)
			(xy 265.168083 -324.721538) (xy 265.190722 -324.771113) (xy 265.206075 -324.823405) (xy 265.21383 -324.87735)
			(xy 265.21383 -324.93185) (xy 265.206075 -324.985795) (xy 265.190722 -325.038087) (xy 265.168083 -325.087662)
			(xy 265.138621 -325.133511) (xy 265.102934 -325.174701) (xy 265.061748 -325.210393) (xy 265.015902 -325.239861)
			(xy 264.96633 -325.262506) (xy 264.91404 -325.277865) (xy 264.860096 -325.285627) (xy 264.832846 -325.286116)
			(xy 264.803734 -325.285528) (xy 264.746184 -325.276687) (xy 264.690646 -325.259203) (xy 264.638411 -325.233483)
			(xy 264.59069 -325.200123) (xy 264.548593 -325.159899) (xy 264.513098 -325.113745) (xy 264.498582 -325.088504)
			(xy 264.49274 -325.077582) (xy 264.472674 -325.06412) (xy 264.366756 -325.050658) (xy 264.34415 -325.058786)
			(xy 264.335514 -325.06793) (xy 264.317414 -325.086492) (xy 264.277086 -325.119071) (xy 264.232715 -325.145886)
			(xy 264.185121 -325.166442) (xy 264.13518 -325.18036) (xy 264.083814 -325.187383) (xy 264.057892 -325.187818)
			(xy 264.028871 -325.187269) (xy 263.971499 -325.178476) (xy 263.916122 -325.161094) (xy 263.864016 -325.135525)
			(xy 263.816384 -325.102358) (xy 263.774326 -325.062358) (xy 263.75614 -325.039736) (xy 263.748266 -325.02983)
			(xy 263.725406 -325.019416) (xy 263.616694 -325.025766) (xy 263.595104 -325.03872) (xy 263.588754 -325.049388)
			(xy 263.573888 -325.073228) (xy 263.538214 -325.11663) (xy 263.496561 -325.154333) (xy 263.449832 -325.185522)
			(xy 263.399035 -325.209523) (xy 263.345268 -325.225818) (xy 263.289693 -325.234055) (xy 263.261602 -325.234554)
			(xy 263.232415 -325.234004) (xy 263.174722 -325.225105) (xy 263.119055 -325.207528) (xy 263.066713 -325.181684)
			(xy 263.018913 -325.148174) (xy 262.976771 -325.10778) (xy 262.95858 -325.084948) (xy 262.950452 -325.07428)
			(xy 262.926576 -325.063866) (xy 262.813546 -325.075804) (xy 262.79221 -325.09079) (xy 262.786368 -325.102982)
			(xy 262.774361 -325.127019) (xy 262.744679 -325.171803) (xy 262.709007 -325.211981) (xy 262.66805 -325.246756)
			(xy 262.62262 -325.27544) (xy 262.573615 -325.297467) (xy 262.522004 -325.3124) (xy 262.468808 -325.319945)
			(xy 262.441944 -325.320406) (xy 262.414692 -325.319904) (xy 262.360742 -325.312153) (xy 262.308445 -325.296802)
			(xy 262.258865 -325.274165) (xy 262.213012 -325.244701) (xy 262.171818 -325.209011) (xy 262.136124 -325.167822)
			(xy 262.106656 -325.121972) (xy 262.084013 -325.072394) (xy 262.068656 -325.020099) (xy 262.060899 -324.96615)
			(xy 262.060436 -324.938898) (xy 262.060903 -324.910805) (xy 262.069132 -324.855226) (xy 262.085426 -324.801455)
			(xy 262.109433 -324.750656) (xy 262.140632 -324.70393) (xy 262.17835 -324.662286) (xy 262.221769 -324.626627)
			(xy 262.245602 -324.611746) (xy 262.257286 -324.604634) (xy 262.27024 -324.581266) (xy 262.268462 -324.46595)
			(xy 262.254746 -324.442836) (xy 262.242808 -324.435978) (xy 262.217786 -324.421427) (xy 262.172076 -324.385919)
			(xy 262.132259 -324.34391) (xy 262.099249 -324.296365) (xy 262.073805 -324.244377) (xy 262.05651 -324.189141)
			(xy 262.047764 -324.131924) (xy 262.047228 -324.102984) (xy 260.41731 -324.102984) (xy 260.41731 -334.736694)
			(xy 272.516854 -334.736694) (xy 272.517303 -334.709323) (xy 272.525123 -334.655143) (xy 272.540615 -334.602639)
			(xy 272.563461 -334.552892) (xy 272.59319 -334.506927) (xy 272.610834 -334.485996) (xy 272.61693 -334.478884)
			(xy 272.62328 -334.461866) (xy 272.62328 -334.376522) (xy 272.61693 -334.359504) (xy 272.610834 -334.352392)
			(xy 272.593187 -334.331464) (xy 272.563462 -334.285496) (xy 272.540617 -334.235749) (xy 272.525121 -334.183246)
			(xy 272.517292 -334.129066) (xy 272.517293 -334.074325) (xy 272.525122 -334.020145) (xy 272.54062 -333.967643)
			(xy 272.563466 -333.917896) (xy 272.593193 -333.871929) (xy 272.610834 -333.850996) (xy 272.61693 -333.843884)
			(xy 272.62328 -333.826866) (xy 272.62328 -333.741522) (xy 272.61693 -333.724504) (xy 272.610834 -333.717392)
			(xy 272.593187 -333.696464) (xy 272.563462 -333.650496) (xy 272.540617 -333.600749) (xy 272.525121 -333.548246)
			(xy 272.517292 -333.494066) (xy 272.517293 -333.439325) (xy 272.525122 -333.385145) (xy 272.54062 -333.332643)
			(xy 272.563466 -333.282896) (xy 272.593193 -333.236929) (xy 272.610834 -333.215996) (xy 272.61693 -333.208884)
			(xy 272.62328 -333.191866) (xy 272.62328 -333.106522) (xy 272.61693 -333.089504) (xy 272.610834 -333.082392)
			(xy 272.593187 -333.061464) (xy 272.563462 -333.015496) (xy 272.540617 -332.965749) (xy 272.525121 -332.913246)
			(xy 272.517292 -332.859066) (xy 272.517293 -332.804325) (xy 272.525122 -332.750145) (xy 272.54062 -332.697643)
			(xy 272.563466 -332.647896) (xy 272.593193 -332.601929) (xy 272.610834 -332.580996) (xy 272.61693 -332.573884)
			(xy 272.62328 -332.556866) (xy 272.62328 -332.471522) (xy 272.61693 -332.454504) (xy 272.610834 -332.447392)
			(xy 272.593187 -332.426464) (xy 272.563462 -332.380496) (xy 272.540617 -332.330749) (xy 272.525121 -332.278246)
			(xy 272.517292 -332.224066) (xy 272.517293 -332.169325) (xy 272.525122 -332.115145) (xy 272.54062 -332.062643)
			(xy 272.563466 -332.012896) (xy 272.593193 -331.966929) (xy 272.610834 -331.945996) (xy 272.61693 -331.938884)
			(xy 272.62328 -331.921866) (xy 272.62328 -331.836522) (xy 272.61693 -331.819504) (xy 272.610834 -331.812392)
			(xy 272.593187 -331.791464) (xy 272.563462 -331.745496) (xy 272.540617 -331.695749) (xy 272.525121 -331.643246)
			(xy 272.517292 -331.589066) (xy 272.517293 -331.534325) (xy 272.525122 -331.480145) (xy 272.54062 -331.427643)
			(xy 272.563466 -331.377896) (xy 272.593193 -331.331929) (xy 272.610834 -331.310996) (xy 272.61693 -331.303884)
			(xy 272.62328 -331.286866) (xy 272.62328 -331.201522) (xy 272.61693 -331.184504) (xy 272.610834 -331.177392)
			(xy 272.593187 -331.156464) (xy 272.563462 -331.110496) (xy 272.540617 -331.060749) (xy 272.525121 -331.008246)
			(xy 272.517292 -330.954066) (xy 272.517293 -330.899325) (xy 272.525122 -330.845145) (xy 272.54062 -330.792643)
			(xy 272.563466 -330.742896) (xy 272.593193 -330.696929) (xy 272.610834 -330.675996) (xy 272.61693 -330.668884)
			(xy 272.62328 -330.651866) (xy 272.62328 -330.566522) (xy 272.61693 -330.549504) (xy 272.610834 -330.542392)
			(xy 272.593183 -330.521469) (xy 272.563472 -330.475495) (xy 272.540638 -330.425745) (xy 272.525149 -330.373242)
			(xy 272.517325 -330.319064) (xy 272.516854 -330.291694) (xy 272.517372 -330.264444) (xy 272.525128 -330.2105)
			(xy 272.540482 -330.158208) (xy 272.563121 -330.108633) (xy 272.592585 -330.062785) (xy 272.628273 -330.021595)
			(xy 272.669459 -329.985904) (xy 272.715305 -329.956437) (xy 272.764878 -329.933794) (xy 272.817168 -329.918435)
			(xy 272.871112 -329.910674) (xy 272.898362 -329.910186) (xy 272.925731 -329.910678) (xy 272.979909 -329.91849)
			(xy 273.032412 -329.933973) (xy 273.082159 -329.956809) (xy 273.128127 -329.986528) (xy 273.14906 -330.004166)
			(xy 273.156172 -330.010262) (xy 273.17319 -330.016612) (xy 273.258534 -330.016612) (xy 273.275552 -330.010262)
			(xy 273.282664 -330.004166) (xy 273.303597 -329.986525) (xy 273.349565 -329.956801) (xy 273.399311 -329.933955)
			(xy 273.451813 -329.918459) (xy 273.505991 -329.91063) (xy 273.560733 -329.91063) (xy 273.614911 -329.918459)
			(xy 273.667413 -329.933955) (xy 273.717159 -329.956801) (xy 273.763127 -329.986525) (xy 273.78406 -330.004166)
			(xy 273.791172 -330.010262) (xy 273.80819 -330.016612) (xy 273.893534 -330.016612) (xy 273.910552 -330.010262)
			(xy 273.917664 -330.004166) (xy 273.938594 -329.986525) (xy 273.984568 -329.956815) (xy 274.034316 -329.93398)
			(xy 274.086817 -329.918489) (xy 274.140993 -329.91066) (xy 274.168362 -329.910186) (xy 274.195614 -329.910691)
			(xy 274.249563 -329.918442) (xy 274.30186 -329.933793) (xy 274.351439 -329.956431) (xy 274.397292 -329.985894)
			(xy 274.438485 -330.021584) (xy 274.474179 -330.062773) (xy 274.503648 -330.108622) (xy 274.526291 -330.158199)
			(xy 274.541648 -330.210494) (xy 274.549406 -330.264442) (xy 274.54987 -330.291694) (xy 274.549408 -330.319064)
			(xy 274.54159 -330.373244) (xy 274.526101 -330.425747) (xy 274.503258 -330.475494) (xy 274.473532 -330.521461)
			(xy 274.45589 -330.542392) (xy 274.449794 -330.549504) (xy 274.443444 -330.566522) (xy 274.443444 -330.651866)
			(xy 274.449794 -330.668884) (xy 274.45589 -330.675996) (xy 274.473524 -330.696934) (xy 274.503248 -330.742901)
			(xy 274.526093 -330.792647) (xy 274.541589 -330.845148) (xy 274.549417 -330.899325) (xy 274.549418 -330.954066)
			(xy 274.54159 -331.008243) (xy 274.526096 -331.060745) (xy 274.503252 -331.110491) (xy 274.47353 -331.156459)
			(xy 274.45589 -331.177392) (xy 274.449794 -331.184504) (xy 274.443444 -331.201522) (xy 274.443444 -331.286866)
			(xy 274.449794 -331.303884) (xy 274.45589 -331.310996) (xy 274.473524 -331.331934) (xy 274.503248 -331.377901)
			(xy 274.526093 -331.427647) (xy 274.541589 -331.480148) (xy 274.549417 -331.534325) (xy 274.549418 -331.589066)
			(xy 274.54159 -331.643243) (xy 274.526096 -331.695745) (xy 274.503252 -331.745491) (xy 274.47353 -331.791459)
			(xy 274.45589 -331.812392) (xy 274.449794 -331.819504) (xy 274.443444 -331.836522) (xy 274.443444 -331.921866)
			(xy 274.449794 -331.938884) (xy 274.45589 -331.945996) (xy 274.473524 -331.966934) (xy 274.503248 -332.012901)
			(xy 274.526093 -332.062647) (xy 274.541589 -332.115148) (xy 274.549417 -332.169325) (xy 274.549418 -332.224066)
			(xy 274.54159 -332.278243) (xy 274.526096 -332.330745) (xy 274.503252 -332.380491) (xy 274.47353 -332.426459)
			(xy 274.45589 -332.447392) (xy 274.449794 -332.454504) (xy 274.443444 -332.471522) (xy 274.443444 -332.556866)
			(xy 274.449794 -332.573884) (xy 274.45589 -332.580996) (xy 274.473524 -332.601934) (xy 274.503248 -332.647901)
			(xy 274.526093 -332.697647) (xy 274.541589 -332.750148) (xy 274.549417 -332.804325) (xy 274.549418 -332.859066)
			(xy 274.54159 -332.913243) (xy 274.526096 -332.965745) (xy 274.503252 -333.015491) (xy 274.47353 -333.061459)
			(xy 274.45589 -333.082392) (xy 274.449794 -333.089504) (xy 274.443444 -333.106522) (xy 274.443444 -333.191866)
			(xy 274.449794 -333.208884) (xy 274.45589 -333.215996) (xy 274.473524 -333.236934) (xy 274.503248 -333.282901)
			(xy 274.526093 -333.332647) (xy 274.541589 -333.385148) (xy 274.549417 -333.439325) (xy 274.549418 -333.494066)
			(xy 274.54159 -333.548243) (xy 274.526096 -333.600745) (xy 274.503252 -333.650491) (xy 274.47353 -333.696459)
			(xy 274.45589 -333.717392) (xy 274.449794 -333.724504) (xy 274.443444 -333.741522) (xy 274.443444 -333.826866)
			(xy 274.449794 -333.843884) (xy 274.45589 -333.850996) (xy 274.473524 -333.871934) (xy 274.503248 -333.917901)
			(xy 274.526093 -333.967647) (xy 274.541589 -334.020148) (xy 274.549417 -334.074325) (xy 274.549418 -334.129066)
			(xy 274.54159 -334.183243) (xy 274.526096 -334.235745) (xy 274.503252 -334.285491) (xy 274.47353 -334.331459)
			(xy 274.45589 -334.352392) (xy 274.449794 -334.359504) (xy 274.443444 -334.376522) (xy 274.443444 -334.461866)
			(xy 274.449794 -334.478884) (xy 274.45589 -334.485996) (xy 274.473539 -334.50692) (xy 274.50325 -334.552895)
			(xy 274.526084 -334.602644) (xy 274.541573 -334.655147) (xy 274.549398 -334.709324) (xy 274.54987 -334.736694)
			(xy 276.530054 -334.736694) (xy 276.530503 -334.709323) (xy 276.538323 -334.655143) (xy 276.553815 -334.602639)
			(xy 276.576661 -334.552892) (xy 276.60639 -334.506927) (xy 276.624034 -334.485996) (xy 276.63013 -334.478884)
			(xy 276.63648 -334.461866) (xy 276.63648 -334.376522) (xy 276.63013 -334.359504) (xy 276.624034 -334.352392)
			(xy 276.606387 -334.331464) (xy 276.576662 -334.285496) (xy 276.553817 -334.235749) (xy 276.538321 -334.183246)
			(xy 276.530492 -334.129066) (xy 276.530493 -334.074325) (xy 276.538322 -334.020145) (xy 276.55382 -333.967643)
			(xy 276.576666 -333.917896) (xy 276.606393 -333.871929) (xy 276.624034 -333.850996) (xy 276.63013 -333.843884)
			(xy 276.63648 -333.826866) (xy 276.63648 -333.741522) (xy 276.63013 -333.724504) (xy 276.624034 -333.717392)
			(xy 276.606387 -333.696464) (xy 276.576662 -333.650496) (xy 276.553817 -333.600749) (xy 276.538321 -333.548246)
			(xy 276.530492 -333.494066) (xy 276.530493 -333.439325) (xy 276.538322 -333.385145) (xy 276.55382 -333.332643)
			(xy 276.576666 -333.282896) (xy 276.606393 -333.236929) (xy 276.624034 -333.215996) (xy 276.63013 -333.208884)
			(xy 276.63648 -333.191866) (xy 276.63648 -333.106522) (xy 276.63013 -333.089504) (xy 276.624034 -333.082392)
			(xy 276.606387 -333.061464) (xy 276.576662 -333.015496) (xy 276.553817 -332.965749) (xy 276.538321 -332.913246)
			(xy 276.530492 -332.859066) (xy 276.530493 -332.804325) (xy 276.538322 -332.750145) (xy 276.55382 -332.697643)
			(xy 276.576666 -332.647896) (xy 276.606393 -332.601929) (xy 276.624034 -332.580996) (xy 276.63013 -332.573884)
			(xy 276.63648 -332.556866) (xy 276.63648 -332.471522) (xy 276.63013 -332.454504) (xy 276.624034 -332.447392)
			(xy 276.606387 -332.426464) (xy 276.576662 -332.380496) (xy 276.553817 -332.330749) (xy 276.538321 -332.278246)
			(xy 276.530492 -332.224066) (xy 276.530493 -332.169325) (xy 276.538322 -332.115145) (xy 276.55382 -332.062643)
			(xy 276.576666 -332.012896) (xy 276.606393 -331.966929) (xy 276.624034 -331.945996) (xy 276.63013 -331.938884)
			(xy 276.63648 -331.921866) (xy 276.63648 -331.836522) (xy 276.63013 -331.819504) (xy 276.624034 -331.812392)
			(xy 276.606387 -331.791464) (xy 276.576662 -331.745496) (xy 276.553817 -331.695749) (xy 276.538321 -331.643246)
			(xy 276.530492 -331.589066) (xy 276.530493 -331.534325) (xy 276.538322 -331.480145) (xy 276.55382 -331.427643)
			(xy 276.576666 -331.377896) (xy 276.606393 -331.331929) (xy 276.624034 -331.310996) (xy 276.63013 -331.303884)
			(xy 276.63648 -331.286866) (xy 276.63648 -331.201522) (xy 276.63013 -331.184504) (xy 276.624034 -331.177392)
			(xy 276.606387 -331.156464) (xy 276.576662 -331.110496) (xy 276.553817 -331.060749) (xy 276.538321 -331.008246)
			(xy 276.530492 -330.954066) (xy 276.530493 -330.899325) (xy 276.538322 -330.845145) (xy 276.55382 -330.792643)
			(xy 276.576666 -330.742896) (xy 276.606393 -330.696929) (xy 276.624034 -330.675996) (xy 276.63013 -330.668884)
			(xy 276.63648 -330.651866) (xy 276.63648 -330.566522) (xy 276.63013 -330.549504) (xy 276.624034 -330.542392)
			(xy 276.606383 -330.521469) (xy 276.576672 -330.475495) (xy 276.553838 -330.425745) (xy 276.538349 -330.373242)
			(xy 276.530525 -330.319064) (xy 276.530054 -330.291694) (xy 276.530572 -330.264444) (xy 276.538328 -330.2105)
			(xy 276.553682 -330.158208) (xy 276.576321 -330.108633) (xy 276.605785 -330.062785) (xy 276.641473 -330.021595)
			(xy 276.682659 -329.985904) (xy 276.728505 -329.956437) (xy 276.778078 -329.933794) (xy 276.830368 -329.918435)
			(xy 276.884312 -329.910674) (xy 276.911562 -329.910186) (xy 276.938931 -329.910678) (xy 276.993109 -329.91849)
			(xy 277.045612 -329.933973) (xy 277.095359 -329.956809) (xy 277.141327 -329.986528) (xy 277.16226 -330.004166)
			(xy 277.169372 -330.010262) (xy 277.18639 -330.016612) (xy 277.271734 -330.016612) (xy 277.288752 -330.010262)
			(xy 277.295864 -330.004166) (xy 277.316797 -329.986525) (xy 277.362765 -329.956801) (xy 277.412511 -329.933955)
			(xy 277.465013 -329.918459) (xy 277.519191 -329.91063) (xy 277.573933 -329.91063) (xy 277.628111 -329.918459)
			(xy 277.680613 -329.933955) (xy 277.730359 -329.956801) (xy 277.776327 -329.986525) (xy 277.79726 -330.004166)
			(xy 277.804372 -330.010262) (xy 277.82139 -330.016612) (xy 277.906734 -330.016612) (xy 277.923752 -330.010262)
			(xy 277.930864 -330.004166) (xy 277.951794 -329.986525) (xy 277.997768 -329.956815) (xy 278.047516 -329.93398)
			(xy 278.100017 -329.918489) (xy 278.154193 -329.91066) (xy 278.181562 -329.910186) (xy 278.208814 -329.910691)
			(xy 278.262763 -329.918442) (xy 278.31506 -329.933793) (xy 278.364639 -329.956431) (xy 278.410492 -329.985894)
			(xy 278.451685 -330.021584) (xy 278.487379 -330.062773) (xy 278.516848 -330.108622) (xy 278.539491 -330.158199)
			(xy 278.554848 -330.210494) (xy 278.562606 -330.264442) (xy 278.56307 -330.291694) (xy 278.562608 -330.319064)
			(xy 278.55479 -330.373244) (xy 278.539301 -330.425747) (xy 278.516458 -330.475494) (xy 278.486732 -330.521461)
			(xy 278.46909 -330.542392) (xy 278.462994 -330.549504) (xy 278.456644 -330.566522) (xy 278.456644 -330.651866)
			(xy 278.462994 -330.668884) (xy 278.46909 -330.675996) (xy 278.486724 -330.696934) (xy 278.516448 -330.742901)
			(xy 278.539293 -330.792647) (xy 278.554789 -330.845148) (xy 278.562617 -330.899325) (xy 278.562618 -330.954066)
			(xy 278.55479 -331.008243) (xy 278.539296 -331.060745) (xy 278.516452 -331.110491) (xy 278.48673 -331.156459)
			(xy 278.46909 -331.177392) (xy 278.462994 -331.184504) (xy 278.456644 -331.201522) (xy 278.456644 -331.286866)
			(xy 278.462994 -331.303884) (xy 278.46909 -331.310996) (xy 278.486724 -331.331934) (xy 278.516448 -331.377901)
			(xy 278.539293 -331.427647) (xy 278.554789 -331.480148) (xy 278.562617 -331.534325) (xy 278.562618 -331.589066)
			(xy 278.55479 -331.643243) (xy 278.539296 -331.695745) (xy 278.516452 -331.745491) (xy 278.48673 -331.791459)
			(xy 278.46909 -331.812392) (xy 278.462994 -331.819504) (xy 278.456644 -331.836522) (xy 278.456644 -331.921866)
			(xy 278.462994 -331.938884) (xy 278.46909 -331.945996) (xy 278.486724 -331.966934) (xy 278.516448 -332.012901)
			(xy 278.539293 -332.062647) (xy 278.554789 -332.115148) (xy 278.562617 -332.169325) (xy 278.562618 -332.224066)
			(xy 278.55479 -332.278243) (xy 278.539296 -332.330745) (xy 278.516452 -332.380491) (xy 278.48673 -332.426459)
			(xy 278.46909 -332.447392) (xy 278.462994 -332.454504) (xy 278.456644 -332.471522) (xy 278.456644 -332.556866)
			(xy 278.462994 -332.573884) (xy 278.46909 -332.580996) (xy 278.486724 -332.601934) (xy 278.516448 -332.647901)
			(xy 278.539293 -332.697647) (xy 278.554789 -332.750148) (xy 278.562617 -332.804325) (xy 278.562618 -332.859066)
			(xy 278.55479 -332.913243) (xy 278.539296 -332.965745) (xy 278.516452 -333.015491) (xy 278.48673 -333.061459)
			(xy 278.46909 -333.082392) (xy 278.462994 -333.089504) (xy 278.456644 -333.106522) (xy 278.456644 -333.191866)
			(xy 278.462994 -333.208884) (xy 278.46909 -333.215996) (xy 278.486724 -333.236934) (xy 278.516448 -333.282901)
			(xy 278.539293 -333.332647) (xy 278.554789 -333.385148) (xy 278.562617 -333.439325) (xy 278.562618 -333.494066)
			(xy 278.55479 -333.548243) (xy 278.539296 -333.600745) (xy 278.516452 -333.650491) (xy 278.48673 -333.696459)
			(xy 278.46909 -333.717392) (xy 278.462994 -333.724504) (xy 278.456644 -333.741522) (xy 278.456644 -333.826866)
			(xy 278.462994 -333.843884) (xy 278.46909 -333.850996) (xy 278.486724 -333.871934) (xy 278.516448 -333.917901)
			(xy 278.539293 -333.967647) (xy 278.554789 -334.020148) (xy 278.562617 -334.074325) (xy 278.562618 -334.129066)
			(xy 278.55479 -334.183243) (xy 278.539296 -334.235745) (xy 278.516452 -334.285491) (xy 278.48673 -334.331459)
			(xy 278.46909 -334.352392) (xy 278.462994 -334.359504) (xy 278.456644 -334.376522) (xy 278.456644 -334.461866)
			(xy 278.462994 -334.478884) (xy 278.46909 -334.485996) (xy 278.486739 -334.50692) (xy 278.51645 -334.552895)
			(xy 278.539284 -334.602644) (xy 278.554773 -334.655147) (xy 278.562598 -334.709324) (xy 278.56307 -334.736694)
			(xy 280.797254 -334.736694) (xy 280.797703 -334.709323) (xy 280.805523 -334.655143) (xy 280.821015 -334.602639)
			(xy 280.843861 -334.552892) (xy 280.87359 -334.506927) (xy 280.891234 -334.485996) (xy 280.89733 -334.478884)
			(xy 280.90368 -334.461866) (xy 280.90368 -334.376522) (xy 280.89733 -334.359504) (xy 280.891234 -334.352392)
			(xy 280.873587 -334.331464) (xy 280.843862 -334.285496) (xy 280.821017 -334.235749) (xy 280.805521 -334.183246)
			(xy 280.797692 -334.129066) (xy 280.797693 -334.074325) (xy 280.805522 -334.020145) (xy 280.82102 -333.967643)
			(xy 280.843866 -333.917896) (xy 280.873593 -333.871929) (xy 280.891234 -333.850996) (xy 280.89733 -333.843884)
			(xy 280.90368 -333.826866) (xy 280.90368 -333.741522) (xy 280.89733 -333.724504) (xy 280.891234 -333.717392)
			(xy 280.873587 -333.696464) (xy 280.843862 -333.650496) (xy 280.821017 -333.600749) (xy 280.805521 -333.548246)
			(xy 280.797692 -333.494066) (xy 280.797693 -333.439325) (xy 280.805522 -333.385145) (xy 280.82102 -333.332643)
			(xy 280.843866 -333.282896) (xy 280.873593 -333.236929) (xy 280.891234 -333.215996) (xy 280.89733 -333.208884)
			(xy 280.90368 -333.191866) (xy 280.90368 -333.106522) (xy 280.89733 -333.089504) (xy 280.891234 -333.082392)
			(xy 280.873587 -333.061464) (xy 280.843862 -333.015496) (xy 280.821017 -332.965749) (xy 280.805521 -332.913246)
			(xy 280.797692 -332.859066) (xy 280.797693 -332.804325) (xy 280.805522 -332.750145) (xy 280.82102 -332.697643)
			(xy 280.843866 -332.647896) (xy 280.873593 -332.601929) (xy 280.891234 -332.580996) (xy 280.89733 -332.573884)
			(xy 280.90368 -332.556866) (xy 280.90368 -332.471522) (xy 280.89733 -332.454504) (xy 280.891234 -332.447392)
			(xy 280.873587 -332.426464) (xy 280.843862 -332.380496) (xy 280.821017 -332.330749) (xy 280.805521 -332.278246)
			(xy 280.797692 -332.224066) (xy 280.797693 -332.169325) (xy 280.805522 -332.115145) (xy 280.82102 -332.062643)
			(xy 280.843866 -332.012896) (xy 280.873593 -331.966929) (xy 280.891234 -331.945996) (xy 280.89733 -331.938884)
			(xy 280.90368 -331.921866) (xy 280.90368 -331.836522) (xy 280.89733 -331.819504) (xy 280.891234 -331.812392)
			(xy 280.873587 -331.791464) (xy 280.843862 -331.745496) (xy 280.821017 -331.695749) (xy 280.805521 -331.643246)
			(xy 280.797692 -331.589066) (xy 280.797693 -331.534325) (xy 280.805522 -331.480145) (xy 280.82102 -331.427643)
			(xy 280.843866 -331.377896) (xy 280.873593 -331.331929) (xy 280.891234 -331.310996) (xy 280.89733 -331.303884)
			(xy 280.90368 -331.286866) (xy 280.90368 -331.201522) (xy 280.89733 -331.184504) (xy 280.891234 -331.177392)
			(xy 280.873587 -331.156464) (xy 280.843862 -331.110496) (xy 280.821017 -331.060749) (xy 280.805521 -331.008246)
			(xy 280.797692 -330.954066) (xy 280.797693 -330.899325) (xy 280.805522 -330.845145) (xy 280.82102 -330.792643)
			(xy 280.843866 -330.742896) (xy 280.873593 -330.696929) (xy 280.891234 -330.675996) (xy 280.89733 -330.668884)
			(xy 280.90368 -330.651866) (xy 280.90368 -330.566522) (xy 280.89733 -330.549504) (xy 280.891234 -330.542392)
			(xy 280.873583 -330.521469) (xy 280.843872 -330.475495) (xy 280.821038 -330.425745) (xy 280.805549 -330.373242)
			(xy 280.797725 -330.319064) (xy 280.797254 -330.291694) (xy 280.797772 -330.264444) (xy 280.805528 -330.2105)
			(xy 280.820882 -330.158208) (xy 280.843521 -330.108633) (xy 280.872985 -330.062785) (xy 280.908673 -330.021595)
			(xy 280.949859 -329.985904) (xy 280.995705 -329.956437) (xy 281.045278 -329.933794) (xy 281.097568 -329.918435)
			(xy 281.151512 -329.910674) (xy 281.178762 -329.910186) (xy 281.206131 -329.910678) (xy 281.260309 -329.91849)
			(xy 281.312812 -329.933973) (xy 281.362559 -329.956809) (xy 281.408527 -329.986528) (xy 281.42946 -330.004166)
			(xy 281.436572 -330.010262) (xy 281.45359 -330.016612) (xy 281.538934 -330.016612) (xy 281.555952 -330.010262)
			(xy 281.563064 -330.004166) (xy 281.583997 -329.986525) (xy 281.629965 -329.956801) (xy 281.679711 -329.933955)
			(xy 281.732213 -329.918459) (xy 281.786391 -329.91063) (xy 281.841133 -329.91063) (xy 281.895311 -329.918459)
			(xy 281.947813 -329.933955) (xy 281.997559 -329.956801) (xy 282.043527 -329.986525) (xy 282.06446 -330.004166)
			(xy 282.071572 -330.010262) (xy 282.08859 -330.016612) (xy 282.173934 -330.016612) (xy 282.190952 -330.010262)
			(xy 282.198064 -330.004166) (xy 282.218994 -329.986525) (xy 282.264968 -329.956815) (xy 282.314716 -329.93398)
			(xy 282.367217 -329.918489) (xy 282.421393 -329.91066) (xy 282.448762 -329.910186) (xy 282.476014 -329.910691)
			(xy 282.529963 -329.918442) (xy 282.58226 -329.933793) (xy 282.631839 -329.956431) (xy 282.677692 -329.985894)
			(xy 282.718885 -330.021584) (xy 282.754579 -330.062773) (xy 282.784048 -330.108622) (xy 282.806691 -330.158199)
			(xy 282.822048 -330.210494) (xy 282.829806 -330.264442) (xy 282.83027 -330.291694) (xy 282.829808 -330.319064)
			(xy 282.82199 -330.373244) (xy 282.806501 -330.425747) (xy 282.783658 -330.475494) (xy 282.753932 -330.521461)
			(xy 282.73629 -330.542392) (xy 282.730194 -330.549504) (xy 282.723844 -330.566522) (xy 282.723844 -330.651866)
			(xy 282.730194 -330.668884) (xy 282.73629 -330.675996) (xy 282.753924 -330.696934) (xy 282.783648 -330.742901)
			(xy 282.806493 -330.792647) (xy 282.821989 -330.845148) (xy 282.829817 -330.899325) (xy 282.829818 -330.954066)
			(xy 282.82199 -331.008243) (xy 282.806496 -331.060745) (xy 282.783652 -331.110491) (xy 282.75393 -331.156459)
			(xy 282.73629 -331.177392) (xy 282.730194 -331.184504) (xy 282.723844 -331.201522) (xy 282.723844 -331.286866)
			(xy 282.730194 -331.303884) (xy 282.73629 -331.310996) (xy 282.753924 -331.331934) (xy 282.783648 -331.377901)
			(xy 282.806493 -331.427647) (xy 282.821989 -331.480148) (xy 282.829817 -331.534325) (xy 282.829818 -331.589066)
			(xy 282.82199 -331.643243) (xy 282.806496 -331.695745) (xy 282.783652 -331.745491) (xy 282.75393 -331.791459)
			(xy 282.73629 -331.812392) (xy 282.730194 -331.819504) (xy 282.723844 -331.836522) (xy 282.723844 -331.921866)
			(xy 282.730194 -331.938884) (xy 282.73629 -331.945996) (xy 282.753924 -331.966934) (xy 282.783648 -332.012901)
			(xy 282.806493 -332.062647) (xy 282.821989 -332.115148) (xy 282.829817 -332.169325) (xy 282.829818 -332.224066)
			(xy 282.82199 -332.278243) (xy 282.806496 -332.330745) (xy 282.783652 -332.380491) (xy 282.75393 -332.426459)
			(xy 282.73629 -332.447392) (xy 282.730194 -332.454504) (xy 282.723844 -332.471522) (xy 282.723844 -332.556866)
			(xy 282.730194 -332.573884) (xy 282.73629 -332.580996) (xy 282.753924 -332.601934) (xy 282.783648 -332.647901)
			(xy 282.806493 -332.697647) (xy 282.821989 -332.750148) (xy 282.829817 -332.804325) (xy 282.829818 -332.859066)
			(xy 282.82199 -332.913243) (xy 282.806496 -332.965745) (xy 282.783652 -333.015491) (xy 282.75393 -333.061459)
			(xy 282.73629 -333.082392) (xy 282.730194 -333.089504) (xy 282.723844 -333.106522) (xy 282.723844 -333.191866)
			(xy 282.730194 -333.208884) (xy 282.73629 -333.215996) (xy 282.753924 -333.236934) (xy 282.783648 -333.282901)
			(xy 282.806493 -333.332647) (xy 282.821989 -333.385148) (xy 282.829817 -333.439325) (xy 282.829818 -333.494066)
			(xy 282.82199 -333.548243) (xy 282.806496 -333.600745) (xy 282.783652 -333.650491) (xy 282.75393 -333.696459)
			(xy 282.73629 -333.717392) (xy 282.730194 -333.724504) (xy 282.723844 -333.741522) (xy 282.723844 -333.826866)
			(xy 282.730194 -333.843884) (xy 282.73629 -333.850996) (xy 282.753924 -333.871934) (xy 282.783648 -333.917901)
			(xy 282.806493 -333.967647) (xy 282.821989 -334.020148) (xy 282.829817 -334.074325) (xy 282.829818 -334.129066)
			(xy 282.82199 -334.183243) (xy 282.806496 -334.235745) (xy 282.783652 -334.285491) (xy 282.75393 -334.331459)
			(xy 282.73629 -334.352392) (xy 282.730194 -334.359504) (xy 282.723844 -334.376522) (xy 282.723844 -334.461866)
			(xy 282.730194 -334.478884) (xy 282.73629 -334.485996) (xy 282.753939 -334.50692) (xy 282.78365 -334.552895)
			(xy 282.806484 -334.602644) (xy 282.821973 -334.655147) (xy 282.829798 -334.709324) (xy 282.83027 -334.736694)
			(xy 284.810454 -334.736694) (xy 284.810903 -334.709323) (xy 284.818723 -334.655143) (xy 284.834215 -334.602639)
			(xy 284.857061 -334.552892) (xy 284.88679 -334.506927) (xy 284.904434 -334.485996) (xy 284.91053 -334.478884)
			(xy 284.91688 -334.461866) (xy 284.91688 -334.376522) (xy 284.91053 -334.359504) (xy 284.904434 -334.352392)
			(xy 284.886787 -334.331464) (xy 284.857062 -334.285496) (xy 284.834217 -334.235749) (xy 284.818721 -334.183246)
			(xy 284.810892 -334.129066) (xy 284.810893 -334.074325) (xy 284.818722 -334.020145) (xy 284.83422 -333.967643)
			(xy 284.857066 -333.917896) (xy 284.886793 -333.871929) (xy 284.904434 -333.850996) (xy 284.91053 -333.843884)
			(xy 284.91688 -333.826866) (xy 284.91688 -333.741522) (xy 284.91053 -333.724504) (xy 284.904434 -333.717392)
			(xy 284.886787 -333.696464) (xy 284.857062 -333.650496) (xy 284.834217 -333.600749) (xy 284.818721 -333.548246)
			(xy 284.810892 -333.494066) (xy 284.810893 -333.439325) (xy 284.818722 -333.385145) (xy 284.83422 -333.332643)
			(xy 284.857066 -333.282896) (xy 284.886793 -333.236929) (xy 284.904434 -333.215996) (xy 284.91053 -333.208884)
			(xy 284.91688 -333.191866) (xy 284.91688 -333.106522) (xy 284.91053 -333.089504) (xy 284.904434 -333.082392)
			(xy 284.886787 -333.061464) (xy 284.857062 -333.015496) (xy 284.834217 -332.965749) (xy 284.818721 -332.913246)
			(xy 284.810892 -332.859066) (xy 284.810893 -332.804325) (xy 284.818722 -332.750145) (xy 284.83422 -332.697643)
			(xy 284.857066 -332.647896) (xy 284.886793 -332.601929) (xy 284.904434 -332.580996) (xy 284.91053 -332.573884)
			(xy 284.91688 -332.556866) (xy 284.91688 -332.471522) (xy 284.91053 -332.454504) (xy 284.904434 -332.447392)
			(xy 284.886787 -332.426464) (xy 284.857062 -332.380496) (xy 284.834217 -332.330749) (xy 284.818721 -332.278246)
			(xy 284.810892 -332.224066) (xy 284.810893 -332.169325) (xy 284.818722 -332.115145) (xy 284.83422 -332.062643)
			(xy 284.857066 -332.012896) (xy 284.886793 -331.966929) (xy 284.904434 -331.945996) (xy 284.91053 -331.938884)
			(xy 284.91688 -331.921866) (xy 284.91688 -331.836522) (xy 284.91053 -331.819504) (xy 284.904434 -331.812392)
			(xy 284.886787 -331.791464) (xy 284.857062 -331.745496) (xy 284.834217 -331.695749) (xy 284.818721 -331.643246)
			(xy 284.810892 -331.589066) (xy 284.810893 -331.534325) (xy 284.818722 -331.480145) (xy 284.83422 -331.427643)
			(xy 284.857066 -331.377896) (xy 284.886793 -331.331929) (xy 284.904434 -331.310996) (xy 284.91053 -331.303884)
			(xy 284.91688 -331.286866) (xy 284.91688 -331.201522) (xy 284.91053 -331.184504) (xy 284.904434 -331.177392)
			(xy 284.886787 -331.156464) (xy 284.857062 -331.110496) (xy 284.834217 -331.060749) (xy 284.818721 -331.008246)
			(xy 284.810892 -330.954066) (xy 284.810893 -330.899325) (xy 284.818722 -330.845145) (xy 284.83422 -330.792643)
			(xy 284.857066 -330.742896) (xy 284.886793 -330.696929) (xy 284.904434 -330.675996) (xy 284.91053 -330.668884)
			(xy 284.91688 -330.651866) (xy 284.91688 -330.566522) (xy 284.91053 -330.549504) (xy 284.904434 -330.542392)
			(xy 284.886783 -330.521469) (xy 284.857072 -330.475495) (xy 284.834238 -330.425745) (xy 284.818749 -330.373242)
			(xy 284.810925 -330.319064) (xy 284.810454 -330.291694) (xy 284.810972 -330.264444) (xy 284.818728 -330.2105)
			(xy 284.834082 -330.158208) (xy 284.856721 -330.108633) (xy 284.886185 -330.062785) (xy 284.921873 -330.021595)
			(xy 284.963059 -329.985904) (xy 285.008905 -329.956437) (xy 285.058478 -329.933794) (xy 285.110768 -329.918435)
			(xy 285.164712 -329.910674) (xy 285.191962 -329.910186) (xy 285.219331 -329.910678) (xy 285.273509 -329.91849)
			(xy 285.326012 -329.933973) (xy 285.375759 -329.956809) (xy 285.421727 -329.986528) (xy 285.44266 -330.004166)
			(xy 285.449772 -330.010262) (xy 285.46679 -330.016612) (xy 285.552134 -330.016612) (xy 285.569152 -330.010262)
			(xy 285.576264 -330.004166) (xy 285.597197 -329.986525) (xy 285.643165 -329.956801) (xy 285.692911 -329.933955)
			(xy 285.745413 -329.918459) (xy 285.799591 -329.91063) (xy 285.854333 -329.91063) (xy 285.908511 -329.918459)
			(xy 285.961013 -329.933955) (xy 286.010759 -329.956801) (xy 286.056727 -329.986525) (xy 286.07766 -330.004166)
			(xy 286.084772 -330.010262) (xy 286.10179 -330.016612) (xy 286.187134 -330.016612) (xy 286.204152 -330.010262)
			(xy 286.211264 -330.004166) (xy 286.232194 -329.986525) (xy 286.278168 -329.956815) (xy 286.327916 -329.93398)
			(xy 286.380417 -329.918489) (xy 286.434593 -329.91066) (xy 286.461962 -329.910186) (xy 286.489214 -329.910691)
			(xy 286.543163 -329.918442) (xy 286.59546 -329.933793) (xy 286.645039 -329.956431) (xy 286.690892 -329.985894)
			(xy 286.732085 -330.021584) (xy 286.767779 -330.062773) (xy 286.797248 -330.108622) (xy 286.819891 -330.158199)
			(xy 286.835248 -330.210494) (xy 286.843006 -330.264442) (xy 286.84347 -330.291694) (xy 286.843008 -330.319064)
			(xy 286.83519 -330.373244) (xy 286.819701 -330.425747) (xy 286.796858 -330.475494) (xy 286.767132 -330.521461)
			(xy 286.74949 -330.542392) (xy 286.743394 -330.549504) (xy 286.737044 -330.566522) (xy 286.737044 -330.651866)
			(xy 286.743394 -330.668884) (xy 286.74949 -330.675996) (xy 286.767124 -330.696934) (xy 286.796848 -330.742901)
			(xy 286.819693 -330.792647) (xy 286.835189 -330.845148) (xy 286.843017 -330.899325) (xy 286.843018 -330.954066)
			(xy 286.83519 -331.008243) (xy 286.819696 -331.060745) (xy 286.796852 -331.110491) (xy 286.76713 -331.156459)
			(xy 286.74949 -331.177392) (xy 286.743394 -331.184504) (xy 286.737044 -331.201522) (xy 286.737044 -331.286866)
			(xy 286.743394 -331.303884) (xy 286.74949 -331.310996) (xy 286.767124 -331.331934) (xy 286.796848 -331.377901)
			(xy 286.819693 -331.427647) (xy 286.835189 -331.480148) (xy 286.843017 -331.534325) (xy 286.843018 -331.589066)
			(xy 286.83519 -331.643243) (xy 286.819696 -331.695745) (xy 286.796852 -331.745491) (xy 286.76713 -331.791459)
			(xy 286.74949 -331.812392) (xy 286.743394 -331.819504) (xy 286.737044 -331.836522) (xy 286.737044 -331.921866)
			(xy 286.743394 -331.938884) (xy 286.74949 -331.945996) (xy 286.767124 -331.966934) (xy 286.796848 -332.012901)
			(xy 286.819693 -332.062647) (xy 286.835189 -332.115148) (xy 286.843017 -332.169325) (xy 286.843018 -332.224066)
			(xy 286.83519 -332.278243) (xy 286.819696 -332.330745) (xy 286.796852 -332.380491) (xy 286.76713 -332.426459)
			(xy 286.74949 -332.447392) (xy 286.743394 -332.454504) (xy 286.737044 -332.471522) (xy 286.737044 -332.556866)
			(xy 286.743394 -332.573884) (xy 286.74949 -332.580996) (xy 286.767124 -332.601934) (xy 286.796848 -332.647901)
			(xy 286.819693 -332.697647) (xy 286.835189 -332.750148) (xy 286.843017 -332.804325) (xy 286.843018 -332.859066)
			(xy 286.83519 -332.913243) (xy 286.819696 -332.965745) (xy 286.796852 -333.015491) (xy 286.76713 -333.061459)
			(xy 286.74949 -333.082392) (xy 286.743394 -333.089504) (xy 286.737044 -333.106522) (xy 286.737044 -333.191866)
			(xy 286.743394 -333.208884) (xy 286.74949 -333.215996) (xy 286.767124 -333.236934) (xy 286.796848 -333.282901)
			(xy 286.819693 -333.332647) (xy 286.835189 -333.385148) (xy 286.843017 -333.439325) (xy 286.843018 -333.494066)
			(xy 286.83519 -333.548243) (xy 286.819696 -333.600745) (xy 286.796852 -333.650491) (xy 286.76713 -333.696459)
			(xy 286.74949 -333.717392) (xy 286.743394 -333.724504) (xy 286.737044 -333.741522) (xy 286.737044 -333.826866)
			(xy 286.743394 -333.843884) (xy 286.74949 -333.850996) (xy 286.767124 -333.871934) (xy 286.796848 -333.917901)
			(xy 286.819693 -333.967647) (xy 286.835189 -334.020148) (xy 286.843017 -334.074325) (xy 286.843018 -334.129066)
			(xy 286.83519 -334.183243) (xy 286.819696 -334.235745) (xy 286.796852 -334.285491) (xy 286.76713 -334.331459)
			(xy 286.74949 -334.352392) (xy 286.743394 -334.359504) (xy 286.737044 -334.376522) (xy 286.737044 -334.461866)
			(xy 286.743394 -334.478884) (xy 286.74949 -334.485996) (xy 286.767139 -334.50692) (xy 286.79685 -334.552895)
			(xy 286.819684 -334.602644) (xy 286.835173 -334.655147) (xy 286.842998 -334.709324) (xy 286.84347 -334.736694)
			(xy 289.103054 -334.736694) (xy 289.103503 -334.709323) (xy 289.111323 -334.655143) (xy 289.126815 -334.602639)
			(xy 289.149661 -334.552892) (xy 289.17939 -334.506927) (xy 289.197034 -334.485996) (xy 289.20313 -334.478884)
			(xy 289.20948 -334.461866) (xy 289.20948 -334.376522) (xy 289.20313 -334.359504) (xy 289.197034 -334.352392)
			(xy 289.179387 -334.331464) (xy 289.149662 -334.285496) (xy 289.126817 -334.235749) (xy 289.111321 -334.183246)
			(xy 289.103492 -334.129066) (xy 289.103493 -334.074325) (xy 289.111322 -334.020145) (xy 289.12682 -333.967643)
			(xy 289.149666 -333.917896) (xy 289.179393 -333.871929) (xy 289.197034 -333.850996) (xy 289.20313 -333.843884)
			(xy 289.20948 -333.826866) (xy 289.20948 -333.741522) (xy 289.20313 -333.724504) (xy 289.197034 -333.717392)
			(xy 289.179387 -333.696464) (xy 289.149662 -333.650496) (xy 289.126817 -333.600749) (xy 289.111321 -333.548246)
			(xy 289.103492 -333.494066) (xy 289.103493 -333.439325) (xy 289.111322 -333.385145) (xy 289.12682 -333.332643)
			(xy 289.149666 -333.282896) (xy 289.179393 -333.236929) (xy 289.197034 -333.215996) (xy 289.20313 -333.208884)
			(xy 289.20948 -333.191866) (xy 289.20948 -333.106522) (xy 289.20313 -333.089504) (xy 289.197034 -333.082392)
			(xy 289.179387 -333.061464) (xy 289.149662 -333.015496) (xy 289.126817 -332.965749) (xy 289.111321 -332.913246)
			(xy 289.103492 -332.859066) (xy 289.103493 -332.804325) (xy 289.111322 -332.750145) (xy 289.12682 -332.697643)
			(xy 289.149666 -332.647896) (xy 289.179393 -332.601929) (xy 289.197034 -332.580996) (xy 289.20313 -332.573884)
			(xy 289.20948 -332.556866) (xy 289.20948 -332.471522) (xy 289.20313 -332.454504) (xy 289.197034 -332.447392)
			(xy 289.179387 -332.426464) (xy 289.149662 -332.380496) (xy 289.126817 -332.330749) (xy 289.111321 -332.278246)
			(xy 289.103492 -332.224066) (xy 289.103493 -332.169325) (xy 289.111322 -332.115145) (xy 289.12682 -332.062643)
			(xy 289.149666 -332.012896) (xy 289.179393 -331.966929) (xy 289.197034 -331.945996) (xy 289.20313 -331.938884)
			(xy 289.20948 -331.921866) (xy 289.20948 -331.836522) (xy 289.20313 -331.819504) (xy 289.197034 -331.812392)
			(xy 289.179387 -331.791464) (xy 289.149662 -331.745496) (xy 289.126817 -331.695749) (xy 289.111321 -331.643246)
			(xy 289.103492 -331.589066) (xy 289.103493 -331.534325) (xy 289.111322 -331.480145) (xy 289.12682 -331.427643)
			(xy 289.149666 -331.377896) (xy 289.179393 -331.331929) (xy 289.197034 -331.310996) (xy 289.20313 -331.303884)
			(xy 289.20948 -331.286866) (xy 289.20948 -331.201522) (xy 289.20313 -331.184504) (xy 289.197034 -331.177392)
			(xy 289.179387 -331.156464) (xy 289.149662 -331.110496) (xy 289.126817 -331.060749) (xy 289.111321 -331.008246)
			(xy 289.103492 -330.954066) (xy 289.103493 -330.899325) (xy 289.111322 -330.845145) (xy 289.12682 -330.792643)
			(xy 289.149666 -330.742896) (xy 289.179393 -330.696929) (xy 289.197034 -330.675996) (xy 289.20313 -330.668884)
			(xy 289.20948 -330.651866) (xy 289.20948 -330.566522) (xy 289.20313 -330.549504) (xy 289.197034 -330.542392)
			(xy 289.179383 -330.521469) (xy 289.149672 -330.475495) (xy 289.126838 -330.425745) (xy 289.111349 -330.373242)
			(xy 289.103525 -330.319064) (xy 289.103054 -330.291694) (xy 289.103572 -330.264444) (xy 289.111328 -330.2105)
			(xy 289.126682 -330.158208) (xy 289.149321 -330.108633) (xy 289.178785 -330.062785) (xy 289.214473 -330.021595)
			(xy 289.255659 -329.985904) (xy 289.301505 -329.956437) (xy 289.351078 -329.933794) (xy 289.403368 -329.918435)
			(xy 289.457312 -329.910674) (xy 289.484562 -329.910186) (xy 289.511931 -329.910678) (xy 289.566109 -329.91849)
			(xy 289.618612 -329.933973) (xy 289.668359 -329.956809) (xy 289.714327 -329.986528) (xy 289.73526 -330.004166)
			(xy 289.742372 -330.010262) (xy 289.75939 -330.016612) (xy 289.844734 -330.016612) (xy 289.861752 -330.010262)
			(xy 289.868864 -330.004166) (xy 289.889797 -329.986525) (xy 289.935765 -329.956801) (xy 289.985511 -329.933955)
			(xy 290.038013 -329.918459) (xy 290.092191 -329.91063) (xy 290.146933 -329.91063) (xy 290.201111 -329.918459)
			(xy 290.253613 -329.933955) (xy 290.303359 -329.956801) (xy 290.349327 -329.986525) (xy 290.37026 -330.004166)
			(xy 290.377372 -330.010262) (xy 290.39439 -330.016612) (xy 290.479734 -330.016612) (xy 290.496752 -330.010262)
			(xy 290.503864 -330.004166) (xy 290.524794 -329.986525) (xy 290.570768 -329.956815) (xy 290.620516 -329.93398)
			(xy 290.673017 -329.918489) (xy 290.727193 -329.91066) (xy 290.754562 -329.910186) (xy 290.781814 -329.910691)
			(xy 290.835763 -329.918442) (xy 290.88806 -329.933793) (xy 290.937639 -329.956431) (xy 290.983492 -329.985894)
			(xy 291.024685 -330.021584) (xy 291.060379 -330.062773) (xy 291.089848 -330.108622) (xy 291.112491 -330.158199)
			(xy 291.127848 -330.210494) (xy 291.135606 -330.264442) (xy 291.13607 -330.291694) (xy 291.135608 -330.319064)
			(xy 291.12779 -330.373244) (xy 291.112301 -330.425747) (xy 291.089458 -330.475494) (xy 291.059732 -330.521461)
			(xy 291.04209 -330.542392) (xy 291.035994 -330.549504) (xy 291.029644 -330.566522) (xy 291.029644 -330.651866)
			(xy 291.035994 -330.668884) (xy 291.04209 -330.675996) (xy 291.059724 -330.696934) (xy 291.089448 -330.742901)
			(xy 291.112293 -330.792647) (xy 291.127789 -330.845148) (xy 291.135617 -330.899325) (xy 291.135618 -330.954066)
			(xy 291.12779 -331.008243) (xy 291.112296 -331.060745) (xy 291.089452 -331.110491) (xy 291.05973 -331.156459)
			(xy 291.04209 -331.177392) (xy 291.035994 -331.184504) (xy 291.029644 -331.201522) (xy 291.029644 -331.286866)
			(xy 291.035994 -331.303884) (xy 291.04209 -331.310996) (xy 291.059724 -331.331934) (xy 291.089448 -331.377901)
			(xy 291.112293 -331.427647) (xy 291.127789 -331.480148) (xy 291.135617 -331.534325) (xy 291.135618 -331.589066)
			(xy 291.12779 -331.643243) (xy 291.112296 -331.695745) (xy 291.089452 -331.745491) (xy 291.05973 -331.791459)
			(xy 291.04209 -331.812392) (xy 291.035994 -331.819504) (xy 291.029644 -331.836522) (xy 291.029644 -331.921866)
			(xy 291.035994 -331.938884) (xy 291.04209 -331.945996) (xy 291.059724 -331.966934) (xy 291.089448 -332.012901)
			(xy 291.112293 -332.062647) (xy 291.127789 -332.115148) (xy 291.135617 -332.169325) (xy 291.135618 -332.224066)
			(xy 291.12779 -332.278243) (xy 291.112296 -332.330745) (xy 291.089452 -332.380491) (xy 291.05973 -332.426459)
			(xy 291.04209 -332.447392) (xy 291.035994 -332.454504) (xy 291.029644 -332.471522) (xy 291.029644 -332.556866)
			(xy 291.035994 -332.573884) (xy 291.04209 -332.580996) (xy 291.059724 -332.601934) (xy 291.089448 -332.647901)
			(xy 291.112293 -332.697647) (xy 291.127789 -332.750148) (xy 291.135617 -332.804325) (xy 291.135618 -332.859066)
			(xy 291.12779 -332.913243) (xy 291.112296 -332.965745) (xy 291.089452 -333.015491) (xy 291.05973 -333.061459)
			(xy 291.04209 -333.082392) (xy 291.035994 -333.089504) (xy 291.029644 -333.106522) (xy 291.029644 -333.191866)
			(xy 291.035994 -333.208884) (xy 291.04209 -333.215996) (xy 291.059724 -333.236934) (xy 291.089448 -333.282901)
			(xy 291.112293 -333.332647) (xy 291.127789 -333.385148) (xy 291.135617 -333.439325) (xy 291.135618 -333.494066)
			(xy 291.12779 -333.548243) (xy 291.112296 -333.600745) (xy 291.089452 -333.650491) (xy 291.05973 -333.696459)
			(xy 291.04209 -333.717392) (xy 291.035994 -333.724504) (xy 291.029644 -333.741522) (xy 291.029644 -333.826866)
			(xy 291.035994 -333.843884) (xy 291.04209 -333.850996) (xy 291.059724 -333.871934) (xy 291.089448 -333.917901)
			(xy 291.112293 -333.967647) (xy 291.127789 -334.020148) (xy 291.135617 -334.074325) (xy 291.135618 -334.129066)
			(xy 291.12779 -334.183243) (xy 291.112296 -334.235745) (xy 291.089452 -334.285491) (xy 291.05973 -334.331459)
			(xy 291.04209 -334.352392) (xy 291.035994 -334.359504) (xy 291.029644 -334.376522) (xy 291.029644 -334.461866)
			(xy 291.035994 -334.478884) (xy 291.04209 -334.485996) (xy 291.059739 -334.50692) (xy 291.08945 -334.552895)
			(xy 291.112284 -334.602644) (xy 291.127773 -334.655147) (xy 291.135598 -334.709324) (xy 291.13607 -334.736694)
			(xy 293.116254 -334.736694) (xy 293.116703 -334.709323) (xy 293.124523 -334.655143) (xy 293.140015 -334.602639)
			(xy 293.162861 -334.552892) (xy 293.19259 -334.506927) (xy 293.210234 -334.485996) (xy 293.21633 -334.478884)
			(xy 293.22268 -334.461866) (xy 293.22268 -334.376522) (xy 293.21633 -334.359504) (xy 293.210234 -334.352392)
			(xy 293.192587 -334.331464) (xy 293.162862 -334.285496) (xy 293.140017 -334.235749) (xy 293.124521 -334.183246)
			(xy 293.116692 -334.129066) (xy 293.116693 -334.074325) (xy 293.124522 -334.020145) (xy 293.14002 -333.967643)
			(xy 293.162866 -333.917896) (xy 293.192593 -333.871929) (xy 293.210234 -333.850996) (xy 293.21633 -333.843884)
			(xy 293.22268 -333.826866) (xy 293.22268 -333.741522) (xy 293.21633 -333.724504) (xy 293.210234 -333.717392)
			(xy 293.192587 -333.696464) (xy 293.162862 -333.650496) (xy 293.140017 -333.600749) (xy 293.124521 -333.548246)
			(xy 293.116692 -333.494066) (xy 293.116693 -333.439325) (xy 293.124522 -333.385145) (xy 293.14002 -333.332643)
			(xy 293.162866 -333.282896) (xy 293.192593 -333.236929) (xy 293.210234 -333.215996) (xy 293.21633 -333.208884)
			(xy 293.22268 -333.191866) (xy 293.22268 -333.106522) (xy 293.21633 -333.089504) (xy 293.210234 -333.082392)
			(xy 293.192587 -333.061464) (xy 293.162862 -333.015496) (xy 293.140017 -332.965749) (xy 293.124521 -332.913246)
			(xy 293.116692 -332.859066) (xy 293.116693 -332.804325) (xy 293.124522 -332.750145) (xy 293.14002 -332.697643)
			(xy 293.162866 -332.647896) (xy 293.192593 -332.601929) (xy 293.210234 -332.580996) (xy 293.21633 -332.573884)
			(xy 293.22268 -332.556866) (xy 293.22268 -332.471522) (xy 293.21633 -332.454504) (xy 293.210234 -332.447392)
			(xy 293.192587 -332.426464) (xy 293.162862 -332.380496) (xy 293.140017 -332.330749) (xy 293.124521 -332.278246)
			(xy 293.116692 -332.224066) (xy 293.116693 -332.169325) (xy 293.124522 -332.115145) (xy 293.14002 -332.062643)
			(xy 293.162866 -332.012896) (xy 293.192593 -331.966929) (xy 293.210234 -331.945996) (xy 293.21633 -331.938884)
			(xy 293.22268 -331.921866) (xy 293.22268 -331.836522) (xy 293.21633 -331.819504) (xy 293.210234 -331.812392)
			(xy 293.192587 -331.791464) (xy 293.162862 -331.745496) (xy 293.140017 -331.695749) (xy 293.124521 -331.643246)
			(xy 293.116692 -331.589066) (xy 293.116693 -331.534325) (xy 293.124522 -331.480145) (xy 293.14002 -331.427643)
			(xy 293.162866 -331.377896) (xy 293.192593 -331.331929) (xy 293.210234 -331.310996) (xy 293.21633 -331.303884)
			(xy 293.22268 -331.286866) (xy 293.22268 -331.201522) (xy 293.21633 -331.184504) (xy 293.210234 -331.177392)
			(xy 293.192587 -331.156464) (xy 293.162862 -331.110496) (xy 293.140017 -331.060749) (xy 293.124521 -331.008246)
			(xy 293.116692 -330.954066) (xy 293.116693 -330.899325) (xy 293.124522 -330.845145) (xy 293.14002 -330.792643)
			(xy 293.162866 -330.742896) (xy 293.192593 -330.696929) (xy 293.210234 -330.675996) (xy 293.21633 -330.668884)
			(xy 293.22268 -330.651866) (xy 293.22268 -330.566522) (xy 293.21633 -330.549504) (xy 293.210234 -330.542392)
			(xy 293.192583 -330.521469) (xy 293.162872 -330.475495) (xy 293.140038 -330.425745) (xy 293.124549 -330.373242)
			(xy 293.116725 -330.319064) (xy 293.116254 -330.291694) (xy 293.116772 -330.264444) (xy 293.124528 -330.2105)
			(xy 293.139882 -330.158208) (xy 293.162521 -330.108633) (xy 293.191985 -330.062785) (xy 293.227673 -330.021595)
			(xy 293.268859 -329.985904) (xy 293.314705 -329.956437) (xy 293.364278 -329.933794) (xy 293.416568 -329.918435)
			(xy 293.470512 -329.910674) (xy 293.497762 -329.910186) (xy 293.525131 -329.910678) (xy 293.579309 -329.91849)
			(xy 293.631812 -329.933973) (xy 293.681559 -329.956809) (xy 293.727527 -329.986528) (xy 293.74846 -330.004166)
			(xy 293.755572 -330.010262) (xy 293.77259 -330.016612) (xy 293.857934 -330.016612) (xy 293.874952 -330.010262)
			(xy 293.882064 -330.004166) (xy 293.902997 -329.986525) (xy 293.948965 -329.956801) (xy 293.998711 -329.933955)
			(xy 294.051213 -329.918459) (xy 294.105391 -329.91063) (xy 294.160133 -329.91063) (xy 294.214311 -329.918459)
			(xy 294.266813 -329.933955) (xy 294.316559 -329.956801) (xy 294.362527 -329.986525) (xy 294.38346 -330.004166)
			(xy 294.390572 -330.010262) (xy 294.40759 -330.016612) (xy 294.492934 -330.016612) (xy 294.509952 -330.010262)
			(xy 294.517064 -330.004166) (xy 294.537994 -329.986525) (xy 294.583968 -329.956815) (xy 294.633716 -329.93398)
			(xy 294.686217 -329.918489) (xy 294.740393 -329.91066) (xy 294.767762 -329.910186) (xy 294.795014 -329.910691)
			(xy 294.848963 -329.918442) (xy 294.90126 -329.933793) (xy 294.950839 -329.956431) (xy 294.996692 -329.985894)
			(xy 295.037885 -330.021584) (xy 295.073579 -330.062773) (xy 295.103048 -330.108622) (xy 295.125691 -330.158199)
			(xy 295.141048 -330.210494) (xy 295.148806 -330.264442) (xy 295.14927 -330.291694) (xy 295.148808 -330.319064)
			(xy 295.14099 -330.373244) (xy 295.125501 -330.425747) (xy 295.102658 -330.475494) (xy 295.072932 -330.521461)
			(xy 295.05529 -330.542392) (xy 295.049194 -330.549504) (xy 295.042844 -330.566522) (xy 295.042844 -330.651866)
			(xy 295.049194 -330.668884) (xy 295.05529 -330.675996) (xy 295.072924 -330.696934) (xy 295.102648 -330.742901)
			(xy 295.125493 -330.792647) (xy 295.140989 -330.845148) (xy 295.148817 -330.899325) (xy 295.148818 -330.954066)
			(xy 295.14099 -331.008243) (xy 295.125496 -331.060745) (xy 295.102652 -331.110491) (xy 295.07293 -331.156459)
			(xy 295.05529 -331.177392) (xy 295.049194 -331.184504) (xy 295.042844 -331.201522) (xy 295.042844 -331.286866)
			(xy 295.049194 -331.303884) (xy 295.05529 -331.310996) (xy 295.072924 -331.331934) (xy 295.102648 -331.377901)
			(xy 295.125493 -331.427647) (xy 295.140989 -331.480148) (xy 295.148817 -331.534325) (xy 295.148818 -331.589066)
			(xy 295.14099 -331.643243) (xy 295.125496 -331.695745) (xy 295.102652 -331.745491) (xy 295.07293 -331.791459)
			(xy 295.05529 -331.812392) (xy 295.049194 -331.819504) (xy 295.042844 -331.836522) (xy 295.042844 -331.921866)
			(xy 295.049194 -331.938884) (xy 295.05529 -331.945996) (xy 295.072924 -331.966934) (xy 295.102648 -332.012901)
			(xy 295.125493 -332.062647) (xy 295.140989 -332.115148) (xy 295.148817 -332.169325) (xy 295.148818 -332.224066)
			(xy 295.14099 -332.278243) (xy 295.125496 -332.330745) (xy 295.102652 -332.380491) (xy 295.07293 -332.426459)
			(xy 295.05529 -332.447392) (xy 295.049194 -332.454504) (xy 295.042844 -332.471522) (xy 295.042844 -332.556866)
			(xy 295.049194 -332.573884) (xy 295.05529 -332.580996) (xy 295.072924 -332.601934) (xy 295.102648 -332.647901)
			(xy 295.125493 -332.697647) (xy 295.140989 -332.750148) (xy 295.148817 -332.804325) (xy 295.148818 -332.859066)
			(xy 295.14099 -332.913243) (xy 295.125496 -332.965745) (xy 295.102652 -333.015491) (xy 295.07293 -333.061459)
			(xy 295.05529 -333.082392) (xy 295.049194 -333.089504) (xy 295.042844 -333.106522) (xy 295.042844 -333.191866)
			(xy 295.049194 -333.208884) (xy 295.05529 -333.215996) (xy 295.072924 -333.236934) (xy 295.102648 -333.282901)
			(xy 295.125493 -333.332647) (xy 295.140989 -333.385148) (xy 295.148817 -333.439325) (xy 295.148818 -333.494066)
			(xy 295.14099 -333.548243) (xy 295.125496 -333.600745) (xy 295.102652 -333.650491) (xy 295.07293 -333.696459)
			(xy 295.05529 -333.717392) (xy 295.049194 -333.724504) (xy 295.042844 -333.741522) (xy 295.042844 -333.826866)
			(xy 295.049194 -333.843884) (xy 295.05529 -333.850996) (xy 295.072924 -333.871934) (xy 295.102648 -333.917901)
			(xy 295.125493 -333.967647) (xy 295.140989 -334.020148) (xy 295.148817 -334.074325) (xy 295.148818 -334.129066)
			(xy 295.14099 -334.183243) (xy 295.125496 -334.235745) (xy 295.102652 -334.285491) (xy 295.07293 -334.331459)
			(xy 295.05529 -334.352392) (xy 295.049194 -334.359504) (xy 295.042844 -334.376522) (xy 295.042844 -334.461866)
			(xy 295.049194 -334.478884) (xy 295.05529 -334.485996) (xy 295.072939 -334.50692) (xy 295.10265 -334.552895)
			(xy 295.125484 -334.602644) (xy 295.140973 -334.655147) (xy 295.148798 -334.709324) (xy 295.14927 -334.736694)
			(xy 297.459654 -334.736694) (xy 297.460103 -334.709323) (xy 297.467923 -334.655143) (xy 297.483415 -334.602639)
			(xy 297.506261 -334.552892) (xy 297.53599 -334.506927) (xy 297.553634 -334.485996) (xy 297.55973 -334.478884)
			(xy 297.56608 -334.461866) (xy 297.56608 -334.376522) (xy 297.55973 -334.359504) (xy 297.553634 -334.352392)
			(xy 297.535987 -334.331464) (xy 297.506262 -334.285496) (xy 297.483417 -334.235749) (xy 297.467921 -334.183246)
			(xy 297.460092 -334.129066) (xy 297.460093 -334.074325) (xy 297.467922 -334.020145) (xy 297.48342 -333.967643)
			(xy 297.506266 -333.917896) (xy 297.535993 -333.871929) (xy 297.553634 -333.850996) (xy 297.55973 -333.843884)
			(xy 297.56608 -333.826866) (xy 297.56608 -333.741522) (xy 297.55973 -333.724504) (xy 297.553634 -333.717392)
			(xy 297.535987 -333.696464) (xy 297.506262 -333.650496) (xy 297.483417 -333.600749) (xy 297.467921 -333.548246)
			(xy 297.460092 -333.494066) (xy 297.460093 -333.439325) (xy 297.467922 -333.385145) (xy 297.48342 -333.332643)
			(xy 297.506266 -333.282896) (xy 297.535993 -333.236929) (xy 297.553634 -333.215996) (xy 297.55973 -333.208884)
			(xy 297.56608 -333.191866) (xy 297.56608 -333.106522) (xy 297.55973 -333.089504) (xy 297.553634 -333.082392)
			(xy 297.535987 -333.061464) (xy 297.506262 -333.015496) (xy 297.483417 -332.965749) (xy 297.467921 -332.913246)
			(xy 297.460092 -332.859066) (xy 297.460093 -332.804325) (xy 297.467922 -332.750145) (xy 297.48342 -332.697643)
			(xy 297.506266 -332.647896) (xy 297.535993 -332.601929) (xy 297.553634 -332.580996) (xy 297.55973 -332.573884)
			(xy 297.56608 -332.556866) (xy 297.56608 -332.471522) (xy 297.55973 -332.454504) (xy 297.553634 -332.447392)
			(xy 297.535987 -332.426464) (xy 297.506262 -332.380496) (xy 297.483417 -332.330749) (xy 297.467921 -332.278246)
			(xy 297.460092 -332.224066) (xy 297.460093 -332.169325) (xy 297.467922 -332.115145) (xy 297.48342 -332.062643)
			(xy 297.506266 -332.012896) (xy 297.535993 -331.966929) (xy 297.553634 -331.945996) (xy 297.55973 -331.938884)
			(xy 297.56608 -331.921866) (xy 297.56608 -331.836522) (xy 297.55973 -331.819504) (xy 297.553634 -331.812392)
			(xy 297.535987 -331.791464) (xy 297.506262 -331.745496) (xy 297.483417 -331.695749) (xy 297.467921 -331.643246)
			(xy 297.460092 -331.589066) (xy 297.460093 -331.534325) (xy 297.467922 -331.480145) (xy 297.48342 -331.427643)
			(xy 297.506266 -331.377896) (xy 297.535993 -331.331929) (xy 297.553634 -331.310996) (xy 297.55973 -331.303884)
			(xy 297.56608 -331.286866) (xy 297.56608 -331.201522) (xy 297.55973 -331.184504) (xy 297.553634 -331.177392)
			(xy 297.535987 -331.156464) (xy 297.506262 -331.110496) (xy 297.483417 -331.060749) (xy 297.467921 -331.008246)
			(xy 297.460092 -330.954066) (xy 297.460093 -330.899325) (xy 297.467922 -330.845145) (xy 297.48342 -330.792643)
			(xy 297.506266 -330.742896) (xy 297.535993 -330.696929) (xy 297.553634 -330.675996) (xy 297.55973 -330.668884)
			(xy 297.56608 -330.651866) (xy 297.56608 -330.566522) (xy 297.55973 -330.549504) (xy 297.553634 -330.542392)
			(xy 297.535983 -330.521469) (xy 297.506272 -330.475495) (xy 297.483438 -330.425745) (xy 297.467949 -330.373242)
			(xy 297.460125 -330.319064) (xy 297.459654 -330.291694) (xy 297.460172 -330.264444) (xy 297.467928 -330.2105)
			(xy 297.483282 -330.158208) (xy 297.505921 -330.108633) (xy 297.535385 -330.062785) (xy 297.571073 -330.021595)
			(xy 297.612259 -329.985904) (xy 297.658105 -329.956437) (xy 297.707678 -329.933794) (xy 297.759968 -329.918435)
			(xy 297.813912 -329.910674) (xy 297.841162 -329.910186) (xy 297.868531 -329.910678) (xy 297.922709 -329.91849)
			(xy 297.975212 -329.933973) (xy 298.024959 -329.956809) (xy 298.070927 -329.986528) (xy 298.09186 -330.004166)
			(xy 298.098972 -330.010262) (xy 298.11599 -330.016612) (xy 298.201334 -330.016612) (xy 298.218352 -330.010262)
			(xy 298.225464 -330.004166) (xy 298.246397 -329.986525) (xy 298.292365 -329.956801) (xy 298.342111 -329.933955)
			(xy 298.394613 -329.918459) (xy 298.448791 -329.91063) (xy 298.503533 -329.91063) (xy 298.557711 -329.918459)
			(xy 298.610213 -329.933955) (xy 298.659959 -329.956801) (xy 298.705927 -329.986525) (xy 298.72686 -330.004166)
			(xy 298.733972 -330.010262) (xy 298.75099 -330.016612) (xy 298.836334 -330.016612) (xy 298.853352 -330.010262)
			(xy 298.860464 -330.004166) (xy 298.881394 -329.986525) (xy 298.927368 -329.956815) (xy 298.977116 -329.93398)
			(xy 299.029617 -329.918489) (xy 299.083793 -329.91066) (xy 299.111162 -329.910186) (xy 299.138414 -329.910691)
			(xy 299.192363 -329.918442) (xy 299.24466 -329.933793) (xy 299.294239 -329.956431) (xy 299.340092 -329.985894)
			(xy 299.381285 -330.021584) (xy 299.416979 -330.062773) (xy 299.446448 -330.108622) (xy 299.469091 -330.158199)
			(xy 299.484448 -330.210494) (xy 299.492206 -330.264442) (xy 299.49267 -330.291694) (xy 299.492208 -330.319064)
			(xy 299.48439 -330.373244) (xy 299.468901 -330.425747) (xy 299.446058 -330.475494) (xy 299.416332 -330.521461)
			(xy 299.39869 -330.542392) (xy 299.392594 -330.549504) (xy 299.386244 -330.566522) (xy 299.386244 -330.651866)
			(xy 299.392594 -330.668884) (xy 299.39869 -330.675996) (xy 299.416324 -330.696934) (xy 299.446048 -330.742901)
			(xy 299.468893 -330.792647) (xy 299.484389 -330.845148) (xy 299.492217 -330.899325) (xy 299.492218 -330.954066)
			(xy 299.48439 -331.008243) (xy 299.468896 -331.060745) (xy 299.446052 -331.110491) (xy 299.41633 -331.156459)
			(xy 299.39869 -331.177392) (xy 299.392594 -331.184504) (xy 299.386244 -331.201522) (xy 299.386244 -331.286866)
			(xy 299.392594 -331.303884) (xy 299.39869 -331.310996) (xy 299.416324 -331.331934) (xy 299.446048 -331.377901)
			(xy 299.468893 -331.427647) (xy 299.484389 -331.480148) (xy 299.492217 -331.534325) (xy 299.492218 -331.589066)
			(xy 299.48439 -331.643243) (xy 299.468896 -331.695745) (xy 299.446052 -331.745491) (xy 299.41633 -331.791459)
			(xy 299.39869 -331.812392) (xy 299.392594 -331.819504) (xy 299.386244 -331.836522) (xy 299.386244 -331.921866)
			(xy 299.392594 -331.938884) (xy 299.39869 -331.945996) (xy 299.416324 -331.966934) (xy 299.446048 -332.012901)
			(xy 299.468893 -332.062647) (xy 299.484389 -332.115148) (xy 299.492217 -332.169325) (xy 299.492218 -332.224066)
			(xy 299.48439 -332.278243) (xy 299.468896 -332.330745) (xy 299.446052 -332.380491) (xy 299.41633 -332.426459)
			(xy 299.39869 -332.447392) (xy 299.392594 -332.454504) (xy 299.386244 -332.471522) (xy 299.386244 -332.556866)
			(xy 299.392594 -332.573884) (xy 299.39869 -332.580996) (xy 299.416324 -332.601934) (xy 299.446048 -332.647901)
			(xy 299.468893 -332.697647) (xy 299.484389 -332.750148) (xy 299.492217 -332.804325) (xy 299.492218 -332.859066)
			(xy 299.48439 -332.913243) (xy 299.468896 -332.965745) (xy 299.446052 -333.015491) (xy 299.41633 -333.061459)
			(xy 299.39869 -333.082392) (xy 299.392594 -333.089504) (xy 299.386244 -333.106522) (xy 299.386244 -333.191866)
			(xy 299.392594 -333.208884) (xy 299.39869 -333.215996) (xy 299.416324 -333.236934) (xy 299.446048 -333.282901)
			(xy 299.468893 -333.332647) (xy 299.484389 -333.385148) (xy 299.492217 -333.439325) (xy 299.492218 -333.494066)
			(xy 299.48439 -333.548243) (xy 299.468896 -333.600745) (xy 299.446052 -333.650491) (xy 299.41633 -333.696459)
			(xy 299.39869 -333.717392) (xy 299.392594 -333.724504) (xy 299.386244 -333.741522) (xy 299.386244 -333.826866)
			(xy 299.392594 -333.843884) (xy 299.39869 -333.850996) (xy 299.416324 -333.871934) (xy 299.446048 -333.917901)
			(xy 299.468893 -333.967647) (xy 299.484389 -334.020148) (xy 299.492217 -334.074325) (xy 299.492218 -334.129066)
			(xy 299.48439 -334.183243) (xy 299.468896 -334.235745) (xy 299.446052 -334.285491) (xy 299.41633 -334.331459)
			(xy 299.39869 -334.352392) (xy 299.392594 -334.359504) (xy 299.386244 -334.376522) (xy 299.386244 -334.461866)
			(xy 299.392594 -334.478884) (xy 299.39869 -334.485996) (xy 299.416339 -334.50692) (xy 299.44605 -334.552895)
			(xy 299.468884 -334.602644) (xy 299.484373 -334.655147) (xy 299.492198 -334.709324) (xy 299.49267 -334.736694)
			(xy 301.472854 -334.736694) (xy 301.473303 -334.709323) (xy 301.481123 -334.655143) (xy 301.496615 -334.602639)
			(xy 301.519461 -334.552892) (xy 301.54919 -334.506927) (xy 301.566834 -334.485996) (xy 301.57293 -334.478884)
			(xy 301.57928 -334.461866) (xy 301.57928 -334.376522) (xy 301.57293 -334.359504) (xy 301.566834 -334.352392)
			(xy 301.549187 -334.331464) (xy 301.519462 -334.285496) (xy 301.496617 -334.235749) (xy 301.481121 -334.183246)
			(xy 301.473292 -334.129066) (xy 301.473293 -334.074325) (xy 301.481122 -334.020145) (xy 301.49662 -333.967643)
			(xy 301.519466 -333.917896) (xy 301.549193 -333.871929) (xy 301.566834 -333.850996) (xy 301.57293 -333.843884)
			(xy 301.57928 -333.826866) (xy 301.57928 -333.741522) (xy 301.57293 -333.724504) (xy 301.566834 -333.717392)
			(xy 301.549187 -333.696464) (xy 301.519462 -333.650496) (xy 301.496617 -333.600749) (xy 301.481121 -333.548246)
			(xy 301.473292 -333.494066) (xy 301.473293 -333.439325) (xy 301.481122 -333.385145) (xy 301.49662 -333.332643)
			(xy 301.519466 -333.282896) (xy 301.549193 -333.236929) (xy 301.566834 -333.215996) (xy 301.57293 -333.208884)
			(xy 301.57928 -333.191866) (xy 301.57928 -333.106522) (xy 301.57293 -333.089504) (xy 301.566834 -333.082392)
			(xy 301.549187 -333.061464) (xy 301.519462 -333.015496) (xy 301.496617 -332.965749) (xy 301.481121 -332.913246)
			(xy 301.473292 -332.859066) (xy 301.473293 -332.804325) (xy 301.481122 -332.750145) (xy 301.49662 -332.697643)
			(xy 301.519466 -332.647896) (xy 301.549193 -332.601929) (xy 301.566834 -332.580996) (xy 301.57293 -332.573884)
			(xy 301.57928 -332.556866) (xy 301.57928 -332.471522) (xy 301.57293 -332.454504) (xy 301.566834 -332.447392)
			(xy 301.549187 -332.426464) (xy 301.519462 -332.380496) (xy 301.496617 -332.330749) (xy 301.481121 -332.278246)
			(xy 301.473292 -332.224066) (xy 301.473293 -332.169325) (xy 301.481122 -332.115145) (xy 301.49662 -332.062643)
			(xy 301.519466 -332.012896) (xy 301.549193 -331.966929) (xy 301.566834 -331.945996) (xy 301.57293 -331.938884)
			(xy 301.57928 -331.921866) (xy 301.57928 -331.836522) (xy 301.57293 -331.819504) (xy 301.566834 -331.812392)
			(xy 301.549187 -331.791464) (xy 301.519462 -331.745496) (xy 301.496617 -331.695749) (xy 301.481121 -331.643246)
			(xy 301.473292 -331.589066) (xy 301.473293 -331.534325) (xy 301.481122 -331.480145) (xy 301.49662 -331.427643)
			(xy 301.519466 -331.377896) (xy 301.549193 -331.331929) (xy 301.566834 -331.310996) (xy 301.57293 -331.303884)
			(xy 301.57928 -331.286866) (xy 301.57928 -331.201522) (xy 301.57293 -331.184504) (xy 301.566834 -331.177392)
			(xy 301.549187 -331.156464) (xy 301.519462 -331.110496) (xy 301.496617 -331.060749) (xy 301.481121 -331.008246)
			(xy 301.473292 -330.954066) (xy 301.473293 -330.899325) (xy 301.481122 -330.845145) (xy 301.49662 -330.792643)
			(xy 301.519466 -330.742896) (xy 301.549193 -330.696929) (xy 301.566834 -330.675996) (xy 301.57293 -330.668884)
			(xy 301.57928 -330.651866) (xy 301.57928 -330.566522) (xy 301.57293 -330.549504) (xy 301.566834 -330.542392)
			(xy 301.549183 -330.521469) (xy 301.519472 -330.475495) (xy 301.496638 -330.425745) (xy 301.481149 -330.373242)
			(xy 301.473325 -330.319064) (xy 301.472854 -330.291694) (xy 301.473372 -330.264444) (xy 301.481128 -330.2105)
			(xy 301.496482 -330.158208) (xy 301.519121 -330.108633) (xy 301.548585 -330.062785) (xy 301.584273 -330.021595)
			(xy 301.625459 -329.985904) (xy 301.671305 -329.956437) (xy 301.720878 -329.933794) (xy 301.773168 -329.918435)
			(xy 301.827112 -329.910674) (xy 301.854362 -329.910186) (xy 301.881731 -329.910678) (xy 301.935909 -329.91849)
			(xy 301.988412 -329.933973) (xy 302.038159 -329.956809) (xy 302.084127 -329.986528) (xy 302.10506 -330.004166)
			(xy 302.112172 -330.010262) (xy 302.12919 -330.016612) (xy 302.214534 -330.016612) (xy 302.231552 -330.010262)
			(xy 302.238664 -330.004166) (xy 302.259597 -329.986525) (xy 302.305565 -329.956801) (xy 302.355311 -329.933955)
			(xy 302.407813 -329.918459) (xy 302.461991 -329.91063) (xy 302.516733 -329.91063) (xy 302.570911 -329.918459)
			(xy 302.623413 -329.933955) (xy 302.673159 -329.956801) (xy 302.719127 -329.986525) (xy 302.74006 -330.004166)
			(xy 302.747172 -330.010262) (xy 302.76419 -330.016612) (xy 302.849534 -330.016612) (xy 302.866552 -330.010262)
			(xy 302.873664 -330.004166) (xy 302.894594 -329.986525) (xy 302.940568 -329.956815) (xy 302.990316 -329.93398)
			(xy 303.042817 -329.918489) (xy 303.096993 -329.91066) (xy 303.124362 -329.910186) (xy 303.151614 -329.910691)
			(xy 303.205563 -329.918442) (xy 303.25786 -329.933793) (xy 303.307439 -329.956431) (xy 303.353292 -329.985894)
			(xy 303.394485 -330.021584) (xy 303.430179 -330.062773) (xy 303.459648 -330.108622) (xy 303.482291 -330.158199)
			(xy 303.497648 -330.210494) (xy 303.505406 -330.264442) (xy 303.50587 -330.291694) (xy 303.505408 -330.319064)
			(xy 303.49759 -330.373244) (xy 303.482101 -330.425747) (xy 303.459258 -330.475494) (xy 303.429532 -330.521461)
			(xy 303.41189 -330.542392) (xy 303.405794 -330.549504) (xy 303.399444 -330.566522) (xy 303.399444 -330.651866)
			(xy 303.405794 -330.668884) (xy 303.41189 -330.675996) (xy 303.429524 -330.696934) (xy 303.459248 -330.742901)
			(xy 303.482093 -330.792647) (xy 303.497589 -330.845148) (xy 303.505417 -330.899325) (xy 303.505418 -330.954066)
			(xy 303.49759 -331.008243) (xy 303.482096 -331.060745) (xy 303.459252 -331.110491) (xy 303.42953 -331.156459)
			(xy 303.41189 -331.177392) (xy 303.405794 -331.184504) (xy 303.399444 -331.201522) (xy 303.399444 -331.286866)
			(xy 303.405794 -331.303884) (xy 303.41189 -331.310996) (xy 303.429524 -331.331934) (xy 303.459248 -331.377901)
			(xy 303.482093 -331.427647) (xy 303.497589 -331.480148) (xy 303.505417 -331.534325) (xy 303.505418 -331.589066)
			(xy 303.49759 -331.643243) (xy 303.482096 -331.695745) (xy 303.459252 -331.745491) (xy 303.42953 -331.791459)
			(xy 303.41189 -331.812392) (xy 303.405794 -331.819504) (xy 303.399444 -331.836522) (xy 303.399444 -331.921866)
			(xy 303.405794 -331.938884) (xy 303.41189 -331.945996) (xy 303.429524 -331.966934) (xy 303.459248 -332.012901)
			(xy 303.482093 -332.062647) (xy 303.497589 -332.115148) (xy 303.505417 -332.169325) (xy 303.505418 -332.224066)
			(xy 303.49759 -332.278243) (xy 303.482096 -332.330745) (xy 303.459252 -332.380491) (xy 303.42953 -332.426459)
			(xy 303.41189 -332.447392) (xy 303.405794 -332.454504) (xy 303.399444 -332.471522) (xy 303.399444 -332.556866)
			(xy 303.405794 -332.573884) (xy 303.41189 -332.580996) (xy 303.429524 -332.601934) (xy 303.459248 -332.647901)
			(xy 303.482093 -332.697647) (xy 303.497589 -332.750148) (xy 303.505417 -332.804325) (xy 303.505418 -332.859066)
			(xy 303.49759 -332.913243) (xy 303.482096 -332.965745) (xy 303.459252 -333.015491) (xy 303.42953 -333.061459)
			(xy 303.41189 -333.082392) (xy 303.405794 -333.089504) (xy 303.399444 -333.106522) (xy 303.399444 -333.191866)
			(xy 303.405794 -333.208884) (xy 303.41189 -333.215996) (xy 303.429524 -333.236934) (xy 303.459248 -333.282901)
			(xy 303.482093 -333.332647) (xy 303.497589 -333.385148) (xy 303.505417 -333.439325) (xy 303.505418 -333.494066)
			(xy 303.49759 -333.548243) (xy 303.482096 -333.600745) (xy 303.459252 -333.650491) (xy 303.42953 -333.696459)
			(xy 303.41189 -333.717392) (xy 303.405794 -333.724504) (xy 303.399444 -333.741522) (xy 303.399444 -333.826866)
			(xy 303.405794 -333.843884) (xy 303.41189 -333.850996) (xy 303.429524 -333.871934) (xy 303.459248 -333.917901)
			(xy 303.482093 -333.967647) (xy 303.497589 -334.020148) (xy 303.505417 -334.074325) (xy 303.505418 -334.129066)
			(xy 303.49759 -334.183243) (xy 303.482096 -334.235745) (xy 303.459252 -334.285491) (xy 303.42953 -334.331459)
			(xy 303.41189 -334.352392) (xy 303.405794 -334.359504) (xy 303.399444 -334.376522) (xy 303.399444 -334.461866)
			(xy 303.405794 -334.478884) (xy 303.41189 -334.485996) (xy 303.429539 -334.50692) (xy 303.45925 -334.552895)
			(xy 303.482084 -334.602644) (xy 303.497573 -334.655147) (xy 303.505398 -334.709324) (xy 303.50587 -334.736694)
			(xy 303.505439 -334.763948) (xy 303.497682 -334.817902) (xy 303.482325 -334.870203) (xy 303.45968 -334.919786)
			(xy 303.430209 -334.965641) (xy 303.394512 -335.006835) (xy 303.353315 -335.042528) (xy 303.307458 -335.071995)
			(xy 303.257873 -335.094636) (xy 303.205571 -335.109989) (xy 303.151616 -335.117741) (xy 303.124362 -335.118202)
			(xy 303.096993 -335.117699) (xy 303.042816 -335.10989) (xy 302.990313 -335.09441) (xy 302.940565 -335.071576)
			(xy 302.894597 -335.041859) (xy 302.873664 -335.024222) (xy 302.866552 -335.018126) (xy 302.849534 -335.011776)
			(xy 302.76419 -335.011776) (xy 302.747172 -335.018126) (xy 302.74006 -335.024222) (xy 302.719127 -335.041863)
			(xy 302.673159 -335.071587) (xy 302.623413 -335.094433) (xy 302.570911 -335.109929) (xy 302.516733 -335.117758)
			(xy 302.461991 -335.117758) (xy 302.407813 -335.109929) (xy 302.355311 -335.094433) (xy 302.305565 -335.071587)
			(xy 302.259597 -335.041863) (xy 302.238664 -335.024222) (xy 302.231552 -335.018126) (xy 302.214534 -335.011776)
			(xy 302.12919 -335.011776) (xy 302.112172 -335.018126) (xy 302.10506 -335.024222) (xy 302.084119 -335.04185)
			(xy 302.038148 -335.071563) (xy 301.988403 -335.0944) (xy 301.935904 -335.109894) (xy 301.88173 -335.117726)
			(xy 301.854362 -335.118202) (xy 301.82711 -335.117758) (xy 301.77316 -335.109996) (xy 301.720864 -335.094635)
			(xy 301.671286 -335.071989) (xy 301.625436 -335.042519) (xy 301.584246 -335.006823) (xy 301.548555 -334.965629)
			(xy 301.519089 -334.919775) (xy 301.496449 -334.870195) (xy 301.481095 -334.817897) (xy 301.473339 -334.763947)
			(xy 301.472854 -334.736694) (xy 299.49267 -334.736694) (xy 299.492239 -334.763948) (xy 299.484482 -334.817902)
			(xy 299.469125 -334.870203) (xy 299.44648 -334.919786) (xy 299.417009 -334.965641) (xy 299.381312 -335.006835)
			(xy 299.340115 -335.042528) (xy 299.294258 -335.071995) (xy 299.244673 -335.094636) (xy 299.192371 -335.109989)
			(xy 299.138416 -335.117741) (xy 299.111162 -335.118202) (xy 299.083793 -335.117699) (xy 299.029616 -335.10989)
			(xy 298.977113 -335.09441) (xy 298.927365 -335.071576) (xy 298.881397 -335.041859) (xy 298.860464 -335.024222)
			(xy 298.853352 -335.018126) (xy 298.836334 -335.011776) (xy 298.75099 -335.011776) (xy 298.733972 -335.018126)
			(xy 298.72686 -335.024222) (xy 298.705927 -335.041863) (xy 298.659959 -335.071587) (xy 298.610213 -335.094433)
			(xy 298.557711 -335.109929) (xy 298.503533 -335.117758) (xy 298.448791 -335.117758) (xy 298.394613 -335.109929)
			(xy 298.342111 -335.094433) (xy 298.292365 -335.071587) (xy 298.246397 -335.041863) (xy 298.225464 -335.024222)
			(xy 298.218352 -335.018126) (xy 298.201334 -335.011776) (xy 298.11599 -335.011776) (xy 298.098972 -335.018126)
			(xy 298.09186 -335.024222) (xy 298.070919 -335.04185) (xy 298.024948 -335.071563) (xy 297.975203 -335.0944)
			(xy 297.922704 -335.109894) (xy 297.86853 -335.117726) (xy 297.841162 -335.118202) (xy 297.81391 -335.117758)
			(xy 297.75996 -335.109996) (xy 297.707664 -335.094635) (xy 297.658086 -335.071989) (xy 297.612236 -335.042519)
			(xy 297.571046 -335.006823) (xy 297.535355 -334.965629) (xy 297.505889 -334.919775) (xy 297.483249 -334.870195)
			(xy 297.467895 -334.817897) (xy 297.460139 -334.763947) (xy 297.459654 -334.736694) (xy 295.14927 -334.736694)
			(xy 295.148839 -334.763948) (xy 295.141082 -334.817902) (xy 295.125725 -334.870203) (xy 295.10308 -334.919786)
			(xy 295.073609 -334.965641) (xy 295.037912 -335.006835) (xy 294.996715 -335.042528) (xy 294.950858 -335.071995)
			(xy 294.901273 -335.094636) (xy 294.848971 -335.109989) (xy 294.795016 -335.117741) (xy 294.767762 -335.118202)
			(xy 294.740393 -335.117699) (xy 294.686216 -335.10989) (xy 294.633713 -335.09441) (xy 294.583965 -335.071576)
			(xy 294.537997 -335.041859) (xy 294.517064 -335.024222) (xy 294.509952 -335.018126) (xy 294.492934 -335.011776)
			(xy 294.40759 -335.011776) (xy 294.390572 -335.018126) (xy 294.38346 -335.024222) (xy 294.362527 -335.041863)
			(xy 294.316559 -335.071587) (xy 294.266813 -335.094433) (xy 294.214311 -335.109929) (xy 294.160133 -335.117758)
			(xy 294.105391 -335.117758) (xy 294.051213 -335.109929) (xy 293.998711 -335.094433) (xy 293.948965 -335.071587)
			(xy 293.902997 -335.041863) (xy 293.882064 -335.024222) (xy 293.874952 -335.018126) (xy 293.857934 -335.011776)
			(xy 293.77259 -335.011776) (xy 293.755572 -335.018126) (xy 293.74846 -335.024222) (xy 293.727519 -335.04185)
			(xy 293.681548 -335.071563) (xy 293.631803 -335.0944) (xy 293.579304 -335.109894) (xy 293.52513 -335.117726)
			(xy 293.497762 -335.118202) (xy 293.47051 -335.117758) (xy 293.41656 -335.109996) (xy 293.364264 -335.094635)
			(xy 293.314686 -335.071989) (xy 293.268836 -335.042519) (xy 293.227646 -335.006823) (xy 293.191955 -334.965629)
			(xy 293.162489 -334.919775) (xy 293.139849 -334.870195) (xy 293.124495 -334.817897) (xy 293.116739 -334.763947)
			(xy 293.116254 -334.736694) (xy 291.13607 -334.736694) (xy 291.135639 -334.763948) (xy 291.127882 -334.817902)
			(xy 291.112525 -334.870203) (xy 291.08988 -334.919786) (xy 291.060409 -334.965641) (xy 291.024712 -335.006835)
			(xy 290.983515 -335.042528) (xy 290.937658 -335.071995) (xy 290.888073 -335.094636) (xy 290.835771 -335.109989)
			(xy 290.781816 -335.117741) (xy 290.754562 -335.118202) (xy 290.727193 -335.117699) (xy 290.673016 -335.10989)
			(xy 290.620513 -335.09441) (xy 290.570765 -335.071576) (xy 290.524797 -335.041859) (xy 290.503864 -335.024222)
			(xy 290.496752 -335.018126) (xy 290.479734 -335.011776) (xy 290.39439 -335.011776) (xy 290.377372 -335.018126)
			(xy 290.37026 -335.024222) (xy 290.349327 -335.041863) (xy 290.303359 -335.071587) (xy 290.253613 -335.094433)
			(xy 290.201111 -335.109929) (xy 290.146933 -335.117758) (xy 290.092191 -335.117758) (xy 290.038013 -335.109929)
			(xy 289.985511 -335.094433) (xy 289.935765 -335.071587) (xy 289.889797 -335.041863) (xy 289.868864 -335.024222)
			(xy 289.861752 -335.018126) (xy 289.844734 -335.011776) (xy 289.75939 -335.011776) (xy 289.742372 -335.018126)
			(xy 289.73526 -335.024222) (xy 289.714319 -335.04185) (xy 289.668348 -335.071563) (xy 289.618603 -335.0944)
			(xy 289.566104 -335.109894) (xy 289.51193 -335.117726) (xy 289.484562 -335.118202) (xy 289.45731 -335.117758)
			(xy 289.40336 -335.109996) (xy 289.351064 -335.094635) (xy 289.301486 -335.071989) (xy 289.255636 -335.042519)
			(xy 289.214446 -335.006823) (xy 289.178755 -334.965629) (xy 289.149289 -334.919775) (xy 289.126649 -334.870195)
			(xy 289.111295 -334.817897) (xy 289.103539 -334.763947) (xy 289.103054 -334.736694) (xy 286.84347 -334.736694)
			(xy 286.843039 -334.763948) (xy 286.835282 -334.817902) (xy 286.819925 -334.870203) (xy 286.79728 -334.919786)
			(xy 286.767809 -334.965641) (xy 286.732112 -335.006835) (xy 286.690915 -335.042528) (xy 286.645058 -335.071995)
			(xy 286.595473 -335.094636) (xy 286.543171 -335.109989) (xy 286.489216 -335.117741) (xy 286.461962 -335.118202)
			(xy 286.434593 -335.117699) (xy 286.380416 -335.10989) (xy 286.327913 -335.09441) (xy 286.278165 -335.071576)
			(xy 286.232197 -335.041859) (xy 286.211264 -335.024222) (xy 286.204152 -335.018126) (xy 286.187134 -335.011776)
			(xy 286.10179 -335.011776) (xy 286.084772 -335.018126) (xy 286.07766 -335.024222) (xy 286.056727 -335.041863)
			(xy 286.010759 -335.071587) (xy 285.961013 -335.094433) (xy 285.908511 -335.109929) (xy 285.854333 -335.117758)
			(xy 285.799591 -335.117758) (xy 285.745413 -335.109929) (xy 285.692911 -335.094433) (xy 285.643165 -335.071587)
			(xy 285.597197 -335.041863) (xy 285.576264 -335.024222) (xy 285.569152 -335.018126) (xy 285.552134 -335.011776)
			(xy 285.46679 -335.011776) (xy 285.449772 -335.018126) (xy 285.44266 -335.024222) (xy 285.421719 -335.04185)
			(xy 285.375748 -335.071563) (xy 285.326003 -335.0944) (xy 285.273504 -335.109894) (xy 285.21933 -335.117726)
			(xy 285.191962 -335.118202) (xy 285.16471 -335.117758) (xy 285.11076 -335.109996) (xy 285.058464 -335.094635)
			(xy 285.008886 -335.071989) (xy 284.963036 -335.042519) (xy 284.921846 -335.006823) (xy 284.886155 -334.965629)
			(xy 284.856689 -334.919775) (xy 284.834049 -334.870195) (xy 284.818695 -334.817897) (xy 284.810939 -334.763947)
			(xy 284.810454 -334.736694) (xy 282.83027 -334.736694) (xy 282.829839 -334.763948) (xy 282.822082 -334.817902)
			(xy 282.806725 -334.870203) (xy 282.78408 -334.919786) (xy 282.754609 -334.965641) (xy 282.718912 -335.006835)
			(xy 282.677715 -335.042528) (xy 282.631858 -335.071995) (xy 282.582273 -335.094636) (xy 282.529971 -335.109989)
			(xy 282.476016 -335.117741) (xy 282.448762 -335.118202) (xy 282.421393 -335.117699) (xy 282.367216 -335.10989)
			(xy 282.314713 -335.09441) (xy 282.264965 -335.071576) (xy 282.218997 -335.041859) (xy 282.198064 -335.024222)
			(xy 282.190952 -335.018126) (xy 282.173934 -335.011776) (xy 282.08859 -335.011776) (xy 282.071572 -335.018126)
			(xy 282.06446 -335.024222) (xy 282.043527 -335.041863) (xy 281.997559 -335.071587) (xy 281.947813 -335.094433)
			(xy 281.895311 -335.109929) (xy 281.841133 -335.117758) (xy 281.786391 -335.117758) (xy 281.732213 -335.109929)
			(xy 281.679711 -335.094433) (xy 281.629965 -335.071587) (xy 281.583997 -335.041863) (xy 281.563064 -335.024222)
			(xy 281.555952 -335.018126) (xy 281.538934 -335.011776) (xy 281.45359 -335.011776) (xy 281.436572 -335.018126)
			(xy 281.42946 -335.024222) (xy 281.408519 -335.04185) (xy 281.362548 -335.071563) (xy 281.312803 -335.0944)
			(xy 281.260304 -335.109894) (xy 281.20613 -335.117726) (xy 281.178762 -335.118202) (xy 281.15151 -335.117758)
			(xy 281.09756 -335.109996) (xy 281.045264 -335.094635) (xy 280.995686 -335.071989) (xy 280.949836 -335.042519)
			(xy 280.908646 -335.006823) (xy 280.872955 -334.965629) (xy 280.843489 -334.919775) (xy 280.820849 -334.870195)
			(xy 280.805495 -334.817897) (xy 280.797739 -334.763947) (xy 280.797254 -334.736694) (xy 278.56307 -334.736694)
			(xy 278.562639 -334.763948) (xy 278.554882 -334.817902) (xy 278.539525 -334.870203) (xy 278.51688 -334.919786)
			(xy 278.487409 -334.965641) (xy 278.451712 -335.006835) (xy 278.410515 -335.042528) (xy 278.364658 -335.071995)
			(xy 278.315073 -335.094636) (xy 278.262771 -335.109989) (xy 278.208816 -335.117741) (xy 278.181562 -335.118202)
			(xy 278.154193 -335.117699) (xy 278.100016 -335.10989) (xy 278.047513 -335.09441) (xy 277.997765 -335.071576)
			(xy 277.951797 -335.041859) (xy 277.930864 -335.024222) (xy 277.923752 -335.018126) (xy 277.906734 -335.011776)
			(xy 277.82139 -335.011776) (xy 277.804372 -335.018126) (xy 277.79726 -335.024222) (xy 277.776327 -335.041863)
			(xy 277.730359 -335.071587) (xy 277.680613 -335.094433) (xy 277.628111 -335.109929) (xy 277.573933 -335.117758)
			(xy 277.519191 -335.117758) (xy 277.465013 -335.109929) (xy 277.412511 -335.094433) (xy 277.362765 -335.071587)
			(xy 277.316797 -335.041863) (xy 277.295864 -335.024222) (xy 277.288752 -335.018126) (xy 277.271734 -335.011776)
			(xy 277.18639 -335.011776) (xy 277.169372 -335.018126) (xy 277.16226 -335.024222) (xy 277.141319 -335.04185)
			(xy 277.095348 -335.071563) (xy 277.045603 -335.0944) (xy 276.993104 -335.109894) (xy 276.93893 -335.117726)
			(xy 276.911562 -335.118202) (xy 276.88431 -335.117758) (xy 276.83036 -335.109996) (xy 276.778064 -335.094635)
			(xy 276.728486 -335.071989) (xy 276.682636 -335.042519) (xy 276.641446 -335.006823) (xy 276.605755 -334.965629)
			(xy 276.576289 -334.919775) (xy 276.553649 -334.870195) (xy 276.538295 -334.817897) (xy 276.530539 -334.763947)
			(xy 276.530054 -334.736694) (xy 274.54987 -334.736694) (xy 274.549439 -334.763948) (xy 274.541682 -334.817902)
			(xy 274.526325 -334.870203) (xy 274.50368 -334.919786) (xy 274.474209 -334.965641) (xy 274.438512 -335.006835)
			(xy 274.397315 -335.042528) (xy 274.351458 -335.071995) (xy 274.301873 -335.094636) (xy 274.249571 -335.109989)
			(xy 274.195616 -335.117741) (xy 274.168362 -335.118202) (xy 274.140993 -335.117699) (xy 274.086816 -335.10989)
			(xy 274.034313 -335.09441) (xy 273.984565 -335.071576) (xy 273.938597 -335.041859) (xy 273.917664 -335.024222)
			(xy 273.910552 -335.018126) (xy 273.893534 -335.011776) (xy 273.80819 -335.011776) (xy 273.791172 -335.018126)
			(xy 273.78406 -335.024222) (xy 273.763127 -335.041863) (xy 273.717159 -335.071587) (xy 273.667413 -335.094433)
			(xy 273.614911 -335.109929) (xy 273.560733 -335.117758) (xy 273.505991 -335.117758) (xy 273.451813 -335.109929)
			(xy 273.399311 -335.094433) (xy 273.349565 -335.071587) (xy 273.303597 -335.041863) (xy 273.282664 -335.024222)
			(xy 273.275552 -335.018126) (xy 273.258534 -335.011776) (xy 273.17319 -335.011776) (xy 273.156172 -335.018126)
			(xy 273.14906 -335.024222) (xy 273.128119 -335.04185) (xy 273.082148 -335.071563) (xy 273.032403 -335.0944)
			(xy 272.979904 -335.109894) (xy 272.92573 -335.117726) (xy 272.898362 -335.118202) (xy 272.87111 -335.117758)
			(xy 272.81716 -335.109996) (xy 272.764864 -335.094635) (xy 272.715286 -335.071989) (xy 272.669436 -335.042519)
			(xy 272.628246 -335.006823) (xy 272.592555 -334.965629) (xy 272.563089 -334.919775) (xy 272.540449 -334.870195)
			(xy 272.525095 -334.817897) (xy 272.517339 -334.763947) (xy 272.516854 -334.736694) (xy 260.41731 -334.736694)
			(xy 260.41731 -347.45422) (xy 260.417737 -347.464288) (xy 260.420833 -347.471746) (xy 271.103852 -347.471746)
			(xy 271.103852 -342.83015) (xy 271.104378 -342.800177) (xy 271.113696 -342.740962) (xy 271.132173 -342.683936)
			(xy 271.159353 -342.630508) (xy 271.194566 -342.581997) (xy 271.215358 -342.560402) (xy 272.221198 -341.554562)
			(xy 272.242846 -341.533833) (xy 272.291357 -341.498641) (xy 272.344774 -341.471467) (xy 272.401782 -341.452979)
			(xy 272.46098 -341.443631) (xy 272.490946 -341.443056) (xy 279.221946 -341.443056) (xy 279.251919 -341.443583)
			(xy 279.311134 -341.452901) (xy 279.36816 -341.471378) (xy 279.421588 -341.498558) (xy 279.470099 -341.53377)
			(xy 279.491694 -341.554562) (xy 279.694132 -341.757) (xy 279.701493 -341.763769) (xy 279.719955 -341.771416)
			(xy 279.739937 -341.771416) (xy 279.758399 -341.763769) (xy 279.76576 -341.757) (xy 279.968198 -341.554562)
			(xy 279.989846 -341.533833) (xy 280.038357 -341.498641) (xy 280.091774 -341.471467) (xy 280.148782 -341.452979)
			(xy 280.20798 -341.443631) (xy 280.237946 -341.443056) (xy 287.857946 -341.443056) (xy 287.887919 -341.443583)
			(xy 287.947134 -341.452901) (xy 288.00416 -341.471378) (xy 288.057588 -341.498558) (xy 288.106099 -341.53377)
			(xy 288.127694 -341.554562) (xy 288.266632 -341.6935) (xy 288.273993 -341.700269) (xy 288.292455 -341.707916)
			(xy 288.312437 -341.707916) (xy 288.330899 -341.700269) (xy 288.33826 -341.6935) (xy 288.604198 -341.427562)
			(xy 288.625846 -341.406833) (xy 288.674357 -341.371641) (xy 288.727774 -341.344467) (xy 288.784782 -341.325979)
			(xy 288.84398 -341.316631) (xy 288.873946 -341.316056) (xy 296.366946 -341.316056) (xy 296.396919 -341.316583)
			(xy 296.456134 -341.325901) (xy 296.51316 -341.344378) (xy 296.566588 -341.371558) (xy 296.615099 -341.40677)
			(xy 296.636694 -341.427562) (xy 296.712132 -341.503) (xy 296.719493 -341.509769) (xy 296.737955 -341.517416)
			(xy 296.757937 -341.517416) (xy 296.776399 -341.509769) (xy 296.78376 -341.503) (xy 296.859198 -341.427562)
			(xy 296.880846 -341.406833) (xy 296.929357 -341.371641) (xy 296.982774 -341.344467) (xy 297.039782 -341.325979)
			(xy 297.09898 -341.316631) (xy 297.128946 -341.316056) (xy 304.240946 -341.316056) (xy 304.270919 -341.316583)
			(xy 304.330134 -341.325901) (xy 304.38716 -341.344378) (xy 304.440588 -341.371558) (xy 304.489099 -341.40677)
			(xy 304.510694 -341.427562) (xy 304.723292 -341.64016) (xy 304.730653 -341.646929) (xy 304.749115 -341.654576)
			(xy 304.769097 -341.654576) (xy 304.787559 -341.646929) (xy 304.79492 -341.64016) (xy 305.007518 -341.427562)
			(xy 305.029158 -341.406824) (xy 305.077671 -341.371633) (xy 305.13109 -341.344461) (xy 305.1881 -341.325975)
			(xy 305.247299 -341.31663) (xy 305.277266 -341.316056) (xy 312.77433 -341.316056) (xy 312.784403 -341.315658)
			(xy 312.803001 -341.307919) (xy 312.810398 -341.30107) (xy 313.407806 -340.703662) (xy 313.414656 -340.69627)
			(xy 313.42237 -340.677665) (xy 313.422792 -340.667594) (xy 313.422792 -336.242152) (xy 313.423336 -336.21218)
			(xy 313.432653 -336.152966) (xy 313.451126 -336.095942) (xy 313.478302 -336.042514) (xy 313.513509 -335.994)
			(xy 313.534298 -335.972404) (xy 313.771788 -335.734914) (xy 313.793389 -335.714134) (xy 313.841914 -335.678951)
			(xy 313.895342 -335.651787) (xy 313.952361 -335.633311) (xy 314.011567 -335.623976) (xy 314.041536 -335.623408)
			(xy 314.045092 -335.623408) (xy 314.055098 -335.622906) (xy 314.073588 -335.61525) (xy 314.087741 -335.601102)
			(xy 314.095402 -335.582614) (xy 314.095892 -335.572608) (xy 314.095892 -331.306424) (xy 314.096418 -331.276451)
			(xy 314.105739 -331.217237) (xy 314.124217 -331.160212) (xy 314.151396 -331.106784) (xy 314.186607 -331.058271)
			(xy 314.207398 -331.036676) (xy 315.246512 -329.997562) (xy 315.268154 -329.976826) (xy 315.316667 -329.941636)
			(xy 315.370085 -329.914463) (xy 315.427095 -329.895976) (xy 315.486294 -329.88663) (xy 315.51626 -329.886056)
			(xy 322.50126 -329.886056) (xy 322.531233 -329.886574) (xy 322.590449 -329.895894) (xy 322.647475 -329.914373)
			(xy 322.700902 -329.941555) (xy 322.749414 -329.976769) (xy 322.771008 -329.997562) (xy 322.909946 -330.1365)
			(xy 322.917307 -330.143269) (xy 322.935769 -330.150916) (xy 322.955751 -330.150916) (xy 322.974213 -330.143269)
			(xy 322.981574 -330.1365) (xy 323.120512 -329.997562) (xy 323.142154 -329.976826) (xy 323.190667 -329.941636)
			(xy 323.244085 -329.914463) (xy 323.301095 -329.895976) (xy 323.360294 -329.88663) (xy 323.39026 -329.886056)
			(xy 330.50226 -329.886056) (xy 330.532233 -329.886574) (xy 330.591449 -329.895894) (xy 330.648475 -329.914373)
			(xy 330.701902 -329.941555) (xy 330.750414 -329.976769) (xy 330.772008 -329.997562) (xy 330.847446 -330.073)
			(xy 330.854807 -330.079769) (xy 330.873269 -330.087416) (xy 330.893251 -330.087416) (xy 330.911713 -330.079769)
			(xy 330.919074 -330.073) (xy 331.121512 -329.870562) (xy 331.143154 -329.849826) (xy 331.191667 -329.814636)
			(xy 331.245085 -329.787463) (xy 331.302095 -329.768976) (xy 331.361294 -329.75963) (xy 331.39126 -329.759056)
			(xy 338.94522 -329.759056) (xy 338.975192 -329.759599) (xy 339.034407 -329.768913) (xy 339.091432 -329.787386)
			(xy 339.14486 -329.814562) (xy 339.193373 -329.849771) (xy 339.214968 -329.870562) (xy 339.386926 -330.04252)
			(xy 339.394287 -330.049289) (xy 339.412749 -330.056936) (xy 339.432731 -330.056936) (xy 339.451193 -330.049289)
			(xy 339.458554 -330.04252) (xy 339.630512 -329.870562) (xy 339.652154 -329.849826) (xy 339.700667 -329.814636)
			(xy 339.754085 -329.787463) (xy 339.811095 -329.768976) (xy 339.870294 -329.75963) (xy 339.90026 -329.759056)
			(xy 347.475048 -329.759056) (xy 347.505021 -329.759582) (xy 347.564236 -329.7689) (xy 347.621262 -329.787377)
			(xy 347.67469 -329.814557) (xy 347.723201 -329.84977) (xy 347.744796 -329.870562) (xy 348.462854 -330.58862)
			(xy 348.483596 -330.610256) (xy 348.518786 -330.658771) (xy 348.545957 -330.71219) (xy 348.564442 -330.769201)
			(xy 348.573786 -330.828401) (xy 348.57436 -330.858368) (xy 348.57436 -335.153) (xy 348.573862 -335.182974)
			(xy 348.564537 -335.24219) (xy 348.546053 -335.299216) (xy 348.518866 -335.352643) (xy 348.483648 -335.401154)
			(xy 348.462854 -335.422748) (xy 348.295976 -335.589372) (xy 348.289265 -335.59684) (xy 348.281684 -335.615409)
			(xy 348.281244 -335.62544) (xy 348.281244 -340.68893) (xy 348.281545 -340.696949) (xy 348.28646 -340.712215)
			(xy 348.290896 -340.718902) (xy 348.308211 -340.743546) (xy 348.335718 -340.797125) (xy 348.354458 -340.854362)
			(xy 348.363967 -340.913833) (xy 348.364556 -340.943946) (xy 348.364043 -340.971866) (xy 348.355856 -341.027103)
			(xy 348.339707 -341.080557) (xy 348.315942 -341.131088) (xy 348.285067 -341.177617) (xy 348.266766 -341.198708)
			(xy 348.260416 -341.20582) (xy 348.253812 -341.223092) (xy 348.253812 -341.30996) (xy 348.260416 -341.327232)
			(xy 348.266766 -341.334344) (xy 348.285107 -341.355436) (xy 348.316011 -341.402011) (xy 348.339785 -341.452599)
			(xy 348.35592 -341.506114) (xy 348.364071 -341.561412) (xy 348.364556 -341.58936) (xy 348.36407 -341.616611)
			(xy 348.356314 -341.670559) (xy 348.340959 -341.722854) (xy 348.318317 -341.772431) (xy 348.288851 -341.818281)
			(xy 348.25316 -341.859472) (xy 348.211969 -341.895163) (xy 348.168809 -341.9229) (xy 351.983695 -341.9229)
			(xy 351.987864 -341.867274) (xy 352.000278 -341.812891) (xy 352.020658 -341.760965) (xy 352.04855 -341.712658)
			(xy 352.083331 -341.669047) (xy 352.124223 -341.631107) (xy 352.170314 -341.599686) (xy 352.220573 -341.575486)
			(xy 352.273878 -341.559047) (xy 352.329037 -341.550737) (xy 352.356928 -341.550244) (xy 352.38335 -341.550699)
			(xy 352.435665 -341.558151) (xy 352.486403 -341.572918) (xy 352.534547 -341.594702) (xy 352.579132 -341.623067)
			(xy 352.599498 -341.639906) (xy 352.606356 -341.646002) (xy 352.623374 -341.652098) (xy 352.707702 -341.652098)
			(xy 352.72472 -341.646002) (xy 352.731578 -341.639906) (xy 352.751944 -341.623067) (xy 352.79653 -341.594702)
			(xy 352.844674 -341.572915) (xy 352.895411 -341.558144) (xy 352.947726 -341.550684) (xy 353.00057 -341.550684)
			(xy 353.052885 -341.558144) (xy 353.103622 -341.572915) (xy 353.151766 -341.594702) (xy 353.196352 -341.623067)
			(xy 353.216718 -341.639906) (xy 353.223576 -341.646002) (xy 353.240594 -341.652098) (xy 353.324922 -341.652098)
			(xy 353.34194 -341.646002) (xy 353.348798 -341.639906) (xy 353.37117 -341.621476) (xy 353.420505 -341.591056)
			(xy 353.473954 -341.568638) (xy 353.50196 -341.561166) (xy 353.513644 -341.558372) (xy 353.531678 -341.542878)
			(xy 353.573334 -341.44712) (xy 353.572318 -341.423498) (xy 353.566476 -341.413084) (xy 353.554996 -341.391721)
			(xy 353.536944 -341.346707) (xy 353.524745 -341.299767) (xy 353.518595 -341.251659) (xy 353.518216 -341.22741)
			(xy 353.518683 -341.199835) (xy 353.526634 -341.145262) (xy 353.542359 -341.092402) (xy 353.565529 -341.042356)
			(xy 353.595661 -340.996167) (xy 353.632129 -340.954796) (xy 353.652836 -340.93658) (xy 353.660965 -340.928987)
			(xy 353.670312 -340.908828) (xy 353.67087 -340.897718) (xy 353.67087 -340.820502) (xy 353.670326 -340.809389)
			(xy 353.660972 -340.78923) (xy 353.652836 -340.78164) (xy 353.632148 -340.763403) (xy 353.595675 -340.722041)
			(xy 353.565539 -340.675857) (xy 353.542368 -340.625813) (xy 353.526647 -340.572955) (xy 353.518703 -340.518383)
			(xy 353.518216 -340.49081) (xy 353.518702 -340.463559) (xy 353.526458 -340.409611) (xy 353.541813 -340.357316)
			(xy 353.564455 -340.307739) (xy 353.593921 -340.261889) (xy 353.629612 -340.220698) (xy 353.670803 -340.185007)
			(xy 353.716653 -340.155541) (xy 353.76623 -340.132899) (xy 353.818525 -340.117544) (xy 353.872473 -340.109788)
			(xy 353.926975 -340.109788) (xy 353.980923 -340.117544) (xy 354.033218 -340.132899) (xy 354.082795 -340.155541)
			(xy 354.128645 -340.185007) (xy 354.169836 -340.220698) (xy 354.205527 -340.261889) (xy 354.234993 -340.307739)
			(xy 354.257635 -340.357316) (xy 354.27299 -340.409611) (xy 354.280746 -340.463559) (xy 354.281232 -340.49081)
			(xy 354.280693 -340.518382) (xy 354.272754 -340.572951) (xy 354.257043 -340.625809) (xy 354.233886 -340.675855)
			(xy 354.203767 -340.722046) (xy 354.167313 -340.763422) (xy 354.146612 -340.78164) (xy 354.138482 -340.789232)
			(xy 354.129133 -340.809391) (xy 354.128578 -340.820502) (xy 354.128578 -340.897718) (xy 354.129095 -340.908835)
			(xy 354.138467 -340.928995) (xy 354.146612 -340.93658) (xy 354.167319 -340.954795) (xy 354.203789 -340.996164)
			(xy 354.233922 -341.042353) (xy 354.257088 -341.0924) (xy 354.272805 -341.145261) (xy 354.280746 -341.199836)
			(xy 354.281232 -341.22741) (xy 354.280647 -341.255884) (xy 354.272167 -341.312198) (xy 354.255412 -341.366627)
			(xy 354.230754 -341.41796) (xy 354.19874 -341.465059) (xy 354.160082 -341.506877) (xy 354.115638 -341.542485)
			(xy 354.066396 -341.571092) (xy 354.013449 -341.592064) (xy 353.98583 -341.599012) (xy 353.9744 -341.601806)
			(xy 353.956112 -341.616792) (xy 353.912932 -341.712042) (xy 353.913694 -341.735664) (xy 353.919536 -341.746078)
			(xy 353.93354 -341.773417) (xy 353.953359 -341.831553) (xy 353.963382 -341.892151) (xy 353.963986 -341.922862)
			(xy 353.96353 -341.94948) (xy 353.955959 -342.002176) (xy 353.940964 -342.053257) (xy 353.918851 -342.101684)
			(xy 353.89007 -342.14647) (xy 353.855208 -342.186704) (xy 353.814975 -342.221567) (xy 353.770189 -342.250348)
			(xy 353.721762 -342.272461) (xy 353.670682 -342.287457) (xy 353.617986 -342.29503) (xy 353.591368 -342.29548)
			(xy 353.564946 -342.295022) (xy 353.512632 -342.287569) (xy 353.461894 -342.272803) (xy 353.41375 -342.25102)
			(xy 353.369164 -342.222656) (xy 353.348798 -342.205818) (xy 353.34194 -342.199722) (xy 353.324922 -342.193626)
			(xy 353.240594 -342.193626) (xy 353.223576 -342.199722) (xy 353.216718 -342.205818) (xy 353.196352 -342.222657)
			(xy 353.151766 -342.251022) (xy 353.103622 -342.272809) (xy 353.052885 -342.28758) (xy 353.00057 -342.29504)
			(xy 352.947726 -342.29504) (xy 352.895411 -342.28758) (xy 352.844674 -342.272809) (xy 352.79653 -342.251022)
			(xy 352.751944 -342.222657) (xy 352.731578 -342.205818) (xy 352.72472 -342.199722) (xy 352.707702 -342.193626)
			(xy 352.623374 -342.193626) (xy 352.606356 -342.199722) (xy 352.599498 -342.205818) (xy 352.579123 -342.222644)
			(xy 352.534537 -342.251004) (xy 352.486395 -342.272787) (xy 352.43566 -342.287557) (xy 352.383348 -342.295019)
			(xy 352.356928 -342.29548) (xy 352.329037 -342.295063) (xy 352.273878 -342.286753) (xy 352.220573 -342.270314)
			(xy 352.170314 -342.246114) (xy 352.124223 -342.214693) (xy 352.083331 -342.176753) (xy 352.04855 -342.133142)
			(xy 352.020658 -342.084835) (xy 352.000278 -342.032909) (xy 351.987864 -341.978526) (xy 351.983695 -341.9229)
			(xy 348.168809 -341.9229) (xy 348.166119 -341.924629) (xy 348.116542 -341.947271) (xy 348.064247 -341.962626)
			(xy 348.010299 -341.970382) (xy 347.955797 -341.970382) (xy 347.901849 -341.962626) (xy 347.849554 -341.947271)
			(xy 347.799977 -341.924629) (xy 347.754127 -341.895163) (xy 347.712936 -341.859472) (xy 347.677245 -341.818281)
			(xy 347.647779 -341.772431) (xy 347.625137 -341.722854) (xy 347.609782 -341.670559) (xy 347.602026 -341.616611)
			(xy 347.60154 -341.58936) (xy 347.602152 -341.559238) (xy 347.611623 -341.499744) (xy 347.630325 -341.442477)
			(xy 347.657792 -341.388859) (xy 347.693341 -341.340223) (xy 347.714316 -341.318596) (xy 347.721152 -341.311193)
			(xy 347.728874 -341.292596) (xy 347.729302 -341.282528) (xy 347.729302 -341.250524) (xy 347.72889 -341.240453)
			(xy 347.721163 -341.221854) (xy 347.714316 -341.214456) (xy 347.7133 -341.213694) (xy 347.629988 -341.130382)
			(xy 347.609155 -341.108813) (xy 347.573906 -341.060303) (xy 347.546682 -341.006875) (xy 347.528155 -340.949844)
			(xy 347.518781 -340.890616) (xy 347.518228 -340.860634) (xy 347.518228 -335.44637) (xy 347.518808 -335.416392)
			(xy 347.528203 -335.357177) (xy 347.54674 -335.300159) (xy 347.573965 -335.246741) (xy 347.609207 -335.198236)
			(xy 347.629988 -335.176622) (xy 347.796866 -335.009998) (xy 347.803695 -335.002589) (xy 347.811422 -334.983997)
			(xy 347.811852 -334.97393) (xy 347.811852 -331.037438) (xy 347.811419 -331.027369) (xy 347.803705 -331.008771)
			(xy 347.796866 -331.00137) (xy 347.332046 -330.53655) (xy 347.324618 -330.529745) (xy 347.30604 -330.522003)
			(xy 347.295978 -330.521564) (xy 340.07933 -330.521564) (xy 340.06926 -330.521988) (xy 340.050661 -330.529708)
			(xy 340.043262 -330.53655) (xy 339.84946 -330.730352) (xy 339.842756 -330.737825) (xy 339.835171 -330.75639)
			(xy 339.834728 -330.76642) (xy 339.834728 -335.600802) (xy 339.835115 -335.610846) (xy 339.842691 -335.629442)
			(xy 339.84946 -335.63687) (xy 339.976968 -335.764124) (xy 339.997796 -335.785697) (xy 340.033048 -335.834205)
			(xy 340.060274 -335.887633) (xy 340.078802 -335.944663) (xy 340.088176 -336.00389) (xy 340.088728 -336.033872)
			(xy 340.088237 -336.061793) (xy 340.080046 -336.117031) (xy 340.063892 -336.170486) (xy 340.040122 -336.221016)
			(xy 340.009242 -336.267544) (xy 339.990938 -336.288634) (xy 339.984588 -336.295746) (xy 339.977984 -336.313018)
			(xy 339.977984 -336.399886) (xy 339.984588 -336.417158) (xy 339.990938 -336.42427) (xy 340.009287 -336.445356)
			(xy 340.040191 -336.491932) (xy 340.063964 -336.542521) (xy 340.080097 -336.596038) (xy 340.088245 -336.651338)
			(xy 340.088728 -336.679286) (xy 340.088242 -336.706537) (xy 340.080486 -336.760485) (xy 340.065131 -336.81278)
			(xy 340.042489 -336.862357) (xy 340.013023 -336.908207) (xy 339.977332 -336.949398) (xy 339.936141 -336.985089)
			(xy 339.893022 -337.0128) (xy 343.707948 -337.0128) (xy 343.712115 -336.957185) (xy 343.724526 -336.902811)
			(xy 343.744901 -336.850895) (xy 343.772787 -336.802596) (xy 343.80756 -336.758992) (xy 343.848443 -336.721058)
			(xy 343.894524 -336.68964) (xy 343.944772 -336.665442) (xy 343.998066 -336.649003) (xy 344.053214 -336.640691)
			(xy 344.0811 -336.64017) (xy 344.107521 -336.640635) (xy 344.159836 -336.648084) (xy 344.210575 -336.662848)
			(xy 344.258719 -336.68463) (xy 344.303304 -336.712993) (xy 344.32367 -336.729832) (xy 344.330528 -336.735928)
			(xy 344.347546 -336.742024) (xy 344.431874 -336.742024) (xy 344.448892 -336.735928) (xy 344.45575 -336.729832)
			(xy 344.476116 -336.712993) (xy 344.520702 -336.684628) (xy 344.568846 -336.662841) (xy 344.619583 -336.64807)
			(xy 344.671898 -336.64061) (xy 344.724742 -336.64061) (xy 344.777057 -336.64807) (xy 344.827794 -336.662841)
			(xy 344.875938 -336.684628) (xy 344.920524 -336.712993) (xy 344.94089 -336.729832) (xy 344.947748 -336.735928)
			(xy 344.964766 -336.742024) (xy 345.049094 -336.742024) (xy 345.066112 -336.735928) (xy 345.07297 -336.729832)
			(xy 345.09535 -336.711413) (xy 345.144682 -336.680989) (xy 345.198128 -336.658566) (xy 345.226132 -336.651092)
			(xy 345.237816 -336.648298) (xy 345.25585 -336.632804) (xy 345.297506 -336.537046) (xy 345.29649 -336.513424)
			(xy 345.290648 -336.50301) (xy 345.279175 -336.481643) (xy 345.261122 -336.43663) (xy 345.248921 -336.389692)
			(xy 345.242769 -336.341585) (xy 345.242388 -336.317336) (xy 345.242883 -336.289763) (xy 345.25083 -336.235191)
			(xy 345.266549 -336.182332) (xy 345.289714 -336.132286) (xy 345.319841 -336.086096) (xy 345.356303 -336.044723)
			(xy 345.377008 -336.026506) (xy 345.385121 -336.018898) (xy 345.394478 -335.998751) (xy 345.395042 -335.987644)
			(xy 345.395042 -335.910428) (xy 345.394493 -335.899315) (xy 345.385143 -335.879156) (xy 345.377008 -335.871566)
			(xy 345.356279 -335.853374) (xy 345.31981 -335.812002) (xy 345.289679 -335.765808) (xy 345.266517 -335.715756)
			(xy 345.250804 -335.66289) (xy 345.24287 -335.608312) (xy 345.242388 -335.580736) (xy 345.242874 -335.553485)
			(xy 345.25063 -335.499537) (xy 345.265985 -335.447242) (xy 345.288627 -335.397665) (xy 345.318093 -335.351815)
			(xy 345.353784 -335.310624) (xy 345.394975 -335.274933) (xy 345.440825 -335.245467) (xy 345.490402 -335.222825)
			(xy 345.542697 -335.20747) (xy 345.596645 -335.199714) (xy 345.651147 -335.199714) (xy 345.705095 -335.20747)
			(xy 345.75739 -335.222825) (xy 345.806967 -335.245467) (xy 345.852817 -335.274933) (xy 345.894008 -335.310624)
			(xy 345.929699 -335.351815) (xy 345.959165 -335.397665) (xy 345.981807 -335.447242) (xy 345.997162 -335.499537)
			(xy 346.004918 -335.553485) (xy 346.005404 -335.580736) (xy 346.004893 -335.608309) (xy 345.996949 -335.66288)
			(xy 345.981233 -335.715739) (xy 345.958072 -335.765785) (xy 345.927947 -335.811976) (xy 345.891488 -335.853349)
			(xy 345.870784 -335.871566) (xy 345.862683 -335.879184) (xy 345.85332 -335.899324) (xy 345.85275 -335.910428)
			(xy 345.85275 -335.987644) (xy 345.853317 -335.998754) (xy 345.862655 -336.018914) (xy 345.870784 -336.026506)
			(xy 345.891498 -336.044714) (xy 345.927969 -336.086083) (xy 345.958101 -336.132273) (xy 345.981266 -336.182322)
			(xy 345.996982 -336.235185) (xy 346.00492 -336.289761) (xy 346.005404 -336.317336) (xy 346.004864 -336.345812)
			(xy 345.99638 -336.402129) (xy 345.979619 -336.45656) (xy 345.954956 -336.507895) (xy 345.922936 -336.554994)
			(xy 345.884272 -336.596812) (xy 345.839823 -336.632418) (xy 345.790575 -336.661023) (xy 345.737623 -336.681992)
			(xy 345.710002 -336.688938) (xy 345.698572 -336.691732) (xy 345.680284 -336.706718) (xy 345.637104 -336.801968)
			(xy 345.637866 -336.82559) (xy 345.643708 -336.836004) (xy 345.657683 -336.863356) (xy 345.677513 -336.921486)
			(xy 345.687548 -336.982079) (xy 345.688158 -337.012788) (xy 345.687632 -337.039402) (xy 345.680059 -337.092089)
			(xy 345.665066 -337.143162) (xy 345.642956 -337.191581) (xy 345.614182 -337.236361) (xy 345.579327 -337.27659)
			(xy 345.539103 -337.31145) (xy 345.494326 -337.340231) (xy 345.44591 -337.362347) (xy 345.39484 -337.377348)
			(xy 345.342154 -337.384929) (xy 345.31554 -337.385406) (xy 345.289117 -337.384982) (xy 345.2368 -337.377523)
			(xy 345.186061 -337.362751) (xy 345.137918 -337.340959) (xy 345.093334 -337.312587) (xy 345.07297 -337.295744)
			(xy 345.066112 -337.289648) (xy 345.049094 -337.283552) (xy 344.964766 -337.283552) (xy 344.947748 -337.289648)
			(xy 344.94089 -337.295744) (xy 344.920524 -337.312583) (xy 344.875938 -337.340948) (xy 344.827794 -337.362735)
			(xy 344.777057 -337.377506) (xy 344.724742 -337.384966) (xy 344.671898 -337.384966) (xy 344.619583 -337.377506)
			(xy 344.568846 -337.362735) (xy 344.520702 -337.340948) (xy 344.476116 -337.312583) (xy 344.45575 -337.295744)
			(xy 344.448892 -337.289648) (xy 344.431874 -337.283552) (xy 344.347546 -337.283552) (xy 344.330528 -337.289648)
			(xy 344.32367 -337.295744) (xy 344.303309 -337.312587) (xy 344.258718 -337.340944) (xy 344.210573 -337.362723)
			(xy 344.159835 -337.377489) (xy 344.107521 -337.384947) (xy 344.0811 -337.385406) (xy 344.053214 -337.384909)
			(xy 343.998066 -337.376597) (xy 343.944772 -337.360158) (xy 343.894524 -337.33596) (xy 343.848443 -337.304542)
			(xy 343.80756 -337.266608) (xy 343.772787 -337.223004) (xy 343.744901 -337.174705) (xy 343.724526 -337.122789)
			(xy 343.712115 -337.068415) (xy 343.707948 -337.0128) (xy 339.893022 -337.0128) (xy 339.890291 -337.014555)
			(xy 339.840714 -337.037197) (xy 339.788419 -337.052552) (xy 339.734471 -337.060308) (xy 339.679969 -337.060308)
			(xy 339.626021 -337.052552) (xy 339.573726 -337.037197) (xy 339.524149 -337.014555) (xy 339.478299 -336.985089)
			(xy 339.437108 -336.949398) (xy 339.401417 -336.908207) (xy 339.371951 -336.862357) (xy 339.349309 -336.81278)
			(xy 339.333954 -336.760485) (xy 339.326198 -336.706537) (xy 339.325712 -336.679286) (xy 339.326256 -336.649161)
			(xy 339.335741 -336.589663) (xy 339.354457 -336.532394) (xy 339.381939 -336.478777) (xy 339.417505 -336.430145)
			(xy 339.438488 -336.408522) (xy 339.445309 -336.401107) (xy 339.45304 -336.382519) (xy 339.453474 -336.372454)
			(xy 339.453474 -336.34045) (xy 339.453029 -336.330383) (xy 339.445323 -336.311784) (xy 339.438488 -336.304382)
			(xy 339.437472 -336.30362) (xy 339.183472 -336.04962) (xy 339.162673 -336.02802) (xy 339.127415 -335.97952)
			(xy 339.100184 -335.9261) (xy 339.081649 -335.869075) (xy 339.072268 -335.809853) (xy 339.071712 -335.779872)
			(xy 339.071712 -330.82738) (xy 339.071351 -330.817333) (xy 339.063758 -330.798736) (xy 339.05698 -330.791312)
			(xy 338.802218 -330.53655) (xy 338.7948 -330.529732) (xy 338.776215 -330.521998) (xy 338.76615 -330.521564)
			(xy 331.57033 -330.521564) (xy 331.56026 -330.521988) (xy 331.541661 -330.529708) (xy 331.534262 -330.53655)
			(xy 331.4065 -330.664312) (xy 331.399805 -330.671792) (xy 331.392217 -330.690352) (xy 331.391768 -330.70038)
			(xy 331.391768 -335.438242) (xy 331.392124 -335.448289) (xy 331.399721 -335.466886) (xy 331.4065 -335.47431)
			(xy 331.645768 -335.713324) (xy 331.666596 -335.734897) (xy 331.701848 -335.783405) (xy 331.729074 -335.836833)
			(xy 331.747602 -335.893863) (xy 331.756976 -335.95309) (xy 331.757528 -335.983072) (xy 331.757037 -336.010993)
			(xy 331.748846 -336.066231) (xy 331.732692 -336.119686) (xy 331.708922 -336.170216) (xy 331.678042 -336.216744)
			(xy 331.659738 -336.237834) (xy 331.653388 -336.244946) (xy 331.646784 -336.262218) (xy 331.646784 -336.349086)
			(xy 331.653388 -336.366358) (xy 331.659738 -336.37347) (xy 331.678087 -336.394556) (xy 331.708991 -336.441132)
			(xy 331.732764 -336.491721) (xy 331.748897 -336.545238) (xy 331.757045 -336.600538) (xy 331.757528 -336.628486)
			(xy 331.757042 -336.655737) (xy 331.749286 -336.709685) (xy 331.733931 -336.76198) (xy 331.711289 -336.811557)
			(xy 331.681823 -336.857407) (xy 331.646132 -336.898598) (xy 331.604941 -336.934289) (xy 331.561822 -336.962)
			(xy 335.376748 -336.962) (xy 335.380915 -336.906385) (xy 335.393326 -336.852011) (xy 335.413701 -336.800095)
			(xy 335.441587 -336.751796) (xy 335.47636 -336.708192) (xy 335.517243 -336.670258) (xy 335.563324 -336.63884)
			(xy 335.613572 -336.614642) (xy 335.666866 -336.598203) (xy 335.722014 -336.589891) (xy 335.7499 -336.58937)
			(xy 335.776321 -336.589835) (xy 335.828636 -336.597284) (xy 335.879375 -336.612048) (xy 335.927519 -336.63383)
			(xy 335.972104 -336.662193) (xy 335.99247 -336.679032) (xy 335.999328 -336.685128) (xy 336.016346 -336.691224)
			(xy 336.100674 -336.691224) (xy 336.117692 -336.685128) (xy 336.12455 -336.679032) (xy 336.144916 -336.662193)
			(xy 336.189502 -336.633828) (xy 336.237646 -336.612041) (xy 336.288383 -336.59727) (xy 336.340698 -336.58981)
			(xy 336.393542 -336.58981) (xy 336.445857 -336.59727) (xy 336.496594 -336.612041) (xy 336.544738 -336.633828)
			(xy 336.589324 -336.662193) (xy 336.60969 -336.679032) (xy 336.616548 -336.685128) (xy 336.633566 -336.691224)
			(xy 336.717894 -336.691224) (xy 336.734912 -336.685128) (xy 336.74177 -336.679032) (xy 336.763705 -336.660961)
			(xy 336.811982 -336.630975) (xy 336.864242 -336.608646) (xy 336.89163 -336.601054) (xy 336.903314 -336.598006)
			(xy 336.921602 -336.582258) (xy 336.96148 -336.484722) (xy 336.959702 -336.460592) (xy 336.953606 -336.450432)
			(xy 336.940633 -336.428091) (xy 336.920214 -336.380636) (xy 336.906392 -336.330857) (xy 336.899422 -336.279667)
			(xy 336.898996 -336.253836) (xy 336.899488 -336.226262) (xy 336.907435 -336.171691) (xy 336.923155 -336.118831)
			(xy 336.94632 -336.068785) (xy 336.976448 -336.022595) (xy 337.012911 -335.981223) (xy 337.033616 -335.963006)
			(xy 337.04173 -335.955399) (xy 337.051086 -335.935251) (xy 337.05165 -335.924144) (xy 337.05165 -335.846928)
			(xy 337.051098 -335.835816) (xy 337.04175 -335.815656) (xy 337.033616 -335.808066) (xy 337.012888 -335.789873)
			(xy 336.976419 -335.748501) (xy 336.946288 -335.702307) (xy 336.923125 -335.652255) (xy 336.907413 -335.59939)
			(xy 336.899478 -335.544812) (xy 336.898996 -335.517236) (xy 336.899482 -335.489985) (xy 336.907238 -335.436037)
			(xy 336.922593 -335.383742) (xy 336.945235 -335.334165) (xy 336.974701 -335.288315) (xy 337.010392 -335.247124)
			(xy 337.051583 -335.211433) (xy 337.097433 -335.181967) (xy 337.14701 -335.159325) (xy 337.199305 -335.14397)
			(xy 337.253253 -335.136214) (xy 337.307755 -335.136214) (xy 337.361703 -335.14397) (xy 337.413998 -335.159325)
			(xy 337.463575 -335.181967) (xy 337.509425 -335.211433) (xy 337.550616 -335.247124) (xy 337.586307 -335.288315)
			(xy 337.615773 -335.334165) (xy 337.638415 -335.383742) (xy 337.65377 -335.436037) (xy 337.661526 -335.489985)
			(xy 337.662012 -335.517236) (xy 337.661498 -335.544809) (xy 337.653555 -335.599379) (xy 337.637839 -335.652238)
			(xy 337.614678 -335.702284) (xy 337.584554 -335.748475) (xy 337.548095 -335.789849) (xy 337.527392 -335.808066)
			(xy 337.519292 -335.815685) (xy 337.509928 -335.835824) (xy 337.509358 -335.846928) (xy 337.509358 -335.924144)
			(xy 337.509923 -335.935255) (xy 337.519261 -335.955415) (xy 337.527392 -335.963006) (xy 337.548108 -335.981212)
			(xy 337.584578 -336.022582) (xy 337.61471 -336.068773) (xy 337.637875 -336.118822) (xy 337.65359 -336.171685)
			(xy 337.661528 -336.226261) (xy 337.662012 -336.253836) (xy 337.661456 -336.282114) (xy 337.653115 -336.338051)
			(xy 337.636607 -336.392144) (xy 337.612293 -336.443206) (xy 337.580706 -336.490119) (xy 337.542539 -336.531855)
			(xy 337.498629 -336.567497) (xy 337.449937 -336.596266) (xy 337.397531 -336.61753) (xy 337.370166 -336.624676)
			(xy 337.358482 -336.62747) (xy 337.340194 -336.642964) (xy 337.298792 -336.739992) (xy 337.300316 -336.764122)
			(xy 337.306412 -336.774536) (xy 337.318417 -336.795967) (xy 337.337324 -336.841304) (xy 337.350114 -336.888731)
			(xy 337.356566 -336.937427) (xy 337.356958 -336.961988) (xy 337.356432 -336.988602) (xy 337.348859 -337.041289)
			(xy 337.333866 -337.092362) (xy 337.311756 -337.140781) (xy 337.282982 -337.185561) (xy 337.248127 -337.22579)
			(xy 337.207903 -337.26065) (xy 337.163126 -337.289431) (xy 337.11471 -337.311547) (xy 337.06364 -337.326548)
			(xy 337.010954 -337.334129) (xy 336.98434 -337.334606) (xy 336.957917 -337.334182) (xy 336.9056 -337.326723)
			(xy 336.854861 -337.311951) (xy 336.806718 -337.290159) (xy 336.762134 -337.261787) (xy 336.74177 -337.244944)
			(xy 336.734912 -337.238848) (xy 336.717894 -337.232752) (xy 336.633566 -337.232752) (xy 336.616548 -337.238848)
			(xy 336.60969 -337.244944) (xy 336.589324 -337.261783) (xy 336.544738 -337.290148) (xy 336.496594 -337.311935)
			(xy 336.445857 -337.326706) (xy 336.393542 -337.334166) (xy 336.340698 -337.334166) (xy 336.288383 -337.326706)
			(xy 336.237646 -337.311935) (xy 336.189502 -337.290148) (xy 336.144916 -337.261783) (xy 336.12455 -337.244944)
			(xy 336.117692 -337.238848) (xy 336.100674 -337.232752) (xy 336.016346 -337.232752) (xy 335.999328 -337.238848)
			(xy 335.99247 -337.244944) (xy 335.972109 -337.261787) (xy 335.927518 -337.290144) (xy 335.879373 -337.311923)
			(xy 335.828635 -337.326689) (xy 335.776321 -337.334147) (xy 335.7499 -337.334606) (xy 335.722014 -337.334109)
			(xy 335.666866 -337.325797) (xy 335.613572 -337.309358) (xy 335.563324 -337.28516) (xy 335.517243 -337.253742)
			(xy 335.47636 -337.215808) (xy 335.441587 -337.172204) (xy 335.413701 -337.123905) (xy 335.393326 -337.071989)
			(xy 335.380915 -337.017615) (xy 335.376748 -336.962) (xy 331.561822 -336.962) (xy 331.559091 -336.963755)
			(xy 331.509514 -336.986397) (xy 331.457219 -337.001752) (xy 331.403271 -337.009508) (xy 331.348769 -337.009508)
			(xy 331.294821 -337.001752) (xy 331.242526 -336.986397) (xy 331.192949 -336.963755) (xy 331.147099 -336.934289)
			(xy 331.105908 -336.898598) (xy 331.070217 -336.857407) (xy 331.040751 -336.811557) (xy 331.018109 -336.76198)
			(xy 331.002754 -336.709685) (xy 330.994998 -336.655737) (xy 330.994512 -336.628486) (xy 330.995056 -336.598361)
			(xy 331.004541 -336.538863) (xy 331.023257 -336.481594) (xy 331.050739 -336.427977) (xy 331.086305 -336.379345)
			(xy 331.107288 -336.357722) (xy 331.114109 -336.350307) (xy 331.12184 -336.331719) (xy 331.122274 -336.321654)
			(xy 331.122274 -336.28965) (xy 331.121829 -336.279583) (xy 331.114123 -336.260984) (xy 331.107288 -336.253582)
			(xy 331.106272 -336.25282) (xy 330.740512 -335.88706) (xy 330.719721 -335.865453) (xy 330.684465 -335.816954)
			(xy 330.657233 -335.763535) (xy 330.638696 -335.706512) (xy 330.629311 -335.647292) (xy 330.628752 -335.617312)
			(xy 330.628752 -330.95438) (xy 330.62838 -330.944335) (xy 330.620794 -330.925738) (xy 330.61402 -330.918312)
			(xy 330.359258 -330.66355) (xy 330.351861 -330.656706) (xy 330.33326 -330.648987) (xy 330.32319 -330.648564)
			(xy 323.56933 -330.648564) (xy 323.55926 -330.648988) (xy 323.540661 -330.656708) (xy 323.533262 -330.66355)
			(xy 323.2785 -330.918312) (xy 323.271805 -330.925792) (xy 323.264217 -330.944352) (xy 323.263768 -330.95438)
			(xy 323.263768 -335.682336) (xy 323.264127 -335.692383) (xy 323.271722 -335.71098) (xy 323.2785 -335.718404)
			(xy 323.288152 -335.727802) (xy 323.308966 -335.749388) (xy 323.344221 -335.797892) (xy 323.371449 -335.851316)
			(xy 323.38998 -335.908344) (xy 323.399357 -335.967569) (xy 323.399912 -335.99755) (xy 323.399387 -336.025469)
			(xy 323.391201 -336.080705) (xy 323.375054 -336.134159) (xy 323.351292 -336.18469) (xy 323.320421 -336.231219)
			(xy 323.302122 -336.252312) (xy 323.295772 -336.259424) (xy 323.289168 -336.276696) (xy 323.289168 -336.363564)
			(xy 323.295772 -336.380836) (xy 323.302122 -336.387948) (xy 323.320458 -336.409045) (xy 323.351364 -336.455618)
			(xy 323.37514 -336.506204) (xy 323.391276 -336.559719) (xy 323.399427 -336.615016) (xy 323.399912 -336.642964)
			(xy 323.399426 -336.670215) (xy 323.39167 -336.724163) (xy 323.376315 -336.776458) (xy 323.353673 -336.826035)
			(xy 323.324207 -336.871885) (xy 323.288516 -336.913076) (xy 323.247325 -336.948767) (xy 323.204172 -336.9765)
			(xy 327.019125 -336.9765) (xy 327.023293 -336.920883) (xy 327.035704 -336.866508) (xy 327.056079 -336.81459)
			(xy 327.083965 -336.766288) (xy 327.118739 -336.722682) (xy 327.159622 -336.684746) (xy 327.205703 -336.653327)
			(xy 327.255953 -336.629126) (xy 327.309247 -336.612685) (xy 327.364397 -336.60437) (xy 327.392284 -336.603848)
			(xy 327.418705 -336.604327) (xy 327.471019 -336.611774) (xy 327.521757 -336.626535) (xy 327.569901 -336.648313)
			(xy 327.614488 -336.676673) (xy 327.634854 -336.69351) (xy 327.641712 -336.699606) (xy 327.65873 -336.705702)
			(xy 327.743058 -336.705702) (xy 327.760076 -336.699606) (xy 327.766934 -336.69351) (xy 327.7873 -336.676671)
			(xy 327.831886 -336.648306) (xy 327.88003 -336.626519) (xy 327.930767 -336.611748) (xy 327.983082 -336.604288)
			(xy 328.035926 -336.604288) (xy 328.088241 -336.611748) (xy 328.138978 -336.626519) (xy 328.187122 -336.648306)
			(xy 328.231708 -336.676671) (xy 328.252074 -336.69351) (xy 328.258932 -336.699606) (xy 328.27595 -336.705702)
			(xy 328.360278 -336.705702) (xy 328.377296 -336.699606) (xy 328.384154 -336.69351) (xy 328.406536 -336.675093)
			(xy 328.455867 -336.644668) (xy 328.509312 -336.622245) (xy 328.537316 -336.61477) (xy 328.549508 -336.611722)
			(xy 328.567796 -336.59572) (xy 328.607674 -336.495644) (xy 328.605134 -336.47126) (xy 328.59853 -336.460846)
			(xy 328.584049 -336.437615) (xy 328.561184 -336.387877) (xy 328.545663 -336.335382) (xy 328.537805 -336.281207)
			(xy 328.537316 -336.253836) (xy 328.537801 -336.226262) (xy 328.545749 -336.17169) (xy 328.56147 -336.11883)
			(xy 328.584636 -336.068784) (xy 328.614765 -336.022594) (xy 328.65123 -335.981222) (xy 328.671936 -335.963006)
			(xy 328.680053 -335.955402) (xy 328.689407 -335.935252) (xy 328.68997 -335.924144) (xy 328.68997 -335.846928)
			(xy 328.689412 -335.835817) (xy 328.680067 -335.815657) (xy 328.671936 -335.808066) (xy 328.651212 -335.789868)
			(xy 328.614742 -335.748498) (xy 328.58461 -335.702305) (xy 328.561446 -335.652254) (xy 328.545733 -335.599389)
			(xy 328.537798 -335.544812) (xy 328.537316 -335.517236) (xy 328.537802 -335.489985) (xy 328.545558 -335.436037)
			(xy 328.560913 -335.383742) (xy 328.583555 -335.334165) (xy 328.613021 -335.288315) (xy 328.648712 -335.247124)
			(xy 328.689903 -335.211433) (xy 328.735753 -335.181967) (xy 328.78533 -335.159325) (xy 328.837625 -335.14397)
			(xy 328.891573 -335.136214) (xy 328.946075 -335.136214) (xy 329.000023 -335.14397) (xy 329.052318 -335.159325)
			(xy 329.101895 -335.181967) (xy 329.147745 -335.211433) (xy 329.188936 -335.247124) (xy 329.224627 -335.288315)
			(xy 329.254093 -335.334165) (xy 329.276735 -335.383742) (xy 329.29209 -335.436037) (xy 329.299846 -335.489985)
			(xy 329.300332 -335.517236) (xy 329.299811 -335.544808) (xy 329.291868 -335.599378) (xy 329.276153 -335.652237)
			(xy 329.252994 -335.702283) (xy 329.222871 -335.748474) (xy 329.186414 -335.789848) (xy 329.165712 -335.808066)
			(xy 329.157615 -335.815688) (xy 329.148248 -335.835825) (xy 329.147678 -335.846928) (xy 329.147678 -335.924144)
			(xy 329.148236 -335.935256) (xy 329.157579 -335.955416) (xy 329.165712 -335.963006) (xy 329.186432 -335.981208)
			(xy 329.222901 -336.022579) (xy 329.253032 -336.068771) (xy 329.276196 -336.118821) (xy 329.29191 -336.171685)
			(xy 329.299848 -336.226261) (xy 329.300332 -336.253836) (xy 329.299861 -336.282294) (xy 329.291415 -336.338579)
			(xy 329.274699 -336.392985) (xy 329.250086 -336.444304) (xy 329.218122 -336.491396) (xy 329.179515 -336.533216)
			(xy 329.135124 -336.568837) (xy 329.085933 -336.597466) (xy 329.033035 -336.61847) (xy 329.005438 -336.625438)
			(xy 328.993246 -336.628232) (xy 328.974704 -336.64398) (xy 328.933556 -336.743548) (xy 328.935588 -336.767932)
			(xy 328.942192 -336.778346) (xy 328.955716 -336.800704) (xy 328.977062 -336.848398) (xy 328.991544 -336.898604)
			(xy 328.998881 -336.95034) (xy 328.999342 -336.976466) (xy 328.998834 -337.003082) (xy 328.991263 -337.055772)
			(xy 328.976271 -337.106849) (xy 328.954161 -337.155272) (xy 328.925386 -337.200056) (xy 328.89053 -337.240289)
			(xy 328.850303 -337.275151) (xy 328.805523 -337.303934) (xy 328.757104 -337.32605) (xy 328.706029 -337.341051)
			(xy 328.65334 -337.34863) (xy 328.626724 -337.349084) (xy 328.600304 -337.348593) (xy 328.54799 -337.341148)
			(xy 328.497253 -337.326389) (xy 328.449108 -337.304614) (xy 328.404521 -337.276257) (xy 328.384154 -337.259422)
			(xy 328.377296 -337.253326) (xy 328.360278 -337.24723) (xy 328.27595 -337.24723) (xy 328.258932 -337.253326)
			(xy 328.252074 -337.259422) (xy 328.231708 -337.276261) (xy 328.187122 -337.304626) (xy 328.138978 -337.326413)
			(xy 328.088241 -337.341184) (xy 328.035926 -337.348644) (xy 327.983082 -337.348644) (xy 327.930767 -337.341184)
			(xy 327.88003 -337.326413) (xy 327.831886 -337.304626) (xy 327.7873 -337.276261) (xy 327.766934 -337.259422)
			(xy 327.760076 -337.253326) (xy 327.743058 -337.24723) (xy 327.65873 -337.24723) (xy 327.641712 -337.253326)
			(xy 327.634854 -337.259422) (xy 327.614496 -337.27627) (xy 327.569905 -337.304626) (xy 327.521759 -337.326404)
			(xy 327.47102 -337.34117) (xy 327.418706 -337.348626) (xy 327.392284 -337.349084) (xy 327.364397 -337.34863)
			(xy 327.309247 -337.340315) (xy 327.255953 -337.323874) (xy 327.205703 -337.299673) (xy 327.159622 -337.268254)
			(xy 327.118739 -337.230318) (xy 327.083965 -337.186712) (xy 327.056079 -337.13841) (xy 327.035704 -337.086492)
			(xy 327.023293 -337.032117) (xy 327.019125 -336.9765) (xy 323.204172 -336.9765) (xy 323.201475 -336.978233)
			(xy 323.151898 -337.000875) (xy 323.099603 -337.01623) (xy 323.045655 -337.023986) (xy 322.991153 -337.023986)
			(xy 322.937205 -337.01623) (xy 322.88491 -337.000875) (xy 322.835333 -336.978233) (xy 322.789483 -336.948767)
			(xy 322.748292 -336.913076) (xy 322.712601 -336.871885) (xy 322.683135 -336.826035) (xy 322.660493 -336.776458)
			(xy 322.645138 -336.724163) (xy 322.637382 -336.670215) (xy 322.636896 -336.642964) (xy 322.63743 -336.612839)
			(xy 322.646918 -336.55334) (xy 322.665637 -336.496071) (xy 322.693121 -336.442455) (xy 322.728689 -336.393823)
			(xy 322.749672 -336.3722) (xy 322.7565 -336.364791) (xy 322.764228 -336.346199) (xy 322.764658 -336.336132)
			(xy 322.764658 -336.304128) (xy 322.764229 -336.294059) (xy 322.756512 -336.27546) (xy 322.749672 -336.26806)
			(xy 322.748656 -336.267298) (xy 322.612512 -336.131154) (xy 322.591718 -336.10955) (xy 322.556462 -336.06105)
			(xy 322.529231 -336.00763) (xy 322.510695 -335.950607) (xy 322.50131 -335.891386) (xy 322.500752 -335.861406)
			(xy 322.500752 -330.82738) (xy 322.50038 -330.817335) (xy 322.492794 -330.798738) (xy 322.48602 -330.791312)
			(xy 322.358258 -330.66355) (xy 322.350861 -330.656706) (xy 322.33226 -330.648987) (xy 322.32219 -330.648564)
			(xy 315.69533 -330.648564) (xy 315.68526 -330.648988) (xy 315.666661 -330.656708) (xy 315.659262 -330.66355)
			(xy 314.873386 -331.449426) (xy 314.86654 -331.456821) (xy 314.858824 -331.475424) (xy 314.8584 -331.485494)
			(xy 314.8584 -335.639918) (xy 314.85879 -335.649992) (xy 314.866532 -335.668591) (xy 314.873386 -335.675986)
			(xy 314.932568 -335.734914) (xy 314.953391 -335.756492) (xy 314.988644 -335.804998) (xy 315.01587 -335.858425)
			(xy 315.0344 -335.915454) (xy 315.043775 -335.97468) (xy 315.044328 -336.004662) (xy 315.043831 -336.032582)
			(xy 315.035641 -336.087821) (xy 315.019489 -336.141275) (xy 314.99572 -336.191806) (xy 314.964841 -336.238333)
			(xy 314.946538 -336.259424) (xy 314.940188 -336.266536) (xy 314.933584 -336.283808) (xy 314.933584 -336.370676)
			(xy 314.940188 -336.387948) (xy 314.946538 -336.39506) (xy 314.964882 -336.41615) (xy 314.995787 -336.462725)
			(xy 315.019561 -336.513313) (xy 315.035695 -336.566829) (xy 315.043844 -336.622128) (xy 315.044328 -336.650076)
			(xy 315.043822 -336.677327) (xy 315.036069 -336.731276) (xy 315.020717 -336.783572) (xy 314.998079 -336.83315)
			(xy 314.968615 -336.879003) (xy 314.932926 -336.920195) (xy 314.891738 -336.955889) (xy 314.848624 -336.9836)
			(xy 318.663538 -336.9836) (xy 318.667705 -336.927983) (xy 318.680116 -336.873608) (xy 318.700492 -336.821691)
			(xy 318.728379 -336.77339) (xy 318.763153 -336.729785) (xy 318.804037 -336.69185) (xy 318.850119 -336.660432)
			(xy 318.900368 -336.636233) (xy 318.953664 -336.619793) (xy 319.008814 -336.611481) (xy 319.0367 -336.61096)
			(xy 319.063121 -336.611427) (xy 319.115436 -336.618876) (xy 319.166174 -336.63364) (xy 319.214319 -336.655421)
			(xy 319.258904 -336.683784) (xy 319.27927 -336.700622) (xy 319.286128 -336.706718) (xy 319.303146 -336.712814)
			(xy 319.387474 -336.712814) (xy 319.404492 -336.706718) (xy 319.41135 -336.700622) (xy 319.431716 -336.683783)
			(xy 319.476302 -336.655418) (xy 319.524446 -336.633631) (xy 319.575183 -336.61886) (xy 319.627498 -336.6114)
			(xy 319.680342 -336.6114) (xy 319.732657 -336.61886) (xy 319.783394 -336.633631) (xy 319.831538 -336.655418)
			(xy 319.876124 -336.683783) (xy 319.89649 -336.700622) (xy 319.903348 -336.706718) (xy 319.920366 -336.712814)
			(xy 320.004694 -336.712814) (xy 320.021712 -336.706718) (xy 320.02857 -336.700622) (xy 320.052017 -336.681287)
			(xy 320.103963 -336.649751) (xy 320.160337 -336.627059) (xy 320.18986 -336.61985) (xy 320.20256 -336.617056)
			(xy 320.221864 -336.600546) (xy 320.261234 -336.497422) (xy 320.257932 -336.472022) (xy 320.250566 -336.461608)
			(xy 320.233767 -336.437185) (xy 320.207124 -336.384235) (xy 320.188982 -336.327805) (xy 320.179776 -336.269249)
			(xy 320.179192 -336.239612) (xy 320.179669 -336.212038) (xy 320.187619 -336.157466) (xy 320.203342 -336.104606)
			(xy 320.22651 -336.05456) (xy 320.256641 -336.00837) (xy 320.293106 -335.966998) (xy 320.313812 -335.948782)
			(xy 320.321936 -335.941184) (xy 320.331287 -335.921029) (xy 320.331846 -335.90992) (xy 320.331846 -335.832704)
			(xy 320.331309 -335.82159) (xy 320.321951 -335.80143) (xy 320.313812 -335.793842) (xy 320.29312 -335.77561)
			(xy 320.256648 -335.734246) (xy 320.226513 -335.68806) (xy 320.203344 -335.638016) (xy 320.187623 -335.585157)
			(xy 320.17968 -335.530586) (xy 320.179192 -335.503012) (xy 320.179678 -335.475761) (xy 320.187434 -335.421813)
			(xy 320.202789 -335.369518) (xy 320.225431 -335.319941) (xy 320.254897 -335.274091) (xy 320.290588 -335.2329)
			(xy 320.331779 -335.197209) (xy 320.377629 -335.167743) (xy 320.427206 -335.145101) (xy 320.479501 -335.129746)
			(xy 320.533449 -335.12199) (xy 320.587951 -335.12199) (xy 320.641899 -335.129746) (xy 320.694194 -335.145101)
			(xy 320.743771 -335.167743) (xy 320.789621 -335.197209) (xy 320.830812 -335.2329) (xy 320.866503 -335.274091)
			(xy 320.895969 -335.319941) (xy 320.918611 -335.369518) (xy 320.933966 -335.421813) (xy 320.941722 -335.475761)
			(xy 320.942208 -335.503012) (xy 320.941679 -335.530584) (xy 320.933739 -335.585154) (xy 320.918026 -335.638013)
			(xy 320.894868 -335.688059) (xy 320.864747 -335.73425) (xy 320.82829 -335.775624) (xy 320.807588 -335.793842)
			(xy 320.799453 -335.80143) (xy 320.790109 -335.821592) (xy 320.789554 -335.832704) (xy 320.789554 -335.90992)
			(xy 320.790078 -335.921036) (xy 320.799446 -335.941195) (xy 320.807588 -335.948782) (xy 320.828291 -335.967002)
			(xy 320.864763 -336.008368) (xy 320.894896 -336.054556) (xy 320.918063 -336.104603) (xy 320.933781 -336.157464)
			(xy 320.941722 -336.212038) (xy 320.942208 -336.239612) (xy 320.941626 -336.268528) (xy 320.932909 -336.3257)
			(xy 320.915662 -336.380901) (xy 320.89028 -336.432865) (xy 320.857344 -336.480403) (xy 320.81761 -336.522424)
			(xy 320.771988 -336.557966) (xy 320.721524 -336.586213) (xy 320.667373 -336.606519) (xy 320.639186 -336.612992)
			(xy 320.62674 -336.615532) (xy 320.607182 -336.632042) (xy 320.566542 -336.734658) (xy 320.56959 -336.760058)
			(xy 320.576702 -336.770472) (xy 320.592505 -336.794045) (xy 320.617534 -336.844979) (xy 320.634565 -336.899114)
			(xy 320.643204 -336.955203) (xy 320.643758 -336.983578) (xy 320.643223 -337.010192) (xy 320.635651 -337.062878)
			(xy 320.620659 -337.113951) (xy 320.598551 -337.16237) (xy 320.569777 -337.20715) (xy 320.534924 -337.24738)
			(xy 320.4947 -337.28224) (xy 320.449924 -337.311021) (xy 320.401509 -337.333137) (xy 320.350439 -337.348138)
			(xy 320.297754 -337.355719) (xy 320.27114 -337.356196) (xy 320.244717 -337.355774) (xy 320.1924 -337.348316)
			(xy 320.141661 -337.333542) (xy 320.093517 -337.311751) (xy 320.048934 -337.283377) (xy 320.02857 -337.266534)
			(xy 320.021712 -337.260438) (xy 320.004694 -337.254342) (xy 319.920366 -337.254342) (xy 319.903348 -337.260438)
			(xy 319.89649 -337.266534) (xy 319.876124 -337.283373) (xy 319.831538 -337.311738) (xy 319.783394 -337.333525)
			(xy 319.732657 -337.348296) (xy 319.680342 -337.355756) (xy 319.627498 -337.355756) (xy 319.575183 -337.348296)
			(xy 319.524446 -337.333525) (xy 319.476302 -337.311738) (xy 319.431716 -337.283373) (xy 319.41135 -337.266534)
			(xy 319.404492 -337.260438) (xy 319.387474 -337.254342) (xy 319.303146 -337.254342) (xy 319.286128 -337.260438)
			(xy 319.27927 -337.266534) (xy 319.258907 -337.283376) (xy 319.214318 -337.311733) (xy 319.166172 -337.333512)
			(xy 319.115435 -337.348279) (xy 319.063121 -337.355737) (xy 319.0367 -337.356196) (xy 319.008814 -337.355719)
			(xy 318.953664 -337.347407) (xy 318.900368 -337.330967) (xy 318.850119 -337.306768) (xy 318.804037 -337.27535)
			(xy 318.763153 -337.237415) (xy 318.728379 -337.19381) (xy 318.700492 -337.145509) (xy 318.680116 -337.093592)
			(xy 318.667705 -337.039217) (xy 318.663538 -336.9836) (xy 314.848624 -336.9836) (xy 314.845889 -336.985358)
			(xy 314.796313 -337.008002) (xy 314.744019 -337.02336) (xy 314.690071 -337.031119) (xy 314.66282 -337.031584)
			(xy 314.634477 -337.031083) (xy 314.578413 -337.022704) (xy 314.52421 -337.006113) (xy 314.473061 -336.981676)
			(xy 314.426097 -336.949932) (xy 314.384354 -336.911581) (xy 314.366148 -336.889852) (xy 314.355734 -336.877152)
			(xy 314.325 -336.868262) (xy 314.219336 -336.905854) (xy 314.209643 -336.909811) (xy 314.194295 -336.924015)
			(xy 314.185865 -336.943153) (xy 314.1853 -336.953606) (xy 314.1853 -337.881722) (xy 315.239144 -337.881722)
			(xy 315.243215 -337.8261) (xy 315.255341 -337.771663) (xy 315.275264 -337.719572) (xy 315.30256 -337.670937)
			(xy 315.336646 -337.626794) (xy 315.376795 -337.588085) (xy 315.422153 -337.555634) (xy 315.471753 -337.530133)
			(xy 315.524537 -337.512126) (xy 315.57938 -337.501996) (xy 315.635114 -337.499959) (xy 315.690551 -337.506059)
			(xy 315.744508 -337.520165) (xy 315.795837 -337.541977) (xy 315.843443 -337.571031) (xy 315.886311 -337.606706)
			(xy 315.923528 -337.648243) (xy 315.954301 -337.694756) (xy 315.977973 -337.745253) (xy 315.994041 -337.79866)
			(xy 316.002161 -337.853836) (xy 316.00267 -337.881722) (xy 316.002161 -337.909608) (xy 315.994041 -337.964784)
			(xy 315.977973 -338.018191) (xy 315.954301 -338.068688) (xy 315.923528 -338.115201) (xy 315.886311 -338.156738)
			(xy 315.843443 -338.192413) (xy 315.795837 -338.221467) (xy 315.744508 -338.243279) (xy 315.690551 -338.257385)
			(xy 315.635114 -338.263485) (xy 315.57938 -338.261448) (xy 315.524537 -338.251318) (xy 315.471753 -338.233311)
			(xy 315.422153 -338.20781) (xy 315.376795 -338.175359) (xy 315.336646 -338.13665) (xy 315.30256 -338.092507)
			(xy 315.275264 -338.043872) (xy 315.255341 -337.991781) (xy 315.243215 -337.937344) (xy 315.239144 -337.881722)
			(xy 314.1853 -337.881722) (xy 314.1853 -338.777072) (xy 314.660024 -338.777072) (xy 314.664095 -338.72145)
			(xy 314.676221 -338.667013) (xy 314.696144 -338.614922) (xy 314.72344 -338.566287) (xy 314.757526 -338.522144)
			(xy 314.797675 -338.483435) (xy 314.843033 -338.450984) (xy 314.892633 -338.425483) (xy 314.945417 -338.407476)
			(xy 315.00026 -338.397346) (xy 315.055994 -338.395309) (xy 315.111431 -338.401409) (xy 315.165388 -338.415515)
			(xy 315.216717 -338.437327) (xy 315.264323 -338.466381) (xy 315.307191 -338.502056) (xy 315.344408 -338.543593)
			(xy 315.375181 -338.590106) (xy 315.398853 -338.640603) (xy 315.414921 -338.69401) (xy 315.423041 -338.749186)
			(xy 315.42355 -338.777072) (xy 315.423041 -338.804958) (xy 315.414921 -338.860134) (xy 315.398853 -338.913541)
			(xy 315.375181 -338.964038) (xy 315.344408 -339.010551) (xy 315.307191 -339.052088) (xy 315.264323 -339.087763)
			(xy 315.216717 -339.116817) (xy 315.165388 -339.138629) (xy 315.111431 -339.152735) (xy 315.055994 -339.158835)
			(xy 315.00026 -339.156798) (xy 314.945417 -339.146668) (xy 314.892633 -339.128661) (xy 314.843033 -339.10316)
			(xy 314.797675 -339.070709) (xy 314.757526 -339.032) (xy 314.72344 -338.987857) (xy 314.696144 -338.939222)
			(xy 314.676221 -338.887131) (xy 314.664095 -338.832694) (xy 314.660024 -338.777072) (xy 314.1853 -338.777072)
			(xy 314.1853 -340.846664) (xy 314.184768 -340.876636) (xy 314.175449 -340.935851) (xy 314.156972 -340.992876)
			(xy 314.129794 -341.046304) (xy 314.094584 -341.094816) (xy 314.073794 -341.116412) (xy 313.223148 -341.967058)
			(xy 313.201527 -341.987816) (xy 313.153008 -342.023003) (xy 313.099585 -342.050172) (xy 313.04257 -342.068653)
			(xy 312.983368 -342.077993) (xy 312.9534 -342.078564) (xy 305.456336 -342.078564) (xy 305.446267 -342.078991)
			(xy 305.427668 -342.086709) (xy 305.420268 -342.09355) (xy 305.155346 -342.358472) (xy 305.148532 -342.365893)
			(xy 305.140796 -342.384476) (xy 305.14036 -342.39454) (xy 305.14036 -347.292676) (xy 305.140782 -347.302746)
			(xy 305.148503 -347.321345) (xy 305.155346 -347.328744) (xy 305.282854 -347.455998) (xy 305.303586 -347.477644)
			(xy 305.338776 -347.526156) (xy 305.36595 -347.579573) (xy 305.384437 -347.636582) (xy 305.393785 -347.69578)
			(xy 305.39436 -347.725746) (xy 305.393882 -347.753657) (xy 305.385742 -347.808883) (xy 305.369642 -347.862334)
			(xy 305.345927 -347.912868) (xy 305.315101 -347.959408) (xy 305.296824 -347.980508) (xy 305.290474 -347.98762)
			(xy 305.28387 -348.004892) (xy 305.28387 -348.09176) (xy 305.290474 -348.109032) (xy 305.296824 -348.116144)
			(xy 305.315159 -348.137242) (xy 305.346065 -348.183815) (xy 305.369841 -348.2344) (xy 305.385978 -348.287915)
			(xy 305.394129 -348.343213) (xy 305.394614 -348.37116) (xy 305.394128 -348.398411) (xy 305.386372 -348.452359)
			(xy 305.371017 -348.504654) (xy 305.348375 -348.554231) (xy 305.318909 -348.600081) (xy 305.283218 -348.641272)
			(xy 305.242027 -348.676963) (xy 305.198867 -348.7047) (xy 309.013821 -348.7047) (xy 309.017989 -348.649082)
			(xy 309.0304 -348.594706) (xy 309.050776 -348.542788) (xy 309.078662 -348.494485) (xy 309.113436 -348.450879)
			(xy 309.154321 -348.412942) (xy 309.200403 -348.381523) (xy 309.250653 -348.357322) (xy 309.303948 -348.340881)
			(xy 309.359099 -348.332566) (xy 309.386986 -348.332044) (xy 309.413407 -348.332523) (xy 309.465721 -348.33997)
			(xy 309.516459 -348.354731) (xy 309.564603 -348.376509) (xy 309.60919 -348.404869) (xy 309.629556 -348.421706)
			(xy 309.636414 -348.427802) (xy 309.653432 -348.433898) (xy 309.73776 -348.433898) (xy 309.754778 -348.427802)
			(xy 309.761636 -348.421706) (xy 309.782002 -348.404867) (xy 309.826588 -348.376502) (xy 309.874732 -348.354715)
			(xy 309.925469 -348.339944) (xy 309.977784 -348.332484) (xy 310.030628 -348.332484) (xy 310.082943 -348.339944)
			(xy 310.13368 -348.354715) (xy 310.181824 -348.376502) (xy 310.22641 -348.404867) (xy 310.246776 -348.421706)
			(xy 310.253634 -348.427802) (xy 310.270652 -348.433898) (xy 310.35498 -348.433898) (xy 310.371998 -348.427802)
			(xy 310.378856 -348.421706) (xy 310.404711 -348.400478) (xy 310.462474 -348.366746) (xy 310.493664 -348.35465)
			(xy 310.504332 -348.35084) (xy 310.520334 -348.33433) (xy 310.553608 -348.23781) (xy 310.550814 -348.21495)
			(xy 310.544718 -348.205298) (xy 310.530854 -348.182405) (xy 310.509015 -348.133543) (xy 310.494215 -348.082109)
			(xy 310.486745 -348.029112) (xy 310.486298 -348.002352) (xy 310.4868 -347.974779) (xy 310.494745 -347.920208)
			(xy 310.510463 -347.867348) (xy 310.533626 -347.817302) (xy 310.563752 -347.771112) (xy 310.600214 -347.729739)
			(xy 310.620918 -347.711522) (xy 310.629025 -347.703909) (xy 310.638385 -347.683765) (xy 310.638952 -347.67266)
			(xy 310.638952 -347.595444) (xy 310.638391 -347.584333) (xy 310.629049 -347.564173) (xy 310.620918 -347.556582)
			(xy 310.600199 -347.53838) (xy 310.563728 -347.49701) (xy 310.533597 -347.450818) (xy 310.510432 -347.400768)
			(xy 310.494718 -347.347904) (xy 310.486781 -347.293327) (xy 310.486298 -347.265752) (xy 310.486784 -347.238501)
			(xy 310.49454 -347.184553) (xy 310.509895 -347.132258) (xy 310.532537 -347.082681) (xy 310.562003 -347.036831)
			(xy 310.597694 -346.99564) (xy 310.638885 -346.959949) (xy 310.684735 -346.930483) (xy 310.734312 -346.907841)
			(xy 310.786607 -346.892486) (xy 310.840555 -346.88473) (xy 310.895057 -346.88473) (xy 310.949005 -346.892486)
			(xy 311.0013 -346.907841) (xy 311.050877 -346.930483) (xy 311.096727 -346.959949) (xy 311.137918 -346.99564)
			(xy 311.173609 -347.036831) (xy 311.203075 -347.082681) (xy 311.225717 -347.132258) (xy 311.241072 -347.184553)
			(xy 311.248828 -347.238501) (xy 311.249314 -347.265752) (xy 311.24881 -347.293325) (xy 311.240865 -347.347896)
			(xy 311.225147 -347.400755) (xy 311.201984 -347.450801) (xy 311.171859 -347.496992) (xy 311.135398 -347.538365)
			(xy 311.114694 -347.556582) (xy 311.106587 -347.564195) (xy 311.097227 -347.584339) (xy 311.09666 -347.595444)
			(xy 311.09666 -347.67266) (xy 311.097215 -347.683772) (xy 311.106561 -347.703932) (xy 311.114694 -347.711522)
			(xy 311.135418 -347.729719) (xy 311.171887 -347.771091) (xy 311.202018 -347.817284) (xy 311.225182 -347.867334)
			(xy 311.240895 -347.920199) (xy 311.248831 -347.974776) (xy 311.249314 -348.002352) (xy 311.248909 -348.028552)
			(xy 311.241751 -348.08046) (xy 311.227549 -348.130898) (xy 311.206572 -348.178915) (xy 311.179215 -348.223605)
			(xy 311.145994 -348.264127) (xy 311.107534 -348.299715) (xy 311.064562 -348.3297) (xy 311.017888 -348.353515)
			(xy 310.993282 -348.362524) (xy 310.98236 -348.366334) (xy 310.966104 -348.38259) (xy 310.93156 -348.478602)
			(xy 310.933846 -348.501462) (xy 310.939942 -348.511368) (xy 310.95275 -348.533323) (xy 310.972985 -348.579949)
			(xy 310.98669 -348.628894) (xy 310.993609 -348.679248) (xy 310.994044 -348.704662) (xy 310.993531 -348.731278)
			(xy 310.98596 -348.783968) (xy 310.970968 -348.835044) (xy 310.94886 -348.883467) (xy 310.920085 -348.928251)
			(xy 310.885229 -348.968484) (xy 310.845002 -349.003346) (xy 310.800224 -349.032129) (xy 310.751805 -349.054246)
			(xy 310.700731 -349.069247) (xy 310.648042 -349.076826) (xy 310.621426 -349.07728) (xy 310.595006 -349.076788)
			(xy 310.542692 -349.069344) (xy 310.491955 -349.054585) (xy 310.44381 -349.03281) (xy 310.399223 -349.004453)
			(xy 310.378856 -348.987618) (xy 310.371998 -348.981522) (xy 310.35498 -348.975426) (xy 310.270652 -348.975426)
			(xy 310.253634 -348.981522) (xy 310.246776 -348.987618) (xy 310.22641 -349.004457) (xy 310.181824 -349.032822)
			(xy 310.13368 -349.054609) (xy 310.082943 -349.06938) (xy 310.030628 -349.07684) (xy 309.977784 -349.07684)
			(xy 309.925469 -349.06938) (xy 309.874732 -349.054609) (xy 309.826588 -349.032822) (xy 309.782002 -349.004457)
			(xy 309.761636 -348.987618) (xy 309.754778 -348.981522) (xy 309.73776 -348.975426) (xy 309.653432 -348.975426)
			(xy 309.636414 -348.981522) (xy 309.629556 -348.987618) (xy 309.609197 -349.004464) (xy 309.564606 -349.032821)
			(xy 309.51646 -349.0546) (xy 309.465722 -349.069365) (xy 309.413408 -349.076822) (xy 309.386986 -349.07728)
			(xy 309.359099 -349.076834) (xy 309.303948 -349.068519) (xy 309.250653 -349.052078) (xy 309.200403 -349.027877)
			(xy 309.154321 -348.996458) (xy 309.113436 -348.958521) (xy 309.078662 -348.914915) (xy 309.050776 -348.866612)
			(xy 309.0304 -348.814694) (xy 309.017989 -348.760318) (xy 309.013821 -348.7047) (xy 305.198867 -348.7047)
			(xy 305.196177 -348.706429) (xy 305.1466 -348.729071) (xy 305.094305 -348.744426) (xy 305.040357 -348.752182)
			(xy 304.985855 -348.752182) (xy 304.931907 -348.744426) (xy 304.879612 -348.729071) (xy 304.830035 -348.706429)
			(xy 304.784185 -348.676963) (xy 304.742994 -348.641272) (xy 304.707303 -348.600081) (xy 304.677837 -348.554231)
			(xy 304.655195 -348.504654) (xy 304.63984 -348.452359) (xy 304.632084 -348.398411) (xy 304.631598 -348.37116)
			(xy 304.632193 -348.341037) (xy 304.641666 -348.281542) (xy 304.66037 -348.224273) (xy 304.687841 -348.170656)
			(xy 304.723397 -348.122021) (xy 304.744374 -348.100396) (xy 304.751204 -348.092988) (xy 304.75893 -348.074395)
			(xy 304.75936 -348.064328) (xy 304.75936 -348.032324) (xy 304.758932 -348.022255) (xy 304.751214 -348.003656)
			(xy 304.744374 -347.996256) (xy 304.743358 -347.995494) (xy 304.489358 -347.741494) (xy 304.468625 -347.71985)
			(xy 304.433434 -347.671338) (xy 304.40626 -347.61792) (xy 304.387773 -347.560911) (xy 304.378427 -347.501712)
			(xy 304.377852 -347.471746) (xy 304.377852 -342.39454) (xy 304.377418 -342.384471) (xy 304.369705 -342.365873)
			(xy 304.362866 -342.358472) (xy 304.097944 -342.09355) (xy 304.090517 -342.086744) (xy 304.071939 -342.079003)
			(xy 304.061876 -342.078564) (xy 297.308016 -342.078564) (xy 297.297945 -342.078981) (xy 297.279347 -342.086706)
			(xy 297.271948 -342.09355) (xy 296.890186 -342.475312) (xy 296.883346 -342.482712) (xy 296.875627 -342.501311)
			(xy 296.8752 -342.51138) (xy 296.8752 -347.358716) (xy 296.875591 -347.36879) (xy 296.883333 -347.387389)
			(xy 296.890186 -347.394784) (xy 296.951654 -347.455998) (xy 296.972386 -347.477644) (xy 297.007576 -347.526156)
			(xy 297.03475 -347.579573) (xy 297.053237 -347.636582) (xy 297.062585 -347.69578) (xy 297.06316 -347.725746)
			(xy 297.062682 -347.753657) (xy 297.054542 -347.808883) (xy 297.038442 -347.862334) (xy 297.014727 -347.912868)
			(xy 296.983901 -347.959408) (xy 296.965624 -347.980508) (xy 296.959274 -347.98762) (xy 296.95267 -348.004892)
			(xy 296.95267 -348.09176) (xy 296.959274 -348.109032) (xy 296.965624 -348.116144) (xy 296.983959 -348.137242)
			(xy 297.014865 -348.183815) (xy 297.038641 -348.2344) (xy 297.054778 -348.287915) (xy 297.062929 -348.343213)
			(xy 297.063414 -348.37116) (xy 297.062928 -348.398411) (xy 297.055172 -348.452359) (xy 297.039817 -348.504654)
			(xy 297.017175 -348.554231) (xy 296.987709 -348.600081) (xy 296.952018 -348.641272) (xy 296.910827 -348.676963)
			(xy 296.867667 -348.7047) (xy 300.682621 -348.7047) (xy 300.686789 -348.649082) (xy 300.6992 -348.594706)
			(xy 300.719576 -348.542788) (xy 300.747462 -348.494485) (xy 300.782236 -348.450879) (xy 300.823121 -348.412942)
			(xy 300.869203 -348.381523) (xy 300.919453 -348.357322) (xy 300.972748 -348.340881) (xy 301.027899 -348.332566)
			(xy 301.055786 -348.332044) (xy 301.082207 -348.332523) (xy 301.134521 -348.33997) (xy 301.185259 -348.354731)
			(xy 301.233403 -348.376509) (xy 301.27799 -348.404869) (xy 301.298356 -348.421706) (xy 301.305214 -348.427802)
			(xy 301.322232 -348.433898) (xy 301.40656 -348.433898) (xy 301.423578 -348.427802) (xy 301.430436 -348.421706)
			(xy 301.450802 -348.404867) (xy 301.495388 -348.376502) (xy 301.543532 -348.354715) (xy 301.594269 -348.339944)
			(xy 301.646584 -348.332484) (xy 301.699428 -348.332484) (xy 301.751743 -348.339944) (xy 301.80248 -348.354715)
			(xy 301.850624 -348.376502) (xy 301.89521 -348.404867) (xy 301.915576 -348.421706) (xy 301.922434 -348.427802)
			(xy 301.939452 -348.433898) (xy 302.02378 -348.433898) (xy 302.040798 -348.427802) (xy 302.047656 -348.421706)
			(xy 302.072125 -348.40159) (xy 302.12653 -348.369155) (xy 302.15586 -348.35719) (xy 302.166782 -348.352872)
			(xy 302.182276 -348.336616) (xy 302.214026 -348.239842) (xy 302.211232 -348.21749) (xy 302.204882 -348.207584)
			(xy 302.190712 -348.184479) (xy 302.168299 -348.13513) (xy 302.153099 -348.083105) (xy 302.145418 -348.029452)
			(xy 302.144938 -348.002352) (xy 302.145426 -347.974778) (xy 302.153372 -347.920206) (xy 302.169092 -347.867346)
			(xy 302.192258 -347.817299) (xy 302.222387 -347.771109) (xy 302.258852 -347.729738) (xy 302.279558 -347.711522)
			(xy 302.287671 -347.703915) (xy 302.297026 -347.683767) (xy 302.297592 -347.67266) (xy 302.297592 -347.595444)
			(xy 302.297018 -347.584335) (xy 302.287684 -347.564176) (xy 302.279558 -347.556582) (xy 302.258827 -347.538393)
			(xy 302.22236 -347.497019) (xy 302.192231 -347.450824) (xy 302.169069 -347.400772) (xy 302.153357 -347.347906)
			(xy 302.145421 -347.293328) (xy 302.144938 -347.265752) (xy 302.145424 -347.238501) (xy 302.15318 -347.184553)
			(xy 302.168535 -347.132258) (xy 302.191177 -347.082681) (xy 302.220643 -347.036831) (xy 302.256334 -346.99564)
			(xy 302.297525 -346.959949) (xy 302.343375 -346.930483) (xy 302.392952 -346.907841) (xy 302.445247 -346.892486)
			(xy 302.499195 -346.88473) (xy 302.553697 -346.88473) (xy 302.607645 -346.892486) (xy 302.65994 -346.907841)
			(xy 302.709517 -346.930483) (xy 302.755367 -346.959949) (xy 302.796558 -346.99564) (xy 302.832249 -347.036831)
			(xy 302.861715 -347.082681) (xy 302.884357 -347.132258) (xy 302.899712 -347.184553) (xy 302.907468 -347.238501)
			(xy 302.907954 -347.265752) (xy 302.907471 -347.293326) (xy 302.899525 -347.347899) (xy 302.883804 -347.400759)
			(xy 302.860637 -347.450806) (xy 302.830507 -347.496995) (xy 302.794041 -347.538367) (xy 302.773334 -347.556582)
			(xy 302.765218 -347.564186) (xy 302.755865 -347.584337) (xy 302.7553 -347.595444) (xy 302.7553 -347.67266)
			(xy 302.755874 -347.683769) (xy 302.765208 -347.703928) (xy 302.773334 -347.711522) (xy 302.794066 -347.72971)
			(xy 302.830533 -347.771085) (xy 302.860662 -347.81728) (xy 302.883824 -347.867332) (xy 302.899536 -347.920198)
			(xy 302.907471 -347.974776) (xy 302.907954 -348.002352) (xy 302.907398 -348.031389) (xy 302.898589 -348.088791)
			(xy 302.881184 -348.144195) (xy 302.855582 -348.196322) (xy 302.822378 -348.243967) (xy 302.782336 -348.28603)
			(xy 302.736382 -348.321538) (xy 302.685578 -348.349673) (xy 302.658526 -348.360238) (xy 302.647604 -348.364302)
			(xy 302.631856 -348.380304) (xy 302.598582 -348.47657) (xy 302.601122 -348.498922) (xy 302.607218 -348.508828)
			(xy 302.620417 -348.530985) (xy 302.641215 -348.57818) (xy 302.655303 -348.627793) (xy 302.66241 -348.678875)
			(xy 302.662844 -348.704662) (xy 302.662331 -348.731278) (xy 302.65476 -348.783968) (xy 302.639768 -348.835044)
			(xy 302.61766 -348.883467) (xy 302.588885 -348.928251) (xy 302.554029 -348.968484) (xy 302.513802 -349.003346)
			(xy 302.469024 -349.032129) (xy 302.420605 -349.054246) (xy 302.369531 -349.069247) (xy 302.316842 -349.076826)
			(xy 302.290226 -349.07728) (xy 302.263806 -349.076788) (xy 302.211492 -349.069344) (xy 302.160755 -349.054585)
			(xy 302.11261 -349.03281) (xy 302.068023 -349.004453) (xy 302.047656 -348.987618) (xy 302.040798 -348.981522)
			(xy 302.02378 -348.975426) (xy 301.939452 -348.975426) (xy 301.922434 -348.981522) (xy 301.915576 -348.987618)
			(xy 301.89521 -349.004457) (xy 301.850624 -349.032822) (xy 301.80248 -349.054609) (xy 301.751743 -349.06938)
			(xy 301.699428 -349.07684) (xy 301.646584 -349.07684) (xy 301.594269 -349.06938) (xy 301.543532 -349.054609)
			(xy 301.495388 -349.032822) (xy 301.450802 -349.004457) (xy 301.430436 -348.987618) (xy 301.423578 -348.981522)
			(xy 301.40656 -348.975426) (xy 301.322232 -348.975426) (xy 301.305214 -348.981522) (xy 301.298356 -348.987618)
			(xy 301.277997 -349.004464) (xy 301.233406 -349.032821) (xy 301.18526 -349.0546) (xy 301.134522 -349.069365)
			(xy 301.082208 -349.076822) (xy 301.055786 -349.07728) (xy 301.027899 -349.076834) (xy 300.972748 -349.068519)
			(xy 300.919453 -349.052078) (xy 300.869203 -349.027877) (xy 300.823121 -348.996458) (xy 300.782236 -348.958521)
			(xy 300.747462 -348.914915) (xy 300.719576 -348.866612) (xy 300.6992 -348.814694) (xy 300.686789 -348.760318)
			(xy 300.682621 -348.7047) (xy 296.867667 -348.7047) (xy 296.864977 -348.706429) (xy 296.8154 -348.729071)
			(xy 296.763105 -348.744426) (xy 296.709157 -348.752182) (xy 296.654655 -348.752182) (xy 296.600707 -348.744426)
			(xy 296.548412 -348.729071) (xy 296.498835 -348.706429) (xy 296.452985 -348.676963) (xy 296.411794 -348.641272)
			(xy 296.376103 -348.600081) (xy 296.346637 -348.554231) (xy 296.323995 -348.504654) (xy 296.30864 -348.452359)
			(xy 296.300884 -348.398411) (xy 296.300398 -348.37116) (xy 296.300993 -348.341037) (xy 296.310466 -348.281542)
			(xy 296.32917 -348.224273) (xy 296.356641 -348.170656) (xy 296.392197 -348.122021) (xy 296.413174 -348.100396)
			(xy 296.420004 -348.092988) (xy 296.42773 -348.074395) (xy 296.42816 -348.064328) (xy 296.42816 -348.032324)
			(xy 296.427732 -348.022255) (xy 296.420014 -348.003656) (xy 296.413174 -347.996256) (xy 296.412158 -347.995494)
			(xy 296.224198 -347.807534) (xy 296.203425 -347.785926) (xy 296.168242 -347.737403) (xy 296.141077 -347.683976)
			(xy 296.122599 -347.626959) (xy 296.113262 -347.567755) (xy 296.112692 -347.537786) (xy 296.112692 -342.33231)
			(xy 296.113269 -342.301741) (xy 296.122961 -342.241377) (xy 296.131996 -342.212168) (xy 296.135806 -342.200738)
			(xy 296.131996 -342.176608) (xy 296.076624 -342.099646) (xy 296.069024 -342.090246) (xy 296.047545 -342.079238)
			(xy 296.035476 -342.078564) (xy 289.053016 -342.078564) (xy 289.042945 -342.078981) (xy 289.024347 -342.086706)
			(xy 289.016948 -342.09355) (xy 288.680906 -342.429592) (xy 288.677096 -342.438736) (xy 288.66719 -342.461434)
			(xy 288.642388 -342.5043) (xy 288.612255 -342.543601) (xy 288.595054 -342.561418) (xy 288.558732 -342.597486)
			(xy 288.552009 -342.604944) (xy 288.544437 -342.623521) (xy 288.544 -342.633554) (xy 288.544 -347.383862)
			(xy 288.544337 -347.393911) (xy 288.551946 -347.412509) (xy 288.558732 -347.41993) (xy 288.595054 -347.455998)
			(xy 288.615786 -347.477644) (xy 288.650976 -347.526156) (xy 288.67815 -347.579573) (xy 288.696637 -347.636582)
			(xy 288.705985 -347.69578) (xy 288.70656 -347.725746) (xy 288.706082 -347.753657) (xy 288.697942 -347.808883)
			(xy 288.681842 -347.862334) (xy 288.658127 -347.912868) (xy 288.627301 -347.959408) (xy 288.609024 -347.980508)
			(xy 288.602674 -347.98762) (xy 288.59607 -348.004892) (xy 288.59607 -348.09176) (xy 288.602674 -348.109032)
			(xy 288.609024 -348.116144) (xy 288.627359 -348.137242) (xy 288.658265 -348.183815) (xy 288.682041 -348.2344)
			(xy 288.698178 -348.287915) (xy 288.706329 -348.343213) (xy 288.706814 -348.37116) (xy 288.706328 -348.398411)
			(xy 288.698572 -348.452359) (xy 288.683217 -348.504654) (xy 288.660575 -348.554231) (xy 288.631109 -348.600081)
			(xy 288.595418 -348.641272) (xy 288.554227 -348.676963) (xy 288.511067 -348.7047) (xy 292.326021 -348.7047)
			(xy 292.330189 -348.649082) (xy 292.3426 -348.594706) (xy 292.362976 -348.542788) (xy 292.390862 -348.494485)
			(xy 292.425636 -348.450879) (xy 292.466521 -348.412942) (xy 292.512603 -348.381523) (xy 292.562853 -348.357322)
			(xy 292.616148 -348.340881) (xy 292.671299 -348.332566) (xy 292.699186 -348.332044) (xy 292.725607 -348.332523)
			(xy 292.777921 -348.33997) (xy 292.828659 -348.354731) (xy 292.876803 -348.376509) (xy 292.92139 -348.404869)
			(xy 292.941756 -348.421706) (xy 292.948614 -348.427802) (xy 292.965632 -348.433898) (xy 293.04996 -348.433898)
			(xy 293.066978 -348.427802) (xy 293.073836 -348.421706) (xy 293.094202 -348.404867) (xy 293.138788 -348.376502)
			(xy 293.186932 -348.354715) (xy 293.237669 -348.339944) (xy 293.289984 -348.332484) (xy 293.342828 -348.332484)
			(xy 293.395143 -348.339944) (xy 293.44588 -348.354715) (xy 293.494024 -348.376502) (xy 293.53861 -348.404867)
			(xy 293.558976 -348.421706) (xy 293.565834 -348.427802) (xy 293.582852 -348.433898) (xy 293.66718 -348.433898)
			(xy 293.684198 -348.427802) (xy 293.691056 -348.421706) (xy 293.716613 -348.400749) (xy 293.77359 -348.367271)
			(xy 293.80434 -348.355158) (xy 293.81577 -348.351094) (xy 293.83228 -348.33306) (xy 293.860982 -348.23019)
			(xy 293.856156 -348.206314) (xy 293.848536 -348.196662) (xy 293.832909 -348.17632) (xy 293.806631 -348.132266)
			(xy 293.786484 -348.085093) (xy 293.772831 -348.035647) (xy 293.765917 -347.984819) (xy 293.765478 -347.959172)
			(xy 293.766001 -347.9316) (xy 293.773943 -347.87703) (xy 293.789657 -347.824171) (xy 293.812816 -347.774125)
			(xy 293.842938 -347.727934) (xy 293.879396 -347.68656) (xy 293.900098 -347.668342) (xy 293.908193 -347.660718)
			(xy 293.91756 -347.640583) (xy 293.918132 -347.62948) (xy 293.918132 -347.552264) (xy 293.917622 -347.541147)
			(xy 293.908245 -347.520987) (xy 293.900098 -347.513402) (xy 293.879384 -347.495194) (xy 293.842914 -347.453824)
			(xy 293.812782 -347.407634) (xy 293.789617 -347.357585) (xy 293.773901 -347.304722) (xy 293.765963 -347.250147)
			(xy 293.765478 -347.222572) (xy 293.765964 -347.195321) (xy 293.77372 -347.141373) (xy 293.789075 -347.089078)
			(xy 293.811717 -347.039501) (xy 293.841183 -346.993651) (xy 293.876874 -346.95246) (xy 293.918065 -346.916769)
			(xy 293.963915 -346.887303) (xy 294.013492 -346.864661) (xy 294.065787 -346.849306) (xy 294.119735 -346.84155)
			(xy 294.174237 -346.84155) (xy 294.228185 -346.849306) (xy 294.28048 -346.864661) (xy 294.330057 -346.887303)
			(xy 294.375907 -346.916769) (xy 294.417098 -346.95246) (xy 294.452789 -346.993651) (xy 294.482255 -347.039501)
			(xy 294.504897 -347.089078) (xy 294.520252 -347.141373) (xy 294.528008 -347.195321) (xy 294.528494 -347.222572)
			(xy 294.528011 -347.250146) (xy 294.520062 -347.304718) (xy 294.504341 -347.357578) (xy 294.481174 -347.407624)
			(xy 294.451045 -347.453814) (xy 294.41458 -347.495186) (xy 294.393874 -347.513402) (xy 294.385755 -347.521004)
			(xy 294.376402 -347.541156) (xy 294.37584 -347.552264) (xy 294.37584 -347.62948) (xy 294.37639 -347.640592)
			(xy 294.38574 -347.660752) (xy 294.393874 -347.668342) (xy 294.414555 -347.686586) (xy 294.451029 -347.727947)
			(xy 294.481165 -347.77413) (xy 294.504337 -347.824172) (xy 294.520059 -347.877029) (xy 294.528005 -347.931599)
			(xy 294.528494 -347.959172) (xy 294.527984 -347.988496) (xy 294.518985 -348.046451) (xy 294.501226 -348.102346)
			(xy 294.475124 -348.154867) (xy 294.441295 -348.202776) (xy 294.400534 -348.244945) (xy 294.353802 -348.280382)
			(xy 294.302198 -348.308253) (xy 294.274748 -348.318582) (xy 294.263064 -348.3229) (xy 294.2463 -348.340426)
			(xy 294.216328 -348.443042) (xy 294.2209 -348.466918) (xy 294.228266 -348.47657) (xy 294.246588 -348.501214)
			(xy 294.275706 -348.555277) (xy 294.295563 -348.613383) (xy 294.305622 -348.673959) (xy 294.306244 -348.704662)
			(xy 294.305731 -348.731278) (xy 294.29816 -348.783968) (xy 294.283168 -348.835044) (xy 294.26106 -348.883467)
			(xy 294.232285 -348.928251) (xy 294.197429 -348.968484) (xy 294.157202 -349.003346) (xy 294.112424 -349.032129)
			(xy 294.064005 -349.054246) (xy 294.012931 -349.069247) (xy 293.960242 -349.076826) (xy 293.933626 -349.07728)
			(xy 293.907206 -349.076788) (xy 293.854892 -349.069344) (xy 293.804155 -349.054585) (xy 293.75601 -349.03281)
			(xy 293.711423 -349.004453) (xy 293.691056 -348.987618) (xy 293.684198 -348.981522) (xy 293.66718 -348.975426)
			(xy 293.582852 -348.975426) (xy 293.565834 -348.981522) (xy 293.558976 -348.987618) (xy 293.53861 -349.004457)
			(xy 293.494024 -349.032822) (xy 293.44588 -349.054609) (xy 293.395143 -349.06938) (xy 293.342828 -349.07684)
			(xy 293.289984 -349.07684) (xy 293.237669 -349.06938) (xy 293.186932 -349.054609) (xy 293.138788 -349.032822)
			(xy 293.094202 -349.004457) (xy 293.073836 -348.987618) (xy 293.066978 -348.981522) (xy 293.04996 -348.975426)
			(xy 292.965632 -348.975426) (xy 292.948614 -348.981522) (xy 292.941756 -348.987618) (xy 292.921397 -349.004464)
			(xy 292.876806 -349.032821) (xy 292.82866 -349.0546) (xy 292.777922 -349.069365) (xy 292.725608 -349.076822)
			(xy 292.699186 -349.07728) (xy 292.671299 -349.076834) (xy 292.616148 -349.068519) (xy 292.562853 -349.052078)
			(xy 292.512603 -349.027877) (xy 292.466521 -348.996458) (xy 292.425636 -348.958521) (xy 292.390862 -348.914915)
			(xy 292.362976 -348.866612) (xy 292.3426 -348.814694) (xy 292.330189 -348.760318) (xy 292.326021 -348.7047)
			(xy 288.511067 -348.7047) (xy 288.508377 -348.706429) (xy 288.4588 -348.729071) (xy 288.406505 -348.744426)
			(xy 288.352557 -348.752182) (xy 288.298055 -348.752182) (xy 288.244107 -348.744426) (xy 288.191812 -348.729071)
			(xy 288.142235 -348.706429) (xy 288.096385 -348.676963) (xy 288.055194 -348.641272) (xy 288.019503 -348.600081)
			(xy 287.990037 -348.554231) (xy 287.967395 -348.504654) (xy 287.95204 -348.452359) (xy 287.944284 -348.398411)
			(xy 287.943798 -348.37116) (xy 287.944393 -348.341037) (xy 287.953866 -348.281542) (xy 287.97257 -348.224273)
			(xy 288.000041 -348.170656) (xy 288.035597 -348.122021) (xy 288.056574 -348.100396) (xy 288.063404 -348.092988)
			(xy 288.07113 -348.074395) (xy 288.07156 -348.064328) (xy 288.07156 -348.032324) (xy 288.071132 -348.022255)
			(xy 288.063414 -348.003656) (xy 288.056574 -347.996256) (xy 288.055558 -347.995494) (xy 287.892744 -347.83268)
			(xy 287.87192 -347.811103) (xy 287.836667 -347.762596) (xy 287.80944 -347.70917) (xy 287.790911 -347.652141)
			(xy 287.781537 -347.592914) (xy 287.780984 -347.562932) (xy 287.780984 -342.454484) (xy 287.781504 -342.425911)
			(xy 287.790043 -342.369408) (xy 287.798002 -342.341962) (xy 287.80232 -342.328246) (xy 287.795716 -342.301322)
			(xy 287.714944 -342.22055) (xy 287.707517 -342.213744) (xy 287.688939 -342.206003) (xy 287.678876 -342.205564)
			(xy 280.417016 -342.205564) (xy 280.406945 -342.205981) (xy 280.388347 -342.213706) (xy 280.380948 -342.22055)
			(xy 280.161746 -342.439752) (xy 280.154941 -342.44718) (xy 280.147199 -342.465758) (xy 280.14676 -342.47582)
			(xy 280.14676 -347.292676) (xy 280.147182 -347.302746) (xy 280.154903 -347.321345) (xy 280.161746 -347.328744)
			(xy 280.289254 -347.455998) (xy 280.309986 -347.477644) (xy 280.345176 -347.526156) (xy 280.37235 -347.579573)
			(xy 280.390837 -347.636582) (xy 280.400185 -347.69578) (xy 280.40076 -347.725746) (xy 280.400282 -347.753657)
			(xy 280.392142 -347.808883) (xy 280.376042 -347.862334) (xy 280.352327 -347.912868) (xy 280.321501 -347.959408)
			(xy 280.303224 -347.980508) (xy 280.296874 -347.98762) (xy 280.29027 -348.004892) (xy 280.29027 -348.09176)
			(xy 280.296874 -348.109032) (xy 280.303224 -348.116144) (xy 280.321559 -348.137242) (xy 280.352465 -348.183815)
			(xy 280.376241 -348.2344) (xy 280.392378 -348.287915) (xy 280.400529 -348.343213) (xy 280.401014 -348.37116)
			(xy 280.400528 -348.398411) (xy 280.392772 -348.452359) (xy 280.377417 -348.504654) (xy 280.354775 -348.554231)
			(xy 280.325309 -348.600081) (xy 280.289618 -348.641272) (xy 280.248427 -348.676963) (xy 280.205267 -348.7047)
			(xy 284.020221 -348.7047) (xy 284.024389 -348.649082) (xy 284.0368 -348.594706) (xy 284.057176 -348.542788)
			(xy 284.085062 -348.494485) (xy 284.119836 -348.450879) (xy 284.160721 -348.412942) (xy 284.206803 -348.381523)
			(xy 284.257053 -348.357322) (xy 284.310348 -348.340881) (xy 284.365499 -348.332566) (xy 284.393386 -348.332044)
			(xy 284.419807 -348.332523) (xy 284.472121 -348.33997) (xy 284.522859 -348.354731) (xy 284.571003 -348.376509)
			(xy 284.61559 -348.404869) (xy 284.635956 -348.421706) (xy 284.642814 -348.427802) (xy 284.659832 -348.433898)
			(xy 284.74416 -348.433898) (xy 284.761178 -348.427802) (xy 284.768036 -348.421706) (xy 284.788402 -348.404867)
			(xy 284.832988 -348.376502) (xy 284.881132 -348.354715) (xy 284.931869 -348.339944) (xy 284.984184 -348.332484)
			(xy 285.037028 -348.332484) (xy 285.089343 -348.339944) (xy 285.14008 -348.354715) (xy 285.188224 -348.376502)
			(xy 285.23281 -348.404867) (xy 285.253176 -348.421706) (xy 285.260034 -348.427802) (xy 285.277052 -348.433898)
			(xy 285.36138 -348.433898) (xy 285.378398 -348.427802) (xy 285.385256 -348.421706) (xy 285.403098 -348.4069)
			(xy 285.441797 -348.381362) (xy 285.483363 -348.360819) (xy 285.505144 -348.352872) (xy 285.516574 -348.348808)
			(xy 285.533084 -348.332044) (xy 285.565596 -348.232222) (xy 285.562294 -348.208854) (xy 285.555436 -348.198948)
			(xy 285.539474 -348.174897) (xy 285.514145 -348.123033) (xy 285.496913 -348.067945) (xy 285.488173 -348.010891)
			(xy 285.487618 -347.982032) (xy 285.488099 -347.954458) (xy 285.496048 -347.899886) (xy 285.511769 -347.847026)
			(xy 285.534936 -347.79698) (xy 285.565066 -347.75079) (xy 285.601532 -347.709418) (xy 285.622238 -347.691202)
			(xy 285.630357 -347.6836) (xy 285.63971 -347.663448) (xy 285.640272 -347.65234) (xy 285.640272 -347.575124)
			(xy 285.639716 -347.564013) (xy 285.63037 -347.543853) (xy 285.622238 -347.536262) (xy 285.601513 -347.518066)
			(xy 285.565042 -347.476695) (xy 285.534911 -347.430502) (xy 285.511747 -347.380451) (xy 285.496034 -347.327585)
			(xy 285.4881 -347.273008) (xy 285.487618 -347.245432) (xy 285.488104 -347.218181) (xy 285.49586 -347.164233)
			(xy 285.511215 -347.111938) (xy 285.533857 -347.062361) (xy 285.563323 -347.016511) (xy 285.599014 -346.97532)
			(xy 285.640205 -346.939629) (xy 285.686055 -346.910163) (xy 285.735632 -346.887521) (xy 285.787927 -346.872166)
			(xy 285.841875 -346.86441) (xy 285.896377 -346.86441) (xy 285.950325 -346.872166) (xy 286.00262 -346.887521)
			(xy 286.052197 -346.910163) (xy 286.098047 -346.939629) (xy 286.139238 -346.97532) (xy 286.174929 -347.016511)
			(xy 286.204395 -347.062361) (xy 286.227037 -347.111938) (xy 286.242392 -347.164233) (xy 286.250148 -347.218181)
			(xy 286.250634 -347.245432) (xy 286.250145 -347.273006) (xy 286.2422 -347.327579) (xy 286.226481 -347.380439)
			(xy 286.203316 -347.430486) (xy 286.173186 -347.476676) (xy 286.136721 -347.518047) (xy 286.116014 -347.536262)
			(xy 286.107919 -347.543886) (xy 286.098551 -347.564021) (xy 286.09798 -347.575124) (xy 286.09798 -347.65234)
			(xy 286.098484 -347.663458) (xy 286.107865 -347.683618) (xy 286.116014 -347.691202) (xy 286.136732 -347.709405)
			(xy 286.173201 -347.750776) (xy 286.203332 -347.796968) (xy 286.226497 -347.847017) (xy 286.242212 -347.899881)
			(xy 286.25015 -347.954457) (xy 286.250634 -347.982032) (xy 286.250151 -348.008525) (xy 286.242802 -348.061)
			(xy 286.228264 -348.111954) (xy 286.206817 -348.160406) (xy 286.178873 -348.205426) (xy 286.144969 -348.246146)
			(xy 286.105757 -348.281785) (xy 286.061993 -348.311655) (xy 286.014516 -348.335184) (xy 285.989522 -348.343982)
			(xy 285.978092 -348.347792) (xy 285.961328 -348.364556) (xy 285.927546 -348.463616) (xy 285.930594 -348.486984)
			(xy 285.937198 -348.497144) (xy 285.952118 -348.520284) (xy 285.975735 -348.570018) (xy 285.991787 -348.622682)
			(xy 285.999927 -348.677134) (xy 286.000444 -348.704662) (xy 285.999931 -348.731278) (xy 285.99236 -348.783968)
			(xy 285.977368 -348.835044) (xy 285.95526 -348.883467) (xy 285.926485 -348.928251) (xy 285.891629 -348.968484)
			(xy 285.851402 -349.003346) (xy 285.806624 -349.032129) (xy 285.758205 -349.054246) (xy 285.707131 -349.069247)
			(xy 285.654442 -349.076826) (xy 285.627826 -349.07728) (xy 285.601406 -349.076788) (xy 285.549092 -349.069344)
			(xy 285.498355 -349.054585) (xy 285.45021 -349.03281) (xy 285.405623 -349.004453) (xy 285.385256 -348.987618)
			(xy 285.378398 -348.981522) (xy 285.36138 -348.975426) (xy 285.277052 -348.975426) (xy 285.260034 -348.981522)
			(xy 285.253176 -348.987618) (xy 285.23281 -349.004457) (xy 285.188224 -349.032822) (xy 285.14008 -349.054609)
			(xy 285.089343 -349.06938) (xy 285.037028 -349.07684) (xy 284.984184 -349.07684) (xy 284.931869 -349.06938)
			(xy 284.881132 -349.054609) (xy 284.832988 -349.032822) (xy 284.788402 -349.004457) (xy 284.768036 -348.987618)
			(xy 284.761178 -348.981522) (xy 284.74416 -348.975426) (xy 284.659832 -348.975426) (xy 284.642814 -348.981522)
			(xy 284.635956 -348.987618) (xy 284.615597 -349.004464) (xy 284.571006 -349.032821) (xy 284.52286 -349.0546)
			(xy 284.472122 -349.069365) (xy 284.419808 -349.076822) (xy 284.393386 -349.07728) (xy 284.365499 -349.076834)
			(xy 284.310348 -349.068519) (xy 284.257053 -349.052078) (xy 284.206803 -349.027877) (xy 284.160721 -348.996458)
			(xy 284.119836 -348.958521) (xy 284.085062 -348.914915) (xy 284.057176 -348.866612) (xy 284.0368 -348.814694)
			(xy 284.024389 -348.760318) (xy 284.020221 -348.7047) (xy 280.205267 -348.7047) (xy 280.202577 -348.706429)
			(xy 280.153 -348.729071) (xy 280.100705 -348.744426) (xy 280.046757 -348.752182) (xy 279.992255 -348.752182)
			(xy 279.938307 -348.744426) (xy 279.886012 -348.729071) (xy 279.836435 -348.706429) (xy 279.790585 -348.676963)
			(xy 279.749394 -348.641272) (xy 279.713703 -348.600081) (xy 279.684237 -348.554231) (xy 279.661595 -348.504654)
			(xy 279.64624 -348.452359) (xy 279.638484 -348.398411) (xy 279.637998 -348.37116) (xy 279.638593 -348.341037)
			(xy 279.648066 -348.281542) (xy 279.66677 -348.224273) (xy 279.694241 -348.170656) (xy 279.729797 -348.122021)
			(xy 279.750774 -348.100396) (xy 279.757604 -348.092988) (xy 279.76533 -348.074395) (xy 279.76576 -348.064328)
			(xy 279.76576 -348.032324) (xy 279.765332 -348.022255) (xy 279.757614 -348.003656) (xy 279.750774 -347.996256)
			(xy 279.749758 -347.995494) (xy 279.495758 -347.741494) (xy 279.475025 -347.71985) (xy 279.439834 -347.671338)
			(xy 279.41266 -347.61792) (xy 279.394173 -347.560911) (xy 279.384827 -347.501712) (xy 279.384252 -347.471746)
			(xy 279.384252 -342.54694) (xy 279.383818 -342.536871) (xy 279.376105 -342.518273) (xy 279.369266 -342.510872)
			(xy 279.078944 -342.22055) (xy 279.071517 -342.213744) (xy 279.052939 -342.206003) (xy 279.042876 -342.205564)
			(xy 272.670016 -342.205564) (xy 272.659945 -342.205981) (xy 272.641347 -342.213706) (xy 272.633948 -342.22055)
			(xy 271.881346 -342.973152) (xy 271.874541 -342.98058) (xy 271.866799 -342.999158) (xy 271.86636 -343.00922)
			(xy 271.86636 -347.292676) (xy 271.866782 -347.302746) (xy 271.874503 -347.321345) (xy 271.881346 -347.328744)
			(xy 272.008854 -347.455998) (xy 272.029586 -347.477644) (xy 272.064776 -347.526156) (xy 272.09195 -347.579573)
			(xy 272.110437 -347.636582) (xy 272.119785 -347.69578) (xy 272.12036 -347.725746) (xy 272.119882 -347.753657)
			(xy 272.111742 -347.808883) (xy 272.095642 -347.862334) (xy 272.071927 -347.912868) (xy 272.041101 -347.959408)
			(xy 272.022824 -347.980508) (xy 272.016474 -347.98762) (xy 272.00987 -348.004892) (xy 272.00987 -348.09176)
			(xy 272.016474 -348.109032) (xy 272.022824 -348.116144) (xy 272.041159 -348.137242) (xy 272.072065 -348.183815)
			(xy 272.095841 -348.2344) (xy 272.111978 -348.287915) (xy 272.120129 -348.343213) (xy 272.120614 -348.37116)
			(xy 272.120128 -348.398411) (xy 272.112372 -348.452359) (xy 272.097017 -348.504654) (xy 272.074375 -348.554231)
			(xy 272.044909 -348.600081) (xy 272.009218 -348.641272) (xy 271.968027 -348.676963) (xy 271.924867 -348.7047)
			(xy 275.739821 -348.7047) (xy 275.743989 -348.649082) (xy 275.7564 -348.594706) (xy 275.776776 -348.542788)
			(xy 275.804662 -348.494485) (xy 275.839436 -348.450879) (xy 275.880321 -348.412942) (xy 275.926403 -348.381523)
			(xy 275.976653 -348.357322) (xy 276.029948 -348.340881) (xy 276.085099 -348.332566) (xy 276.112986 -348.332044)
			(xy 276.139407 -348.332523) (xy 276.191721 -348.33997) (xy 276.242459 -348.354731) (xy 276.290603 -348.376509)
			(xy 276.33519 -348.404869) (xy 276.355556 -348.421706) (xy 276.362414 -348.427802) (xy 276.379432 -348.433898)
			(xy 276.46376 -348.433898) (xy 276.480778 -348.427802) (xy 276.487636 -348.421706) (xy 276.508002 -348.404867)
			(xy 276.552588 -348.376502) (xy 276.600732 -348.354715) (xy 276.651469 -348.339944) (xy 276.703784 -348.332484)
			(xy 276.756628 -348.332484) (xy 276.808943 -348.339944) (xy 276.85968 -348.354715) (xy 276.907824 -348.376502)
			(xy 276.95241 -348.404867) (xy 276.972776 -348.421706) (xy 276.979634 -348.427802) (xy 276.996652 -348.433898)
			(xy 277.08098 -348.433898) (xy 277.097998 -348.427802) (xy 277.104856 -348.421706) (xy 277.128853 -348.401962)
			(xy 277.182096 -348.369922) (xy 277.210774 -348.357952) (xy 277.221188 -348.353888) (xy 277.236428 -348.33814)
			(xy 277.269448 -348.244668) (xy 277.267416 -348.223078) (xy 277.261828 -348.213426) (xy 277.250031 -348.191825)
			(xy 277.231486 -348.146234) (xy 277.218961 -348.098636) (xy 277.212665 -348.049822) (xy 277.212298 -348.025212)
			(xy 277.212773 -347.997638) (xy 277.220723 -347.943065) (xy 277.236447 -347.890206) (xy 277.259615 -347.84016)
			(xy 277.289746 -347.79397) (xy 277.326212 -347.752598) (xy 277.346918 -347.734382) (xy 277.355043 -347.726785)
			(xy 277.364393 -347.706629) (xy 277.364952 -347.69552) (xy 277.364952 -347.618304) (xy 277.364413 -347.60719)
			(xy 277.355056 -347.587031) (xy 277.346918 -347.579442) (xy 277.326228 -347.561208) (xy 277.289755 -347.519845)
			(xy 277.25962 -347.47366) (xy 277.23645 -347.423616) (xy 277.22073 -347.370757) (xy 277.212786 -347.316185)
			(xy 277.212298 -347.288612) (xy 277.212784 -347.261361) (xy 277.22054 -347.207413) (xy 277.235895 -347.155118)
			(xy 277.258537 -347.105541) (xy 277.288003 -347.059691) (xy 277.323694 -347.0185) (xy 277.364885 -346.982809)
			(xy 277.410735 -346.953343) (xy 277.460312 -346.930701) (xy 277.512607 -346.915346) (xy 277.566555 -346.90759)
			(xy 277.621057 -346.90759) (xy 277.675005 -346.915346) (xy 277.7273 -346.930701) (xy 277.776877 -346.953343)
			(xy 277.822727 -346.982809) (xy 277.863918 -347.0185) (xy 277.899609 -347.059691) (xy 277.929075 -347.105541)
			(xy 277.951717 -347.155118) (xy 277.967072 -347.207413) (xy 277.974828 -347.261361) (xy 277.975314 -347.288612)
			(xy 277.974783 -347.316184) (xy 277.966843 -347.370754) (xy 277.951131 -347.423612) (xy 277.927973 -347.473658)
			(xy 277.897852 -347.51985) (xy 277.861396 -347.561224) (xy 277.840694 -347.579442) (xy 277.83256 -347.587031)
			(xy 277.823215 -347.607193) (xy 277.82266 -347.618304) (xy 277.82266 -347.69552) (xy 277.823182 -347.706636)
			(xy 277.832551 -347.726795) (xy 277.840694 -347.734382) (xy 277.861398 -347.7526) (xy 277.89787 -347.793967)
			(xy 277.928003 -347.840156) (xy 277.95117 -347.890202) (xy 277.966887 -347.943064) (xy 277.974828 -347.997638)
			(xy 277.975314 -348.025212) (xy 277.974776 -348.054113) (xy 277.966042 -348.111252) (xy 277.948791 -348.16642)
			(xy 277.923417 -348.218355) (xy 277.890501 -348.265869) (xy 277.850796 -348.307877) (xy 277.80521 -348.343415)
			(xy 277.754785 -348.371672) (xy 277.727918 -348.382336) (xy 277.717504 -348.3864) (xy 277.70201 -348.40164)
			(xy 277.667466 -348.494604) (xy 277.669244 -348.516194) (xy 277.674578 -348.5261) (xy 277.688923 -348.553648)
			(xy 277.709201 -348.612352) (xy 277.719452 -348.673608) (xy 277.720044 -348.704662) (xy 277.719531 -348.731278)
			(xy 277.71196 -348.783968) (xy 277.696968 -348.835044) (xy 277.67486 -348.883467) (xy 277.646085 -348.928251)
			(xy 277.611229 -348.968484) (xy 277.571002 -349.003346) (xy 277.526224 -349.032129) (xy 277.477805 -349.054246)
			(xy 277.426731 -349.069247) (xy 277.374042 -349.076826) (xy 277.347426 -349.07728) (xy 277.321006 -349.076788)
			(xy 277.268692 -349.069344) (xy 277.217955 -349.054585) (xy 277.16981 -349.03281) (xy 277.125223 -349.004453)
			(xy 277.104856 -348.987618) (xy 277.097998 -348.981522) (xy 277.08098 -348.975426) (xy 276.996652 -348.975426)
			(xy 276.979634 -348.981522) (xy 276.972776 -348.987618) (xy 276.95241 -349.004457) (xy 276.907824 -349.032822)
			(xy 276.85968 -349.054609) (xy 276.808943 -349.06938) (xy 276.756628 -349.07684) (xy 276.703784 -349.07684)
			(xy 276.651469 -349.06938) (xy 276.600732 -349.054609) (xy 276.552588 -349.032822) (xy 276.508002 -349.004457)
			(xy 276.487636 -348.987618) (xy 276.480778 -348.981522) (xy 276.46376 -348.975426) (xy 276.379432 -348.975426)
			(xy 276.362414 -348.981522) (xy 276.355556 -348.987618) (xy 276.335197 -349.004464) (xy 276.290606 -349.032821)
			(xy 276.24246 -349.0546) (xy 276.191722 -349.069365) (xy 276.139408 -349.076822) (xy 276.112986 -349.07728)
			(xy 276.085099 -349.076834) (xy 276.029948 -349.068519) (xy 275.976653 -349.052078) (xy 275.926403 -349.027877)
			(xy 275.880321 -348.996458) (xy 275.839436 -348.958521) (xy 275.804662 -348.914915) (xy 275.776776 -348.866612)
			(xy 275.7564 -348.814694) (xy 275.743989 -348.760318) (xy 275.739821 -348.7047) (xy 271.924867 -348.7047)
			(xy 271.922177 -348.706429) (xy 271.8726 -348.729071) (xy 271.820305 -348.744426) (xy 271.766357 -348.752182)
			(xy 271.711855 -348.752182) (xy 271.657907 -348.744426) (xy 271.605612 -348.729071) (xy 271.556035 -348.706429)
			(xy 271.510185 -348.676963) (xy 271.468994 -348.641272) (xy 271.433303 -348.600081) (xy 271.403837 -348.554231)
			(xy 271.381195 -348.504654) (xy 271.36584 -348.452359) (xy 271.358084 -348.398411) (xy 271.357598 -348.37116)
			(xy 271.358193 -348.341037) (xy 271.367666 -348.281542) (xy 271.38637 -348.224273) (xy 271.413841 -348.170656)
			(xy 271.449397 -348.122021) (xy 271.470374 -348.100396) (xy 271.477204 -348.092988) (xy 271.48493 -348.074395)
			(xy 271.48536 -348.064328) (xy 271.48536 -348.032324) (xy 271.484932 -348.022255) (xy 271.477214 -348.003656)
			(xy 271.470374 -347.996256) (xy 271.469358 -347.995494) (xy 271.215358 -347.741494) (xy 271.194625 -347.71985)
			(xy 271.159434 -347.671338) (xy 271.13226 -347.61792) (xy 271.113773 -347.560911) (xy 271.104427 -347.501712)
			(xy 271.103852 -347.471746) (xy 260.420833 -347.471746) (xy 260.425458 -347.482887) (xy 260.432296 -347.490288)
			(xy 262.544814 -349.602806) (xy 272.31543 -349.602806) (xy 272.319501 -349.547184) (xy 272.331627 -349.492747)
			(xy 272.35155 -349.440656) (xy 272.378846 -349.392021) (xy 272.412932 -349.347878) (xy 272.453081 -349.309169)
			(xy 272.498439 -349.276718) (xy 272.548039 -349.251217) (xy 272.600823 -349.23321) (xy 272.655666 -349.22308)
			(xy 272.7114 -349.221043) (xy 272.766837 -349.227143) (xy 272.820794 -349.241249) (xy 272.872123 -349.263061)
			(xy 272.919729 -349.292115) (xy 272.962597 -349.32779) (xy 272.999814 -349.369327) (xy 273.030587 -349.41584)
			(xy 273.054259 -349.466337) (xy 273.070327 -349.519744) (xy 273.078447 -349.57492) (xy 273.078956 -349.602806)
			(xy 273.078447 -349.630692) (xy 273.070327 -349.685868) (xy 273.054259 -349.739275) (xy 273.030587 -349.789772)
			(xy 272.999814 -349.836285) (xy 272.962597 -349.877822) (xy 272.919729 -349.913497) (xy 272.872123 -349.942551)
			(xy 272.820794 -349.964363) (xy 272.766837 -349.978469) (xy 272.7114 -349.984569) (xy 272.655666 -349.982532)
			(xy 272.600823 -349.972402) (xy 272.548039 -349.954395) (xy 272.498439 -349.928894) (xy 272.453081 -349.896443)
			(xy 272.412932 -349.857734) (xy 272.378846 -349.813591) (xy 272.35155 -349.764956) (xy 272.331627 -349.712865)
			(xy 272.319501 -349.658428) (xy 272.31543 -349.602806) (xy 262.544814 -349.602806) (xy 263.440164 -350.498156)
			(xy 271.73631 -350.498156) (xy 271.740381 -350.442534) (xy 271.752507 -350.388097) (xy 271.77243 -350.336006)
			(xy 271.799726 -350.287371) (xy 271.833812 -350.243228) (xy 271.873961 -350.204519) (xy 271.919319 -350.172068)
			(xy 271.968919 -350.146567) (xy 272.021703 -350.12856) (xy 272.076546 -350.11843) (xy 272.13228 -350.116393)
			(xy 272.187717 -350.122493) (xy 272.241674 -350.136599) (xy 272.293003 -350.158411) (xy 272.340609 -350.187465)
			(xy 272.383477 -350.22314) (xy 272.420694 -350.264677) (xy 272.451467 -350.31119) (xy 272.475139 -350.361687)
			(xy 272.491207 -350.415094) (xy 272.499327 -350.47027) (xy 272.499836 -350.498156) (xy 272.499327 -350.526042)
			(xy 272.491207 -350.581218) (xy 272.475139 -350.634625) (xy 272.451467 -350.685122) (xy 272.420694 -350.731635)
			(xy 272.383477 -350.773172) (xy 272.340609 -350.808847) (xy 272.293003 -350.837901) (xy 272.241674 -350.859713)
			(xy 272.187717 -350.873819) (xy 272.13228 -350.879919) (xy 272.076546 -350.877882) (xy 272.021703 -350.867752)
			(xy 271.968919 -350.849745) (xy 271.919319 -350.824244) (xy 271.873961 -350.791793) (xy 271.833812 -350.753084)
			(xy 271.799726 -350.708941) (xy 271.77243 -350.660306) (xy 271.752507 -350.608215) (xy 271.740381 -350.553778)
			(xy 271.73631 -350.498156) (xy 263.440164 -350.498156) (xy 267.653008 -354.711) (xy 302.969166 -354.711)
			(xy 302.973237 -354.655378) (xy 302.985363 -354.600941) (xy 303.005286 -354.54885) (xy 303.032582 -354.500215)
			(xy 303.066668 -354.456072) (xy 303.106817 -354.417363) (xy 303.152175 -354.384912) (xy 303.201775 -354.359411)
			(xy 303.254559 -354.341404) (xy 303.309402 -354.331274) (xy 303.365136 -354.329237) (xy 303.420573 -354.335337)
			(xy 303.47453 -354.349443) (xy 303.525859 -354.371255) (xy 303.573465 -354.400309) (xy 303.616333 -354.435984)
			(xy 303.65355 -354.477521) (xy 303.684323 -354.524034) (xy 303.707995 -354.574531) (xy 303.724063 -354.627938)
			(xy 303.732183 -354.683114) (xy 303.732692 -354.711) (xy 303.732183 -354.738886) (xy 303.724063 -354.794062)
			(xy 303.707995 -354.847469) (xy 303.684323 -354.897966) (xy 303.65355 -354.944479) (xy 303.616333 -354.986016)
			(xy 303.573465 -355.021691) (xy 303.525859 -355.050745) (xy 303.47453 -355.072557) (xy 303.420573 -355.086663)
			(xy 303.365136 -355.092763) (xy 303.309402 -355.090726) (xy 303.254559 -355.080596) (xy 303.201775 -355.062589)
			(xy 303.152175 -355.037088) (xy 303.106817 -355.004637) (xy 303.066668 -354.965928) (xy 303.032582 -354.921785)
			(xy 303.005286 -354.87315) (xy 302.985363 -354.821059) (xy 302.973237 -354.766622) (xy 302.969166 -354.711)
			(xy 267.653008 -354.711) (xy 268.221206 -355.279198) (xy 285.984442 -355.279198) (xy 285.984854 -355.251943)
			(xy 285.992612 -355.197987) (xy 286.007971 -355.145686) (xy 286.030617 -355.096102) (xy 286.06009 -355.050247)
			(xy 286.095789 -355.009053) (xy 286.136988 -354.973359) (xy 286.182848 -354.943892) (xy 286.232434 -354.921253)
			(xy 286.284738 -354.905901) (xy 286.338695 -354.89815) (xy 286.36595 -354.89769) (xy 286.393319 -354.898188)
			(xy 286.447497 -354.905998) (xy 286.499999 -354.92148) (xy 286.549747 -354.944315) (xy 286.595715 -354.974032)
			(xy 286.616648 -354.99167) (xy 286.62376 -354.997766) (xy 286.640778 -355.004116) (xy 286.726122 -355.004116)
			(xy 286.74314 -354.997766) (xy 286.750252 -354.99167) (xy 286.771185 -354.974029) (xy 286.817153 -354.944305)
			(xy 286.866899 -354.921459) (xy 286.919401 -354.905963) (xy 286.973579 -354.898134) (xy 287.028321 -354.898134)
			(xy 287.082499 -354.905963) (xy 287.135001 -354.921459) (xy 287.184747 -354.944305) (xy 287.230715 -354.974029)
			(xy 287.251648 -354.99167) (xy 287.25876 -354.997766) (xy 287.275778 -355.004116) (xy 287.361122 -355.004116)
			(xy 287.37814 -354.997766) (xy 287.385252 -354.99167) (xy 287.406185 -354.974029) (xy 287.452153 -354.944305)
			(xy 287.501899 -354.921459) (xy 287.554401 -354.905963) (xy 287.608579 -354.898134) (xy 287.663321 -354.898134)
			(xy 287.717499 -354.905963) (xy 287.770001 -354.921459) (xy 287.819747 -354.944305) (xy 287.865715 -354.974029)
			(xy 287.886648 -354.99167) (xy 287.89376 -354.997766) (xy 287.910778 -355.004116) (xy 287.996122 -355.004116)
			(xy 288.01314 -354.997766) (xy 288.020252 -354.99167) (xy 288.041185 -354.974029) (xy 288.087153 -354.944305)
			(xy 288.136899 -354.921459) (xy 288.189401 -354.905963) (xy 288.243579 -354.898134) (xy 288.298321 -354.898134)
			(xy 288.352499 -354.905963) (xy 288.405001 -354.921459) (xy 288.454747 -354.944305) (xy 288.500715 -354.974029)
			(xy 288.521648 -354.99167) (xy 288.52876 -354.997766) (xy 288.545778 -355.004116) (xy 288.631122 -355.004116)
			(xy 288.64814 -354.997766) (xy 288.655252 -354.99167) (xy 288.676187 -354.974035) (xy 288.72216 -354.944324)
			(xy 288.771907 -354.921488) (xy 288.824406 -354.905995) (xy 288.878581 -354.898165) (xy 288.90595 -354.89769)
			(xy 288.933202 -354.898202) (xy 288.987151 -354.905952) (xy 289.039447 -354.921302) (xy 289.089027 -354.943938)
			(xy 289.134881 -354.973401) (xy 289.176074 -355.009089) (xy 289.211768 -355.050278) (xy 289.241237 -355.096127)
			(xy 289.26388 -355.145704) (xy 289.279237 -355.197999) (xy 289.286994 -355.251947) (xy 289.287458 -355.279198)
			(xy 289.286959 -355.307902) (xy 289.278357 -355.364663) (xy 289.261346 -355.419494) (xy 289.236312 -355.471157)
			(xy 289.203819 -355.518485) (xy 289.184588 -355.539802) (xy 289.17773 -355.547168) (xy 289.170618 -355.565202)
			(xy 289.172142 -355.65588) (xy 289.179508 -355.67366) (xy 289.18662 -355.680772) (xy 289.207284 -355.702351)
			(xy 289.242299 -355.750757) (xy 289.269336 -355.804033) (xy 289.285509 -355.854) (xy 302.893982 -355.854)
			(xy 302.898053 -355.798378) (xy 302.910179 -355.743941) (xy 302.930102 -355.69185) (xy 302.957398 -355.643215)
			(xy 302.991484 -355.599072) (xy 303.031633 -355.560363) (xy 303.076991 -355.527912) (xy 303.126591 -355.502411)
			(xy 303.179375 -355.484404) (xy 303.234218 -355.474274) (xy 303.289952 -355.472237) (xy 303.345389 -355.478337)
			(xy 303.399346 -355.492443) (xy 303.450675 -355.514255) (xy 303.498281 -355.543309) (xy 303.541149 -355.578984)
			(xy 303.578366 -355.620521) (xy 303.609139 -355.667034) (xy 303.632811 -355.717531) (xy 303.648879 -355.770938)
			(xy 303.656999 -355.826114) (xy 303.657508 -355.854) (xy 303.656999 -355.881886) (xy 303.648879 -355.937062)
			(xy 303.632811 -355.990469) (xy 303.609139 -356.040966) (xy 303.578366 -356.087479) (xy 303.541149 -356.129016)
			(xy 303.498281 -356.164691) (xy 303.450675 -356.193745) (xy 303.399346 -356.215557) (xy 303.345389 -356.229663)
			(xy 303.289952 -356.235763) (xy 303.234218 -356.233726) (xy 303.179375 -356.223596) (xy 303.126591 -356.205589)
			(xy 303.076991 -356.180088) (xy 303.031633 -356.147637) (xy 302.991484 -356.108928) (xy 302.957398 -356.064785)
			(xy 302.930102 -356.01615) (xy 302.910179 -355.964059) (xy 302.898053 -355.909622) (xy 302.893982 -355.854)
			(xy 289.285509 -355.854) (xy 289.287734 -355.860873) (xy 289.297042 -355.919886) (xy 289.297618 -355.949758)
			(xy 289.297147 -355.977128) (xy 289.289334 -356.031308) (xy 289.273847 -356.083812) (xy 289.251006 -356.133559)
			(xy 289.22128 -356.179525) (xy 289.203638 -356.200456) (xy 289.197542 -356.207568) (xy 289.191192 -356.224586)
			(xy 289.191192 -356.30993) (xy 289.197542 -356.326948) (xy 289.203638 -356.33406) (xy 289.221278 -356.354991)
			(xy 289.250989 -356.400965) (xy 289.273824 -356.450713) (xy 289.289315 -356.503213) (xy 289.297144 -356.557389)
			(xy 289.297618 -356.584758) (xy 289.297106 -356.612009) (xy 289.289355 -356.665958) (xy 289.274004 -356.718254)
			(xy 289.251368 -356.767834) (xy 289.221905 -356.813687) (xy 289.186216 -356.854879) (xy 289.145028 -356.890574)
			(xy 289.099179 -356.920043) (xy 289.049603 -356.942686) (xy 288.997309 -356.958044) (xy 288.943361 -356.965802)
			(xy 288.91611 -356.966266) (xy 288.88874 -356.965802) (xy 288.83456 -356.957985) (xy 288.782057 -356.942496)
			(xy 288.73231 -356.919654) (xy 288.686343 -356.889928) (xy 288.665412 -356.872286) (xy 288.6583 -356.86619)
			(xy 288.641282 -356.85984) (xy 288.555938 -356.85984) (xy 288.53892 -356.86619) (xy 288.531808 -356.872286)
			(xy 288.510875 -356.889927) (xy 288.464907 -356.919651) (xy 288.415161 -356.942497) (xy 288.362659 -356.957993)
			(xy 288.308481 -356.965822) (xy 288.253739 -356.965822) (xy 288.199561 -356.957993) (xy 288.147059 -356.942497)
			(xy 288.097313 -356.919651) (xy 288.051345 -356.889927) (xy 288.030412 -356.872286) (xy 288.0233 -356.86619)
			(xy 288.006282 -356.85984) (xy 287.920938 -356.85984) (xy 287.90392 -356.86619) (xy 287.896808 -356.872286)
			(xy 287.875875 -356.889927) (xy 287.829907 -356.919651) (xy 287.780161 -356.942497) (xy 287.727659 -356.957993)
			(xy 287.673481 -356.965822) (xy 287.618739 -356.965822) (xy 287.564561 -356.957993) (xy 287.512059 -356.942497)
			(xy 287.462313 -356.919651) (xy 287.416345 -356.889927) (xy 287.395412 -356.872286) (xy 287.3883 -356.86619)
			(xy 287.371282 -356.85984) (xy 287.285938 -356.85984) (xy 287.26892 -356.86619) (xy 287.261808 -356.872286)
			(xy 287.240875 -356.889927) (xy 287.194907 -356.919651) (xy 287.145161 -356.942497) (xy 287.092659 -356.957993)
			(xy 287.038481 -356.965822) (xy 286.983739 -356.965822) (xy 286.929561 -356.957993) (xy 286.877059 -356.942497)
			(xy 286.827313 -356.919651) (xy 286.781345 -356.889927) (xy 286.760412 -356.872286) (xy 286.7533 -356.86619)
			(xy 286.736282 -356.85984) (xy 286.650938 -356.85984) (xy 286.63392 -356.86619) (xy 286.626808 -356.872286)
			(xy 286.605882 -356.889933) (xy 286.559908 -356.919644) (xy 286.510159 -356.942479) (xy 286.457657 -356.957968)
			(xy 286.40348 -356.965793) (xy 286.37611 -356.966266) (xy 286.348855 -356.965835) (xy 286.294901 -356.958079)
			(xy 286.2426 -356.942722) (xy 286.193017 -356.920077) (xy 286.147162 -356.890606) (xy 286.105968 -356.854909)
			(xy 286.070274 -356.813712) (xy 286.040807 -356.767855) (xy 286.018167 -356.71827) (xy 286.002815 -356.665967)
			(xy 285.995062 -356.612013) (xy 285.994602 -356.584758) (xy 285.995102 -356.557389) (xy 286.002911 -356.503211)
			(xy 286.018392 -356.450709) (xy 286.041227 -356.400961) (xy 286.070944 -356.354993) (xy 286.088582 -356.33406)
			(xy 286.094678 -356.326948) (xy 286.101028 -356.30993) (xy 286.101028 -356.224586) (xy 286.094678 -356.207568)
			(xy 286.088582 -356.200456) (xy 286.070953 -356.179516) (xy 286.04124 -356.133545) (xy 286.018403 -356.0838)
			(xy 286.002909 -356.031301) (xy 285.995078 -355.977127) (xy 285.994602 -355.949758) (xy 285.995146 -355.921055)
			(xy 286.003739 -355.864297) (xy 286.020739 -355.809467) (xy 286.045764 -355.757803) (xy 286.078246 -355.710473)
			(xy 286.097472 -355.689154) (xy 286.10433 -355.681788) (xy 286.111442 -355.663754) (xy 286.109918 -355.573076)
			(xy 286.102552 -355.555296) (xy 286.09544 -355.548184) (xy 286.074796 -355.526587) (xy 286.03978 -355.478185)
			(xy 286.01274 -355.424914) (xy 285.994337 -355.368078) (xy 285.985022 -355.309068) (xy 285.984442 -355.279198)
			(xy 268.221206 -355.279198) (xy 269.939008 -356.997) (xy 302.986946 -356.997) (xy 302.991017 -356.941378)
			(xy 303.003143 -356.886941) (xy 303.023066 -356.83485) (xy 303.050362 -356.786215) (xy 303.084448 -356.742072)
			(xy 303.124597 -356.703363) (xy 303.169955 -356.670912) (xy 303.219555 -356.645411) (xy 303.272339 -356.627404)
			(xy 303.327182 -356.617274) (xy 303.382916 -356.615237) (xy 303.438353 -356.621337) (xy 303.49231 -356.635443)
			(xy 303.543639 -356.657255) (xy 303.591245 -356.686309) (xy 303.634113 -356.721984) (xy 303.67133 -356.763521)
			(xy 303.702103 -356.810034) (xy 303.725775 -356.860531) (xy 303.741843 -356.913938) (xy 303.749963 -356.969114)
			(xy 303.750472 -356.997) (xy 303.749963 -357.024886) (xy 303.741843 -357.080062) (xy 303.725775 -357.133469)
			(xy 303.702103 -357.183966) (xy 303.67133 -357.230479) (xy 303.634113 -357.272016) (xy 303.591245 -357.307691)
			(xy 303.543639 -357.336745) (xy 303.49231 -357.358557) (xy 303.438353 -357.372663) (xy 303.382916 -357.378763)
			(xy 303.327182 -357.376726) (xy 303.272339 -357.366596) (xy 303.219555 -357.348589) (xy 303.169955 -357.323088)
			(xy 303.124597 -357.290637) (xy 303.084448 -357.251928) (xy 303.050362 -357.207785) (xy 303.023066 -357.15915)
			(xy 303.003143 -357.107059) (xy 302.991017 -357.052622) (xy 302.986946 -356.997) (xy 269.939008 -356.997)
			(xy 270.43507 -357.493062) (xy 305.065174 -357.493062) (xy 305.069245 -357.43744) (xy 305.081371 -357.383003)
			(xy 305.101294 -357.330912) (xy 305.12859 -357.282277) (xy 305.162676 -357.238134) (xy 305.202825 -357.199425)
			(xy 305.248183 -357.166974) (xy 305.297783 -357.141473) (xy 305.350567 -357.123466) (xy 305.40541 -357.113336)
			(xy 305.461144 -357.111299) (xy 305.516581 -357.117399) (xy 305.570538 -357.131505) (xy 305.621867 -357.153317)
			(xy 305.669473 -357.182371) (xy 305.712341 -357.218046) (xy 305.749558 -357.259583) (xy 305.780331 -357.306096)
			(xy 305.804003 -357.356593) (xy 305.820071 -357.41) (xy 305.828191 -357.465176) (xy 305.8287 -357.493062)
			(xy 305.828191 -357.520948) (xy 305.820071 -357.576124) (xy 305.804003 -357.629531) (xy 305.780331 -357.680028)
			(xy 305.749558 -357.726541) (xy 305.712341 -357.768078) (xy 305.669473 -357.803753) (xy 305.621867 -357.832807)
			(xy 305.570538 -357.854619) (xy 305.516581 -357.868725) (xy 305.461144 -357.874825) (xy 305.40541 -357.872788)
			(xy 305.350567 -357.862658) (xy 305.297783 -357.844651) (xy 305.248183 -357.81915) (xy 305.202825 -357.786699)
			(xy 305.162676 -357.74799) (xy 305.12859 -357.703847) (xy 305.101294 -357.655212) (xy 305.081371 -357.603121)
			(xy 305.069245 -357.548684) (xy 305.065174 -357.493062) (xy 270.43507 -357.493062) (xy 271.738852 -358.796844)
			(xy 271.746251 -358.803688) (xy 271.764849 -358.811413) (xy 271.77492 -358.81183) (xy 275.069046 -358.81183)
			(xy 275.073333 -358.812014) (xy 295.410886 -358.812014) (xy 295.410886 -358.727318) (xy 295.418937 -358.643004)
			(xy 295.434966 -358.559838) (xy 295.458827 -358.478571) (xy 295.490306 -358.399941) (xy 295.529117 -358.32466)
			(xy 295.574907 -358.253408) (xy 295.627263 -358.186832) (xy 295.685711 -358.125534) (xy 295.749721 -358.070069)
			(xy 295.818713 -358.02094) (xy 295.892063 -357.978591) (xy 295.969106 -357.943407) (xy 296.049145 -357.915705)
			(xy 296.131454 -357.895737) (xy 296.215289 -357.883684) (xy 296.29989 -357.879654) (xy 296.384491 -357.883684)
			(xy 296.468326 -357.895737) (xy 296.550635 -357.915705) (xy 296.630674 -357.943407) (xy 296.707717 -357.978591)
			(xy 296.781067 -358.02094) (xy 296.850059 -358.070069) (xy 296.914069 -358.125534) (xy 296.927862 -358.14)
			(xy 302.875948 -358.14) (xy 302.880019 -358.084378) (xy 302.892145 -358.029941) (xy 302.912068 -357.97785)
			(xy 302.939364 -357.929215) (xy 302.97345 -357.885072) (xy 303.013599 -357.846363) (xy 303.058957 -357.813912)
			(xy 303.108557 -357.788411) (xy 303.161341 -357.770404) (xy 303.216184 -357.760274) (xy 303.271918 -357.758237)
			(xy 303.327355 -357.764337) (xy 303.381312 -357.778443) (xy 303.432641 -357.800255) (xy 303.480247 -357.829309)
			(xy 303.523115 -357.864984) (xy 303.560332 -357.906521) (xy 303.591105 -357.953034) (xy 303.614777 -358.003531)
			(xy 303.630845 -358.056938) (xy 303.638965 -358.112114) (xy 303.639474 -358.14) (xy 303.638965 -358.167886)
			(xy 303.630845 -358.223062) (xy 303.614777 -358.276469) (xy 303.591105 -358.326966) (xy 303.560332 -358.373479)
			(xy 303.523115 -358.415016) (xy 303.480247 -358.450691) (xy 303.432641 -358.479745) (xy 303.381312 -358.501557)
			(xy 303.327355 -358.515663) (xy 303.271918 -358.521763) (xy 303.216184 -358.519726) (xy 303.161341 -358.509596)
			(xy 303.108557 -358.491589) (xy 303.058957 -358.466088) (xy 303.013599 -358.433637) (xy 302.97345 -358.394928)
			(xy 302.939364 -358.350785) (xy 302.912068 -358.30215) (xy 302.892145 -358.250059) (xy 302.880019 -358.195622)
			(xy 302.875948 -358.14) (xy 296.927862 -358.14) (xy 296.972517 -358.186832) (xy 297.024873 -358.253408)
			(xy 297.070663 -358.32466) (xy 297.109474 -358.399941) (xy 297.140953 -358.478571) (xy 297.164814 -358.559838)
			(xy 297.180843 -358.643004) (xy 297.188894 -358.727318) (xy 297.189398 -358.769666) (xy 297.188894 -358.812014)
			(xy 297.180843 -358.896328) (xy 297.164814 -358.979494) (xy 297.140953 -359.060761) (xy 297.109474 -359.139391)
			(xy 297.070663 -359.214672) (xy 297.024873 -359.285924) (xy 296.972517 -359.3525) (xy 296.914069 -359.413798)
			(xy 296.850059 -359.469263) (xy 296.781067 -359.518392) (xy 296.707717 -359.560741) (xy 296.630674 -359.595925)
			(xy 296.550635 -359.623627) (xy 296.468326 -359.643595) (xy 296.384491 -359.655648) (xy 296.29989 -359.659679)
			(xy 296.215289 -359.655648) (xy 296.131454 -359.643595) (xy 296.049145 -359.623627) (xy 295.969106 -359.595925)
			(xy 295.892063 -359.560741) (xy 295.818713 -359.518392) (xy 295.749721 -359.469263) (xy 295.685711 -359.413798)
			(xy 295.627263 -359.3525) (xy 295.574907 -359.285924) (xy 295.529117 -359.214672) (xy 295.490306 -359.139391)
			(xy 295.458827 -359.060761) (xy 295.434966 -358.979494) (xy 295.418937 -358.896328) (xy 295.410886 -358.812014)
			(xy 275.073333 -358.812014) (xy 275.079112 -358.812262) (xy 275.097701 -358.819992) (xy 275.105114 -358.826816)
			(xy 276.507194 -360.228896) (xy 276.514592 -360.235744) (xy 276.53319 -360.243481) (xy 276.543262 -360.243882)
			(xy 281.976322 -360.243882) (xy 281.986391 -360.244309) (xy 282.004991 -360.252027) (xy 282.01239 -360.258868)
			(xy 283.24683 -361.493308) (xy 283.253683 -361.500704) (xy 283.261425 -361.519302) (xy 283.261816 -361.529376)
			(xy 283.261816 -361.565952) (xy 285.209742 -361.565952) (xy 285.21011 -361.538696) (xy 285.217875 -361.484739)
			(xy 285.23324 -361.432436) (xy 285.255892 -361.382852) (xy 285.285369 -361.336997) (xy 285.321073 -361.295803)
			(xy 285.362276 -361.26011) (xy 285.408138 -361.230645) (xy 285.457728 -361.208006) (xy 285.510035 -361.192654)
			(xy 285.563994 -361.184903) (xy 285.59125 -361.184444) (xy 285.61862 -361.184929) (xy 285.672798 -361.19274)
			(xy 285.725302 -361.208224) (xy 285.775049 -361.231062) (xy 285.821016 -361.260784) (xy 285.841948 -361.278424)
			(xy 285.84906 -361.28452) (xy 285.866078 -361.29087) (xy 285.951422 -361.29087) (xy 285.96844 -361.28452)
			(xy 285.975552 -361.278424) (xy 285.996494 -361.260798) (xy 286.042464 -361.231083) (xy 286.092209 -361.208244)
			(xy 286.144707 -361.19275) (xy 286.198881 -361.184919) (xy 286.22625 -361.184444) (xy 286.252898 -361.184913)
			(xy 286.305674 -361.192349) (xy 286.356902 -361.207056) (xy 286.405586 -361.228747) (xy 286.450777 -361.257001)
			(xy 286.491599 -361.291268) (xy 286.527255 -361.330882) (xy 286.557053 -361.375071) (xy 286.56915 -361.39882)
			(xy 286.57423 -361.409234) (xy 286.592264 -361.423458) (xy 286.692594 -361.446064) (xy 286.714946 -361.44073)
			(xy 286.72409 -361.433618) (xy 286.744487 -361.417796) (xy 286.788733 -361.391204) (xy 286.836157 -361.370812)
			(xy 286.885894 -361.356991) (xy 286.937039 -361.349993) (xy 286.96285 -361.349544) (xy 286.99022 -361.350029)
			(xy 287.044398 -361.35784) (xy 287.096902 -361.373324) (xy 287.146649 -361.396162) (xy 287.192616 -361.425884)
			(xy 287.213548 -361.443524) (xy 287.22066 -361.44962) (xy 287.237678 -361.45597) (xy 287.323022 -361.45597)
			(xy 287.34004 -361.44962) (xy 287.347152 -361.443524) (xy 287.368085 -361.425883) (xy 287.414053 -361.396159)
			(xy 287.463799 -361.373313) (xy 287.516301 -361.357817) (xy 287.570479 -361.349988) (xy 287.625221 -361.349988)
			(xy 287.679399 -361.357817) (xy 287.731901 -361.373313) (xy 287.781647 -361.396159) (xy 287.827615 -361.425883)
			(xy 287.848548 -361.443524) (xy 287.85566 -361.44962) (xy 287.872678 -361.45597) (xy 287.958022 -361.45597)
			(xy 287.97504 -361.44962) (xy 287.982152 -361.443524) (xy 288.003085 -361.425883) (xy 288.049053 -361.396159)
			(xy 288.098799 -361.373313) (xy 288.151301 -361.357817) (xy 288.205479 -361.349988) (xy 288.260221 -361.349988)
			(xy 288.314399 -361.357817) (xy 288.366901 -361.373313) (xy 288.416647 -361.396159) (xy 288.462615 -361.425883)
			(xy 288.483548 -361.443524) (xy 288.49066 -361.44962) (xy 288.507678 -361.45597) (xy 288.593022 -361.45597)
			(xy 288.61004 -361.44962) (xy 288.617152 -361.443524) (xy 288.638094 -361.425898) (xy 288.684064 -361.396183)
			(xy 288.733809 -361.373344) (xy 288.786307 -361.35785) (xy 288.840481 -361.350019) (xy 288.86785 -361.349544)
			(xy 288.893663 -361.35) (xy 288.944816 -361.356964) (xy 288.994561 -361.370771) (xy 289.041985 -361.391168)
			(xy 289.086222 -361.417781) (xy 289.10661 -361.433618) (xy 289.115754 -361.44073) (xy 289.138106 -361.446064)
			(xy 289.238436 -361.423458) (xy 289.25647 -361.409234) (xy 289.26155 -361.39882) (xy 289.273615 -361.375051)
			(xy 289.303402 -361.330844) (xy 289.339054 -361.291217) (xy 289.379878 -361.256941) (xy 289.425077 -361.228684)
			(xy 289.473771 -361.206996) (xy 289.525011 -361.192301) (xy 289.577797 -361.184885) (xy 289.60445 -361.184444)
			(xy 289.63182 -361.184929) (xy 289.685998 -361.19274) (xy 289.738502 -361.208224) (xy 289.788249 -361.231062)
			(xy 289.834216 -361.260784) (xy 289.855148 -361.278424) (xy 289.86226 -361.28452) (xy 289.879278 -361.29087)
			(xy 289.964622 -361.29087) (xy 289.98164 -361.28452) (xy 289.988752 -361.278424) (xy 290.009694 -361.260798)
			(xy 290.055664 -361.231083) (xy 290.105409 -361.208244) (xy 290.157907 -361.19275) (xy 290.212081 -361.184919)
			(xy 290.23945 -361.184444) (xy 290.265295 -361.184875) (xy 290.316511 -361.19186) (xy 290.366315 -361.205696)
			(xy 290.413795 -361.226128) (xy 290.458082 -361.252783) (xy 290.498365 -361.285173) (xy 290.533907 -361.322705)
			(xy 290.54933 -361.343448) (xy 290.556442 -361.353354) (xy 290.57727 -361.364276) (xy 290.682934 -361.366816)
			(xy 290.70427 -361.356656) (xy 290.71189 -361.347004) (xy 290.73011 -361.324759) (xy 290.772036 -361.285413)
			(xy 290.819395 -361.25281) (xy 290.871113 -361.227688) (xy 290.926017 -361.210617) (xy 290.982862 -361.201984)
			(xy 291.01161 -361.201462) (xy 291.03886 -361.201968) (xy 291.092806 -361.209725) (xy 291.145098 -361.22508)
			(xy 291.194673 -361.24772) (xy 291.240522 -361.277185) (xy 291.28086 -361.312136) (xy 295.410886 -361.312136)
			(xy 295.410886 -361.22744) (xy 295.418937 -361.143126) (xy 295.434966 -361.05996) (xy 295.458827 -360.978693)
			(xy 295.490306 -360.900063) (xy 295.529117 -360.824782) (xy 295.574907 -360.75353) (xy 295.627263 -360.686954)
			(xy 295.685711 -360.625656) (xy 295.749721 -360.570191) (xy 295.818713 -360.521062) (xy 295.892063 -360.478713)
			(xy 295.969106 -360.443529) (xy 296.049145 -360.415827) (xy 296.131454 -360.395859) (xy 296.215289 -360.383806)
			(xy 296.29989 -360.379776) (xy 296.384491 -360.383806) (xy 296.468326 -360.395859) (xy 296.550635 -360.415827)
			(xy 296.630674 -360.443529) (xy 296.707717 -360.478713) (xy 296.781067 -360.521062) (xy 296.850059 -360.570191)
			(xy 296.914069 -360.625656) (xy 296.972517 -360.686954) (xy 297.024873 -360.75353) (xy 297.070663 -360.824782)
			(xy 297.109474 -360.900063) (xy 297.140953 -360.978693) (xy 297.164814 -361.05996) (xy 297.180843 -361.143126)
			(xy 297.188894 -361.22744) (xy 297.189398 -361.269788) (xy 297.188894 -361.312136) (xy 297.180843 -361.39645)
			(xy 297.164814 -361.479616) (xy 297.140953 -361.560883) (xy 297.109474 -361.639513) (xy 297.070663 -361.714794)
			(xy 297.024873 -361.786046) (xy 296.972517 -361.852622) (xy 296.914069 -361.91392) (xy 296.850059 -361.969385)
			(xy 296.781067 -362.018514) (xy 296.707717 -362.060863) (xy 296.630674 -362.096047) (xy 296.550635 -362.123749)
			(xy 296.468326 -362.143717) (xy 296.384491 -362.15577) (xy 296.29989 -362.159801) (xy 296.215289 -362.15577)
			(xy 296.131454 -362.143717) (xy 296.049145 -362.123749) (xy 295.969106 -362.096047) (xy 295.892063 -362.060863)
			(xy 295.818713 -362.018514) (xy 295.749721 -361.969385) (xy 295.685711 -361.91392) (xy 295.627263 -361.852622)
			(xy 295.574907 -361.786046) (xy 295.529117 -361.714794) (xy 295.490306 -361.639513) (xy 295.458827 -361.560883)
			(xy 295.434966 -361.479616) (xy 295.418937 -361.39645) (xy 295.410886 -361.312136) (xy 291.28086 -361.312136)
			(xy 291.281712 -361.312874) (xy 291.317403 -361.354062) (xy 291.34687 -361.399909) (xy 291.369513 -361.449483)
			(xy 291.38487 -361.501775) (xy 291.39263 -361.55572) (xy 291.393118 -361.58297) (xy 291.3926 -361.612245)
			(xy 291.383625 -361.670104) (xy 291.365911 -361.725911) (xy 291.339876 -361.778355) (xy 291.306131 -361.826203)
			(xy 291.286184 -361.847638) (xy 291.279072 -361.855004) (xy 291.27196 -361.873546) (xy 291.27323 -361.965494)
			(xy 291.281104 -361.983782) (xy 291.28847 -361.990894) (xy 291.30629 -362.008912) (xy 291.33752 -362.048822)
			(xy 291.36319 -362.092515) (xy 291.38285 -362.139223) (xy 291.396152 -362.188122) (xy 291.402863 -362.238352)
			(xy 291.403278 -362.26369) (xy 291.402811 -362.29106) (xy 291.394995 -362.34524) (xy 291.379506 -362.397743)
			(xy 291.356664 -362.44749) (xy 291.326939 -362.493456) (xy 291.309298 -362.514388) (xy 291.303202 -362.5215)
			(xy 291.296852 -362.538518) (xy 291.296852 -362.623862) (xy 291.303202 -362.64088) (xy 291.309298 -362.647992)
			(xy 291.326928 -362.668933) (xy 291.356651 -362.7149) (xy 291.379496 -362.764645) (xy 291.394992 -362.817146)
			(xy 291.402821 -362.871323) (xy 291.402822 -362.926062) (xy 291.394995 -362.98024) (xy 291.379501 -363.032741)
			(xy 291.356658 -363.082487) (xy 291.326937 -363.128455) (xy 291.309298 -363.149388) (xy 291.303202 -363.1565)
			(xy 291.296852 -363.173518) (xy 291.296852 -363.258862) (xy 291.303202 -363.27588) (xy 291.309298 -363.282992)
			(xy 291.326928 -363.303933) (xy 291.356651 -363.3499) (xy 291.379496 -363.399645) (xy 291.394992 -363.452146)
			(xy 291.402821 -363.506323) (xy 291.402822 -363.561062) (xy 291.394995 -363.61524) (xy 291.379501 -363.667741)
			(xy 291.356658 -363.717487) (xy 291.326937 -363.763455) (xy 291.309298 -363.784388) (xy 291.303202 -363.7915)
			(xy 291.296852 -363.808518) (xy 291.296852 -363.893862) (xy 291.303202 -363.91088) (xy 291.309298 -363.917992)
			(xy 291.326946 -363.938917) (xy 291.356657 -363.984891) (xy 291.379491 -364.034641) (xy 291.39498 -364.087143)
			(xy 291.402805 -364.14132) (xy 291.403278 -364.16869) (xy 291.402835 -364.195944) (xy 291.395079 -364.249897)
			(xy 291.379723 -364.302197) (xy 291.357079 -364.351779) (xy 291.327609 -364.397634) (xy 291.291913 -364.438828)
			(xy 291.250718 -364.474521) (xy 291.204862 -364.503989) (xy 291.155278 -364.52663) (xy 291.102978 -364.541983)
			(xy 291.049024 -364.549737) (xy 291.02177 -364.550198) (xy 290.995926 -364.549734) (xy 290.944713 -364.542753)
			(xy 290.89491 -364.528922) (xy 290.847431 -364.508494) (xy 290.803143 -364.481845) (xy 290.762859 -364.44946)
			(xy 290.727315 -364.411934) (xy 290.71189 -364.391194) (xy 290.704778 -364.381288) (xy 290.68395 -364.370366)
			(xy 290.578286 -364.367826) (xy 290.55695 -364.377986) (xy 290.54933 -364.387638) (xy 290.531166 -364.40993)
			(xy 290.489227 -364.449271) (xy 290.441856 -364.481868) (xy 290.390127 -364.506981) (xy 290.335214 -364.524042)
			(xy 290.278361 -364.532664) (xy 290.24961 -364.53318) (xy 290.22224 -364.532713) (xy 290.168061 -364.524896)
			(xy 290.115557 -364.509408) (xy 290.06581 -364.486566) (xy 290.019844 -364.456841) (xy 289.998912 -364.4392)
			(xy 289.9918 -364.433104) (xy 289.974782 -364.426754) (xy 289.889438 -364.426754) (xy 289.87242 -364.433104)
			(xy 289.865308 -364.4392) (xy 289.844384 -364.456849) (xy 289.798409 -364.486559) (xy 289.748659 -364.509393)
			(xy 289.696157 -364.524882) (xy 289.64198 -364.532707) (xy 289.61461 -364.53318) (xy 289.587035 -364.532714)
			(xy 289.532462 -364.524763) (xy 289.479602 -364.509038) (xy 289.429556 -364.485868) (xy 289.383366 -364.455735)
			(xy 289.341996 -364.419267) (xy 289.32378 -364.39856) (xy 289.316188 -364.390431) (xy 289.296028 -364.381084)
			(xy 289.284918 -364.380526) (xy 289.207702 -364.380526) (xy 289.196589 -364.381071) (xy 289.17643 -364.390425)
			(xy 289.16884 -364.39856) (xy 289.150602 -364.419247) (xy 289.10924 -364.455721) (xy 289.063056 -364.485857)
			(xy 289.013013 -364.509027) (xy 288.960155 -364.524748) (xy 288.905583 -364.532693) (xy 288.87801 -364.53318)
			(xy 288.85064 -364.532713) (xy 288.796461 -364.524896) (xy 288.743957 -364.509408) (xy 288.69421 -364.486566)
			(xy 288.648244 -364.456841) (xy 288.627312 -364.4392) (xy 288.6202 -364.433104) (xy 288.603182 -364.426754)
			(xy 288.517838 -364.426754) (xy 288.50082 -364.433104) (xy 288.493708 -364.4392) (xy 288.472775 -364.456841)
			(xy 288.426807 -364.486565) (xy 288.377061 -364.509411) (xy 288.324559 -364.524907) (xy 288.270381 -364.532736)
			(xy 288.215639 -364.532736) (xy 288.161461 -364.524907) (xy 288.108959 -364.509411) (xy 288.059213 -364.486565)
			(xy 288.013245 -364.456841) (xy 287.992312 -364.4392) (xy 287.9852 -364.433104) (xy 287.968182 -364.426754)
			(xy 287.882838 -364.426754) (xy 287.86582 -364.433104) (xy 287.858708 -364.4392) (xy 287.837775 -364.456841)
			(xy 287.791807 -364.486565) (xy 287.742061 -364.509411) (xy 287.689559 -364.524907) (xy 287.635381 -364.532736)
			(xy 287.580639 -364.532736) (xy 287.526461 -364.524907) (xy 287.473959 -364.509411) (xy 287.424213 -364.486565)
			(xy 287.378245 -364.456841) (xy 287.357312 -364.4392) (xy 287.3502 -364.433104) (xy 287.333182 -364.426754)
			(xy 287.247838 -364.426754) (xy 287.23082 -364.433104) (xy 287.223708 -364.4392) (xy 287.202784 -364.456849)
			(xy 287.156809 -364.486559) (xy 287.107059 -364.509393) (xy 287.054557 -364.524882) (xy 287.00038 -364.532707)
			(xy 286.97301 -364.53318) (xy 286.945435 -364.532714) (xy 286.890862 -364.524763) (xy 286.838002 -364.509038)
			(xy 286.787956 -364.485868) (xy 286.741766 -364.455735) (xy 286.700396 -364.419267) (xy 286.68218 -364.39856)
			(xy 286.674588 -364.390431) (xy 286.654428 -364.381084) (xy 286.643318 -364.380526) (xy 286.566102 -364.380526)
			(xy 286.554989 -364.381071) (xy 286.53483 -364.390425) (xy 286.52724 -364.39856) (xy 286.509002 -364.419247)
			(xy 286.46764 -364.455721) (xy 286.421456 -364.485857) (xy 286.371413 -364.509027) (xy 286.318555 -364.524748)
			(xy 286.263983 -364.532693) (xy 286.23641 -364.53318) (xy 286.20904 -364.532713) (xy 286.154861 -364.524896)
			(xy 286.102357 -364.509408) (xy 286.05261 -364.486566) (xy 286.006644 -364.456841) (xy 285.985712 -364.4392)
			(xy 285.9786 -364.433104) (xy 285.961582 -364.426754) (xy 285.876238 -364.426754) (xy 285.85922 -364.433104)
			(xy 285.852108 -364.4392) (xy 285.831184 -364.456849) (xy 285.785209 -364.486559) (xy 285.735459 -364.509393)
			(xy 285.682957 -364.524882) (xy 285.62878 -364.532707) (xy 285.60141 -364.53318) (xy 285.574156 -364.532735)
			(xy 285.520203 -364.524979) (xy 285.467903 -364.509623) (xy 285.418321 -364.486979) (xy 285.372467 -364.45751)
			(xy 285.331273 -364.421814) (xy 285.295579 -364.380619) (xy 285.266112 -364.334763) (xy 285.243471 -364.28518)
			(xy 285.228117 -364.232879) (xy 285.220363 -364.178926) (xy 285.219902 -364.151672) (xy 285.220351 -364.124301)
			(xy 285.228173 -364.070121) (xy 285.243666 -364.017618) (xy 285.266511 -363.967871) (xy 285.296239 -363.921905)
			(xy 285.313882 -363.900974) (xy 285.319978 -363.893862) (xy 285.326328 -363.876844) (xy 285.326328 -363.7915)
			(xy 285.319978 -363.774482) (xy 285.313882 -363.76737) (xy 285.296216 -363.746459) (xy 285.266496 -363.700486)
			(xy 285.243655 -363.650736) (xy 285.228162 -363.598231) (xy 285.220337 -363.54405) (xy 285.22034 -363.489308)
			(xy 285.228171 -363.435128) (xy 285.243669 -363.382625) (xy 285.266516 -363.332877) (xy 285.296241 -363.286908)
			(xy 285.313882 -363.265974) (xy 285.319978 -363.258862) (xy 285.326328 -363.241844) (xy 285.326328 -363.1565)
			(xy 285.319978 -363.139482) (xy 285.313882 -363.13237) (xy 285.296216 -363.111459) (xy 285.266496 -363.065486)
			(xy 285.243655 -363.015736) (xy 285.228162 -362.963231) (xy 285.220337 -362.90905) (xy 285.22034 -362.854308)
			(xy 285.228171 -362.800128) (xy 285.243669 -362.747625) (xy 285.266516 -362.697877) (xy 285.296241 -362.651908)
			(xy 285.313882 -362.630974) (xy 285.319978 -362.623862) (xy 285.326328 -362.606844) (xy 285.326328 -362.5215)
			(xy 285.319978 -362.504482) (xy 285.313882 -362.49737) (xy 285.296259 -362.476425) (xy 285.266546 -362.430455)
			(xy 285.243707 -362.380711) (xy 285.228212 -362.328213) (xy 285.220379 -362.27404) (xy 285.219902 -362.246672)
			(xy 285.22044 -362.217398) (xy 285.22941 -362.159539) (xy 285.247118 -362.103732) (xy 285.273149 -362.051288)
			(xy 285.306891 -362.003439) (xy 285.326836 -361.982004) (xy 285.333948 -361.974638) (xy 285.34106 -361.956096)
			(xy 285.33979 -361.864148) (xy 285.331916 -361.84586) (xy 285.32455 -361.838748) (xy 285.306706 -361.820753)
			(xy 285.275478 -361.780839) (xy 285.24981 -361.73714) (xy 285.230155 -361.690428) (xy 285.216858 -361.641525)
			(xy 285.210153 -361.591291) (xy 285.209742 -361.565952) (xy 283.261816 -361.565952) (xy 283.261816 -365.151924)
			(xy 283.262244 -365.161992) (xy 283.269966 -365.180589) (xy 283.276802 -365.187992) (xy 283.457396 -365.368586)
			(xy 283.464794 -365.375434) (xy 283.483392 -365.383172) (xy 283.493464 -365.383572) (xy 299.433996 -365.383572)
			(xy 299.444016 -365.383153) (xy 299.462529 -365.375482) (xy 299.476696 -365.361309) (xy 299.484357 -365.342792)
			(xy 299.484796 -365.332772) (xy 299.484796 -364.414562) (xy 299.485289 -364.386588) (xy 299.493996 -364.331323)
			(xy 299.511252 -364.278104) (xy 299.53663 -364.228245) (xy 299.569504 -364.182976) (xy 299.588936 -364.162848)
			(xy 300.470062 -363.281722) (xy 300.476882 -363.274356) (xy 300.484613 -363.255847) (xy 300.48466 -363.235788)
			(xy 300.481238 -363.22635) (xy 300.475142 -363.211872) (xy 300.449742 -363.195108) (xy 300.238668 -363.195108)
			(xy 300.210693 -363.194535) (xy 300.155437 -363.18574) (xy 300.102234 -363.168419) (xy 300.052391 -363.142997)
			(xy 300.007133 -363.110099) (xy 299.986954 -363.090714) (xy 299.171868 -362.275628) (xy 299.152497 -362.255451)
			(xy 299.119652 -362.210178) (xy 299.094288 -362.160328) (xy 299.077029 -362.107126) (xy 299.068299 -362.05188)
			(xy 299.067728 -362.023914) (xy 299.067728 -360.491278) (xy 299.068228 -360.463307) (xy 299.076947 -360.40805)
			(xy 299.094213 -360.35484) (xy 299.119601 -360.304992) (xy 299.152482 -360.259735) (xy 299.171868 -360.239564)
			(xy 300.703742 -358.70769) (xy 300.723883 -358.68826) (xy 300.769138 -358.65534) (xy 300.818988 -358.629911)
			(xy 300.872205 -358.612599) (xy 300.927475 -358.603832) (xy 300.955456 -358.603296) (xy 302.095408 -358.603296)
			(xy 302.123384 -358.603867) (xy 302.178642 -358.612659) (xy 302.231847 -358.629977) (xy 302.281693 -358.655397)
			(xy 302.326953 -358.688294) (xy 302.347122 -358.70769) (xy 302.402748 -358.763316) (xy 305.14366 -358.763316)
			(xy 305.147731 -358.707694) (xy 305.159857 -358.653257) (xy 305.17978 -358.601166) (xy 305.207076 -358.552531)
			(xy 305.241162 -358.508388) (xy 305.281311 -358.469679) (xy 305.326669 -358.437228) (xy 305.376269 -358.411727)
			(xy 305.429053 -358.39372) (xy 305.483896 -358.38359) (xy 305.53963 -358.381553) (xy 305.595067 -358.387653)
			(xy 305.649024 -358.401759) (xy 305.700353 -358.423571) (xy 305.747959 -358.452625) (xy 305.790827 -358.4883)
			(xy 305.828044 -358.529837) (xy 305.858817 -358.57635) (xy 305.882489 -358.626847) (xy 305.898557 -358.680254)
			(xy 305.906677 -358.73543) (xy 305.907186 -358.763316) (xy 305.906677 -358.791202) (xy 305.898557 -358.846378)
			(xy 305.882489 -358.899785) (xy 305.858817 -358.950282) (xy 305.828044 -358.996795) (xy 305.790827 -359.038332)
			(xy 305.747959 -359.074007) (xy 305.700353 -359.103061) (xy 305.649024 -359.124873) (xy 305.595067 -359.138979)
			(xy 305.53963 -359.145079) (xy 305.483896 -359.143042) (xy 305.429053 -359.132912) (xy 305.376269 -359.114905)
			(xy 305.326669 -359.089404) (xy 305.281311 -359.056953) (xy 305.241162 -359.018244) (xy 305.207076 -358.974101)
			(xy 305.17978 -358.925466) (xy 305.159857 -358.873375) (xy 305.147731 -358.818938) (xy 305.14366 -358.763316)
			(xy 302.402748 -358.763316) (xy 302.551592 -358.91216) (xy 302.558999 -358.91885) (xy 302.577436 -358.926441)
			(xy 302.587406 -358.926892) (xy 303.138586 -358.926892) (xy 303.146968 -358.924098) (xy 303.178188 -358.913592)
			(xy 303.243067 -358.902228) (xy 303.276 -358.901492) (xy 303.303251 -358.901978) (xy 303.357199 -358.909734)
			(xy 303.409494 -358.925089) (xy 303.459071 -358.947731) (xy 303.504921 -358.977197) (xy 303.546112 -359.012888)
			(xy 303.581803 -359.054079) (xy 303.611269 -359.099929) (xy 303.633911 -359.149506) (xy 303.649266 -359.201801)
			(xy 303.657022 -359.255749) (xy 303.657022 -359.310251) (xy 303.649266 -359.364199) (xy 303.633911 -359.416494)
			(xy 303.611269 -359.466071) (xy 303.581803 -359.511921) (xy 303.546112 -359.553112) (xy 303.504921 -359.588803)
			(xy 303.459071 -359.618269) (xy 303.409494 -359.640911) (xy 303.357199 -359.656266) (xy 303.303251 -359.664022)
			(xy 303.276 -359.664508) (xy 303.243066 -359.663792) (xy 303.178186 -359.65242) (xy 303.146968 -359.641902)
			(xy 303.138586 -359.639108) (xy 302.419004 -359.639108) (xy 302.391028 -359.638538) (xy 302.335769 -359.629748)
			(xy 302.282562 -359.612431) (xy 302.232715 -359.587012) (xy 302.187453 -359.554116) (xy 302.16729 -359.534714)
			(xy 301.96282 -359.330244) (xy 301.955409 -359.323563) (xy 301.936973 -359.315982) (xy 301.927006 -359.315512)
			(xy 301.123858 -359.315512) (xy 301.113894 -359.315994) (xy 301.095465 -359.323577) (xy 301.088044 -359.330244)
			(xy 300.388528 -360.02976) (xy 305.24145 -360.02976) (xy 305.245521 -359.974138) (xy 305.257647 -359.919701)
			(xy 305.27757 -359.86761) (xy 305.304866 -359.818975) (xy 305.338952 -359.774832) (xy 305.379101 -359.736123)
			(xy 305.424459 -359.703672) (xy 305.474059 -359.678171) (xy 305.526843 -359.660164) (xy 305.581686 -359.650034)
			(xy 305.63742 -359.647997) (xy 305.692857 -359.654097) (xy 305.746814 -359.668203) (xy 305.798143 -359.690015)
			(xy 305.845749 -359.719069) (xy 305.888617 -359.754744) (xy 305.925834 -359.796281) (xy 305.956607 -359.842794)
			(xy 305.980279 -359.893291) (xy 305.996347 -359.946698) (xy 306.004467 -360.001874) (xy 306.004976 -360.02976)
			(xy 306.004467 -360.057646) (xy 305.996347 -360.112822) (xy 305.980279 -360.166229) (xy 305.956607 -360.216726)
			(xy 305.925834 -360.263239) (xy 305.888617 -360.304776) (xy 305.845749 -360.340451) (xy 305.798143 -360.369505)
			(xy 305.746814 -360.391317) (xy 305.692857 -360.405423) (xy 305.63742 -360.411523) (xy 305.581686 -360.409486)
			(xy 305.526843 -360.399356) (xy 305.474059 -360.381349) (xy 305.424459 -360.355848) (xy 305.379101 -360.323397)
			(xy 305.338952 -360.284688) (xy 305.304866 -360.240545) (xy 305.27757 -360.19191) (xy 305.257647 -360.139819)
			(xy 305.245521 -360.085382) (xy 305.24145 -360.02976) (xy 300.388528 -360.02976) (xy 299.794422 -360.623866)
			(xy 299.787619 -360.631214) (xy 299.779908 -360.649677) (xy 299.779436 -360.65968) (xy 299.779436 -361.443851)
			(xy 300.100978 -361.443851) (xy 300.100978 -361.389349) (xy 300.108734 -361.335401) (xy 300.124089 -361.283106)
			(xy 300.146731 -361.233529) (xy 300.176197 -361.187679) (xy 300.211888 -361.146488) (xy 300.253079 -361.110797)
			(xy 300.298929 -361.081331) (xy 300.348506 -361.058689) (xy 300.400801 -361.043334) (xy 300.454749 -361.035578)
			(xy 300.482 -361.035092) (xy 301.376842 -361.035092) (xy 301.386407 -361.034737) (xy 301.404233 -361.027799)
			(xy 301.418288 -361.014824) (xy 301.422816 -361.00639) (xy 301.468536 -360.910124) (xy 301.46498 -360.881168)
			(xy 301.455836 -360.869484) (xy 301.439783 -360.849016) (xy 301.412792 -360.804549) (xy 301.392088 -360.756828)
			(xy 301.378055 -360.706739) (xy 301.370952 -360.655209) (xy 301.370492 -360.6292) (xy 301.370978 -360.601949)
			(xy 301.378734 -360.548001) (xy 301.394089 -360.495706) (xy 301.416731 -360.446129) (xy 301.446197 -360.400279)
			(xy 301.481888 -360.359088) (xy 301.523079 -360.323397) (xy 301.568929 -360.293931) (xy 301.618506 -360.271289)
			(xy 301.670801 -360.255934) (xy 301.724749 -360.248178) (xy 301.779251 -360.248178) (xy 301.833199 -360.255934)
			(xy 301.885494 -360.271289) (xy 301.935071 -360.293931) (xy 301.980921 -360.323397) (xy 302.022112 -360.359088)
			(xy 302.057803 -360.400279) (xy 302.087269 -360.446129) (xy 302.109911 -360.495706) (xy 302.125266 -360.548001)
			(xy 302.133022 -360.601949) (xy 302.133508 -360.6292) (xy 302.133438 -360.640338) (xy 302.13217 -360.662577)
			(xy 302.130968 -360.67365) (xy 302.128936 -360.689906) (xy 302.14443 -360.718354) (xy 302.245522 -360.767122)
			(xy 302.255216 -360.771236) (xy 302.276234 -360.7721) (xy 302.29585 -360.764503) (xy 302.303688 -360.75747)
			(xy 302.422052 -360.638852) (xy 302.443661 -360.618062) (xy 302.492159 -360.582805) (xy 302.545577 -360.555572)
			(xy 302.602599 -360.537035) (xy 302.66182 -360.52765) (xy 302.6918 -360.527092) (xy 304.3428 -360.527092)
			(xy 304.372778 -360.527673) (xy 304.431994 -360.537064) (xy 304.489013 -360.555601) (xy 304.542431 -360.582826)
			(xy 304.590935 -360.61807) (xy 304.612548 -360.638852) (xy 304.764948 -360.791252) (xy 304.785738 -360.812861)
			(xy 304.820995 -360.861359) (xy 304.848228 -360.914777) (xy 304.866765 -360.971799) (xy 304.87615 -361.03102)
			(xy 304.876708 -361.061) (xy 304.876222 -361.088251) (xy 304.868466 -361.142199) (xy 304.853111 -361.194494)
			(xy 304.830469 -361.244071) (xy 304.801003 -361.289921) (xy 304.789837 -361.302808) (xy 305.2097 -361.302808)
			(xy 305.213771 -361.247186) (xy 305.225897 -361.192749) (xy 305.24582 -361.140658) (xy 305.273116 -361.092023)
			(xy 305.307202 -361.04788) (xy 305.347351 -361.009171) (xy 305.392709 -360.97672) (xy 305.442309 -360.951219)
			(xy 305.495093 -360.933212) (xy 305.549936 -360.923082) (xy 305.60567 -360.921045) (xy 305.661107 -360.927145)
			(xy 305.715064 -360.941251) (xy 305.766393 -360.963063) (xy 305.813999 -360.992117) (xy 305.856867 -361.027792)
			(xy 305.894084 -361.069329) (xy 305.924857 -361.115842) (xy 305.948529 -361.166339) (xy 305.964597 -361.219746)
			(xy 305.972717 -361.274922) (xy 305.973226 -361.302808) (xy 305.972717 -361.330694) (xy 305.964597 -361.38587)
			(xy 305.948529 -361.439277) (xy 305.924857 -361.489774) (xy 305.894084 -361.536287) (xy 305.856867 -361.577824)
			(xy 305.813999 -361.613499) (xy 305.766393 -361.642553) (xy 305.715064 -361.664365) (xy 305.661107 -361.678471)
			(xy 305.60567 -361.684571) (xy 305.549936 -361.682534) (xy 305.495093 -361.672404) (xy 305.442309 -361.654397)
			(xy 305.392709 -361.628896) (xy 305.347351 -361.596445) (xy 305.307202 -361.557736) (xy 305.273116 -361.513593)
			(xy 305.24582 -361.464958) (xy 305.225897 -361.412867) (xy 305.213771 -361.35843) (xy 305.2097 -361.302808)
			(xy 304.789837 -361.302808) (xy 304.765312 -361.331112) (xy 304.724121 -361.366803) (xy 304.678271 -361.396269)
			(xy 304.628694 -361.418911) (xy 304.576399 -361.434266) (xy 304.522451 -361.442022) (xy 304.4952 -361.442508)
			(xy 304.465222 -361.441927) (xy 304.406006 -361.432536) (xy 304.348987 -361.413999) (xy 304.295569 -361.386774)
			(xy 304.247065 -361.35153) (xy 304.225452 -361.330748) (xy 304.199798 -361.30484) (xy 304.19231 -361.298155)
			(xy 304.173756 -361.29056) (xy 304.16373 -361.290108) (xy 303.651158 -361.290108) (xy 303.641593 -361.290463)
			(xy 303.623767 -361.297401) (xy 303.609712 -361.310376) (xy 303.605184 -361.31881) (xy 303.559464 -361.415076)
			(xy 303.56302 -361.444032) (xy 303.572164 -361.455716) (xy 303.588217 -361.476184) (xy 303.615208 -361.520651)
			(xy 303.635912 -361.568372) (xy 303.649945 -361.618461) (xy 303.657048 -361.669991) (xy 303.657508 -361.696)
			(xy 303.657022 -361.723251) (xy 303.649266 -361.777199) (xy 303.633911 -361.829494) (xy 303.611269 -361.879071)
			(xy 303.581803 -361.924921) (xy 303.546112 -361.966112) (xy 303.504921 -362.001803) (xy 303.459071 -362.031269)
			(xy 303.409494 -362.053911) (xy 303.357199 -362.069266) (xy 303.303251 -362.077022) (xy 303.248749 -362.077022)
			(xy 303.194801 -362.069266) (xy 303.142506 -362.053911) (xy 303.092929 -362.031269) (xy 303.047079 -362.001803)
			(xy 303.005888 -361.966112) (xy 302.970197 -361.924921) (xy 302.940731 -361.879071) (xy 302.918089 -361.829494)
			(xy 302.902734 -361.777199) (xy 302.894978 -361.723251) (xy 302.894492 -361.696) (xy 302.894962 -361.669991)
			(xy 302.902048 -361.618457) (xy 302.916074 -361.568365) (xy 302.93678 -361.520645) (xy 302.963781 -361.476183)
			(xy 302.979836 -361.455716) (xy 302.98898 -361.444032) (xy 302.992536 -361.415076) (xy 302.946816 -361.31881)
			(xy 302.942272 -361.310384) (xy 302.928234 -361.297394) (xy 302.910407 -361.290464) (xy 302.900842 -361.290108)
			(xy 302.87087 -361.290108) (xy 302.860826 -361.290485) (xy 302.84223 -361.298069) (xy 302.834802 -361.30484)
			(xy 302.453548 -361.686348) (xy 302.426624 -361.710732) (xy 302.418541 -361.718118) (xy 302.409098 -361.737853)
			(xy 302.408702 -361.759728) (xy 302.417426 -361.779791) (xy 302.433693 -361.794421) (xy 302.454566 -361.800975)
			(xy 302.465486 -361.80014) (xy 302.477562 -361.798696) (xy 302.501838 -361.797169) (xy 302.514 -361.797092)
			(xy 302.541251 -361.797578) (xy 302.595199 -361.805334) (xy 302.647494 -361.820689) (xy 302.697071 -361.843331)
			(xy 302.742921 -361.872797) (xy 302.784112 -361.908488) (xy 302.819803 -361.949679) (xy 302.849269 -361.995529)
			(xy 302.871911 -362.045106) (xy 302.887266 -362.097401) (xy 302.895022 -362.151349) (xy 302.895022 -362.205851)
			(xy 302.887266 -362.259799) (xy 302.871911 -362.312094) (xy 302.849269 -362.361671) (xy 302.819803 -362.407521)
			(xy 302.784112 -362.448712) (xy 302.742921 -362.484403) (xy 302.697071 -362.513869) (xy 302.647494 -362.536511)
			(xy 302.595199 -362.551866) (xy 302.541251 -362.559622) (xy 302.486749 -362.559622) (xy 302.432801 -362.551866)
			(xy 302.380506 -362.536511) (xy 302.330929 -362.513869) (xy 302.285079 -362.484403) (xy 302.243888 -362.448712)
			(xy 302.208197 -362.407521) (xy 302.178731 -362.361671) (xy 302.156089 -362.312094) (xy 302.140734 -362.259799)
			(xy 302.132978 -362.205851) (xy 302.132492 -362.1786) (xy 302.132971 -362.150589) (xy 302.14117 -362.095171)
			(xy 302.157391 -362.041549) (xy 302.181285 -361.990879) (xy 302.212337 -361.944251) (xy 302.249879 -361.902669)
			(xy 302.271176 -361.884468) (xy 302.278163 -361.878133) (xy 302.287454 -361.861745) (xy 302.290195 -361.843108)
			(xy 302.286014 -361.82474) (xy 302.275477 -361.809124) (xy 302.260009 -361.798372) (xy 302.2417 -361.793938)
			(xy 302.232314 -361.794806) (xy 302.220241 -361.796309) (xy 302.195965 -361.797964) (xy 302.1838 -361.798108)
			(xy 300.482 -361.798108) (xy 300.454749 -361.797622) (xy 300.400801 -361.789866) (xy 300.348506 -361.774511)
			(xy 300.298929 -361.751869) (xy 300.253079 -361.722403) (xy 300.211888 -361.686712) (xy 300.176197 -361.645521)
			(xy 300.146731 -361.599671) (xy 300.124089 -361.550094) (xy 300.108734 -361.497799) (xy 300.100978 -361.443851)
			(xy 299.779436 -361.443851) (xy 299.779436 -361.855512) (xy 299.779977 -361.865498) (xy 299.787697 -361.883923)
			(xy 299.794422 -361.891326) (xy 300.371256 -362.46816) (xy 300.378661 -362.474855) (xy 300.397098 -362.48246)
			(xy 300.40707 -362.482892) (xy 300.827186 -362.482892) (xy 300.835568 -362.480098) (xy 300.866788 -362.469592)
			(xy 300.931667 -362.458228) (xy 300.9646 -362.457492) (xy 300.991851 -362.457978) (xy 301.045799 -362.465734)
			(xy 301.098094 -362.481089) (xy 301.147671 -362.503731) (xy 301.193521 -362.533197) (xy 301.226924 -362.56214)
			(xy 305.030376 -362.56214) (xy 305.034447 -362.506518) (xy 305.046573 -362.452081) (xy 305.066496 -362.39999)
			(xy 305.093792 -362.351355) (xy 305.127878 -362.307212) (xy 305.168027 -362.268503) (xy 305.213385 -362.236052)
			(xy 305.262985 -362.210551) (xy 305.315769 -362.192544) (xy 305.370612 -362.182414) (xy 305.426346 -362.180377)
			(xy 305.481783 -362.186477) (xy 305.53574 -362.200583) (xy 305.587069 -362.222395) (xy 305.634675 -362.251449)
			(xy 305.677543 -362.287124) (xy 305.71476 -362.328661) (xy 305.745533 -362.375174) (xy 305.769205 -362.425671)
			(xy 305.785273 -362.479078) (xy 305.793393 -362.534254) (xy 305.793902 -362.56214) (xy 305.793393 -362.590026)
			(xy 305.785273 -362.645202) (xy 305.769205 -362.698609) (xy 305.745533 -362.749106) (xy 305.71476 -362.795619)
			(xy 305.677543 -362.837156) (xy 305.634675 -362.872831) (xy 305.587069 -362.901885) (xy 305.53574 -362.923697)
			(xy 305.481783 -362.937803) (xy 305.426346 -362.943903) (xy 305.370612 -362.941866) (xy 305.315769 -362.931736)
			(xy 305.262985 -362.913729) (xy 305.213385 -362.888228) (xy 305.168027 -362.855777) (xy 305.127878 -362.817068)
			(xy 305.093792 -362.772925) (xy 305.066496 -362.72429) (xy 305.046573 -362.672199) (xy 305.034447 -362.617762)
			(xy 305.030376 -362.56214) (xy 301.226924 -362.56214) (xy 301.234712 -362.568888) (xy 301.270403 -362.610079)
			(xy 301.299869 -362.655929) (xy 301.322511 -362.705506) (xy 301.337866 -362.757801) (xy 301.345622 -362.811749)
			(xy 301.346108 -362.839) (xy 301.345392 -362.871934) (xy 301.33402 -362.936814) (xy 301.323502 -362.968032)
			(xy 301.320708 -362.976414) (xy 301.320708 -363.290612) (xy 301.320137 -363.318588) (xy 301.311345 -363.373846)
			(xy 301.294026 -363.427051) (xy 301.268606 -363.476896) (xy 301.235709 -363.522156) (xy 301.216314 -363.542326)
			(xy 300.911768 -363.846872) (xy 305.046632 -363.846872) (xy 305.050703 -363.79125) (xy 305.062829 -363.736813)
			(xy 305.082752 -363.684722) (xy 305.110048 -363.636087) (xy 305.144134 -363.591944) (xy 305.184283 -363.553235)
			(xy 305.229641 -363.520784) (xy 305.279241 -363.495283) (xy 305.332025 -363.477276) (xy 305.386868 -363.467146)
			(xy 305.442602 -363.465109) (xy 305.498039 -363.471209) (xy 305.551996 -363.485315) (xy 305.603325 -363.507127)
			(xy 305.650931 -363.536181) (xy 305.693799 -363.571856) (xy 305.731016 -363.613393) (xy 305.761789 -363.659906)
			(xy 305.785461 -363.710403) (xy 305.801529 -363.76381) (xy 305.809649 -363.818986) (xy 305.810158 -363.846872)
			(xy 305.809649 -363.874758) (xy 305.801529 -363.929934) (xy 305.785461 -363.983341) (xy 305.761789 -364.033838)
			(xy 305.731016 -364.080351) (xy 305.693799 -364.121888) (xy 305.650931 -364.157563) (xy 305.603325 -364.186617)
			(xy 305.551996 -364.208429) (xy 305.498039 -364.222535) (xy 305.442602 -364.228635) (xy 305.386868 -364.226598)
			(xy 305.332025 -364.216468) (xy 305.279241 -364.198461) (xy 305.229641 -364.17296) (xy 305.184283 -364.140509)
			(xy 305.144134 -364.1018) (xy 305.110048 -364.057657) (xy 305.082752 -364.009022) (xy 305.062829 -363.956931)
			(xy 305.050703 -363.902494) (xy 305.046632 -363.846872) (xy 300.911768 -363.846872) (xy 300.669706 -364.088934)
			(xy 300.662683 -364.096611) (xy 300.654932 -364.115899) (xy 300.655421 -364.136679) (xy 300.659292 -364.146338)
			(xy 300.706282 -364.24743) (xy 300.73346 -364.263432) (xy 300.749716 -364.262162) (xy 300.78045 -364.260892)
			(xy 300.807704 -364.261352) (xy 300.861657 -364.269102) (xy 300.913958 -364.284452) (xy 300.963542 -364.307089)
			(xy 301.0094 -364.336553) (xy 301.050598 -364.372243) (xy 301.086297 -364.413433) (xy 301.115771 -364.459284)
			(xy 301.138419 -364.508864) (xy 301.15378 -364.561161) (xy 301.161542 -364.615113) (xy 301.161547 -364.66962)
			(xy 301.153794 -364.723573) (xy 301.138442 -364.775874) (xy 301.115803 -364.825457) (xy 301.086337 -364.871314)
			(xy 301.050645 -364.91251) (xy 301.009454 -364.948207) (xy 300.963601 -364.977679) (xy 300.914021 -365.000325)
			(xy 300.861722 -365.015684) (xy 300.80777 -365.023443) (xy 300.753263 -365.023446) (xy 300.69931 -365.015691)
			(xy 300.64701 -365.000336) (xy 300.597428 -364.977695) (xy 300.551573 -364.948227) (xy 300.510378 -364.912533)
			(xy 300.474683 -364.87134) (xy 300.445213 -364.825486) (xy 300.42257 -364.775905) (xy 300.407213 -364.723606)
			(xy 300.399455 -364.669654) (xy 300.398942 -364.6424) (xy 300.400212 -364.611666) (xy 300.401482 -364.59541)
			(xy 300.38548 -364.568232) (xy 300.284388 -364.521242) (xy 300.274739 -364.517325) (xy 300.253941 -364.516811)
			(xy 300.234655 -364.524611) (xy 300.226984 -364.531656) (xy 300.21149 -364.54715) (xy 300.204688 -364.554499)
			(xy 300.196976 -364.572961) (xy 300.196504 -364.582964) (xy 300.196504 -365.125) (xy 302.893982 -365.125)
			(xy 302.898053 -365.069378) (xy 302.910179 -365.014941) (xy 302.930102 -364.96285) (xy 302.957398 -364.914215)
			(xy 302.991484 -364.870072) (xy 303.031633 -364.831363) (xy 303.076991 -364.798912) (xy 303.126591 -364.773411)
			(xy 303.179375 -364.755404) (xy 303.234218 -364.745274) (xy 303.289952 -364.743237) (xy 303.345389 -364.749337)
			(xy 303.399346 -364.763443) (xy 303.450675 -364.785255) (xy 303.498281 -364.814309) (xy 303.541149 -364.849984)
			(xy 303.578366 -364.891521) (xy 303.609139 -364.938034) (xy 303.632811 -364.988531) (xy 303.648879 -365.041938)
			(xy 303.656999 -365.097114) (xy 303.657508 -365.125) (xy 305.190142 -365.125) (xy 305.194213 -365.069378)
			(xy 305.206339 -365.014941) (xy 305.226262 -364.96285) (xy 305.253558 -364.914215) (xy 305.287644 -364.870072)
			(xy 305.327793 -364.831363) (xy 305.373151 -364.798912) (xy 305.422751 -364.773411) (xy 305.475535 -364.755404)
			(xy 305.530378 -364.745274) (xy 305.586112 -364.743237) (xy 305.641549 -364.749337) (xy 305.695506 -364.763443)
			(xy 305.746835 -364.785255) (xy 305.794441 -364.814309) (xy 305.837309 -364.849984) (xy 305.874526 -364.891521)
			(xy 305.878979 -364.898251) (xy 306.984378 -364.898251) (xy 306.984378 -364.843749) (xy 306.992134 -364.789801)
			(xy 307.007489 -364.737506) (xy 307.030131 -364.687929) (xy 307.059597 -364.642079) (xy 307.095288 -364.600888)
			(xy 307.136479 -364.565197) (xy 307.182329 -364.535731) (xy 307.231906 -364.513089) (xy 307.284201 -364.497734)
			(xy 307.338149 -364.489978) (xy 307.3654 -364.489492) (xy 307.391858 -364.489953) (xy 307.444268 -364.497261)
			(xy 307.495166 -364.511736) (xy 307.543578 -364.533102) (xy 307.566314 -364.546642) (xy 307.579346 -364.554087)
			(xy 307.608341 -364.561787) (xy 307.638322 -364.56074) (xy 307.666709 -364.551035) (xy 307.691056 -364.533507)
			(xy 307.709267 -364.509668) (xy 307.719774 -364.481568) (xy 307.721254 -364.466632) (xy 307.723585 -364.437914)
			(xy 307.735709 -364.381591) (xy 307.756165 -364.327731) (xy 307.78449 -364.277561) (xy 307.820038 -364.232222)
			(xy 307.862001 -364.192745) (xy 307.909424 -364.160029) (xy 307.961228 -364.134817) (xy 308.016235 -364.117684)
			(xy 308.073193 -364.109019) (xy 308.102 -364.108492) (xy 308.129251 -364.108978) (xy 308.183199 -364.116734)
			(xy 308.235494 -364.132089) (xy 308.285071 -364.154731) (xy 308.330921 -364.184197) (xy 308.372112 -364.219888)
			(xy 308.407803 -364.261079) (xy 308.437269 -364.306929) (xy 308.459911 -364.356506) (xy 308.475266 -364.408801)
			(xy 308.483022 -364.462749) (xy 308.483022 -364.517251) (xy 308.475266 -364.571199) (xy 308.459911 -364.623494)
			(xy 308.437269 -364.673071) (xy 308.407803 -364.718921) (xy 308.386073 -364.744) (xy 309.370982 -364.744)
			(xy 309.375053 -364.688378) (xy 309.387179 -364.633941) (xy 309.407102 -364.58185) (xy 309.434398 -364.533215)
			(xy 309.468484 -364.489072) (xy 309.508633 -364.450363) (xy 309.553991 -364.417912) (xy 309.603591 -364.392411)
			(xy 309.656375 -364.374404) (xy 309.711218 -364.364274) (xy 309.766952 -364.362237) (xy 309.822389 -364.368337)
			(xy 309.876346 -364.382443) (xy 309.927675 -364.404255) (xy 309.975281 -364.433309) (xy 310.018149 -364.468984)
			(xy 310.055366 -364.510521) (xy 310.086139 -364.557034) (xy 310.109811 -364.607531) (xy 310.125879 -364.660938)
			(xy 310.133999 -364.716114) (xy 310.134508 -364.744) (xy 310.133999 -364.771886) (xy 310.125879 -364.827062)
			(xy 310.109811 -364.880469) (xy 310.086139 -364.930966) (xy 310.055366 -364.977479) (xy 310.018149 -365.019016)
			(xy 309.975281 -365.054691) (xy 309.927675 -365.083745) (xy 309.876346 -365.105557) (xy 309.822389 -365.119663)
			(xy 309.766952 -365.125763) (xy 309.711218 -365.123726) (xy 309.656375 -365.113596) (xy 309.603591 -365.095589)
			(xy 309.553991 -365.070088) (xy 309.508633 -365.037637) (xy 309.468484 -364.998928) (xy 309.434398 -364.954785)
			(xy 309.407102 -364.90615) (xy 309.387179 -364.854059) (xy 309.375053 -364.799622) (xy 309.370982 -364.744)
			(xy 308.386073 -364.744) (xy 308.372112 -364.760112) (xy 308.330921 -364.795803) (xy 308.285071 -364.825269)
			(xy 308.235494 -364.847911) (xy 308.183199 -364.863266) (xy 308.129251 -364.871022) (xy 308.102 -364.871508)
			(xy 308.075542 -364.871047) (xy 308.023132 -364.863739) (xy 307.972234 -364.849264) (xy 307.923822 -364.827898)
			(xy 307.901086 -364.814358) (xy 307.888054 -364.806913) (xy 307.859059 -364.799213) (xy 307.829078 -364.80026)
			(xy 307.800691 -364.809965) (xy 307.776344 -364.827493) (xy 307.758133 -364.851332) (xy 307.747626 -364.879432)
			(xy 307.746146 -364.894368) (xy 307.743815 -364.923086) (xy 307.731691 -364.979409) (xy 307.711235 -365.033269)
			(xy 307.68291 -365.083439) (xy 307.647362 -365.128778) (xy 307.605399 -365.168255) (xy 307.557976 -365.200971)
			(xy 307.506172 -365.226183) (xy 307.451165 -365.243316) (xy 307.394207 -365.251981) (xy 307.3654 -365.252508)
			(xy 307.338149 -365.252022) (xy 307.284201 -365.244266) (xy 307.231906 -365.228911) (xy 307.182329 -365.206269)
			(xy 307.136479 -365.176803) (xy 307.095288 -365.141112) (xy 307.059597 -365.099921) (xy 307.030131 -365.054071)
			(xy 307.007489 -365.004494) (xy 306.992134 -364.952199) (xy 306.984378 -364.898251) (xy 305.878979 -364.898251)
			(xy 305.905299 -364.938034) (xy 305.928971 -364.988531) (xy 305.945039 -365.041938) (xy 305.953159 -365.097114)
			(xy 305.953668 -365.125) (xy 305.953159 -365.152886) (xy 305.945039 -365.208062) (xy 305.928971 -365.261469)
			(xy 305.905299 -365.311966) (xy 305.874526 -365.358479) (xy 305.837309 -365.400016) (xy 305.794441 -365.435691)
			(xy 305.746835 -365.464745) (xy 305.695506 -365.486557) (xy 305.641549 -365.500663) (xy 305.586112 -365.506763)
			(xy 305.530378 -365.504726) (xy 305.475535 -365.494596) (xy 305.422751 -365.476589) (xy 305.373151 -365.451088)
			(xy 305.327793 -365.418637) (xy 305.287644 -365.379928) (xy 305.253558 -365.335785) (xy 305.226262 -365.28715)
			(xy 305.206339 -365.235059) (xy 305.194213 -365.180622) (xy 305.190142 -365.125) (xy 303.657508 -365.125)
			(xy 303.656999 -365.152886) (xy 303.648879 -365.208062) (xy 303.632811 -365.261469) (xy 303.609139 -365.311966)
			(xy 303.578366 -365.358479) (xy 303.541149 -365.400016) (xy 303.498281 -365.435691) (xy 303.450675 -365.464745)
			(xy 303.399346 -365.486557) (xy 303.345389 -365.500663) (xy 303.289952 -365.506763) (xy 303.234218 -365.504726)
			(xy 303.179375 -365.494596) (xy 303.126591 -365.476589) (xy 303.076991 -365.451088) (xy 303.031633 -365.418637)
			(xy 302.991484 -365.379928) (xy 302.957398 -365.335785) (xy 302.930102 -365.28715) (xy 302.910179 -365.235059)
			(xy 302.898053 -365.180622) (xy 302.893982 -365.125) (xy 300.196504 -365.125) (xy 300.196504 -365.41202)
			(xy 300.197045 -365.422006) (xy 300.204764 -365.440432) (xy 300.21149 -365.447834) (xy 300.523656 -365.76)
			(xy 307.059582 -365.76) (xy 307.063653 -365.704378) (xy 307.075779 -365.649941) (xy 307.095702 -365.59785)
			(xy 307.122998 -365.549215) (xy 307.157084 -365.505072) (xy 307.197233 -365.466363) (xy 307.242591 -365.433912)
			(xy 307.292191 -365.408411) (xy 307.344975 -365.390404) (xy 307.399818 -365.380274) (xy 307.455552 -365.378237)
			(xy 307.510989 -365.384337) (xy 307.564946 -365.398443) (xy 307.616275 -365.420255) (xy 307.663881 -365.449309)
			(xy 307.706749 -365.484984) (xy 307.743966 -365.526521) (xy 307.774739 -365.573034) (xy 307.798411 -365.623531)
			(xy 307.814479 -365.676938) (xy 307.819227 -365.7092) (xy 308.202582 -365.7092) (xy 308.206653 -365.653578)
			(xy 308.218779 -365.599141) (xy 308.238702 -365.54705) (xy 308.265998 -365.498415) (xy 308.300084 -365.454272)
			(xy 308.340233 -365.415563) (xy 308.385591 -365.383112) (xy 308.435191 -365.357611) (xy 308.487975 -365.339604)
			(xy 308.542818 -365.329474) (xy 308.598552 -365.327437) (xy 308.653989 -365.333537) (xy 308.707946 -365.347643)
			(xy 308.759275 -365.369455) (xy 308.806881 -365.398509) (xy 308.849749 -365.434184) (xy 308.868579 -365.4552)
			(xy 309.96458 -365.4552) (xy 309.968651 -365.399578) (xy 309.980777 -365.345141) (xy 310.0007 -365.29305)
			(xy 310.027996 -365.244415) (xy 310.062082 -365.200272) (xy 310.102231 -365.161563) (xy 310.147589 -365.129112)
			(xy 310.197189 -365.103611) (xy 310.249973 -365.085604) (xy 310.304816 -365.075474) (xy 310.36055 -365.073437)
			(xy 310.415987 -365.079537) (xy 310.469944 -365.093643) (xy 310.521273 -365.115455) (xy 310.568879 -365.144509)
			(xy 310.611747 -365.180184) (xy 310.648964 -365.221721) (xy 310.679737 -365.268234) (xy 310.703409 -365.318731)
			(xy 310.719477 -365.372138) (xy 310.727597 -365.427314) (xy 310.728106 -365.4552) (xy 310.727597 -365.483086)
			(xy 310.719477 -365.538262) (xy 310.703409 -365.591669) (xy 310.679737 -365.642166) (xy 310.648964 -365.688679)
			(xy 310.611747 -365.730216) (xy 310.568879 -365.765891) (xy 310.521273 -365.794945) (xy 310.469944 -365.816757)
			(xy 310.415987 -365.830863) (xy 310.36055 -365.836963) (xy 310.304816 -365.834926) (xy 310.249973 -365.824796)
			(xy 310.197189 -365.806789) (xy 310.147589 -365.781288) (xy 310.102231 -365.748837) (xy 310.062082 -365.710128)
			(xy 310.027996 -365.665985) (xy 310.0007 -365.61735) (xy 309.980777 -365.565259) (xy 309.968651 -365.510822)
			(xy 309.96458 -365.4552) (xy 308.868579 -365.4552) (xy 308.886966 -365.475721) (xy 308.917739 -365.522234)
			(xy 308.941411 -365.572731) (xy 308.957479 -365.626138) (xy 308.965599 -365.681314) (xy 308.966108 -365.7092)
			(xy 308.965599 -365.737086) (xy 308.957479 -365.792262) (xy 308.941411 -365.845669) (xy 308.917739 -365.896166)
			(xy 308.886966 -365.942679) (xy 308.849749 -365.984216) (xy 308.806881 -366.019891) (xy 308.759275 -366.048945)
			(xy 308.707946 -366.070757) (xy 308.653989 -366.084863) (xy 308.598552 -366.090963) (xy 308.542818 -366.088926)
			(xy 308.487975 -366.078796) (xy 308.435191 -366.060789) (xy 308.385591 -366.035288) (xy 308.340233 -366.002837)
			(xy 308.300084 -365.964128) (xy 308.265998 -365.919985) (xy 308.238702 -365.87135) (xy 308.218779 -365.819259)
			(xy 308.206653 -365.764822) (xy 308.202582 -365.7092) (xy 307.819227 -365.7092) (xy 307.822599 -365.732114)
			(xy 307.823108 -365.76) (xy 307.822599 -365.787886) (xy 307.814479 -365.843062) (xy 307.798411 -365.896469)
			(xy 307.774739 -365.946966) (xy 307.743966 -365.993479) (xy 307.706749 -366.035016) (xy 307.663881 -366.070691)
			(xy 307.616275 -366.099745) (xy 307.564946 -366.121557) (xy 307.510989 -366.135663) (xy 307.455552 -366.141763)
			(xy 307.399818 -366.139726) (xy 307.344975 -366.129596) (xy 307.292191 -366.111589) (xy 307.242591 -366.086088)
			(xy 307.197233 -366.053637) (xy 307.157084 -366.014928) (xy 307.122998 -365.970785) (xy 307.095702 -365.92215)
			(xy 307.075779 -365.870059) (xy 307.063653 -365.815622) (xy 307.059582 -365.76) (xy 300.523656 -365.76)
			(xy 301.381922 -366.618266) (xy 301.38932 -366.625113) (xy 301.407918 -366.632845) (xy 301.41799 -366.633252)
			(xy 302.812704 -366.633252)
		)
		(stroke
			(width 0)
			(type solid)
		)
		(fill yes)
		(layer "In6.Cu")
		(net "GND")
	)
	(gr_poly
		(pts
			(xy 101.048058 -193.01968) (xy 101.057932 -193.019212) (xy 101.076218 -193.011757) (xy 101.083618 -193.005202)
			(xy 101.083872 -193.004948) (xy 104.640634 -189.448186) (xy 104.64803 -189.441335) (xy 104.666629 -189.4336)
			(xy 104.676702 -189.4332) (xy 127.197358 -189.4332) (xy 127.207232 -189.432733) (xy 127.22552 -189.425279)
			(xy 127.232918 -189.418722) (xy 127.233172 -189.418468) (xy 146.875754 -169.775886) (xy 146.876262 -169.775378)
			(xy 146.882848 -169.767998) (xy 146.890308 -169.749699) (xy 146.89074 -169.739818) (xy 146.89074 -150.340822)
			(xy 146.890301 -150.330759) (xy 146.88256 -150.312181) (xy 146.875754 -150.304754) (xy 134.411466 -137.840466)
			(xy 134.404354 -137.8331) (xy 134.385558 -137.82548) (xy 105.638854 -137.82548) (xy 105.627228 -137.826045)
			(xy 105.606319 -137.83622) (xy 105.598722 -137.845038) (xy 105.549446 -137.90803) (xy 105.543349 -137.916676)
			(xy 105.538088 -137.937144) (xy 105.539286 -137.947654) (xy 105.53954 -137.949686) (xy 105.540048 -137.951972)
			(xy 105.545357 -137.974589) (xy 105.551086 -138.020692) (xy 105.551478 -138.04392) (xy 105.5497 -138.081766)
			(xy 105.549105 -138.091389) (xy 105.554343 -138.109925) (xy 105.55986 -138.117834) (xy 105.574917 -138.137956)
			(xy 105.600179 -138.181402) (xy 105.61952 -138.227787) (xy 105.632604 -138.276311) (xy 105.639207 -138.326132)
			(xy 105.639616 -138.35126) (xy 105.63913 -138.378511) (xy 105.631374 -138.432459) (xy 105.616019 -138.484754)
			(xy 105.593377 -138.534331) (xy 105.563911 -138.580181) (xy 105.52822 -138.621372) (xy 105.487029 -138.657063)
			(xy 105.441179 -138.686529) (xy 105.391602 -138.709171) (xy 105.339307 -138.724526) (xy 105.285359 -138.732282)
			(xy 105.230857 -138.732282) (xy 105.176909 -138.724526) (xy 105.124614 -138.709171) (xy 105.075037 -138.686529)
			(xy 105.029187 -138.657063) (xy 104.987996 -138.621372) (xy 104.952305 -138.580181) (xy 104.922839 -138.534331)
			(xy 104.900197 -138.484754) (xy 104.884842 -138.432459) (xy 104.877086 -138.378511) (xy 104.8766 -138.35126)
			(xy 104.878378 -138.313414) (xy 104.878988 -138.303787) (xy 104.873771 -138.285233) (xy 104.868218 -138.277346)
			(xy 104.85316 -138.257225) (xy 104.827895 -138.21378) (xy 104.808552 -138.167394) (xy 104.795467 -138.11887)
			(xy 104.788866 -138.069049) (xy 104.788462 -138.04392) (xy 104.788853 -138.020692) (xy 104.794584 -137.974589)
			(xy 104.799892 -137.951972) (xy 104.8004 -137.949686) (xy 104.800654 -137.947654) (xy 104.801953 -137.937139)
			(xy 104.796676 -137.916637) (xy 104.790494 -137.90803) (xy 104.741218 -137.845038) (xy 104.733623 -137.836217)
			(xy 104.712714 -137.826048) (xy 104.701086 -137.82548) (xy 98.227896 -137.82548) (xy 98.217908 -137.826017)
			(xy 98.199475 -137.83373) (xy 98.192082 -137.840466) (xy 98.015044 -138.017504) (xy 97.87001 -138.162538)
			(xy 97.864654 -138.169004) (xy 97.858043 -138.184426) (xy 97.857056 -138.192764) (xy 97.857056 -138.443716)
			(xy 97.85731 -138.443716) (xy 97.85731 -138.50747) (xy 97.856752 -138.536033) (xy 97.847821 -138.592457)
			(xy 97.830173 -138.646789) (xy 97.804244 -138.697692) (xy 97.770672 -138.743912) (xy 97.750884 -138.764518)
			(xy 97.691448 -138.8237) (xy 97.546414 -138.968988) (xy 97.542858 -138.975338) (xy 97.528433 -139.000883)
			(xy 97.492964 -139.047608) (xy 97.450765 -139.088357) (xy 97.40283 -139.122174) (xy 97.350287 -139.148261)
			(xy 97.294372 -139.166004) (xy 97.236401 -139.174987) (xy 97.20707 -139.17549) (xy 97.179821 -139.175002)
			(xy 97.125877 -139.167242) (xy 97.073587 -139.151884) (xy 97.024015 -139.129241) (xy 96.97817 -139.099773)
			(xy 96.936984 -139.064082) (xy 96.901298 -139.022892) (xy 96.871836 -138.977043) (xy 96.8492 -138.927468)
			(xy 96.833848 -138.875176) (xy 96.826095 -138.821231) (xy 96.825562 -138.793982) (xy 96.826109 -138.764908)
			(xy 96.834933 -138.707432) (xy 96.852374 -138.651961) (xy 96.878028 -138.599777) (xy 96.911302 -138.552089)
			(xy 96.951425 -138.510001) (xy 96.997468 -138.474486) (xy 97.022666 -138.459972) (xy 97.025206 -138.458448)
			(xy 97.033334 -138.452606) (xy 97.039684 -138.447272) (xy 97.117154 -138.369548) (xy 97.122511 -138.363083)
			(xy 97.129123 -138.34766) (xy 97.130108 -138.339322) (xy 97.130108 -138.024616) (xy 97.130149 -138.012389)
			(xy 97.131672 -137.987984) (xy 97.133156 -137.975848) (xy 97.13341 -137.975594) (xy 97.137982 -137.948162)
			(xy 97.140522 -137.936732) (xy 97.135188 -137.914888) (xy 97.078292 -137.84453) (xy 97.073212 -137.838942)
			(xy 97.067296 -137.833879) (xy 97.053206 -137.827268) (xy 97.045526 -137.825988) (xy 97.038922 -137.82548)
			(xy 96.98228 -137.82548) (xy 96.972294 -137.82602) (xy 96.953865 -137.833737) (xy 96.946466 -137.840466)
			(xy 96.836484 -137.950448) (xy 96.745806 -138.041126) (xy 96.739902 -138.048372) (xy 96.733254 -138.065824)
			(xy 96.732852 -138.075162) (xy 96.732852 -138.321796) (xy 96.732418 -138.348392) (xy 96.724724 -138.401024)
			(xy 96.70944 -138.451972) (xy 96.686894 -138.500148) (xy 96.657567 -138.544524) (xy 96.640142 -138.56462)
			(xy 96.638364 -138.566398) (xy 96.630998 -138.576304) (xy 96.629474 -138.579098) (xy 96.614997 -138.604425)
			(xy 96.579546 -138.650751) (xy 96.537453 -138.691137) (xy 96.489699 -138.72464) (xy 96.4374 -138.750479)
			(xy 96.381775 -138.76805) (xy 96.324123 -138.776943) (xy 96.294956 -138.777472) (xy 96.267708 -138.776983)
			(xy 96.213767 -138.769221) (xy 96.161479 -138.753862) (xy 96.11191 -138.731217) (xy 96.066068 -138.701749)
			(xy 96.024886 -138.666057) (xy 95.989203 -138.624868) (xy 95.959744 -138.57902) (xy 95.93711 -138.529446)
			(xy 95.921762 -138.477155) (xy 95.914012 -138.423212) (xy 95.913448 -138.395964) (xy 95.913194 -138.395964)
			(xy 95.913803 -138.365141) (xy 95.923744 -138.304301) (xy 95.943332 -138.245849) (xy 95.972055 -138.191303)
			(xy 95.990156 -138.166348) (xy 95.994982 -138.159744) (xy 96.002602 -138.137646) (xy 96.003904 -138.133577)
			(xy 96.005313 -138.125153) (xy 96.005396 -138.120882) (xy 96.005396 -137.903458) (xy 96.00565 -137.890504)
			(xy 96.00565 -137.889996) (xy 96.006412 -137.879582) (xy 96.006412 -137.87628) (xy 96.00592 -137.866274)
			(xy 95.998258 -137.847787) (xy 95.984106 -137.833638) (xy 95.965618 -137.825978) (xy 95.955612 -137.82548)
			(xy 95.704914 -137.82548) (xy 95.67926 -137.843006) (xy 95.673418 -137.857484) (xy 95.662419 -137.883728)
			(xy 95.633779 -137.932895) (xy 95.598155 -137.977265) (xy 95.556337 -138.015852) (xy 95.509253 -138.047802)
			(xy 95.457946 -138.072406) (xy 95.403555 -138.089117) (xy 95.347284 -138.097567) (xy 95.290384 -138.097567)
			(xy 95.234113 -138.089117) (xy 95.179722 -138.072406) (xy 95.128415 -138.047802) (xy 95.081331 -138.015852)
			(xy 95.039513 -137.977265) (xy 95.003889 -137.932895) (xy 94.975249 -137.883728) (xy 94.96425 -137.857484)
			(xy 94.958408 -137.843006) (xy 94.932754 -137.82548) (xy 94.073726 -137.82548) (xy 94.063727 -137.825971)
			(xy 94.045239 -137.8336) (xy 94.031038 -137.847684) (xy 94.026736 -137.856722) (xy 94.020894 -137.8712)
			(xy 94.026736 -137.901172) (xy 96.047052 -139.921234) (xy 96.06087 -139.935712) (xy 96.08308 -139.968999)
			(xy 96.098356 -140.005985) (xy 96.106109 -140.045243) (xy 96.106488 -140.065252) (xy 96.106488 -140.153644)
			(xy 96.106931 -140.163825) (xy 96.114833 -140.182588) (xy 96.129415 -140.196798) (xy 96.138746 -140.200888)
			(xy 96.241108 -140.241528) (xy 96.271334 -140.23467) (xy 96.282256 -140.22324) (xy 96.300353 -140.204678)
			(xy 96.340692 -140.172119) (xy 96.385067 -140.145318) (xy 96.432661 -140.12477) (xy 96.482597 -140.110852)
			(xy 96.533958 -140.103819) (xy 96.559878 -140.103352) (xy 96.574798 -140.103475) (xy 96.604551 -140.105761)
			(xy 96.619314 -140.107924) (xy 96.631506 -140.109956) (xy 96.654366 -140.102336) (xy 97.40011 -139.356592)
			(xy 97.414592 -139.342783) (xy 97.447882 -139.320592) (xy 97.484868 -139.305334) (xy 97.524122 -139.297598)
			(xy 97.544128 -139.297156) (xy 102.134416 -139.297156) (xy 102.143739 -139.296736) (xy 102.161147 -139.290053)
			(xy 102.175006 -139.277579) (xy 102.179628 -139.26947) (xy 102.227634 -139.17676) (xy 102.225602 -139.148566)
			(xy 102.217474 -139.136882) (xy 102.200941 -139.11257) (xy 102.17475 -139.059933) (xy 102.156937 -139.003904)
			(xy 102.147923 -138.945806) (xy 102.14737 -138.91641) (xy 102.147856 -138.889159) (xy 102.155612 -138.835211)
			(xy 102.170967 -138.782916) (xy 102.193609 -138.733339) (xy 102.223075 -138.687489) (xy 102.258766 -138.646298)
			(xy 102.299957 -138.610607) (xy 102.345807 -138.581141) (xy 102.395384 -138.558499) (xy 102.447679 -138.543144)
			(xy 102.501627 -138.535388) (xy 102.556129 -138.535388) (xy 102.610077 -138.543144) (xy 102.662372 -138.558499)
			(xy 102.711949 -138.581141) (xy 102.757799 -138.610607) (xy 102.79899 -138.646298) (xy 102.834681 -138.687489)
			(xy 102.864147 -138.733339) (xy 102.886789 -138.782916) (xy 102.902144 -138.835211) (xy 102.9099 -138.889159)
			(xy 102.910386 -138.91641) (xy 102.91064 -138.91641) (xy 102.910097 -138.945807) (xy 102.901082 -139.003905)
			(xy 102.883265 -139.059934) (xy 102.857068 -139.112568) (xy 102.840536 -139.136882) (xy 102.832154 -139.14882)
			(xy 102.830122 -139.17676) (xy 102.878128 -139.26947) (xy 102.882744 -139.277581) (xy 102.896611 -139.290046)
			(xy 102.914017 -139.296732) (xy 102.92334 -139.297156) (xy 104.831896 -139.297156) (xy 104.851897 -139.297625)
			(xy 104.891139 -139.305382) (xy 104.928116 -139.32064) (xy 104.96141 -139.342812) (xy 104.975914 -139.356592)
			(xy 107.248452 -141.62913) (xy 107.262263 -141.64361) (xy 107.284457 -141.6769) (xy 107.299716 -141.713886)
			(xy 107.30745 -141.753142) (xy 107.307888 -141.773148) (xy 107.307888 -143.649446) (xy 112.505996 -143.649446)
			(xy 112.510067 -143.593824) (xy 112.522193 -143.539387) (xy 112.542116 -143.487296) (xy 112.569412 -143.438661)
			(xy 112.603498 -143.394518) (xy 112.643647 -143.355809) (xy 112.689005 -143.323358) (xy 112.738605 -143.297857)
			(xy 112.791389 -143.27985) (xy 112.846232 -143.26972) (xy 112.901966 -143.267683) (xy 112.957403 -143.273783)
			(xy 113.01136 -143.287889) (xy 113.062689 -143.309701) (xy 113.110295 -143.338755) (xy 113.153163 -143.37443)
			(xy 113.19038 -143.415967) (xy 113.221153 -143.46248) (xy 113.244825 -143.512977) (xy 113.260893 -143.566384)
			(xy 113.269013 -143.62156) (xy 113.269522 -143.649446) (xy 113.269013 -143.677332) (xy 113.260893 -143.732508)
			(xy 113.244825 -143.785915) (xy 113.221153 -143.836412) (xy 113.19038 -143.882925) (xy 113.153163 -143.924462)
			(xy 113.110295 -143.960137) (xy 113.062689 -143.989191) (xy 113.01136 -144.011003) (xy 112.957403 -144.025109)
			(xy 112.901966 -144.031209) (xy 112.846232 -144.029172) (xy 112.791389 -144.019042) (xy 112.738605 -144.001035)
			(xy 112.689005 -143.975534) (xy 112.643647 -143.943083) (xy 112.603498 -143.904374) (xy 112.569412 -143.860231)
			(xy 112.542116 -143.811596) (xy 112.522193 -143.759505) (xy 112.510067 -143.705068) (xy 112.505996 -143.649446)
			(xy 107.307888 -143.649446) (xy 107.307888 -146.464528) (xy 115.805966 -146.464528) (xy 115.806432 -146.437158)
			(xy 115.814248 -146.382978) (xy 115.829736 -146.330474) (xy 115.852578 -146.280727) (xy 115.882304 -146.234761)
			(xy 115.899946 -146.21383) (xy 115.906042 -146.206718) (xy 115.912392 -146.1897) (xy 115.912392 -146.104356)
			(xy 115.906042 -146.087338) (xy 115.899946 -146.080226) (xy 115.882332 -146.059271) (xy 115.852605 -146.013308)
			(xy 115.829756 -145.963565) (xy 115.814257 -145.911066) (xy 115.806426 -145.856891) (xy 115.806422 -145.802152)
			(xy 115.814248 -145.747975) (xy 115.829742 -145.695474) (xy 115.852584 -145.645729) (xy 115.882307 -145.599762)
			(xy 115.899946 -145.57883) (xy 115.906042 -145.571718) (xy 115.912392 -145.5547) (xy 115.912392 -145.469356)
			(xy 115.906042 -145.452338) (xy 115.899946 -145.445226) (xy 115.882332 -145.424271) (xy 115.852605 -145.378308)
			(xy 115.829756 -145.328565) (xy 115.814257 -145.276066) (xy 115.806426 -145.221891) (xy 115.806422 -145.167152)
			(xy 115.814248 -145.112975) (xy 115.829742 -145.060474) (xy 115.852584 -145.010729) (xy 115.882307 -144.964762)
			(xy 115.899946 -144.94383) (xy 115.906042 -144.936718) (xy 115.912392 -144.9197) (xy 115.912392 -144.834356)
			(xy 115.906042 -144.817338) (xy 115.899946 -144.810226) (xy 115.882332 -144.789271) (xy 115.852605 -144.743308)
			(xy 115.829756 -144.693565) (xy 115.814257 -144.641066) (xy 115.806426 -144.586891) (xy 115.806422 -144.532152)
			(xy 115.814248 -144.477975) (xy 115.829742 -144.425474) (xy 115.852584 -144.375729) (xy 115.882307 -144.329762)
			(xy 115.899946 -144.30883) (xy 115.906042 -144.301718) (xy 115.912392 -144.2847) (xy 115.912392 -144.199356)
			(xy 115.906042 -144.182338) (xy 115.899946 -144.175226) (xy 115.882313 -144.154289) (xy 115.852598 -144.108318)
			(xy 115.829761 -144.058572) (xy 115.814268 -144.006072) (xy 115.80644 -143.951897) (xy 115.805966 -143.924528)
			(xy 115.806481 -143.897277) (xy 115.814234 -143.843329) (xy 115.829585 -143.791034) (xy 115.852222 -143.741456)
			(xy 115.881685 -143.695604) (xy 115.917373 -143.654411) (xy 115.95856 -143.618717) (xy 116.004408 -143.589248)
			(xy 116.053983 -143.566604) (xy 116.106276 -143.551245) (xy 116.160223 -143.543485) (xy 116.187474 -143.54302)
			(xy 116.214844 -143.543496) (xy 116.269023 -143.551311) (xy 116.321526 -143.566797) (xy 116.371273 -143.589637)
			(xy 116.41724 -143.61936) (xy 116.438172 -143.637) (xy 116.445284 -143.643096) (xy 116.462302 -143.649446)
			(xy 116.547646 -143.649446) (xy 116.564664 -143.643096) (xy 116.571776 -143.637) (xy 116.592706 -143.619359)
			(xy 116.63868 -143.589647) (xy 116.688428 -143.566812) (xy 116.740929 -143.551321) (xy 116.795105 -143.543494)
			(xy 116.822474 -143.54302) (xy 116.850048 -143.543497) (xy 116.904621 -143.551446) (xy 116.957481 -143.567168)
			(xy 117.007527 -143.590336) (xy 117.053717 -143.620467) (xy 117.095088 -143.656933) (xy 117.113304 -143.67764)
			(xy 117.120903 -143.685762) (xy 117.141057 -143.695113) (xy 117.152166 -143.695674) (xy 117.229382 -143.695674)
			(xy 117.240494 -143.69512) (xy 117.260653 -143.685773) (xy 117.268244 -143.67764) (xy 117.28649 -143.656961)
			(xy 117.32785 -143.620486) (xy 117.374033 -143.590349) (xy 117.424074 -143.567177) (xy 117.476931 -143.551455)
			(xy 117.531501 -143.543509) (xy 117.559074 -143.54302) (xy 117.586444 -143.543496) (xy 117.640623 -143.551311)
			(xy 117.693126 -143.566797) (xy 117.742873 -143.589637) (xy 117.78884 -143.61936) (xy 117.809772 -143.637)
			(xy 117.816884 -143.643096) (xy 117.833902 -143.649446) (xy 117.919246 -143.649446) (xy 117.936264 -143.643096)
			(xy 117.943376 -143.637) (xy 117.964309 -143.619359) (xy 118.010277 -143.589635) (xy 118.060023 -143.566789)
			(xy 118.112525 -143.551293) (xy 118.166703 -143.543464) (xy 118.221445 -143.543464) (xy 118.275623 -143.551293)
			(xy 118.328125 -143.566789) (xy 118.377871 -143.589635) (xy 118.423839 -143.619359) (xy 118.444772 -143.637)
			(xy 118.451884 -143.643096) (xy 118.468902 -143.649446) (xy 118.554246 -143.649446) (xy 118.571264 -143.643096)
			(xy 118.578376 -143.637) (xy 118.599309 -143.619359) (xy 118.645277 -143.589635) (xy 118.695023 -143.566789)
			(xy 118.747525 -143.551293) (xy 118.801703 -143.543464) (xy 118.856445 -143.543464) (xy 118.910623 -143.551293)
			(xy 118.963125 -143.566789) (xy 119.012871 -143.589635) (xy 119.058839 -143.619359) (xy 119.079772 -143.637)
			(xy 119.086884 -143.643096) (xy 119.103902 -143.649446) (xy 119.189246 -143.649446) (xy 119.206264 -143.643096)
			(xy 119.213376 -143.637) (xy 119.234306 -143.619359) (xy 119.28028 -143.589647) (xy 119.330028 -143.566812)
			(xy 119.382529 -143.551321) (xy 119.436705 -143.543494) (xy 119.464074 -143.54302) (xy 119.491648 -143.543497)
			(xy 119.546221 -143.551446) (xy 119.599081 -143.567168) (xy 119.649127 -143.590336) (xy 119.695317 -143.620467)
			(xy 119.736688 -143.656933) (xy 119.754904 -143.67764) (xy 119.762503 -143.685762) (xy 119.782657 -143.695113)
			(xy 119.793766 -143.695674) (xy 119.870982 -143.695674) (xy 119.882094 -143.69512) (xy 119.902253 -143.685773)
			(xy 119.909844 -143.67764) (xy 119.92809 -143.656961) (xy 119.96945 -143.620486) (xy 120.015633 -143.590349)
			(xy 120.065674 -143.567177) (xy 120.118531 -143.551455) (xy 120.173101 -143.543509) (xy 120.200674 -143.54302)
			(xy 120.228044 -143.543496) (xy 120.282223 -143.551311) (xy 120.334726 -143.566797) (xy 120.384473 -143.589637)
			(xy 120.43044 -143.61936) (xy 120.451372 -143.637) (xy 120.458484 -143.643096) (xy 120.475502 -143.649446)
			(xy 120.560846 -143.649446) (xy 120.577864 -143.643096) (xy 120.584976 -143.637) (xy 120.605906 -143.619359)
			(xy 120.65188 -143.589647) (xy 120.701628 -143.566812) (xy 120.754129 -143.551321) (xy 120.808305 -143.543494)
			(xy 120.835674 -143.54302) (xy 120.862927 -143.54348) (xy 120.91688 -143.551234) (xy 120.96918 -143.566588)
			(xy 121.018762 -143.589229) (xy 121.064616 -143.618697) (xy 121.10581 -143.654392) (xy 121.141504 -143.695585)
			(xy 121.170972 -143.74144) (xy 121.193613 -143.791022) (xy 121.208967 -143.843322) (xy 121.216721 -143.897275)
			(xy 121.217182 -143.924528) (xy 121.216737 -143.951899) (xy 121.208915 -144.006079) (xy 121.193421 -144.058583)
			(xy 121.170574 -144.108329) (xy 121.140845 -144.154295) (xy 121.123202 -144.175226) (xy 121.117106 -144.182338)
			(xy 121.110756 -144.199356) (xy 121.110756 -144.2847) (xy 121.117106 -144.301718) (xy 121.123202 -144.30883)
			(xy 121.140869 -144.329741) (xy 121.17059 -144.375713) (xy 121.193432 -144.425463) (xy 121.208925 -144.477968)
			(xy 121.216751 -144.532149) (xy 121.216747 -144.586893) (xy 121.208916 -144.641073) (xy 121.193417 -144.693576)
			(xy 121.17057 -144.743324) (xy 121.140843 -144.789293) (xy 121.123202 -144.810226) (xy 121.117106 -144.817338)
			(xy 121.110756 -144.834356) (xy 121.110756 -144.9197) (xy 121.117106 -144.936718) (xy 121.123202 -144.94383)
			(xy 121.140869 -144.964741) (xy 121.17059 -145.010713) (xy 121.193432 -145.060463) (xy 121.208925 -145.112968)
			(xy 121.216751 -145.167149) (xy 121.216747 -145.221893) (xy 121.208916 -145.276073) (xy 121.193417 -145.328576)
			(xy 121.17057 -145.378324) (xy 121.140843 -145.424293) (xy 121.123202 -145.445226) (xy 121.117106 -145.452338)
			(xy 121.110756 -145.469356) (xy 121.110756 -145.5547) (xy 121.117106 -145.571718) (xy 121.123202 -145.57883)
			(xy 121.140869 -145.599741) (xy 121.17059 -145.645713) (xy 121.193432 -145.695463) (xy 121.208925 -145.747968)
			(xy 121.216751 -145.802149) (xy 121.216747 -145.856893) (xy 121.208916 -145.911073) (xy 121.193417 -145.963576)
			(xy 121.17057 -146.013324) (xy 121.140843 -146.059293) (xy 121.123202 -146.080226) (xy 121.117106 -146.087338)
			(xy 121.110756 -146.104356) (xy 121.110756 -146.1897) (xy 121.117106 -146.206718) (xy 121.123202 -146.21383)
			(xy 121.140822 -146.234777) (xy 121.170537 -146.280746) (xy 121.193376 -146.33049) (xy 121.208872 -146.382987)
			(xy 121.216705 -146.43716) (xy 121.217182 -146.464528) (xy 121.216748 -146.491781) (xy 121.208987 -146.545732)
			(xy 121.193627 -146.598029) (xy 121.170981 -146.647608) (xy 121.141509 -146.69346) (xy 121.105812 -146.734651)
			(xy 121.064617 -146.770342) (xy 121.018761 -146.799807) (xy 120.969179 -146.822446) (xy 120.916879 -146.837799)
			(xy 120.862927 -146.845552) (xy 120.835674 -146.846036) (xy 120.808302 -146.845601) (xy 120.754121 -146.837778)
			(xy 120.701617 -146.822282) (xy 120.651871 -146.799433) (xy 120.605906 -146.769701) (xy 120.584976 -146.752056)
			(xy 120.577864 -146.74596) (xy 120.560846 -146.73961) (xy 120.475502 -146.73961) (xy 120.458484 -146.74596)
			(xy 120.451372 -146.752056) (xy 120.430418 -146.769668) (xy 120.384452 -146.799385) (xy 120.33471 -146.822227)
			(xy 120.282214 -146.837725) (xy 120.228042 -146.845559) (xy 120.200674 -146.846036) (xy 120.173354 -146.845559)
			(xy 120.119273 -146.83776) (xy 120.066857 -146.822326) (xy 120.01718 -146.799573) (xy 119.971256 -146.769965)
			(xy 119.930026 -146.734109) (xy 119.894333 -146.692738) (xy 119.864907 -146.646698) (xy 119.853202 -146.622008)
			(xy 119.847106 -146.608292) (xy 119.82196 -146.592036) (xy 119.759984 -146.592036) (xy 119.741188 -146.59991)
			(xy 119.734076 -146.607022) (xy 119.714472 -146.626004) (xy 119.670814 -146.658738) (xy 119.622937 -146.684918)
			(xy 119.571819 -146.704009) (xy 119.518502 -146.715621) (xy 119.464074 -146.719519) (xy 119.409646 -146.715621)
			(xy 119.356329 -146.704009) (xy 119.305211 -146.684918) (xy 119.257334 -146.658738) (xy 119.213676 -146.626004)
			(xy 119.194072 -146.607022) (xy 119.18696 -146.59991) (xy 119.168164 -146.592036) (xy 119.124984 -146.592036)
			(xy 119.106188 -146.59991) (xy 119.099076 -146.607022) (xy 119.079472 -146.626004) (xy 119.035814 -146.658738)
			(xy 118.987937 -146.684918) (xy 118.936819 -146.704009) (xy 118.883502 -146.715621) (xy 118.829074 -146.719519)
			(xy 118.774646 -146.715621) (xy 118.721329 -146.704009) (xy 118.670211 -146.684918) (xy 118.622334 -146.658738)
			(xy 118.578676 -146.626004) (xy 118.559072 -146.607022) (xy 118.55196 -146.59991) (xy 118.533164 -146.592036)
			(xy 118.489984 -146.592036) (xy 118.471188 -146.59991) (xy 118.464076 -146.607022) (xy 118.444472 -146.626004)
			(xy 118.400814 -146.658738) (xy 118.352937 -146.684918) (xy 118.301819 -146.704009) (xy 118.248502 -146.715621)
			(xy 118.194074 -146.719519) (xy 118.139646 -146.715621) (xy 118.086329 -146.704009) (xy 118.035211 -146.684918)
			(xy 117.987334 -146.658738) (xy 117.943676 -146.626004) (xy 117.924072 -146.607022) (xy 117.91696 -146.59991)
			(xy 117.898164 -146.592036) (xy 117.854984 -146.592036) (xy 117.836188 -146.59991) (xy 117.829076 -146.607022)
			(xy 117.809472 -146.626004) (xy 117.765814 -146.658738) (xy 117.717937 -146.684918) (xy 117.666819 -146.704009)
			(xy 117.613502 -146.715621) (xy 117.559074 -146.719519) (xy 117.504646 -146.715621) (xy 117.451329 -146.704009)
			(xy 117.400211 -146.684918) (xy 117.352334 -146.658738) (xy 117.308676 -146.626004) (xy 117.289072 -146.607022)
			(xy 117.28196 -146.59991) (xy 117.263164 -146.592036) (xy 117.201188 -146.592036) (xy 117.176042 -146.608292)
			(xy 117.169946 -146.622008) (xy 117.158242 -146.6467) (xy 117.128821 -146.692745) (xy 117.093131 -146.734122)
			(xy 117.051901 -146.769981) (xy 117.005977 -146.799591) (xy 116.956297 -146.822344) (xy 116.903879 -146.837776)
			(xy 116.849795 -146.845569) (xy 116.822474 -146.846036) (xy 116.795102 -146.845601) (xy 116.740921 -146.837778)
			(xy 116.688417 -146.822282) (xy 116.638671 -146.799433) (xy 116.592706 -146.769701) (xy 116.571776 -146.752056)
			(xy 116.564664 -146.74596) (xy 116.547646 -146.73961) (xy 116.462302 -146.73961) (xy 116.445284 -146.74596)
			(xy 116.438172 -146.752056) (xy 116.417218 -146.769668) (xy 116.371252 -146.799385) (xy 116.32151 -146.822227)
			(xy 116.269014 -146.837725) (xy 116.214842 -146.845559) (xy 116.187474 -146.846036) (xy 116.160223 -146.845546)
			(xy 116.106277 -146.837787) (xy 116.053984 -146.82243) (xy 116.004409 -146.799788) (xy 115.95856 -146.770322)
			(xy 115.917371 -146.734631) (xy 115.88168 -146.693442) (xy 115.852213 -146.647593) (xy 115.829571 -146.598018)
			(xy 115.814213 -146.545725) (xy 115.806454 -146.491779) (xy 115.805966 -146.464528) (xy 107.307888 -146.464528)
			(xy 107.307888 -150.984134) (xy 109.251492 -150.984134) (xy 109.251492 -150.899438) (xy 109.259543 -150.815124)
			(xy 109.275572 -150.731958) (xy 109.299433 -150.650691) (xy 109.330912 -150.572061) (xy 109.369723 -150.49678)
			(xy 109.415513 -150.425528) (xy 109.467869 -150.358952) (xy 109.526317 -150.297654) (xy 109.590327 -150.242189)
			(xy 109.659319 -150.19306) (xy 109.732669 -150.150711) (xy 109.809712 -150.115527) (xy 109.889751 -150.087825)
			(xy 109.97206 -150.067857) (xy 110.055895 -150.055804) (xy 110.140496 -150.051774) (xy 110.225097 -150.055804)
			(xy 110.308932 -150.067857) (xy 110.391241 -150.087825) (xy 110.47128 -150.115527) (xy 110.548323 -150.150711)
			(xy 110.621673 -150.19306) (xy 110.690665 -150.242189) (xy 110.754675 -150.297654) (xy 110.813123 -150.358952)
			(xy 110.865479 -150.425528) (xy 110.911269 -150.49678) (xy 110.95008 -150.572061) (xy 110.981559 -150.650691)
			(xy 111.00542 -150.731958) (xy 111.021449 -150.815124) (xy 111.0295 -150.899438) (xy 111.030004 -150.941786)
			(xy 111.0295 -150.984134) (xy 111.751614 -150.984134) (xy 111.751614 -150.899438) (xy 111.759665 -150.815124)
			(xy 111.775694 -150.731958) (xy 111.799555 -150.650691) (xy 111.831034 -150.572061) (xy 111.869845 -150.49678)
			(xy 111.915635 -150.425528) (xy 111.967991 -150.358952) (xy 112.026439 -150.297654) (xy 112.090449 -150.242189)
			(xy 112.159441 -150.19306) (xy 112.232791 -150.150711) (xy 112.309834 -150.115527) (xy 112.389873 -150.087825)
			(xy 112.472182 -150.067857) (xy 112.556017 -150.055804) (xy 112.640618 -150.051774) (xy 112.725219 -150.055804)
			(xy 112.809054 -150.067857) (xy 112.891363 -150.087825) (xy 112.971402 -150.115527) (xy 113.048445 -150.150711)
			(xy 113.121795 -150.19306) (xy 113.190787 -150.242189) (xy 113.254797 -150.297654) (xy 113.313245 -150.358952)
			(xy 113.365601 -150.425528) (xy 113.411391 -150.49678) (xy 113.430378 -150.533608) (xy 136.287 -150.533608)
			(xy 136.291071 -150.477986) (xy 136.303197 -150.423549) (xy 136.32312 -150.371458) (xy 136.350416 -150.322823)
			(xy 136.384502 -150.27868) (xy 136.424651 -150.239971) (xy 136.470009 -150.20752) (xy 136.519609 -150.182019)
			(xy 136.572393 -150.164012) (xy 136.627236 -150.153882) (xy 136.68297 -150.151845) (xy 136.738407 -150.157945)
			(xy 136.792364 -150.172051) (xy 136.843693 -150.193863) (xy 136.891299 -150.222917) (xy 136.934167 -150.258592)
			(xy 136.971384 -150.300129) (xy 137.002157 -150.346642) (xy 137.025829 -150.397139) (xy 137.041897 -150.450546)
			(xy 137.050017 -150.505722) (xy 137.050526 -150.533608) (xy 137.050017 -150.561494) (xy 137.041897 -150.61667)
			(xy 137.033492 -150.644606) (xy 137.304016 -150.644606) (xy 137.308087 -150.588984) (xy 137.320213 -150.534547)
			(xy 137.340136 -150.482456) (xy 137.367432 -150.433821) (xy 137.401518 -150.389678) (xy 137.441667 -150.350969)
			(xy 137.487025 -150.318518) (xy 137.536625 -150.293017) (xy 137.589409 -150.27501) (xy 137.644252 -150.26488)
			(xy 137.699986 -150.262843) (xy 137.755423 -150.268943) (xy 137.80938 -150.283049) (xy 137.860709 -150.304861)
			(xy 137.908315 -150.333915) (xy 137.951183 -150.36959) (xy 137.9884 -150.411127) (xy 138.019173 -150.45764)
			(xy 138.042845 -150.508137) (xy 138.058913 -150.561544) (xy 138.067033 -150.61672) (xy 138.067542 -150.644606)
			(xy 138.067033 -150.672492) (xy 138.058913 -150.727668) (xy 138.042845 -150.781075) (xy 138.019173 -150.831572)
			(xy 137.9884 -150.878085) (xy 137.951183 -150.919622) (xy 137.908315 -150.955297) (xy 137.860709 -150.984351)
			(xy 137.80938 -151.006163) (xy 137.755423 -151.020269) (xy 137.699986 -151.026369) (xy 137.644252 -151.024332)
			(xy 137.589409 -151.014202) (xy 137.536625 -150.996195) (xy 137.487025 -150.970694) (xy 137.441667 -150.938243)
			(xy 137.401518 -150.899534) (xy 137.367432 -150.855391) (xy 137.340136 -150.806756) (xy 137.320213 -150.754665)
			(xy 137.308087 -150.700228) (xy 137.304016 -150.644606) (xy 137.033492 -150.644606) (xy 137.025829 -150.670077)
			(xy 137.002157 -150.720574) (xy 136.971384 -150.767087) (xy 136.934167 -150.808624) (xy 136.891299 -150.844299)
			(xy 136.843693 -150.873353) (xy 136.792364 -150.895165) (xy 136.738407 -150.909271) (xy 136.68297 -150.915371)
			(xy 136.627236 -150.913334) (xy 136.572393 -150.903204) (xy 136.519609 -150.885197) (xy 136.470009 -150.859696)
			(xy 136.424651 -150.827245) (xy 136.384502 -150.788536) (xy 136.350416 -150.744393) (xy 136.32312 -150.695758)
			(xy 136.303197 -150.643667) (xy 136.291071 -150.58923) (xy 136.287 -150.533608) (xy 113.430378 -150.533608)
			(xy 113.450202 -150.572061) (xy 113.481681 -150.650691) (xy 113.505542 -150.731958) (xy 113.521571 -150.815124)
			(xy 113.529622 -150.899438) (xy 113.530126 -150.941786) (xy 113.529622 -150.984134) (xy 113.521571 -151.068448)
			(xy 113.505542 -151.151614) (xy 113.481681 -151.232881) (xy 113.450202 -151.311511) (xy 113.411391 -151.386792)
			(xy 113.365601 -151.458044) (xy 113.313245 -151.52462) (xy 113.254797 -151.585918) (xy 113.190787 -151.641383)
			(xy 113.121795 -151.690512) (xy 113.048445 -151.732861) (xy 112.971402 -151.768045) (xy 112.891363 -151.795747)
			(xy 112.809054 -151.815715) (xy 112.725219 -151.827768) (xy 112.640618 -151.831799) (xy 112.556017 -151.827768)
			(xy 112.472182 -151.815715) (xy 112.389873 -151.795747) (xy 112.309834 -151.768045) (xy 112.232791 -151.732861)
			(xy 112.159441 -151.690512) (xy 112.090449 -151.641383) (xy 112.026439 -151.585918) (xy 111.967991 -151.52462)
			(xy 111.915635 -151.458044) (xy 111.869845 -151.386792) (xy 111.831034 -151.311511) (xy 111.799555 -151.232881)
			(xy 111.775694 -151.151614) (xy 111.759665 -151.068448) (xy 111.751614 -150.984134) (xy 111.0295 -150.984134)
			(xy 111.021449 -151.068448) (xy 111.00542 -151.151614) (xy 110.981559 -151.232881) (xy 110.95008 -151.311511)
			(xy 110.911269 -151.386792) (xy 110.865479 -151.458044) (xy 110.813123 -151.52462) (xy 110.754675 -151.585918)
			(xy 110.690665 -151.641383) (xy 110.621673 -151.690512) (xy 110.548323 -151.732861) (xy 110.47128 -151.768045)
			(xy 110.391241 -151.795747) (xy 110.308932 -151.815715) (xy 110.225097 -151.827768) (xy 110.140496 -151.831799)
			(xy 110.055895 -151.827768) (xy 109.97206 -151.815715) (xy 109.889751 -151.795747) (xy 109.809712 -151.768045)
			(xy 109.732669 -151.732861) (xy 109.659319 -151.690512) (xy 109.590327 -151.641383) (xy 109.526317 -151.585918)
			(xy 109.467869 -151.52462) (xy 109.415513 -151.458044) (xy 109.369723 -151.386792) (xy 109.330912 -151.311511)
			(xy 109.299433 -151.232881) (xy 109.275572 -151.151614) (xy 109.259543 -151.068448) (xy 109.251492 -150.984134)
			(xy 107.307888 -150.984134) (xy 107.307888 -152.244044) (xy 107.308319 -152.254111) (xy 107.316043 -152.272705)
			(xy 107.322874 -152.280112) (xy 107.700357 -152.657556) (xy 115.877086 -152.657556) (xy 115.877588 -152.630187)
			(xy 115.885398 -152.57601) (xy 115.900879 -152.523507) (xy 115.923712 -152.47376) (xy 115.953429 -152.427791)
			(xy 115.971066 -152.406858) (xy 115.977162 -152.399746) (xy 115.983512 -152.382728) (xy 115.983512 -152.297384)
			(xy 115.977162 -152.280366) (xy 115.971066 -152.273254) (xy 115.953433 -152.252317) (xy 115.923722 -152.206345)
			(xy 115.900885 -152.156599) (xy 115.885392 -152.104099) (xy 115.877562 -152.049925) (xy 115.877086 -152.022556)
			(xy 115.877537 -151.995304) (xy 115.885299 -151.941355) (xy 115.90066 -151.88906) (xy 115.923305 -151.839483)
			(xy 115.952776 -151.793633) (xy 115.988471 -151.752444) (xy 116.029664 -151.716753) (xy 116.075517 -151.687287)
			(xy 116.125096 -151.664646) (xy 116.177392 -151.649291) (xy 116.231342 -151.641534) (xy 116.258594 -151.641048)
			(xy 116.285965 -151.641506) (xy 116.340145 -151.649324) (xy 116.392648 -151.664814) (xy 116.442395 -151.687658)
			(xy 116.488361 -151.717385) (xy 116.509292 -151.735028) (xy 116.516404 -151.741124) (xy 116.533422 -151.747474)
			(xy 116.618766 -151.747474) (xy 116.635784 -151.741124) (xy 116.642896 -151.735028) (xy 116.663822 -151.717382)
			(xy 116.709796 -151.68767) (xy 116.759545 -151.664835) (xy 116.812047 -151.649346) (xy 116.866224 -151.64152)
			(xy 116.893594 -151.641048) (xy 116.922607 -151.64157) (xy 116.979966 -151.65034) (xy 117.035335 -151.667693)
			(xy 117.087439 -151.69323) (xy 117.135076 -151.726361) (xy 117.156484 -151.74595) (xy 117.163596 -151.752808)
			(xy 117.181376 -151.75992) (xy 117.271292 -151.75992) (xy 117.289072 -151.752808) (xy 117.296184 -151.74595)
			(xy 117.317594 -151.726366) (xy 117.365238 -151.693251) (xy 117.417343 -151.667723) (xy 117.472709 -151.650369)
			(xy 117.530063 -151.64159) (xy 117.559074 -151.641048) (xy 117.586444 -151.641518) (xy 117.640624 -151.649333)
			(xy 117.693127 -151.66482) (xy 117.742874 -151.687662) (xy 117.788841 -151.717386) (xy 117.809772 -151.735028)
			(xy 117.816884 -151.741124) (xy 117.833902 -151.747474) (xy 117.919246 -151.747474) (xy 117.936264 -151.741124)
			(xy 117.943376 -151.735028) (xy 117.964309 -151.717387) (xy 118.010277 -151.687663) (xy 118.060023 -151.664817)
			(xy 118.112525 -151.649321) (xy 118.166703 -151.641492) (xy 118.221445 -151.641492) (xy 118.275623 -151.649321)
			(xy 118.328125 -151.664817) (xy 118.377871 -151.687663) (xy 118.423839 -151.717387) (xy 118.444772 -151.735028)
			(xy 118.451884 -151.741124) (xy 118.468902 -151.747474) (xy 118.554246 -151.747474) (xy 118.571264 -151.741124)
			(xy 118.578376 -151.735028) (xy 118.599309 -151.717387) (xy 118.645277 -151.687663) (xy 118.695023 -151.664817)
			(xy 118.747525 -151.649321) (xy 118.801703 -151.641492) (xy 118.856445 -151.641492) (xy 118.910623 -151.649321)
			(xy 118.963125 -151.664817) (xy 119.012871 -151.687663) (xy 119.058839 -151.717387) (xy 119.079772 -151.735028)
			(xy 119.086884 -151.741124) (xy 119.103902 -151.747474) (xy 119.189246 -151.747474) (xy 119.206264 -151.741124)
			(xy 119.213376 -151.735028) (xy 119.23431 -151.717391) (xy 119.280282 -151.687678) (xy 119.330029 -151.664841)
			(xy 119.382529 -151.64935) (xy 119.436705 -151.641522) (xy 119.464074 -151.641048) (xy 119.491323 -151.641602)
			(xy 119.545266 -151.649354) (xy 119.597556 -151.664704) (xy 119.64713 -151.687339) (xy 119.692979 -151.716798)
			(xy 119.734168 -151.752482) (xy 119.76986 -151.793665) (xy 119.799328 -151.839508) (xy 119.821972 -151.889078)
			(xy 119.837331 -151.941366) (xy 119.845093 -151.995308) (xy 119.845582 -152.022556) (xy 119.845095 -152.049926)
			(xy 119.837283 -152.104104) (xy 119.821799 -152.156607) (xy 119.798962 -152.206354) (xy 119.769241 -152.252322)
			(xy 119.751602 -152.273254) (xy 119.745506 -152.280366) (xy 119.739156 -152.297384) (xy 119.739156 -152.382728)
			(xy 119.745506 -152.399746) (xy 119.751602 -152.406858) (xy 119.769235 -152.427795) (xy 119.798948 -152.473766)
			(xy 119.821785 -152.523513) (xy 119.837277 -152.576012) (xy 119.845107 -152.630187) (xy 119.845582 -152.657556)
			(xy 119.845104 -152.684809) (xy 119.837352 -152.738761) (xy 119.822 -152.79106) (xy 119.799361 -152.840642)
			(xy 119.769895 -152.886496) (xy 119.734203 -152.92769) (xy 119.693011 -152.963384) (xy 119.647157 -152.992852)
			(xy 119.597577 -153.015494) (xy 119.545278 -153.030848) (xy 119.491327 -153.038602) (xy 119.464074 -153.039064)
			(xy 119.436703 -153.038622) (xy 119.382522 -153.0308) (xy 119.330019 -153.015305) (xy 119.280272 -152.992458)
			(xy 119.234307 -152.962728) (xy 119.213376 -152.945084) (xy 119.206264 -152.938988) (xy 119.189246 -152.932638)
			(xy 119.103902 -152.932638) (xy 119.086884 -152.938988) (xy 119.079772 -152.945084) (xy 119.058839 -152.962725)
			(xy 119.012871 -152.992449) (xy 118.963125 -153.015295) (xy 118.910623 -153.030791) (xy 118.856445 -153.03862)
			(xy 118.801703 -153.03862) (xy 118.747525 -153.030791) (xy 118.695023 -153.015295) (xy 118.645277 -152.992449)
			(xy 118.599309 -152.962725) (xy 118.578376 -152.945084) (xy 118.571264 -152.938988) (xy 118.554246 -152.932638)
			(xy 118.468902 -152.932638) (xy 118.451884 -152.938988) (xy 118.444772 -152.945084) (xy 118.423839 -152.962725)
			(xy 118.377871 -152.992449) (xy 118.328125 -153.015295) (xy 118.275623 -153.030791) (xy 118.221445 -153.03862)
			(xy 118.166703 -153.03862) (xy 118.112525 -153.030791) (xy 118.060023 -153.015295) (xy 118.010277 -152.992449)
			(xy 117.964309 -152.962725) (xy 117.943376 -152.945084) (xy 117.936264 -152.938988) (xy 117.919246 -152.932638)
			(xy 117.833902 -152.932638) (xy 117.816884 -152.938988) (xy 117.809772 -152.945084) (xy 117.788822 -152.9627)
			(xy 117.742854 -152.992416) (xy 117.693111 -153.015257) (xy 117.640615 -153.030753) (xy 117.586442 -153.038587)
			(xy 117.559074 -153.039064) (xy 117.530061 -153.038558) (xy 117.472701 -153.029784) (xy 117.417332 -153.012427)
			(xy 117.365228 -152.986886) (xy 117.317592 -152.953752) (xy 117.296184 -152.934162) (xy 117.289072 -152.927304)
			(xy 117.271292 -152.920192) (xy 117.181376 -152.920192) (xy 117.163596 -152.927304) (xy 117.156484 -152.934162)
			(xy 117.135089 -152.953763) (xy 117.087441 -152.986876) (xy 117.035332 -153.0124) (xy 116.979963 -153.029749)
			(xy 116.922606 -153.038525) (xy 116.893594 -153.039064) (xy 116.866223 -153.03861) (xy 116.812043 -153.030791)
			(xy 116.75954 -153.015299) (xy 116.709793 -152.992455) (xy 116.663827 -152.962727) (xy 116.642896 -152.945084)
			(xy 116.635784 -152.938988) (xy 116.618766 -152.932638) (xy 116.533422 -152.932638) (xy 116.516404 -152.938988)
			(xy 116.509292 -152.945084) (xy 116.488372 -152.962738) (xy 116.442396 -152.992448) (xy 116.392645 -153.015281)
			(xy 116.340142 -153.030769) (xy 116.285964 -153.038593) (xy 116.258594 -153.039064) (xy 116.231339 -153.03865)
			(xy 116.177384 -153.030891) (xy 116.125083 -153.015532) (xy 116.075499 -152.992886) (xy 116.029644 -152.963413)
			(xy 115.988451 -152.927714) (xy 115.952757 -152.886516) (xy 115.92329 -152.840657) (xy 115.90065 -152.791071)
			(xy 115.885298 -152.738767) (xy 115.877546 -152.684811) (xy 115.877086 -152.657556) (xy 107.700357 -152.657556)
			(xy 109.794802 -154.751786) (xy 109.802147 -154.758598) (xy 109.820609 -154.766331) (xy 109.830616 -154.766772)
			(xy 121.991374 -154.766772) (xy 122.001363 -154.766239) (xy 122.019799 -154.758529) (xy 122.027188 -154.751786)
			(xy 126.170182 -150.608792) (xy 126.184663 -150.594981) (xy 126.217953 -150.572785) (xy 126.254938 -150.557522)
			(xy 126.294194 -150.549781) (xy 126.3142 -150.549356) (xy 131.060952 -150.549356) (xy 131.080955 -150.54982)
			(xy 131.120201 -150.557571) (xy 131.157184 -150.572823) (xy 131.190484 -150.594991) (xy 131.20497 -150.608792)
			(xy 132.404866 -151.808688) (xy 132.427726 -151.816308) (xy 132.439918 -151.814276) (xy 132.454681 -151.812115)
			(xy 132.484434 -151.809828) (xy 132.499354 -151.809704) (xy 132.526609 -151.810164) (xy 132.580564 -151.817916)
			(xy 132.632867 -151.833268) (xy 132.682452 -151.855908) (xy 132.72831 -151.885375) (xy 132.769507 -151.921069)
			(xy 132.805205 -151.962263) (xy 132.834676 -152.008118) (xy 132.85732 -152.057701) (xy 132.863483 -152.07869)
			(xy 134.023354 -152.07869) (xy 134.02384 -152.051439) (xy 134.031596 -151.997491) (xy 134.046951 -151.945196)
			(xy 134.069593 -151.895619) (xy 134.099059 -151.849769) (xy 134.13475 -151.808578) (xy 134.175941 -151.772887)
			(xy 134.221791 -151.743421) (xy 134.271368 -151.720779) (xy 134.323663 -151.705424) (xy 134.377611 -151.697668)
			(xy 134.432113 -151.697668) (xy 134.486061 -151.705424) (xy 134.538356 -151.720779) (xy 134.587933 -151.743421)
			(xy 134.633783 -151.772887) (xy 134.674974 -151.808578) (xy 134.710665 -151.849769) (xy 134.740131 -151.895619)
			(xy 134.762773 -151.945196) (xy 134.778128 -151.997491) (xy 134.785884 -152.051439) (xy 134.78637 -152.07869)
			(xy 134.785938 -152.104179) (xy 134.779161 -152.154704) (xy 134.765712 -152.203876) (xy 134.745833 -152.250818)
			(xy 134.719877 -152.294693) (xy 134.688307 -152.334719) (xy 134.670292 -152.352756) (xy 134.662418 -152.360376)
			(xy 134.654544 -152.380188) (xy 134.657338 -152.476454) (xy 134.666482 -152.495758) (xy 134.67461 -152.50287)
			(xy 134.695019 -152.52108) (xy 134.730949 -152.562319) (xy 134.760621 -152.608266) (xy 134.783427 -152.65798)
			(xy 134.7989 -152.710441) (xy 134.804508 -152.74925) (xy 135.34593 -152.74925) (xy 135.350001 -152.693628)
			(xy 135.362127 -152.639191) (xy 135.38205 -152.5871) (xy 135.409346 -152.538465) (xy 135.443432 -152.494322)
			(xy 135.483581 -152.455613) (xy 135.528939 -152.423162) (xy 135.578539 -152.397661) (xy 135.631323 -152.379654)
			(xy 135.686166 -152.369524) (xy 135.7419 -152.367487) (xy 135.797337 -152.373587) (xy 135.851294 -152.387693)
			(xy 135.902623 -152.409505) (xy 135.950229 -152.438559) (xy 135.993097 -152.474234) (xy 136.030314 -152.515771)
			(xy 136.061087 -152.562284) (xy 136.084759 -152.612781) (xy 136.100827 -152.666188) (xy 136.108947 -152.721364)
			(xy 136.109456 -152.74925) (xy 136.108947 -152.777136) (xy 136.100827 -152.832312) (xy 136.084759 -152.885719)
			(xy 136.061087 -152.936216) (xy 136.030314 -152.982729) (xy 135.993097 -153.024266) (xy 135.950229 -153.059941)
			(xy 135.902623 -153.088995) (xy 135.851294 -153.110807) (xy 135.797337 -153.124913) (xy 135.7419 -153.131013)
			(xy 135.686166 -153.128976) (xy 135.631323 -153.118846) (xy 135.578539 -153.100839) (xy 135.528939 -153.075338)
			(xy 135.483581 -153.042887) (xy 135.443432 -153.004178) (xy 135.409346 -152.960035) (xy 135.38205 -152.9114)
			(xy 135.362127 -152.859309) (xy 135.350001 -152.804872) (xy 135.34593 -152.74925) (xy 134.804508 -152.74925)
			(xy 134.806722 -152.764574) (xy 134.807198 -152.791922) (xy 134.806712 -152.819173) (xy 134.798956 -152.873121)
			(xy 134.783601 -152.925416) (xy 134.760959 -152.974993) (xy 134.731493 -153.020843) (xy 134.695802 -153.062034)
			(xy 134.654611 -153.097725) (xy 134.608761 -153.127191) (xy 134.559184 -153.149833) (xy 134.506889 -153.165188)
			(xy 134.452941 -153.172944) (xy 134.398439 -153.172944) (xy 134.344491 -153.165188) (xy 134.292196 -153.149833)
			(xy 134.242619 -153.127191) (xy 134.196769 -153.097725) (xy 134.155578 -153.062034) (xy 134.119887 -153.020843)
			(xy 134.090421 -152.974993) (xy 134.067779 -152.925416) (xy 134.052424 -152.873121) (xy 134.044668 -152.819173)
			(xy 134.044182 -152.791922) (xy 134.044637 -152.766434) (xy 134.051411 -152.71591) (xy 134.064856 -152.666739)
			(xy 134.084731 -152.619797) (xy 134.110683 -152.575922) (xy 134.142248 -152.535894) (xy 134.16026 -152.517856)
			(xy 134.168134 -152.510236) (xy 134.176008 -152.490424) (xy 134.173214 -152.394158) (xy 134.16407 -152.374854)
			(xy 134.155942 -152.367742) (xy 134.135549 -152.349514) (xy 134.099616 -152.30828) (xy 134.06994 -152.262337)
			(xy 134.047131 -152.212627) (xy 134.031655 -152.160168) (xy 134.023831 -152.106037) (xy 134.023354 -152.07869)
			(xy 132.863483 -152.07869) (xy 132.872677 -152.110003) (xy 132.880433 -152.163957) (xy 132.880862 -152.191212)
			(xy 132.88019 -152.222732) (xy 132.869785 -152.284909) (xy 132.849309 -152.344532) (xy 132.834888 -152.372568)
			(xy 132.830062 -152.381712) (xy 132.82803 -152.40127) (xy 132.853684 -152.489408) (xy 132.86613 -152.504902)
			(xy 132.87502 -152.509982) (xy 132.878068 -152.511506) (xy 132.878576 -152.51176) (xy 132.882894 -152.5143)
			(xy 132.8928 -152.519888) (xy 132.91439 -152.52192) (xy 133.008878 -152.488392) (xy 133.024626 -152.472898)
			(xy 133.02869 -152.46223) (xy 133.039412 -152.43548) (xy 133.06774 -152.385296) (xy 133.103293 -152.339943)
			(xy 133.145262 -152.300451) (xy 133.192692 -152.26772) (xy 133.244505 -152.242494) (xy 133.299522 -152.225345)
			(xy 133.356492 -152.216665) (xy 133.385306 -152.216104) (xy 133.412556 -152.216591) (xy 133.466501 -152.224348)
			(xy 133.518794 -152.239703) (xy 133.568369 -152.262344) (xy 133.614217 -152.291809) (xy 133.655405 -152.327499)
			(xy 133.691095 -152.368688) (xy 133.720559 -152.414537) (xy 133.743199 -152.464112) (xy 133.758554 -152.516404)
			(xy 133.76631 -152.57035) (xy 133.76631 -152.62485) (xy 133.758554 -152.678796) (xy 133.743199 -152.731088)
			(xy 133.720559 -152.780663) (xy 133.691095 -152.826512) (xy 133.655405 -152.867701) (xy 133.614217 -152.903391)
			(xy 133.568369 -152.932856) (xy 133.518794 -152.955497) (xy 133.466501 -152.970852) (xy 133.412556 -152.978609)
			(xy 133.385306 -152.97912) (xy 133.360073 -152.978709) (xy 133.310047 -152.972059) (xy 133.261331 -152.958887)
			(xy 133.21477 -152.939421) (xy 133.192774 -152.92705) (xy 133.182868 -152.921208) (xy 133.161024 -152.919176)
			(xy 133.066282 -152.952704) (xy 133.050534 -152.968198) (xy 133.04647 -152.978866) (xy 133.035749 -153.005618)
			(xy 133.007423 -153.055808) (xy 132.971871 -153.101168) (xy 132.929904 -153.140666) (xy 132.882474 -153.173404)
			(xy 132.830661 -153.198639) (xy 132.775642 -153.215796) (xy 132.71867 -153.224485) (xy 132.689854 -153.224992)
			(xy 132.662605 -153.224503) (xy 132.608664 -153.216741) (xy 132.556375 -153.201381) (xy 132.506805 -153.178737)
			(xy 132.460961 -153.14927) (xy 132.419778 -153.113578) (xy 132.384093 -153.072389) (xy 132.354633 -153.026541)
			(xy 132.331997 -152.976967) (xy 132.316646 -152.924676) (xy 132.308893 -152.870733) (xy 132.308346 -152.843484)
			(xy 132.309019 -152.811964) (xy 132.319424 -152.749788) (xy 132.339901 -152.690165) (xy 132.35432 -152.662128)
			(xy 132.359146 -152.652984) (xy 132.361178 -152.633426) (xy 132.335524 -152.545288) (xy 132.323078 -152.529794)
			(xy 132.314188 -152.524714) (xy 132.289096 -152.510158) (xy 132.243233 -152.47464) (xy 132.203273 -152.43259)
			(xy 132.170138 -152.384977) (xy 132.14459 -152.332898) (xy 132.127218 -152.277553) (xy 132.118423 -152.220216)
			(xy 132.117846 -152.191212) (xy 132.11797 -152.176292) (xy 132.120256 -152.146539) (xy 132.122418 -152.131776)
			(xy 132.12445 -152.119584) (xy 132.11683 -152.096724) (xy 130.99161 -150.97125) (xy 130.984214 -150.964397)
			(xy 130.965616 -150.956651) (xy 130.955542 -150.956264) (xy 126.416054 -150.956264) (xy 126.407701 -150.957192)
			(xy 126.392265 -150.963814) (xy 126.385828 -150.969218) (xy 122.889558 -154.465274) (xy 128.331722 -154.465274)
			(xy 128.332231 -154.437701) (xy 128.340174 -154.38313) (xy 128.35589 -154.33027) (xy 128.379051 -154.280224)
			(xy 128.409177 -154.234033) (xy 128.445638 -154.192661) (xy 128.466342 -154.174444) (xy 128.474443 -154.166826)
			(xy 128.483805 -154.146686) (xy 128.484376 -154.135582) (xy 128.484376 -154.058366) (xy 128.483851 -154.047251)
			(xy 128.474483 -154.027092) (xy 128.466342 -154.019504) (xy 128.445609 -154.001318) (xy 128.409141 -153.959944)
			(xy 128.379012 -153.913751) (xy 128.355848 -153.8637) (xy 128.340133 -153.810835) (xy 128.332193 -153.756259)
			(xy 128.332196 -153.701108) (xy 128.34014 -153.646532) (xy 128.35586 -153.593669) (xy 128.379028 -153.54362)
			(xy 128.409162 -153.497429) (xy 128.445633 -153.456059) (xy 128.466342 -153.437844) (xy 128.474443 -153.430226)
			(xy 128.483805 -153.410086) (xy 128.484376 -153.398982) (xy 128.484376 -153.321766) (xy 128.483851 -153.310651)
			(xy 128.474483 -153.290492) (xy 128.466342 -153.282904) (xy 128.445638 -153.264685) (xy 128.409165 -153.223319)
			(xy 128.379031 -153.177131) (xy 128.355864 -153.127084) (xy 128.340147 -153.074223) (xy 128.332207 -153.019648)
			(xy 128.331722 -152.992074) (xy 128.332131 -152.964819) (xy 128.339892 -152.910865) (xy 128.355253 -152.858564)
			(xy 128.377901 -152.808982) (xy 128.407374 -152.763127) (xy 128.443074 -152.721934) (xy 128.484272 -152.686241)
			(xy 128.530131 -152.656774) (xy 128.579716 -152.634133) (xy 128.632019 -152.61878) (xy 128.685975 -152.611027)
			(xy 128.71323 -152.610566) (xy 128.741085 -152.611087) (xy 128.796199 -152.619214) (xy 128.849548 -152.635262)
			(xy 128.9 -152.65889) (xy 128.946483 -152.689597) (xy 128.988012 -152.726732) (xy 129.023706 -152.769506)
			(xy 129.052806 -152.817012) (xy 129.074696 -152.868242) (xy 129.082292 -152.895046) (xy 129.084578 -152.903936)
			(xy 129.095246 -152.919176) (xy 129.167128 -152.966928) (xy 129.185162 -152.970992) (xy 129.194306 -152.969722)
			(xy 129.207323 -152.968054) (xy 129.233507 -152.966273) (xy 129.24663 -152.966166) (xy 129.260779 -152.966257)
			(xy 129.289002 -152.968293) (xy 129.303018 -152.97023) (xy 129.313178 -152.971754) (xy 129.332736 -152.966928)
			(xy 129.407158 -152.911048) (xy 129.417318 -152.893522) (xy 129.418588 -152.883362) (xy 129.422677 -152.856208)
			(xy 129.437649 -152.803378) (xy 129.46004 -152.753239) (xy 129.489387 -152.706828) (xy 129.525085 -152.665104)
			(xy 129.566394 -152.628927) (xy 129.612463 -152.599046) (xy 129.66234 -152.576077) (xy 129.714994 -152.560496)
			(xy 129.769338 -152.552624) (xy 129.796794 -152.552146) (xy 129.824043 -152.552683) (xy 129.877987 -152.560438)
			(xy 129.930277 -152.57579) (xy 129.979852 -152.598427) (xy 130.0257 -152.627888) (xy 130.066889 -152.663574)
			(xy 130.102581 -152.704758) (xy 130.132048 -152.750603) (xy 130.154692 -152.800174) (xy 130.170051 -152.852463)
			(xy 130.177813 -152.906405) (xy 130.178302 -152.933654) (xy 130.177804 -152.961227) (xy 130.169858 -153.015799)
			(xy 130.154139 -153.068658) (xy 130.130975 -153.118704) (xy 130.100849 -153.164894) (xy 130.064387 -153.206267)
			(xy 130.043682 -153.224484) (xy 130.035573 -153.232095) (xy 130.026214 -153.25224) (xy 130.025648 -153.263346)
			(xy 130.025648 -153.340562) (xy 130.026206 -153.351673) (xy 130.03555 -153.371833) (xy 130.043682 -153.379424)
			(xy 130.064404 -153.397623) (xy 130.100875 -153.438994) (xy 130.131006 -153.485186) (xy 130.15417 -153.535237)
			(xy 130.169883 -153.588102) (xy 130.177819 -153.642678) (xy 130.177853 -153.6446) (xy 134.76681 -153.6446)
			(xy 134.770881 -153.588978) (xy 134.783007 -153.534541) (xy 134.80293 -153.48245) (xy 134.830226 -153.433815)
			(xy 134.864312 -153.389672) (xy 134.904461 -153.350963) (xy 134.949819 -153.318512) (xy 134.999419 -153.293011)
			(xy 135.052203 -153.275004) (xy 135.107046 -153.264874) (xy 135.16278 -153.262837) (xy 135.218217 -153.268937)
			(xy 135.272174 -153.283043) (xy 135.323503 -153.304855) (xy 135.371109 -153.333909) (xy 135.413977 -153.369584)
			(xy 135.451194 -153.411121) (xy 135.481967 -153.457634) (xy 135.505639 -153.508131) (xy 135.521707 -153.561538)
			(xy 135.529827 -153.616714) (xy 135.530336 -153.6446) (xy 135.529827 -153.672486) (xy 135.521707 -153.727662)
			(xy 135.505639 -153.781069) (xy 135.481967 -153.831566) (xy 135.451194 -153.878079) (xy 135.413977 -153.919616)
			(xy 135.371109 -153.955291) (xy 135.323503 -153.984345) (xy 135.272174 -154.006157) (xy 135.218217 -154.020263)
			(xy 135.16278 -154.026363) (xy 135.107046 -154.024326) (xy 135.052203 -154.014196) (xy 134.999419 -153.996189)
			(xy 134.949819 -153.970688) (xy 134.904461 -153.938237) (xy 134.864312 -153.899528) (xy 134.830226 -153.855385)
			(xy 134.80293 -153.80675) (xy 134.783007 -153.754659) (xy 134.770881 -153.700222) (xy 134.76681 -153.6446)
			(xy 130.177853 -153.6446) (xy 130.178302 -153.670254) (xy 130.177802 -153.697506) (xy 130.170051 -153.751456)
			(xy 130.154701 -153.803753) (xy 130.132063 -153.853334) (xy 130.102599 -153.899187) (xy 130.066909 -153.940381)
			(xy 130.02572 -153.976075) (xy 129.979869 -154.005544) (xy 129.930291 -154.028187) (xy 129.877995 -154.043543)
			(xy 129.824046 -154.051299) (xy 129.796794 -154.051762) (xy 129.762504 -154.050238) (xy 129.752344 -154.049222)
			(xy 129.73304 -154.055318) (xy 129.662428 -154.1145) (xy 129.65303 -154.132534) (xy 129.652014 -154.142694)
			(xy 129.649102 -154.170872) (xy 129.635921 -154.225965) (xy 129.614737 -154.278502) (xy 129.586014 -154.327328)
			(xy 129.550385 -154.371368) (xy 129.508633 -154.409654) (xy 129.461678 -154.441342) (xy 129.410552 -154.465737)
			(xy 129.35638 -154.482301) (xy 129.300354 -154.49067) (xy 129.27203 -154.491182) (xy 129.254011 -154.490966)
			(xy 129.218136 -154.487528) (xy 129.200402 -154.484324) (xy 129.191004 -154.482546) (xy 129.171954 -154.486356)
			(xy 129.09677 -154.534108) (xy 129.08534 -154.549856) (xy 129.083054 -154.559254) (xy 129.075689 -154.586308)
			(xy 129.054056 -154.638036) (xy 129.025088 -154.686042) (xy 128.989409 -154.729294) (xy 128.947785 -154.766861)
			(xy 128.901113 -154.797934) (xy 128.850398 -154.821844) (xy 128.79673 -154.838078) (xy 128.741265 -154.846285)
			(xy 128.71323 -154.846782) (xy 128.685977 -154.846317) (xy 128.632024 -154.838563) (xy 128.579725 -154.82321)
			(xy 128.530143 -154.800569) (xy 128.484289 -154.771101) (xy 128.443095 -154.735408) (xy 128.407401 -154.694214)
			(xy 128.377933 -154.64836) (xy 128.355292 -154.598779) (xy 128.339938 -154.546479) (xy 128.332184 -154.492527)
			(xy 128.331722 -154.465274) (xy 122.889558 -154.465274) (xy 122.240548 -155.114244) (xy 122.240548 -155.114498)
			(xy 122.226049 -155.128301) (xy 122.19277 -155.150539) (xy 122.155795 -155.165864) (xy 122.116542 -155.17369)
			(xy 122.09653 -155.174188) (xy 109.72546 -155.174188) (xy 109.705442 -155.173734) (xy 109.666174 -155.165926)
			(xy 109.629187 -155.1506) (xy 109.595905 -155.128346) (xy 109.581442 -155.114498) (xy 109.581442 -155.114244)
			(xy 106.960416 -152.493472) (xy 106.946607 -152.478991) (xy 106.924416 -152.4457) (xy 106.909159 -152.408714)
			(xy 106.901426 -152.36946) (xy 106.90098 -152.349454) (xy 106.90098 -141.878558) (xy 106.900549 -141.868492)
			(xy 106.892821 -141.8499) (xy 106.885994 -141.84249) (xy 104.762554 -139.71905) (xy 104.755155 -139.712205)
			(xy 104.736557 -139.70448) (xy 104.726486 -139.704064) (xy 104.455468 -139.704064) (xy 104.445424 -139.704493)
			(xy 104.426875 -139.712204) (xy 104.412697 -139.726435) (xy 104.408478 -139.73556) (xy 104.402636 -139.750038)
			(xy 104.408478 -139.779756) (xy 106.181652 -141.55293) (xy 106.195463 -141.56741) (xy 106.217657 -141.6007)
			(xy 106.232916 -141.637686) (xy 106.24065 -141.676942) (xy 106.241088 -141.696948) (xy 106.241088 -155.94076)
			(xy 129.92354 -155.94076) (xy 129.924033 -155.913186) (xy 129.931978 -155.858614) (xy 129.947697 -155.805754)
			(xy 129.970862 -155.755708) (xy 130.00099 -155.709517) (xy 130.037454 -155.668146) (xy 130.05816 -155.64993)
			(xy 130.06627 -155.64232) (xy 130.075626 -155.622174) (xy 130.076194 -155.611068) (xy 130.076194 -155.533852)
			(xy 130.075614 -155.522744) (xy 130.066284 -155.502585) (xy 130.05816 -155.49499) (xy 130.037433 -155.476797)
			(xy 130.000965 -155.435423) (xy 129.970836 -155.389229) (xy 129.947674 -155.339178) (xy 129.93196 -155.286313)
			(xy 129.924024 -155.231736) (xy 129.92354 -155.20416) (xy 129.923989 -155.177973) (xy 129.93117 -155.126093)
			(xy 129.945377 -155.075683) (xy 129.966344 -155.027688) (xy 129.993677 -154.983012) (xy 130.026862 -154.942493)
			(xy 130.065276 -154.906892) (xy 130.108198 -154.876878) (xy 130.131312 -154.864562) (xy 130.140456 -154.859736)
			(xy 130.153664 -154.843988) (xy 130.180842 -154.754072) (xy 130.178556 -154.733752) (xy 130.173476 -154.724608)
			(xy 130.158585 -154.696638) (xy 130.137512 -154.636883) (xy 130.126844 -154.574425) (xy 130.126232 -154.542744)
			(xy 130.126675 -154.516125) (xy 130.134247 -154.463428) (xy 130.149242 -154.412346) (xy 130.171355 -154.363918)
			(xy 130.200137 -154.31913) (xy 130.235 -154.278896) (xy 130.275235 -154.244033) (xy 130.320023 -154.215252)
			(xy 130.368451 -154.19314) (xy 130.419534 -154.178145) (xy 130.472231 -154.170575) (xy 130.49885 -154.170126)
			(xy 130.525272 -154.170572) (xy 130.577587 -154.178028) (xy 130.628325 -154.192796) (xy 130.676469 -154.214582)
			(xy 130.721054 -154.242948) (xy 130.74142 -154.259788) (xy 130.748278 -154.265884) (xy 130.765296 -154.27198)
			(xy 130.849624 -154.27198) (xy 130.866642 -154.265884) (xy 130.8735 -154.259788) (xy 130.893866 -154.242949)
			(xy 130.938452 -154.214584) (xy 130.986596 -154.192797) (xy 131.037333 -154.178026) (xy 131.089648 -154.170566)
			(xy 131.142492 -154.170566) (xy 131.194807 -154.178026) (xy 131.245544 -154.192797) (xy 131.293688 -154.214584)
			(xy 131.338274 -154.242949) (xy 131.35864 -154.259788) (xy 131.365498 -154.265884) (xy 131.382516 -154.27198)
			(xy 131.466844 -154.27198) (xy 131.483862 -154.265884) (xy 131.49072 -154.259788) (xy 131.511077 -154.242939)
			(xy 131.555669 -154.214586) (xy 131.603816 -154.192809) (xy 131.654554 -154.178044) (xy 131.706869 -154.170586)
			(xy 131.73329 -154.170126) (xy 131.761181 -154.170532) (xy 131.816339 -154.178845) (xy 131.869642 -154.195285)
			(xy 131.919899 -154.219487) (xy 131.965988 -154.250909) (xy 132.006879 -154.288849) (xy 132.041659 -154.33246)
			(xy 132.06955 -154.380767) (xy 132.089929 -154.432692) (xy 132.102342 -154.487075) (xy 132.106511 -154.5427)
			(xy 132.102342 -154.598325) (xy 132.089929 -154.652708) (xy 132.06955 -154.704633) (xy 132.041659 -154.75294)
			(xy 132.006879 -154.796551) (xy 131.965988 -154.834491) (xy 131.919899 -154.865913) (xy 131.869642 -154.890115)
			(xy 131.816339 -154.906555) (xy 131.761181 -154.914868) (xy 131.73329 -154.915362) (xy 131.706869 -154.914895)
			(xy 131.654554 -154.907445) (xy 131.603816 -154.892682) (xy 131.555672 -154.8709) (xy 131.511086 -154.842538)
			(xy 131.49072 -154.8257) (xy 131.483862 -154.819604) (xy 131.466844 -154.813508) (xy 131.382516 -154.813508)
			(xy 131.365498 -154.819604) (xy 131.35864 -154.8257) (xy 131.338274 -154.842539) (xy 131.293688 -154.870904)
			(xy 131.245544 -154.892691) (xy 131.194807 -154.907462) (xy 131.142492 -154.914922) (xy 131.089648 -154.914922)
			(xy 131.037333 -154.907462) (xy 130.986596 -154.892691) (xy 130.938452 -154.870904) (xy 130.893866 -154.842539)
			(xy 130.8735 -154.8257) (xy 130.866642 -154.819604) (xy 130.849624 -154.813508) (xy 130.765296 -154.813508)
			(xy 130.748278 -154.819604) (xy 130.74142 -154.8257) (xy 130.725853 -154.838706) (xy 130.692378 -154.861619)
			(xy 130.674618 -154.87142) (xy 130.665474 -154.876246) (xy 130.65252 -154.892248) (xy 130.626866 -154.982672)
			(xy 130.629406 -155.002992) (xy 130.63474 -155.012136) (xy 130.647068 -155.034075) (xy 130.666446 -155.08052)
			(xy 130.679551 -155.129108) (xy 130.686158 -155.178997) (xy 130.686556 -155.20416) (xy 130.686078 -155.231734)
			(xy 130.67813 -155.286307) (xy 130.662409 -155.339168) (xy 130.639241 -155.389214) (xy 130.60911 -155.435404)
			(xy 130.572643 -155.476775) (xy 130.551936 -155.49499) (xy 130.543816 -155.502591) (xy 130.534968 -155.52166)
			(xy 135.725662 -155.52166) (xy 135.726138 -155.493749) (xy 135.734277 -155.438522) (xy 135.750377 -155.385072)
			(xy 135.774094 -155.334537) (xy 135.80492 -155.287998) (xy 135.823198 -155.266898) (xy 135.829548 -155.259786)
			(xy 135.836152 -155.242514) (xy 135.836152 -155.155392) (xy 135.829548 -155.13812) (xy 135.823198 -155.131008)
			(xy 135.804902 -155.109923) (xy 135.774077 -155.063381) (xy 135.750365 -155.012842) (xy 135.734273 -154.959388)
			(xy 135.726144 -154.904158) (xy 135.725662 -154.876246) (xy 135.726148 -154.848995) (xy 135.733904 -154.795047)
			(xy 135.749259 -154.742752) (xy 135.771901 -154.693175) (xy 135.801367 -154.647325) (xy 135.837058 -154.606134)
			(xy 135.878249 -154.570443) (xy 135.924099 -154.540977) (xy 135.973676 -154.518335) (xy 136.025971 -154.50298)
			(xy 136.079919 -154.495224) (xy 136.134421 -154.495224) (xy 136.188369 -154.50298) (xy 136.240664 -154.518335)
			(xy 136.290241 -154.540977) (xy 136.336091 -154.570443) (xy 136.377282 -154.606134) (xy 136.412973 -154.647325)
			(xy 136.442439 -154.693175) (xy 136.465081 -154.742752) (xy 136.480436 -154.795047) (xy 136.488192 -154.848995)
			(xy 136.488678 -154.876246) (xy 136.488196 -154.904157) (xy 136.480056 -154.959383) (xy 136.463957 -155.012833)
			(xy 136.440243 -155.063367) (xy 136.409418 -155.109907) (xy 136.391142 -155.131008) (xy 136.384792 -155.13812)
			(xy 136.378188 -155.155392) (xy 136.378188 -155.242514) (xy 136.384792 -155.259786) (xy 136.391142 -155.266898)
			(xy 136.4094 -155.288014) (xy 136.440229 -155.334549) (xy 136.463947 -155.385079) (xy 136.480049 -155.438527)
			(xy 136.488189 -155.49375) (xy 136.488678 -155.52166) (xy 136.488192 -155.548911) (xy 136.480436 -155.602859)
			(xy 136.465081 -155.655154) (xy 136.442439 -155.704731) (xy 136.412973 -155.750581) (xy 136.377282 -155.791772)
			(xy 136.336091 -155.827463) (xy 136.290241 -155.856929) (xy 136.240664 -155.879571) (xy 136.188369 -155.894926)
			(xy 136.134421 -155.902682) (xy 136.079919 -155.902682) (xy 136.025971 -155.894926) (xy 135.973676 -155.879571)
			(xy 135.924099 -155.856929) (xy 135.878249 -155.827463) (xy 135.837058 -155.791772) (xy 135.801367 -155.750581)
			(xy 135.771901 -155.704731) (xy 135.749259 -155.655154) (xy 135.733904 -155.602859) (xy 135.726148 -155.548911)
			(xy 135.725662 -155.52166) (xy 130.534968 -155.52166) (xy 130.534465 -155.522744) (xy 130.533902 -155.533852)
			(xy 130.533902 -155.611068) (xy 130.534471 -155.622178) (xy 130.543809 -155.642336) (xy 130.551936 -155.64993)
			(xy 130.572672 -155.668114) (xy 130.609139 -155.709489) (xy 130.639267 -155.755685) (xy 130.662428 -155.805738)
			(xy 130.67814 -155.858605) (xy 130.686074 -155.913184) (xy 130.686556 -155.94076) (xy 130.68607 -155.968011)
			(xy 130.678314 -156.021959) (xy 130.662959 -156.074254) (xy 130.640317 -156.123831) (xy 130.610851 -156.169681)
			(xy 130.57516 -156.210872) (xy 130.533969 -156.246563) (xy 130.488119 -156.276029) (xy 130.438542 -156.298671)
			(xy 130.386247 -156.314026) (xy 130.332299 -156.321782) (xy 130.277797 -156.321782) (xy 130.223849 -156.314026)
			(xy 130.171554 -156.298671) (xy 130.121977 -156.276029) (xy 130.076127 -156.246563) (xy 130.034936 -156.210872)
			(xy 129.999245 -156.169681) (xy 129.969779 -156.123831) (xy 129.947137 -156.074254) (xy 129.931782 -156.021959)
			(xy 129.924026 -155.968011) (xy 129.92354 -155.94076) (xy 106.241088 -155.94076) (xy 106.241088 -156.42082)
			(xy 106.241514 -156.430889) (xy 106.249232 -156.449489) (xy 106.256074 -156.456888) (xy 109.808518 -160.009078)
			(xy 109.815863 -160.015888) (xy 109.834326 -160.023617) (xy 109.844332 -160.024064) (xy 123.416314 -160.024064)
			(xy 123.436333 -160.024516) (xy 123.475602 -160.032321) (xy 123.51259 -160.047646) (xy 123.545872 -160.069903)
			(xy 123.560332 -160.083754) (xy 123.580398 -160.104074) (xy 123.946666 -160.470088) (xy 123.969526 -160.477708)
			(xy 123.981718 -160.475676) (xy 123.996481 -160.473515) (xy 124.026234 -160.471228) (xy 124.041154 -160.471104)
			(xy 124.068409 -160.471564) (xy 124.122364 -160.479316) (xy 124.174667 -160.494668) (xy 124.224252 -160.517308)
			(xy 124.27011 -160.546775) (xy 124.311307 -160.582469) (xy 124.347005 -160.623663) (xy 124.376476 -160.669518)
			(xy 124.39912 -160.719101) (xy 124.403791 -160.73501) (xy 125.549914 -160.73501) (xy 125.5504 -160.707759)
			(xy 125.558156 -160.653811) (xy 125.573511 -160.601516) (xy 125.596153 -160.551939) (xy 125.625619 -160.506089)
			(xy 125.66131 -160.464898) (xy 125.702501 -160.429207) (xy 125.748351 -160.399741) (xy 125.797928 -160.377099)
			(xy 125.850223 -160.361744) (xy 125.904171 -160.353988) (xy 125.958673 -160.353988) (xy 126.012621 -160.361744)
			(xy 126.064916 -160.377099) (xy 126.114493 -160.399741) (xy 126.160343 -160.429207) (xy 126.201534 -160.464898)
			(xy 126.237225 -160.506089) (xy 126.266691 -160.551939) (xy 126.289333 -160.601516) (xy 126.304688 -160.653811)
			(xy 126.312444 -160.707759) (xy 126.31293 -160.73501) (xy 126.312484 -160.761804) (xy 126.304979 -160.814864)
			(xy 126.290129 -160.866354) (xy 126.268229 -160.915263) (xy 126.239707 -160.960631) (xy 126.22276 -160.98139)
			(xy 126.216664 -160.988502) (xy 126.210568 -161.00552) (xy 126.212092 -161.091372) (xy 126.21895 -161.108136)
			(xy 126.2253 -161.115248) (xy 126.243886 -161.136439) (xy 126.275271 -161.183257) (xy 126.299425 -161.234183)
			(xy 126.315825 -161.288108) (xy 126.324111 -161.34386) (xy 126.324614 -161.372042) (xy 126.324128 -161.399293)
			(xy 126.322495 -161.41065) (xy 126.88773 -161.41065) (xy 126.891801 -161.355028) (xy 126.903927 -161.300591)
			(xy 126.92385 -161.2485) (xy 126.951146 -161.199865) (xy 126.985232 -161.155722) (xy 127.025381 -161.117013)
			(xy 127.070739 -161.084562) (xy 127.120339 -161.059061) (xy 127.173123 -161.041054) (xy 127.227966 -161.030924)
			(xy 127.2837 -161.028887) (xy 127.339137 -161.034987) (xy 127.393094 -161.049093) (xy 127.444423 -161.070905)
			(xy 127.492029 -161.099959) (xy 127.534897 -161.135634) (xy 127.572114 -161.177171) (xy 127.602887 -161.223684)
			(xy 127.626559 -161.274181) (xy 127.642627 -161.327588) (xy 127.650747 -161.382764) (xy 127.651256 -161.41065)
			(xy 127.650747 -161.438536) (xy 127.642627 -161.493712) (xy 127.626559 -161.547119) (xy 127.602887 -161.597616)
			(xy 127.572114 -161.644129) (xy 127.534897 -161.685666) (xy 127.492029 -161.721341) (xy 127.444423 -161.750395)
			(xy 127.393094 -161.772207) (xy 127.339137 -161.786313) (xy 127.2837 -161.792413) (xy 127.227966 -161.790376)
			(xy 127.173123 -161.780246) (xy 127.120339 -161.762239) (xy 127.070739 -161.736738) (xy 127.025381 -161.704287)
			(xy 126.985232 -161.665578) (xy 126.951146 -161.621435) (xy 126.92385 -161.5728) (xy 126.903927 -161.520709)
			(xy 126.891801 -161.466272) (xy 126.88773 -161.41065) (xy 126.322495 -161.41065) (xy 126.316372 -161.453241)
			(xy 126.301017 -161.505536) (xy 126.278375 -161.555113) (xy 126.248909 -161.600963) (xy 126.213218 -161.642154)
			(xy 126.172027 -161.677845) (xy 126.126177 -161.707311) (xy 126.0766 -161.729953) (xy 126.024305 -161.745308)
			(xy 125.970357 -161.753064) (xy 125.915855 -161.753064) (xy 125.861907 -161.745308) (xy 125.809612 -161.729953)
			(xy 125.760035 -161.707311) (xy 125.714185 -161.677845) (xy 125.672994 -161.642154) (xy 125.637303 -161.600963)
			(xy 125.607837 -161.555113) (xy 125.585195 -161.505536) (xy 125.56984 -161.453241) (xy 125.562084 -161.399293)
			(xy 125.561598 -161.372042) (xy 125.562067 -161.345249) (xy 125.569567 -161.292189) (xy 125.58441 -161.240699)
			(xy 125.606306 -161.19179) (xy 125.634823 -161.146422) (xy 125.651768 -161.125662) (xy 125.657864 -161.11855)
			(xy 125.66396 -161.101532) (xy 125.662436 -161.01568) (xy 125.655578 -160.998916) (xy 125.649228 -160.991804)
			(xy 125.630608 -160.970642) (xy 125.59923 -160.923815) (xy 125.575084 -160.872882) (xy 125.558692 -160.81895)
			(xy 125.550413 -160.763194) (xy 125.549914 -160.73501) (xy 124.403791 -160.73501) (xy 124.414477 -160.771403)
			(xy 124.422233 -160.825357) (xy 124.422662 -160.852612) (xy 124.42199 -160.884132) (xy 124.411585 -160.946309)
			(xy 124.391109 -161.005932) (xy 124.376688 -161.033968) (xy 124.371862 -161.043112) (xy 124.36983 -161.06267)
			(xy 124.395484 -161.150808) (xy 124.40793 -161.166302) (xy 124.41682 -161.171382) (xy 124.419868 -161.172906)
			(xy 124.420376 -161.17316) (xy 124.424694 -161.1757) (xy 124.4346 -161.181288) (xy 124.45619 -161.18332)
			(xy 124.550678 -161.149792) (xy 124.566426 -161.134298) (xy 124.57049 -161.12363) (xy 124.581212 -161.09688)
			(xy 124.60954 -161.046696) (xy 124.645093 -161.001343) (xy 124.687062 -160.961851) (xy 124.734492 -160.92912)
			(xy 124.786305 -160.903894) (xy 124.841322 -160.886745) (xy 124.898292 -160.878065) (xy 124.927106 -160.877504)
			(xy 124.954356 -160.877991) (xy 125.008301 -160.885748) (xy 125.060594 -160.901103) (xy 125.110169 -160.923744)
			(xy 125.156017 -160.953209) (xy 125.197205 -160.988899) (xy 125.232895 -161.030088) (xy 125.262359 -161.075937)
			(xy 125.284999 -161.125512) (xy 125.300354 -161.177804) (xy 125.30811 -161.23175) (xy 125.30811 -161.28625)
			(xy 125.300354 -161.340196) (xy 125.284999 -161.392488) (xy 125.262359 -161.442063) (xy 125.232895 -161.487912)
			(xy 125.197205 -161.529101) (xy 125.156017 -161.564791) (xy 125.110169 -161.594256) (xy 125.060594 -161.616897)
			(xy 125.008301 -161.632252) (xy 124.954356 -161.640009) (xy 124.927106 -161.64052) (xy 124.901873 -161.640109)
			(xy 124.851847 -161.633459) (xy 124.803131 -161.620287) (xy 124.75657 -161.600821) (xy 124.734574 -161.58845)
			(xy 124.724668 -161.582608) (xy 124.702824 -161.580576) (xy 124.608082 -161.614104) (xy 124.592334 -161.629598)
			(xy 124.58827 -161.640266) (xy 124.577549 -161.667018) (xy 124.549223 -161.717208) (xy 124.513671 -161.762568)
			(xy 124.471704 -161.802066) (xy 124.424274 -161.834804) (xy 124.372461 -161.860039) (xy 124.317442 -161.877196)
			(xy 124.26047 -161.885885) (xy 124.231654 -161.886392) (xy 124.204405 -161.885903) (xy 124.150464 -161.878141)
			(xy 124.098175 -161.862781) (xy 124.048605 -161.840137) (xy 124.002761 -161.81067) (xy 123.961578 -161.774978)
			(xy 123.925893 -161.733789) (xy 123.896433 -161.687941) (xy 123.873797 -161.638367) (xy 123.858446 -161.586076)
			(xy 123.850693 -161.532133) (xy 123.850146 -161.504884) (xy 123.850819 -161.473364) (xy 123.861224 -161.411188)
			(xy 123.881701 -161.351565) (xy 123.89612 -161.323528) (xy 123.900946 -161.314384) (xy 123.902978 -161.294826)
			(xy 123.877324 -161.206688) (xy 123.864878 -161.191194) (xy 123.855988 -161.186114) (xy 123.830896 -161.171558)
			(xy 123.785033 -161.13604) (xy 123.745073 -161.09399) (xy 123.711938 -161.046377) (xy 123.68639 -160.994298)
			(xy 123.669018 -160.938953) (xy 123.660223 -160.881616) (xy 123.659646 -160.852612) (xy 123.65977 -160.837692)
			(xy 123.662056 -160.807939) (xy 123.664218 -160.793176) (xy 123.66625 -160.780984) (xy 123.65863 -160.758124)
			(xy 123.346972 -160.446466) (xy 123.339628 -160.439653) (xy 123.321165 -160.43192) (xy 123.311158 -160.43148)
			(xy 109.739176 -160.43148) (xy 109.719157 -160.431027) (xy 109.679888 -160.423222) (xy 109.642899 -160.407898)
			(xy 109.609615 -160.385644) (xy 109.595158 -160.37179) (xy 109.595158 -160.371536) (xy 105.893616 -156.670248)
			(xy 105.879801 -156.655769) (xy 105.857598 -156.62248) (xy 105.842327 -156.585495) (xy 105.834579 -156.546238)
			(xy 105.83418 -156.52623) (xy 105.83418 -141.802358) (xy 105.833749 -141.792292) (xy 105.826021 -141.7737)
			(xy 105.819194 -141.76629) (xy 104.178354 -140.12545) (xy 104.170955 -140.118605) (xy 104.152357 -140.11088)
			(xy 104.142286 -140.110464) (xy 104.133396 -140.110464) (xy 104.123349 -140.110888) (xy 104.104791 -140.118593)
			(xy 104.090605 -140.132823) (xy 104.086406 -140.14196) (xy 104.080564 -140.156438) (xy 104.086406 -140.186156)
			(xy 104.901238 -141.001242) (xy 105.064052 -141.163802) (xy 105.077865 -141.178282) (xy 105.100064 -141.211571)
			(xy 105.115327 -141.248557) (xy 105.123067 -141.287813) (xy 105.123488 -141.30782) (xy 105.123488 -158.019242)
			(xy 105.123918 -158.029309) (xy 105.131642 -158.047904) (xy 105.138474 -158.05531) (xy 110.209976 -163.126674)
			(xy 119.873522 -163.126674) (xy 119.874031 -163.099101) (xy 119.881974 -163.04453) (xy 119.89769 -162.99167)
			(xy 119.920851 -162.941624) (xy 119.950977 -162.895433) (xy 119.987438 -162.854061) (xy 120.008142 -162.835844)
			(xy 120.016243 -162.828226) (xy 120.025605 -162.808086) (xy 120.026176 -162.796982) (xy 120.026176 -162.719766)
			(xy 120.025651 -162.708651) (xy 120.016283 -162.688492) (xy 120.008142 -162.680904) (xy 119.987409 -162.662718)
			(xy 119.950941 -162.621344) (xy 119.920812 -162.575151) (xy 119.897648 -162.5251) (xy 119.881933 -162.472235)
			(xy 119.873993 -162.417659) (xy 119.873996 -162.362508) (xy 119.88194 -162.307932) (xy 119.89766 -162.255069)
			(xy 119.920828 -162.20502) (xy 119.950962 -162.158829) (xy 119.987433 -162.117459) (xy 120.008142 -162.099244)
			(xy 120.016243 -162.091626) (xy 120.025605 -162.071486) (xy 120.026176 -162.060382) (xy 120.026176 -161.983166)
			(xy 120.025651 -161.972051) (xy 120.016283 -161.951892) (xy 120.008142 -161.944304) (xy 119.987438 -161.926085)
			(xy 119.950965 -161.884719) (xy 119.920831 -161.838531) (xy 119.897664 -161.788484) (xy 119.881947 -161.735623)
			(xy 119.874007 -161.681048) (xy 119.873522 -161.653474) (xy 119.873931 -161.626219) (xy 119.881692 -161.572265)
			(xy 119.897053 -161.519964) (xy 119.919701 -161.470382) (xy 119.949174 -161.424527) (xy 119.984874 -161.383334)
			(xy 120.026072 -161.347641) (xy 120.071931 -161.318174) (xy 120.121516 -161.295533) (xy 120.173819 -161.28018)
			(xy 120.227775 -161.272427) (xy 120.25503 -161.271966) (xy 120.282885 -161.272487) (xy 120.337999 -161.280614)
			(xy 120.391348 -161.296662) (xy 120.4418 -161.32029) (xy 120.488283 -161.350997) (xy 120.529812 -161.388132)
			(xy 120.565506 -161.430906) (xy 120.594606 -161.478412) (xy 120.616496 -161.529642) (xy 120.624092 -161.556446)
			(xy 120.626378 -161.565336) (xy 120.637046 -161.580576) (xy 120.708928 -161.628328) (xy 120.726962 -161.632392)
			(xy 120.736106 -161.631122) (xy 120.749123 -161.629454) (xy 120.775307 -161.627673) (xy 120.78843 -161.627566)
			(xy 120.802579 -161.627657) (xy 120.830802 -161.629693) (xy 120.844818 -161.63163) (xy 120.854978 -161.633154)
			(xy 120.874536 -161.628328) (xy 120.948958 -161.572448) (xy 120.959118 -161.554922) (xy 120.960388 -161.544762)
			(xy 120.964477 -161.517608) (xy 120.979449 -161.464778) (xy 121.00184 -161.414639) (xy 121.031187 -161.368228)
			(xy 121.066885 -161.326504) (xy 121.108194 -161.290327) (xy 121.154263 -161.260446) (xy 121.20414 -161.237477)
			(xy 121.256794 -161.221896) (xy 121.311138 -161.214024) (xy 121.338594 -161.213546) (xy 121.365843 -161.214083)
			(xy 121.419787 -161.221838) (xy 121.472077 -161.23719) (xy 121.521652 -161.259827) (xy 121.5675 -161.289288)
			(xy 121.608689 -161.324974) (xy 121.644381 -161.366158) (xy 121.673848 -161.412003) (xy 121.696492 -161.461574)
			(xy 121.711851 -161.513863) (xy 121.719613 -161.567805) (xy 121.720102 -161.595054) (xy 121.719604 -161.622627)
			(xy 121.711658 -161.677199) (xy 121.695939 -161.730058) (xy 121.672775 -161.780104) (xy 121.642649 -161.826294)
			(xy 121.606187 -161.867667) (xy 121.585482 -161.885884) (xy 121.577373 -161.893495) (xy 121.568014 -161.91364)
			(xy 121.567448 -161.924746) (xy 121.567448 -162.001962) (xy 121.568006 -162.013073) (xy 121.57735 -162.033233)
			(xy 121.585482 -162.040824) (xy 121.606204 -162.059023) (xy 121.642675 -162.100394) (xy 121.672806 -162.146586)
			(xy 121.69597 -162.196637) (xy 121.711683 -162.249502) (xy 121.719619 -162.304078) (xy 121.719653 -162.306)
			(xy 126.30861 -162.306) (xy 126.312681 -162.250378) (xy 126.324807 -162.195941) (xy 126.34473 -162.14385)
			(xy 126.372026 -162.095215) (xy 126.406112 -162.051072) (xy 126.446261 -162.012363) (xy 126.491619 -161.979912)
			(xy 126.541219 -161.954411) (xy 126.594003 -161.936404) (xy 126.648846 -161.926274) (xy 126.70458 -161.924237)
			(xy 126.760017 -161.930337) (xy 126.813974 -161.944443) (xy 126.865303 -161.966255) (xy 126.912909 -161.995309)
			(xy 126.955777 -162.030984) (xy 126.992994 -162.072521) (xy 127.023767 -162.119034) (xy 127.047439 -162.169531)
			(xy 127.063507 -162.222938) (xy 127.071627 -162.278114) (xy 127.072136 -162.306) (xy 127.071627 -162.333886)
			(xy 127.063507 -162.389062) (xy 127.047439 -162.442469) (xy 127.023767 -162.492966) (xy 126.992994 -162.539479)
			(xy 126.955777 -162.581016) (xy 126.912909 -162.616691) (xy 126.865303 -162.645745) (xy 126.813974 -162.667557)
			(xy 126.760017 -162.681663) (xy 126.70458 -162.687763) (xy 126.648846 -162.685726) (xy 126.594003 -162.675596)
			(xy 126.541219 -162.657589) (xy 126.491619 -162.632088) (xy 126.446261 -162.599637) (xy 126.406112 -162.560928)
			(xy 126.372026 -162.516785) (xy 126.34473 -162.46815) (xy 126.324807 -162.416059) (xy 126.312681 -162.361622)
			(xy 126.30861 -162.306) (xy 121.719653 -162.306) (xy 121.720102 -162.331654) (xy 121.719602 -162.358906)
			(xy 121.711851 -162.412856) (xy 121.696501 -162.465153) (xy 121.673863 -162.514734) (xy 121.644399 -162.560587)
			(xy 121.608709 -162.601781) (xy 121.56752 -162.637475) (xy 121.521669 -162.666944) (xy 121.472091 -162.689587)
			(xy 121.419795 -162.704943) (xy 121.365846 -162.712699) (xy 121.338594 -162.713162) (xy 121.304304 -162.711638)
			(xy 121.294144 -162.710622) (xy 121.27484 -162.716718) (xy 121.204228 -162.7759) (xy 121.19483 -162.793934)
			(xy 121.193814 -162.804094) (xy 121.190902 -162.832272) (xy 121.177721 -162.887365) (xy 121.156537 -162.939902)
			(xy 121.127814 -162.988728) (xy 121.092185 -163.032768) (xy 121.050433 -163.071054) (xy 121.003478 -163.102742)
			(xy 120.952352 -163.127137) (xy 120.89818 -163.143701) (xy 120.842154 -163.15207) (xy 120.81383 -163.152582)
			(xy 120.795811 -163.152366) (xy 120.759936 -163.148928) (xy 120.742202 -163.145724) (xy 120.732804 -163.143946)
			(xy 120.713754 -163.147756) (xy 120.63857 -163.195508) (xy 120.62714 -163.211256) (xy 120.624854 -163.220654)
			(xy 120.617489 -163.247708) (xy 120.595856 -163.299436) (xy 120.566888 -163.347442) (xy 120.531209 -163.390694)
			(xy 120.489585 -163.428261) (xy 120.442913 -163.459334) (xy 120.392198 -163.483244) (xy 120.33853 -163.499478)
			(xy 120.283065 -163.507685) (xy 120.25503 -163.508182) (xy 120.227777 -163.507717) (xy 120.173824 -163.499963)
			(xy 120.121525 -163.48461) (xy 120.071943 -163.461969) (xy 120.026089 -163.432501) (xy 119.984895 -163.396808)
			(xy 119.949201 -163.355614) (xy 119.919733 -163.30976) (xy 119.897092 -163.260179) (xy 119.881738 -163.207879)
			(xy 119.873984 -163.153927) (xy 119.873522 -163.126674) (xy 110.209976 -163.126674) (xy 111.710903 -164.62756)
			(xy 121.49074 -164.62756) (xy 121.491233 -164.599986) (xy 121.499178 -164.545414) (xy 121.514897 -164.492554)
			(xy 121.538062 -164.442508) (xy 121.56819 -164.396317) (xy 121.604654 -164.354946) (xy 121.62536 -164.33673)
			(xy 121.63347 -164.32912) (xy 121.642826 -164.308974) (xy 121.643394 -164.297868) (xy 121.643394 -164.220652)
			(xy 121.642814 -164.209544) (xy 121.633484 -164.189385) (xy 121.62536 -164.18179) (xy 121.604633 -164.163597)
			(xy 121.568165 -164.122223) (xy 121.538036 -164.076029) (xy 121.514874 -164.025978) (xy 121.49916 -163.973113)
			(xy 121.491224 -163.918536) (xy 121.49074 -163.89096) (xy 121.491336 -163.861514) (xy 121.500398 -163.803322)
			(xy 121.518285 -163.747211) (xy 121.544574 -163.694511) (xy 121.578641 -163.646472) (xy 121.619678 -163.604231)
			(xy 121.666714 -163.56879) (xy 121.692416 -163.55441) (xy 121.701814 -163.54933) (xy 121.715022 -163.532566)
			(xy 121.738898 -163.439094) (xy 121.735342 -163.418012) (xy 121.7295 -163.409122) (xy 121.714965 -163.386192)
			(xy 121.691987 -163.337005) (xy 121.676395 -163.285003) (xy 121.668519 -163.231289) (xy 121.668032 -163.204144)
			(xy 121.668475 -163.177525) (xy 121.676047 -163.124828) (xy 121.691042 -163.073746) (xy 121.713155 -163.025318)
			(xy 121.741937 -162.98053) (xy 121.7768 -162.940296) (xy 121.817035 -162.905433) (xy 121.861823 -162.876652)
			(xy 121.910251 -162.85454) (xy 121.961334 -162.839545) (xy 122.014031 -162.831975) (xy 122.04065 -162.831526)
			(xy 122.067072 -162.831972) (xy 122.119387 -162.839428) (xy 122.170125 -162.854196) (xy 122.218269 -162.875982)
			(xy 122.262854 -162.904348) (xy 122.28322 -162.921188) (xy 122.290078 -162.927284) (xy 122.307096 -162.93338)
			(xy 122.391424 -162.93338) (xy 122.408442 -162.927284) (xy 122.4153 -162.921188) (xy 122.435666 -162.904349)
			(xy 122.480252 -162.875984) (xy 122.528396 -162.854197) (xy 122.579133 -162.839426) (xy 122.631448 -162.831966)
			(xy 122.684292 -162.831966) (xy 122.736607 -162.839426) (xy 122.787344 -162.854197) (xy 122.835488 -162.875984)
			(xy 122.880074 -162.904349) (xy 122.90044 -162.921188) (xy 122.907298 -162.927284) (xy 122.924316 -162.93338)
			(xy 123.008644 -162.93338) (xy 123.025662 -162.927284) (xy 123.03252 -162.921188) (xy 123.052877 -162.904339)
			(xy 123.097469 -162.875986) (xy 123.145616 -162.854209) (xy 123.196354 -162.839444) (xy 123.248669 -162.831986)
			(xy 123.27509 -162.831526) (xy 123.302981 -162.831932) (xy 123.358139 -162.840245) (xy 123.411442 -162.856685)
			(xy 123.461699 -162.880887) (xy 123.507788 -162.912309) (xy 123.548679 -162.950249) (xy 123.583459 -162.99386)
			(xy 123.61135 -163.042167) (xy 123.631729 -163.094092) (xy 123.644142 -163.148475) (xy 123.648311 -163.2041)
			(xy 123.644142 -163.259725) (xy 123.631729 -163.314108) (xy 123.61135 -163.366033) (xy 123.583459 -163.41434)
			(xy 123.548679 -163.457951) (xy 123.507788 -163.495891) (xy 123.461699 -163.527313) (xy 123.411442 -163.551515)
			(xy 123.358139 -163.567955) (xy 123.302981 -163.576268) (xy 123.27509 -163.576762) (xy 123.248669 -163.576295)
			(xy 123.196354 -163.568845) (xy 123.145616 -163.554082) (xy 123.097472 -163.5323) (xy 123.052886 -163.503938)
			(xy 123.03252 -163.4871) (xy 123.025662 -163.481004) (xy 123.008644 -163.474908) (xy 122.924316 -163.474908)
			(xy 122.907298 -163.481004) (xy 122.90044 -163.4871) (xy 122.880074 -163.503939) (xy 122.835488 -163.532304)
			(xy 122.787344 -163.554091) (xy 122.736607 -163.568862) (xy 122.684292 -163.576322) (xy 122.631448 -163.576322)
			(xy 122.579133 -163.568862) (xy 122.528396 -163.554091) (xy 122.480252 -163.532304) (xy 122.435666 -163.503939)
			(xy 122.4153 -163.4871) (xy 122.408442 -163.481004) (xy 122.391424 -163.474908) (xy 122.307096 -163.474908)
			(xy 122.290078 -163.481004) (xy 122.28322 -163.4871) (xy 122.268829 -163.499111) (xy 122.238035 -163.520486)
			(xy 122.221752 -163.529772) (xy 122.212354 -163.534852) (xy 122.199654 -163.552124) (xy 122.177302 -163.64585)
			(xy 122.181366 -163.666932) (xy 122.187208 -163.675822) (xy 122.202891 -163.699729) (xy 122.227735 -163.751224)
			(xy 122.244629 -163.805845) (xy 122.253197 -163.862373) (xy 122.253756 -163.89096) (xy 122.253278 -163.918534)
			(xy 122.24533 -163.973107) (xy 122.229609 -164.025968) (xy 122.206441 -164.076014) (xy 122.17631 -164.122204)
			(xy 122.139843 -164.163575) (xy 122.119136 -164.18179) (xy 122.111016 -164.189391) (xy 122.101665 -164.209544)
			(xy 122.101102 -164.220652) (xy 122.101102 -164.297868) (xy 122.101671 -164.308978) (xy 122.111009 -164.329136)
			(xy 122.119136 -164.33673) (xy 122.139872 -164.354914) (xy 122.176339 -164.396289) (xy 122.206467 -164.442485)
			(xy 122.229628 -164.492538) (xy 122.24534 -164.545405) (xy 122.253274 -164.599984) (xy 122.253756 -164.62756)
			(xy 122.25327 -164.654811) (xy 122.245514 -164.708759) (xy 122.230159 -164.761054) (xy 122.207517 -164.810631)
			(xy 122.178051 -164.856481) (xy 122.14236 -164.897672) (xy 122.101169 -164.933363) (xy 122.055319 -164.962829)
			(xy 122.005742 -164.985471) (xy 121.953447 -165.000826) (xy 121.899499 -165.008582) (xy 121.844997 -165.008582)
			(xy 121.791049 -165.000826) (xy 121.738754 -164.985471) (xy 121.689177 -164.962829) (xy 121.643327 -164.933363)
			(xy 121.602136 -164.897672) (xy 121.566445 -164.856481) (xy 121.536979 -164.810631) (xy 121.514337 -164.761054)
			(xy 121.498982 -164.708759) (xy 121.491226 -164.654811) (xy 121.49074 -164.62756) (xy 111.710903 -164.62756)
			(xy 114.448336 -167.364918) (xy 114.455679 -167.371732) (xy 114.474143 -167.379464) (xy 114.48415 -167.379904)
			(xy 115.399312 -167.379904) (xy 115.405323 -167.379741) (xy 115.417009 -167.376925) (xy 115.422426 -167.374316)
			(xy 115.447064 -167.36187) (xy 115.455446 -167.355012) (xy 115.459002 -167.350186) (xy 115.477186 -167.32756)
			(xy 115.519242 -167.287555) (xy 115.566873 -167.254381) (xy 115.618979 -167.228805) (xy 115.674358 -167.211416)
			(xy 115.731732 -167.202617) (xy 115.760754 -167.202104) (xy 115.788009 -167.202564) (xy 115.841964 -167.210316)
			(xy 115.894267 -167.225668) (xy 115.943852 -167.248308) (xy 115.98971 -167.277775) (xy 116.030907 -167.313469)
			(xy 116.066605 -167.354663) (xy 116.096076 -167.400518) (xy 116.11872 -167.450101) (xy 116.134077 -167.502403)
			(xy 116.141833 -167.556357) (xy 116.142262 -167.583612) (xy 116.14159 -167.615132) (xy 116.131185 -167.677309)
			(xy 116.110709 -167.736932) (xy 116.096288 -167.764968) (xy 116.091462 -167.774112) (xy 116.08943 -167.79367)
			(xy 116.115084 -167.881808) (xy 116.12753 -167.897302) (xy 116.13642 -167.902382) (xy 116.139468 -167.903906)
			(xy 116.139976 -167.90416) (xy 116.144294 -167.9067) (xy 116.1542 -167.912288) (xy 116.17579 -167.91432)
			(xy 116.270278 -167.880792) (xy 116.286026 -167.865298) (xy 116.29009 -167.85463) (xy 116.300812 -167.82788)
			(xy 116.32914 -167.777696) (xy 116.364693 -167.732343) (xy 116.406662 -167.692851) (xy 116.454092 -167.66012)
			(xy 116.505905 -167.634894) (xy 116.560922 -167.617745) (xy 116.617892 -167.609065) (xy 116.646706 -167.608504)
			(xy 116.673956 -167.608991) (xy 116.727901 -167.616748) (xy 116.780194 -167.632103) (xy 116.829769 -167.654744)
			(xy 116.875617 -167.684209) (xy 116.916805 -167.719899) (xy 116.952495 -167.761088) (xy 116.981959 -167.806937)
			(xy 117.004599 -167.856512) (xy 117.019954 -167.908804) (xy 117.02771 -167.96275) (xy 117.02771 -168.01725)
			(xy 117.019954 -168.071196) (xy 117.010603 -168.103042) (xy 117.269514 -168.103042) (xy 117.270022 -168.075568)
			(xy 117.277908 -168.021189) (xy 117.293523 -167.968507) (xy 117.316543 -167.918614) (xy 117.34649 -167.872544)
			(xy 117.364256 -167.851582) (xy 117.370352 -167.84447) (xy 117.376702 -167.827452) (xy 117.376702 -167.7416)
			(xy 117.370352 -167.724582) (xy 117.364256 -167.71747) (xy 117.34649 -167.69651) (xy 117.316567 -167.650427)
			(xy 117.293555 -167.600532) (xy 117.27793 -167.547855) (xy 117.270013 -167.493482) (xy 117.269514 -167.46601)
			(xy 117.27 -167.438759) (xy 117.277756 -167.384811) (xy 117.293111 -167.332516) (xy 117.315753 -167.282939)
			(xy 117.345219 -167.237089) (xy 117.38091 -167.195898) (xy 117.422101 -167.160207) (xy 117.467951 -167.130741)
			(xy 117.517528 -167.108099) (xy 117.569823 -167.092744) (xy 117.623771 -167.084988) (xy 117.678273 -167.084988)
			(xy 117.732221 -167.092744) (xy 117.784516 -167.108099) (xy 117.834093 -167.130741) (xy 117.879943 -167.160207)
			(xy 117.921134 -167.195898) (xy 117.956825 -167.237089) (xy 117.986291 -167.282939) (xy 118.008933 -167.332516)
			(xy 118.024288 -167.384811) (xy 118.032044 -167.438759) (xy 118.03253 -167.46601) (xy 118.032042 -167.493484)
			(xy 118.02415 -167.547864) (xy 118.008529 -167.600546) (xy 117.985505 -167.650439) (xy 117.955555 -167.696508)
			(xy 117.937788 -167.71747) (xy 117.931692 -167.724582) (xy 117.925342 -167.7416) (xy 117.925342 -167.827452)
			(xy 117.931692 -167.84447) (xy 117.937788 -167.851582) (xy 117.955523 -167.872568) (xy 117.985452 -167.918643)
			(xy 118.008471 -167.968531) (xy 118.024104 -168.021203) (xy 118.032027 -168.075571) (xy 118.03253 -168.103042)
			(xy 118.032044 -168.130293) (xy 118.030411 -168.14165) (xy 118.60733 -168.14165) (xy 118.611401 -168.086028)
			(xy 118.623527 -168.031591) (xy 118.64345 -167.9795) (xy 118.670746 -167.930865) (xy 118.704832 -167.886722)
			(xy 118.744981 -167.848013) (xy 118.790339 -167.815562) (xy 118.839939 -167.790061) (xy 118.892723 -167.772054)
			(xy 118.947566 -167.761924) (xy 119.0033 -167.759887) (xy 119.058737 -167.765987) (xy 119.112694 -167.780093)
			(xy 119.164023 -167.801905) (xy 119.211629 -167.830959) (xy 119.254497 -167.866634) (xy 119.291714 -167.908171)
			(xy 119.322487 -167.954684) (xy 119.346159 -168.005181) (xy 119.362227 -168.058588) (xy 119.370347 -168.113764)
			(xy 119.370856 -168.14165) (xy 119.370347 -168.169536) (xy 119.362227 -168.224712) (xy 119.346159 -168.278119)
			(xy 119.322487 -168.328616) (xy 119.291714 -168.375129) (xy 119.254497 -168.416666) (xy 119.211629 -168.452341)
			(xy 119.164023 -168.481395) (xy 119.112694 -168.503207) (xy 119.058737 -168.517313) (xy 119.0033 -168.523413)
			(xy 118.947566 -168.521376) (xy 118.892723 -168.511246) (xy 118.839939 -168.493239) (xy 118.790339 -168.467738)
			(xy 118.744981 -168.435287) (xy 118.704832 -168.396578) (xy 118.670746 -168.352435) (xy 118.64345 -168.3038)
			(xy 118.623527 -168.251709) (xy 118.611401 -168.197272) (xy 118.60733 -168.14165) (xy 118.030411 -168.14165)
			(xy 118.024288 -168.184241) (xy 118.008933 -168.236536) (xy 117.986291 -168.286113) (xy 117.956825 -168.331963)
			(xy 117.921134 -168.373154) (xy 117.879943 -168.408845) (xy 117.834093 -168.438311) (xy 117.784516 -168.460953)
			(xy 117.732221 -168.476308) (xy 117.678273 -168.484064) (xy 117.623771 -168.484064) (xy 117.569823 -168.476308)
			(xy 117.517528 -168.460953) (xy 117.467951 -168.438311) (xy 117.422101 -168.408845) (xy 117.38091 -168.373154)
			(xy 117.345219 -168.331963) (xy 117.315753 -168.286113) (xy 117.293111 -168.236536) (xy 117.277756 -168.184241)
			(xy 117.27 -168.130293) (xy 117.269514 -168.103042) (xy 117.010603 -168.103042) (xy 117.004599 -168.123488)
			(xy 116.981959 -168.173063) (xy 116.952495 -168.218912) (xy 116.916805 -168.260101) (xy 116.875617 -168.295791)
			(xy 116.829769 -168.325256) (xy 116.780194 -168.347897) (xy 116.727901 -168.363252) (xy 116.673956 -168.371009)
			(xy 116.646706 -168.37152) (xy 116.621473 -168.371109) (xy 116.571447 -168.364459) (xy 116.522731 -168.351287)
			(xy 116.47617 -168.331821) (xy 116.454174 -168.31945) (xy 116.444268 -168.313608) (xy 116.422424 -168.311576)
			(xy 116.327682 -168.345104) (xy 116.311934 -168.360598) (xy 116.30787 -168.371266) (xy 116.297149 -168.398018)
			(xy 116.268823 -168.448208) (xy 116.233271 -168.493568) (xy 116.191304 -168.533066) (xy 116.143874 -168.565804)
			(xy 116.092061 -168.591039) (xy 116.037042 -168.608196) (xy 115.98007 -168.616885) (xy 115.951254 -168.617392)
			(xy 115.924005 -168.616903) (xy 115.870064 -168.609141) (xy 115.817775 -168.593781) (xy 115.768205 -168.571137)
			(xy 115.722361 -168.54167) (xy 115.681178 -168.505978) (xy 115.645493 -168.464789) (xy 115.616033 -168.418941)
			(xy 115.593397 -168.369367) (xy 115.578046 -168.317076) (xy 115.570293 -168.263133) (xy 115.569746 -168.235884)
			(xy 115.570419 -168.204364) (xy 115.580824 -168.142188) (xy 115.601301 -168.082565) (xy 115.61572 -168.054528)
			(xy 115.620546 -168.045384) (xy 115.622578 -168.025826) (xy 115.596924 -167.937688) (xy 115.584478 -167.922194)
			(xy 115.575588 -167.917114) (xy 115.553245 -167.904219) (xy 115.511925 -167.873332) (xy 115.475132 -167.837171)
			(xy 115.459002 -167.817038) (xy 115.455446 -167.812212) (xy 115.447064 -167.805354) (xy 115.422426 -167.792908)
			(xy 115.416999 -167.790328) (xy 115.405319 -167.787511) (xy 115.399312 -167.78732) (xy 114.378994 -167.78732)
			(xy 114.358975 -167.786869) (xy 114.319705 -167.779065) (xy 114.282717 -167.763739) (xy 114.249435 -167.741482)
			(xy 114.234976 -167.72763) (xy 114.234976 -167.727376) (xy 104.776016 -158.26867) (xy 104.762207 -158.254189)
			(xy 104.740016 -158.220898) (xy 104.72476 -158.183912) (xy 104.717027 -158.144657) (xy 104.71658 -158.124652)
			(xy 104.71658 -141.41323) (xy 104.716144 -141.403166) (xy 104.708409 -141.384582) (xy 104.701594 -141.377162)
			(xy 103.872792 -140.548614) (xy 103.865447 -140.541803) (xy 103.846984 -140.534072) (xy 103.836978 -140.533628)
			(xy 100.899976 -140.533628) (xy 100.889991 -140.53417) (xy 100.871568 -140.541893) (xy 100.864162 -140.548614)
			(xy 99.718667 -141.6939) (xy 103.389682 -141.6939) (xy 103.393753 -141.638278) (xy 103.405879 -141.583841)
			(xy 103.425802 -141.53175) (xy 103.453098 -141.483115) (xy 103.487184 -141.438972) (xy 103.527333 -141.400263)
			(xy 103.572691 -141.367812) (xy 103.622291 -141.342311) (xy 103.675075 -141.324304) (xy 103.729918 -141.314174)
			(xy 103.785652 -141.312137) (xy 103.841089 -141.318237) (xy 103.895046 -141.332343) (xy 103.946375 -141.354155)
			(xy 103.993981 -141.383209) (xy 104.036849 -141.418884) (xy 104.074066 -141.460421) (xy 104.104839 -141.506934)
			(xy 104.128511 -141.557431) (xy 104.144579 -141.610838) (xy 104.152699 -141.666014) (xy 104.153208 -141.6939)
			(xy 104.152699 -141.721786) (xy 104.144579 -141.776962) (xy 104.128511 -141.830369) (xy 104.104839 -141.880866)
			(xy 104.074066 -141.927379) (xy 104.036849 -141.968916) (xy 103.993981 -142.004591) (xy 103.946375 -142.033645)
			(xy 103.895046 -142.055457) (xy 103.841089 -142.069563) (xy 103.785652 -142.075663) (xy 103.729918 -142.073626)
			(xy 103.675075 -142.063496) (xy 103.622291 -142.045489) (xy 103.572691 -142.019988) (xy 103.527333 -141.987537)
			(xy 103.487184 -141.948828) (xy 103.453098 -141.904685) (xy 103.425802 -141.85605) (xy 103.405879 -141.803959)
			(xy 103.393753 -141.749522) (xy 103.389682 -141.6939) (xy 99.718667 -141.6939) (xy 99.473258 -141.939264)
			(xy 99.473258 -141.939518) (xy 99.458759 -141.953321) (xy 99.425479 -141.975558) (xy 99.388505 -141.990884)
			(xy 99.349252 -141.99871) (xy 99.32924 -141.999208) (xy 98.39198 -141.999208) (xy 98.371961 -141.998756)
			(xy 98.33269 -141.990953) (xy 98.295699 -141.97563) (xy 98.262413 -141.953379) (xy 98.247962 -141.939518)
			(xy 98.247962 -141.939264) (xy 97.726754 -141.41831) (xy 97.718626 -141.409975) (xy 97.704113 -141.391769)
			(xy 97.697798 -141.381988) (xy 97.69475 -141.376908) (xy 97.67697 -141.359128) (xy 97.67189 -141.35608)
			(xy 97.649594 -141.341927) (xy 97.608763 -141.308434) (xy 97.572941 -141.269631) (xy 97.542812 -141.226258)
			(xy 97.518951 -141.179145) (xy 97.501816 -141.129192) (xy 97.496376 -141.10335) (xy 97.494344 -141.093444)
			(xy 97.488756 -141.085062) (xy 97.48587 -141.080839) (xy 97.478706 -141.07354) (xy 97.474532 -141.070584)
			(xy 97.406206 -141.025118) (xy 97.386648 -141.021308) (xy 97.376488 -141.02334) (xy 97.357586 -141.027)
			(xy 97.319285 -141.030946) (xy 97.300034 -141.031214) (xy 97.273275 -141.030765) (xy 97.220281 -141.023288)
			(xy 97.168853 -141.008477) (xy 97.120001 -140.986621) (xy 97.074683 -140.958152) (xy 97.033791 -140.923626)
			(xy 96.998126 -140.883724) (xy 96.968389 -140.839227) (xy 96.956372 -140.815314) (xy 96.951038 -140.804646)
			(xy 96.933258 -140.790422) (xy 96.832674 -140.76807) (xy 96.810068 -140.773404) (xy 96.800924 -140.78077)
			(xy 96.779397 -140.797679) (xy 96.732437 -140.825805) (xy 96.68194 -140.846932) (xy 96.628942 -140.860626)
			(xy 96.601788 -140.864082) (xy 96.591344 -140.865156) (xy 96.570377 -140.866299) (xy 96.559878 -140.866368)
			(xy 96.53046 -140.865803) (xy 96.472324 -140.856744) (xy 96.416262 -140.838888) (xy 96.389698 -140.826236)
			(xy 96.389444 -140.826236) (xy 96.37944 -140.821779) (xy 96.357578 -140.820985) (xy 96.34728 -140.824712)
			(xy 96.276414 -140.854176) (xy 96.266559 -140.858838) (xy 96.251699 -140.874762) (xy 96.247712 -140.88491)
			(xy 96.247712 -140.885164) (xy 96.238911 -140.910181) (xy 96.215371 -140.957701) (xy 96.185483 -141.001507)
			(xy 96.149822 -141.040757) (xy 96.109074 -141.074697) (xy 96.064022 -141.102673) (xy 96.015534 -141.124147)
			(xy 95.96454 -141.138706) (xy 95.912023 -141.146072) (xy 95.885508 -141.14653) (xy 95.858256 -141.146045)
			(xy 95.804306 -141.138289) (xy 95.752009 -141.122935) (xy 95.702429 -141.100295) (xy 95.656576 -141.070829)
			(xy 95.615383 -141.035138) (xy 95.579689 -140.993948) (xy 95.55022 -140.948097) (xy 95.527575 -140.898519)
			(xy 95.512217 -140.846223) (xy 95.504457 -140.792274) (xy 95.504 -140.765022) (xy 95.504 -140.755624)
			(xy 95.504508 -140.745464) (xy 95.496126 -140.72489) (xy 95.42399 -140.657834) (xy 95.403416 -140.650976)
			(xy 95.392494 -140.651992) (xy 95.35414 -140.654024) (xy 95.326885 -140.653564) (xy 95.272929 -140.645812)
			(xy 95.220625 -140.630459) (xy 95.171039 -140.607819) (xy 95.125179 -140.578352) (xy 95.083981 -140.542659)
			(xy 95.048281 -140.501465) (xy 95.018808 -140.45561) (xy 94.99616 -140.406028) (xy 94.9808 -140.353726)
			(xy 94.97304 -140.299771) (xy 94.972632 -140.272516) (xy 94.972755 -140.257596) (xy 94.975041 -140.227843)
			(xy 94.977204 -140.21308) (xy 94.979236 -140.200888) (xy 94.971616 -140.178028) (xy 93.111574 -138.317986)
			(xy 93.104232 -138.31117) (xy 93.085768 -138.303434) (xy 93.07576 -138.303) (xy 92.930218 -138.303)
			(xy 92.920229 -138.303534) (xy 92.901792 -138.311243) (xy 92.894404 -138.317986) (xy 90.178382 -141.034008)
			(xy 90.173024 -141.040474) (xy 90.166408 -141.055895) (xy 90.165428 -141.064234) (xy 90.165428 -150.156926)
			(xy 90.164956 -150.176926) (xy 90.157193 -150.216164) (xy 90.141931 -150.253136) (xy 90.119755 -150.286425)
			(xy 90.105992 -150.300944) (xy 89.308686 -151.097996) (xy 89.308686 -151.09825) (xy 89.298958 -151.10768)
			(xy 89.277422 -151.124119) (xy 89.26576 -151.131016) (xy 89.253822 -151.137874) (xy 89.240106 -151.161242)
			(xy 89.240106 -151.175212) (xy 89.240596 -151.185218) (xy 89.248258 -151.203704) (xy 89.262411 -151.217852)
			(xy 89.2809 -151.225507) (xy 89.290906 -151.226012) (xy 89.60485 -151.226012) (xy 89.614916 -151.22558)
			(xy 89.633509 -151.217854) (xy 89.640918 -151.211026) (xy 90.289634 -150.56231) (xy 90.296489 -150.554915)
			(xy 90.304238 -150.536317) (xy 90.30462 -150.526242) (xy 90.30462 -142.183612) (xy 90.305088 -142.163611)
			(xy 90.312846 -142.12437) (xy 90.328107 -142.087395) (xy 90.350283 -142.054105) (xy 90.364056 -142.039594)
			(xy 92.345764 -140.05814) (xy 92.35313 -140.03528) (xy 92.351098 -140.023088) (xy 92.348936 -140.008325)
			(xy 92.346649 -139.978572) (xy 92.346526 -139.963652) (xy 92.347016 -139.936405) (xy 92.354777 -139.882465)
			(xy 92.370136 -139.830179) (xy 92.39278 -139.780611) (xy 92.422247 -139.73477) (xy 92.457937 -139.693588)
			(xy 92.499125 -139.657905) (xy 92.544971 -139.628447) (xy 92.594544 -139.605812) (xy 92.646832 -139.590463)
			(xy 92.700773 -139.582711) (xy 92.755268 -139.582714) (xy 92.809208 -139.590472) (xy 92.861495 -139.605827)
			(xy 92.911065 -139.628467) (xy 92.956908 -139.65793) (xy 92.998092 -139.693618) (xy 93.033778 -139.734803)
			(xy 93.06324 -139.780647) (xy 93.085878 -139.830218) (xy 93.101231 -139.882505) (xy 93.108987 -139.936446)
			(xy 93.108988 -139.990941) (xy 93.101234 -140.044881) (xy 93.085883 -140.09717) (xy 93.063247 -140.146741)
			(xy 93.033786 -140.192586) (xy 92.998102 -140.233773) (xy 92.956919 -140.269462) (xy 92.911077 -140.298927)
			(xy 92.861508 -140.321569) (xy 92.809221 -140.336926) (xy 92.755282 -140.344685) (xy 92.728034 -140.34516)
			(xy 92.713114 -140.345033) (xy 92.683362 -140.342741) (xy 92.668598 -140.340588) (xy 92.656406 -140.338556)
			(xy 92.633546 -140.345922) (xy 90.726514 -142.252954) (xy 90.719674 -142.260355) (xy 90.711957 -142.278953)
			(xy 90.711528 -142.289022) (xy 90.711528 -142.505176) (xy 91.124276 -142.505176) (xy 91.128347 -142.449554)
			(xy 91.140473 -142.395117) (xy 91.160396 -142.343026) (xy 91.187692 -142.294391) (xy 91.221778 -142.250248)
			(xy 91.261927 -142.211539) (xy 91.307285 -142.179088) (xy 91.356885 -142.153587) (xy 91.409669 -142.13558)
			(xy 91.464512 -142.12545) (xy 91.520246 -142.123413) (xy 91.575683 -142.129513) (xy 91.62964 -142.143619)
			(xy 91.680969 -142.165431) (xy 91.728575 -142.194485) (xy 91.771443 -142.23016) (xy 91.80866 -142.271697)
			(xy 91.839433 -142.31821) (xy 91.863105 -142.368707) (xy 91.879173 -142.422114) (xy 91.887293 -142.47729)
			(xy 91.887802 -142.505176) (xy 91.887293 -142.533062) (xy 91.879173 -142.588238) (xy 91.863105 -142.641645)
			(xy 91.839433 -142.692142) (xy 91.80866 -142.738655) (xy 91.771443 -142.780192) (xy 91.728575 -142.815867)
			(xy 91.680969 -142.844921) (xy 91.62964 -142.866733) (xy 91.575683 -142.880839) (xy 91.520246 -142.886939)
			(xy 91.464512 -142.884902) (xy 91.409669 -142.874772) (xy 91.356885 -142.856765) (xy 91.307285 -142.831264)
			(xy 91.261927 -142.798813) (xy 91.221778 -142.760104) (xy 91.187692 -142.715961) (xy 91.160396 -142.667326)
			(xy 91.140473 -142.615235) (xy 91.128347 -142.560798) (xy 91.124276 -142.505176) (xy 90.711528 -142.505176)
			(xy 90.711528 -144.042754) (xy 90.855738 -144.042754) (xy 90.855738 -143.988246) (xy 90.863495 -143.934293)
			(xy 90.878852 -143.881992) (xy 90.901495 -143.83241) (xy 90.930965 -143.786555) (xy 90.96666 -143.74536)
			(xy 91.007855 -143.709665) (xy 91.05371 -143.680195) (xy 91.103292 -143.657552) (xy 91.155593 -143.642195)
			(xy 91.209546 -143.634438) (xy 91.2368 -143.633952) (xy 91.26329 -143.634388) (xy 91.315759 -143.641738)
			(xy 91.366705 -143.65628) (xy 91.415147 -143.677737) (xy 91.460151 -143.705694) (xy 91.500851 -143.739612)
			(xy 91.518994 -143.75892) (xy 91.52822 -143.768469) (xy 91.550551 -143.782819) (xy 91.575827 -143.790926)
			(xy 91.602338 -143.792242) (xy 91.628293 -143.786678) (xy 91.651935 -143.77461) (xy 91.671666 -143.756854)
			(xy 91.679268 -143.745966) (xy 91.694495 -143.723592) (xy 91.730189 -143.682913) (xy 91.771271 -143.647684)
			(xy 91.816917 -143.618611) (xy 91.866212 -143.596277) (xy 91.918167 -143.581129) (xy 91.971741 -143.573471)
			(xy 91.9988 -143.572992) (xy 92.026051 -143.573478) (xy 92.079999 -143.581234) (xy 92.132294 -143.596589)
			(xy 92.181871 -143.619231) (xy 92.227721 -143.648697) (xy 92.268912 -143.684388) (xy 92.304603 -143.725579)
			(xy 92.334069 -143.771429) (xy 92.356711 -143.821006) (xy 92.372066 -143.873301) (xy 92.379822 -143.927249)
			(xy 92.379822 -143.981751) (xy 92.372066 -144.035699) (xy 92.356711 -144.087994) (xy 92.334069 -144.137571)
			(xy 92.304603 -144.183421) (xy 92.268912 -144.224612) (xy 92.227721 -144.260303) (xy 92.181871 -144.289769)
			(xy 92.132294 -144.312411) (xy 92.079999 -144.327766) (xy 92.026051 -144.335522) (xy 91.9988 -144.336008)
			(xy 91.972309 -144.335585) (xy 91.919839 -144.328235) (xy 91.868893 -144.31369) (xy 91.820451 -144.292231)
			(xy 91.775447 -144.264272) (xy 91.734748 -144.23035) (xy 91.716606 -144.21104) (xy 91.705788 -144.199934)
			(xy 91.679009 -144.184333) (xy 91.648787 -144.177468) (xy 91.617896 -144.179968) (xy 91.589172 -144.191605)
			(xy 91.565251 -144.21131) (xy 91.556332 -144.223994) (xy 91.541125 -144.246382) (xy 91.505425 -144.287057)
			(xy 91.464339 -144.322283) (xy 91.418689 -144.351353) (xy 91.369392 -144.373686) (xy 91.317435 -144.388832)
			(xy 91.26386 -144.396489) (xy 91.2368 -144.396968) (xy 91.209546 -144.396562) (xy 91.155593 -144.388805)
			(xy 91.103292 -144.373448) (xy 91.05371 -144.350805) (xy 91.007855 -144.321335) (xy 90.96666 -144.28564)
			(xy 90.930965 -144.244445) (xy 90.901495 -144.19859) (xy 90.878852 -144.149008) (xy 90.863495 -144.096707)
			(xy 90.855738 -144.042754) (xy 90.711528 -144.042754) (xy 90.711528 -144.958308) (xy 90.97086 -144.958308)
			(xy 90.974931 -144.902686) (xy 90.987057 -144.848249) (xy 91.00698 -144.796158) (xy 91.034276 -144.747523)
			(xy 91.068362 -144.70338) (xy 91.108511 -144.664671) (xy 91.153869 -144.63222) (xy 91.203469 -144.606719)
			(xy 91.256253 -144.588712) (xy 91.311096 -144.578582) (xy 91.36683 -144.576545) (xy 91.422267 -144.582645)
			(xy 91.476224 -144.596751) (xy 91.527553 -144.618563) (xy 91.575159 -144.647617) (xy 91.618027 -144.683292)
			(xy 91.655244 -144.724829) (xy 91.686017 -144.771342) (xy 91.709689 -144.821839) (xy 91.725757 -144.875246)
			(xy 91.733877 -144.930422) (xy 91.734386 -144.958308) (xy 91.733877 -144.986194) (xy 91.725757 -145.04137)
			(xy 91.709689 -145.094777) (xy 91.686017 -145.145274) (xy 91.655244 -145.191787) (xy 91.618027 -145.233324)
			(xy 91.575159 -145.268999) (xy 91.527553 -145.298053) (xy 91.476224 -145.319865) (xy 91.422267 -145.333971)
			(xy 91.36683 -145.340071) (xy 91.311096 -145.338034) (xy 91.256253 -145.327904) (xy 91.203469 -145.309897)
			(xy 91.153869 -145.284396) (xy 91.108511 -145.251945) (xy 91.068362 -145.213236) (xy 91.034276 -145.169093)
			(xy 91.00698 -145.120458) (xy 90.987057 -145.068367) (xy 90.974931 -145.01393) (xy 90.97086 -144.958308)
			(xy 90.711528 -144.958308) (xy 90.711528 -145.90141) (xy 90.84386 -145.90141) (xy 90.847931 -145.845788)
			(xy 90.860057 -145.791351) (xy 90.87998 -145.73926) (xy 90.907276 -145.690625) (xy 90.941362 -145.646482)
			(xy 90.981511 -145.607773) (xy 91.026869 -145.575322) (xy 91.076469 -145.549821) (xy 91.129253 -145.531814)
			(xy 91.184096 -145.521684) (xy 91.23983 -145.519647) (xy 91.295267 -145.525747) (xy 91.349224 -145.539853)
			(xy 91.400553 -145.561665) (xy 91.448159 -145.590719) (xy 91.491027 -145.626394) (xy 91.528244 -145.667931)
			(xy 91.559017 -145.714444) (xy 91.582689 -145.764941) (xy 91.598757 -145.818348) (xy 91.606877 -145.873524)
			(xy 91.607386 -145.90141) (xy 91.606877 -145.929296) (xy 91.598757 -145.984472) (xy 91.582689 -146.037879)
			(xy 91.559017 -146.088376) (xy 91.528244 -146.134889) (xy 91.491027 -146.176426) (xy 91.448159 -146.212101)
			(xy 91.400553 -146.241155) (xy 91.349224 -146.262967) (xy 91.295267 -146.277073) (xy 91.23983 -146.283173)
			(xy 91.184096 -146.281136) (xy 91.129253 -146.271006) (xy 91.076469 -146.252999) (xy 91.026869 -146.227498)
			(xy 90.981511 -146.195047) (xy 90.941362 -146.156338) (xy 90.907276 -146.112195) (xy 90.87998 -146.06356)
			(xy 90.860057 -146.011469) (xy 90.847931 -145.957032) (xy 90.84386 -145.90141) (xy 90.711528 -145.90141)
			(xy 90.711528 -149.336252) (xy 93.292674 -149.336252) (xy 93.296745 -149.28063) (xy 93.308871 -149.226193)
			(xy 93.328794 -149.174102) (xy 93.35609 -149.125467) (xy 93.390176 -149.081324) (xy 93.430325 -149.042615)
			(xy 93.475683 -149.010164) (xy 93.525283 -148.984663) (xy 93.578067 -148.966656) (xy 93.63291 -148.956526)
			(xy 93.688644 -148.954489) (xy 93.744081 -148.960589) (xy 93.798038 -148.974695) (xy 93.849367 -148.996507)
			(xy 93.896973 -149.025561) (xy 93.939841 -149.061236) (xy 93.977058 -149.102773) (xy 94.007831 -149.149286)
			(xy 94.031503 -149.199783) (xy 94.047571 -149.25319) (xy 94.055691 -149.308366) (xy 94.0562 -149.336252)
			(xy 94.055691 -149.364138) (xy 94.047571 -149.419314) (xy 94.031503 -149.472721) (xy 94.007831 -149.523218)
			(xy 93.977058 -149.569731) (xy 93.939841 -149.611268) (xy 93.896973 -149.646943) (xy 93.849367 -149.675997)
			(xy 93.798038 -149.697809) (xy 93.744081 -149.711915) (xy 93.688644 -149.718015) (xy 93.63291 -149.715978)
			(xy 93.578067 -149.705848) (xy 93.525283 -149.687841) (xy 93.475683 -149.66234) (xy 93.430325 -149.629889)
			(xy 93.390176 -149.59118) (xy 93.35609 -149.547037) (xy 93.328794 -149.498402) (xy 93.308871 -149.446311)
			(xy 93.296745 -149.391874) (xy 93.292674 -149.336252) (xy 90.711528 -149.336252) (xy 90.711528 -150.631652)
			(xy 90.711063 -150.651655) (xy 90.703313 -150.690901) (xy 90.68806 -150.727883) (xy 90.66589 -150.761182)
			(xy 90.65814 -150.76932) (xy 92.368114 -150.76932) (xy 92.372185 -150.713698) (xy 92.384311 -150.659261)
			(xy 92.404234 -150.60717) (xy 92.43153 -150.558535) (xy 92.465616 -150.514392) (xy 92.505765 -150.475683)
			(xy 92.551123 -150.443232) (xy 92.600723 -150.417731) (xy 92.653507 -150.399724) (xy 92.70835 -150.389594)
			(xy 92.764084 -150.387557) (xy 92.819521 -150.393657) (xy 92.873478 -150.407763) (xy 92.924807 -150.429575)
			(xy 92.972413 -150.458629) (xy 93.015281 -150.494304) (xy 93.052498 -150.535841) (xy 93.083271 -150.582354)
			(xy 93.106943 -150.632851) (xy 93.123011 -150.686258) (xy 93.131131 -150.741434) (xy 93.13164 -150.76932)
			(xy 93.131131 -150.797206) (xy 93.123011 -150.852382) (xy 93.106943 -150.905789) (xy 93.083271 -150.956286)
			(xy 93.052498 -151.002799) (xy 93.015281 -151.044336) (xy 92.972413 -151.080011) (xy 92.924807 -151.109065)
			(xy 92.873478 -151.130877) (xy 92.819521 -151.144983) (xy 92.764084 -151.151083) (xy 92.70835 -151.149046)
			(xy 92.653507 -151.138916) (xy 92.600723 -151.120909) (xy 92.551123 -151.095408) (xy 92.505765 -151.062957)
			(xy 92.465616 -151.024248) (xy 92.43153 -150.980105) (xy 92.404234 -150.93147) (xy 92.384311 -150.879379)
			(xy 92.372185 -150.824942) (xy 92.368114 -150.76932) (xy 90.65814 -150.76932) (xy 90.652092 -150.77567)
			(xy 89.854278 -151.573484) (xy 89.839797 -151.587293) (xy 89.806506 -151.609486) (xy 89.76952 -151.624743)
			(xy 89.730266 -151.632478) (xy 89.71026 -151.63292) (xy 84.364322 -151.63292) (xy 84.354333 -151.633454)
			(xy 84.335897 -151.641164) (xy 84.328508 -151.647906) (xy 84.19973 -151.776684) (xy 92.368114 -151.776684)
			(xy 92.372185 -151.721062) (xy 92.384311 -151.666625) (xy 92.404234 -151.614534) (xy 92.43153 -151.565899)
			(xy 92.465616 -151.521756) (xy 92.505765 -151.483047) (xy 92.551123 -151.450596) (xy 92.600723 -151.425095)
			(xy 92.653507 -151.407088) (xy 92.70835 -151.396958) (xy 92.764084 -151.394921) (xy 92.819521 -151.401021)
			(xy 92.873478 -151.415127) (xy 92.924807 -151.436939) (xy 92.972413 -151.465993) (xy 93.015281 -151.501668)
			(xy 93.052498 -151.543205) (xy 93.083271 -151.589718) (xy 93.106943 -151.640215) (xy 93.123011 -151.693622)
			(xy 93.131131 -151.748798) (xy 93.13164 -151.776684) (xy 93.131131 -151.80457) (xy 93.123011 -151.859746)
			(xy 93.106943 -151.913153) (xy 93.083271 -151.96365) (xy 93.052498 -152.010163) (xy 93.015281 -152.0517)
			(xy 92.972413 -152.087375) (xy 92.924807 -152.116429) (xy 92.873478 -152.138241) (xy 92.819521 -152.152347)
			(xy 92.764084 -152.158447) (xy 92.70835 -152.15641) (xy 92.653507 -152.14628) (xy 92.600723 -152.128273)
			(xy 92.551123 -152.102772) (xy 92.505765 -152.070321) (xy 92.465616 -152.031612) (xy 92.43153 -151.987469)
			(xy 92.404234 -151.938834) (xy 92.384311 -151.886743) (xy 92.372185 -151.832306) (xy 92.368114 -151.776684)
			(xy 84.19973 -151.776684) (xy 82.990182 -152.986232) (xy 82.983368 -152.993575) (xy 82.975634 -153.012038)
			(xy 82.975196 -153.022046) (xy 82.975196 -153.894282) (xy 83.466178 -153.894282) (xy 83.466726 -153.865366)
			(xy 83.475445 -153.808195) (xy 83.492695 -153.752995) (xy 83.518081 -153.701033) (xy 83.551021 -153.653498)
			(xy 83.590759 -153.611482) (xy 83.613244 -153.593292) (xy 83.622012 -153.585737) (xy 83.63219 -153.564973)
			(xy 83.632802 -153.553414) (xy 83.632802 -153.47315) (xy 83.632202 -153.461586) (xy 83.622028 -153.440815)
			(xy 83.613244 -153.433272) (xy 83.590756 -153.415086) (xy 83.551019 -153.373066) (xy 83.51808 -153.325531)
			(xy 83.492691 -153.273568) (xy 83.475437 -153.218369) (xy 83.466711 -153.161199) (xy 83.466178 -153.132282)
			(xy 83.466661 -153.105031) (xy 83.47442 -153.051084) (xy 83.489776 -152.99879) (xy 83.512419 -152.949214)
			(xy 83.541885 -152.903364) (xy 83.577577 -152.862174) (xy 83.618767 -152.826483) (xy 83.664617 -152.797017)
			(xy 83.714194 -152.774375) (xy 83.766488 -152.759019) (xy 83.820435 -152.751261) (xy 83.847686 -152.750774)
			(xy 83.874961 -152.751244) (xy 83.928959 -152.758987) (xy 83.981303 -152.774346) (xy 84.030923 -152.797008)
			(xy 84.076808 -152.82651) (xy 84.11802 -152.86225) (xy 84.153718 -152.903497) (xy 84.183174 -152.949411)
			(xy 84.194904 -152.97404) (xy 84.201 -152.987248) (xy 84.224622 -153.00325) (xy 84.344256 -153.008076)
			(xy 84.369148 -152.994106) (xy 84.376006 -152.981406) (xy 84.388811 -152.959294) (xy 84.419408 -152.918369)
			(xy 84.455175 -152.881876) (xy 84.475066 -152.865836) (xy 84.483818 -152.858266) (xy 84.494004 -152.837513)
			(xy 84.494624 -152.825958) (xy 84.494624 -152.745694) (xy 84.494084 -152.734121) (xy 84.483871 -152.713349)
			(xy 84.475066 -152.705816) (xy 84.452583 -152.687625) (xy 84.412849 -152.645604) (xy 84.379911 -152.598069)
			(xy 84.354523 -152.546108) (xy 84.337266 -152.490911) (xy 84.328536 -152.433742) (xy 84.328 -152.404826)
			(xy 84.328486 -152.377575) (xy 84.336242 -152.323627) (xy 84.351597 -152.271332) (xy 84.374239 -152.221755)
			(xy 84.403705 -152.175905) (xy 84.439396 -152.134714) (xy 84.480587 -152.099023) (xy 84.526437 -152.069557)
			(xy 84.576014 -152.046915) (xy 84.628309 -152.03156) (xy 84.682257 -152.023804) (xy 84.736759 -152.023804)
			(xy 84.790707 -152.03156) (xy 84.843002 -152.046915) (xy 84.892579 -152.069557) (xy 84.938429 -152.099023)
			(xy 84.97962 -152.134714) (xy 85.015311 -152.175905) (xy 85.044777 -152.221755) (xy 85.067419 -152.271332)
			(xy 85.082774 -152.323627) (xy 85.09053 -152.377575) (xy 85.091016 -152.404826) (xy 85.090476 -152.433743)
			(xy 85.090276 -152.435052) (xy 93.412816 -152.435052) (xy 93.416887 -152.37943) (xy 93.429013 -152.324993)
			(xy 93.448936 -152.272902) (xy 93.476232 -152.224267) (xy 93.510318 -152.180124) (xy 93.550467 -152.141415)
			(xy 93.595825 -152.108964) (xy 93.645425 -152.083463) (xy 93.698209 -152.065456) (xy 93.753052 -152.055326)
			(xy 93.808786 -152.053289) (xy 93.864223 -152.059389) (xy 93.91818 -152.073495) (xy 93.969509 -152.095307)
			(xy 94.017115 -152.124361) (xy 94.059983 -152.160036) (xy 94.0972 -152.201573) (xy 94.127973 -152.248086)
			(xy 94.151645 -152.298583) (xy 94.167713 -152.35199) (xy 94.175833 -152.407166) (xy 94.176342 -152.435052)
			(xy 94.175833 -152.462938) (xy 94.167713 -152.518114) (xy 94.151645 -152.571521) (xy 94.127973 -152.622018)
			(xy 94.0972 -152.668531) (xy 94.059983 -152.710068) (xy 94.017115 -152.745743) (xy 93.969509 -152.774797)
			(xy 93.91818 -152.796609) (xy 93.864223 -152.810715) (xy 93.808786 -152.816815) (xy 93.753052 -152.814778)
			(xy 93.698209 -152.804648) (xy 93.645425 -152.786641) (xy 93.595825 -152.76114) (xy 93.550467 -152.728689)
			(xy 93.510318 -152.68998) (xy 93.476232 -152.645837) (xy 93.448936 -152.597202) (xy 93.429013 -152.545111)
			(xy 93.416887 -152.490674) (xy 93.412816 -152.435052) (xy 85.090276 -152.435052) (xy 85.081756 -152.490914)
			(xy 85.064505 -152.546114) (xy 85.039117 -152.598076) (xy 85.006176 -152.645611) (xy 84.966435 -152.687626)
			(xy 84.94395 -152.705816) (xy 84.935177 -152.713367) (xy 84.925001 -152.734134) (xy 84.924392 -152.745694)
			(xy 84.924392 -152.825958) (xy 84.924989 -152.837522) (xy 84.935165 -152.858293) (xy 84.94395 -152.865836)
			(xy 84.966461 -152.883994) (xy 85.006192 -152.926022) (xy 85.039127 -152.973564) (xy 85.06451 -153.025532)
			(xy 85.081761 -153.080735) (xy 85.090484 -153.137908) (xy 85.091016 -153.166826) (xy 85.090546 -153.194078)
			(xy 85.082787 -153.248025) (xy 85.067429 -153.30032) (xy 85.044785 -153.349897) (xy 85.015317 -153.395747)
			(xy 84.979624 -153.436936) (xy 84.938432 -153.472628) (xy 84.892581 -153.502094) (xy 84.843003 -153.524735)
			(xy 84.790708 -153.54009) (xy 84.73676 -153.547848) (xy 84.709508 -153.548334) (xy 84.682233 -153.547865)
			(xy 84.628235 -153.540121) (xy 84.575892 -153.524761) (xy 84.526271 -153.502099) (xy 84.480387 -153.472597)
			(xy 84.439175 -153.436857) (xy 84.403476 -153.39561) (xy 84.37402 -153.349696) (xy 84.36229 -153.325068)
			(xy 84.356194 -153.31186) (xy 84.332572 -153.295858) (xy 84.212938 -153.291032) (xy 84.188046 -153.305002)
			(xy 84.181188 -153.317702) (xy 84.168386 -153.339816) (xy 84.137788 -153.38074) (xy 84.102019 -153.417232)
			(xy 84.082128 -153.433272) (xy 84.073371 -153.440838) (xy 84.063188 -153.461594) (xy 84.06257 -153.47315)
			(xy 84.06257 -153.553414) (xy 84.063108 -153.564987) (xy 84.073323 -153.585759) (xy 84.082128 -153.593292)
			(xy 84.104613 -153.61148) (xy 84.144347 -153.653502) (xy 84.177285 -153.701037) (xy 84.202673 -153.752999)
			(xy 84.219929 -153.808197) (xy 84.228659 -153.865366) (xy 84.229194 -153.894282) (xy 84.228708 -153.921533)
			(xy 84.220952 -153.975481) (xy 84.205597 -154.027776) (xy 84.182955 -154.077353) (xy 84.153489 -154.123203)
			(xy 84.117798 -154.164394) (xy 84.076607 -154.200085) (xy 84.030757 -154.229551) (xy 83.98118 -154.252193)
			(xy 83.928885 -154.267548) (xy 83.874937 -154.275304) (xy 83.820435 -154.275304) (xy 83.766487 -154.267548)
			(xy 83.714192 -154.252193) (xy 83.664615 -154.229551) (xy 83.618765 -154.200085) (xy 83.577574 -154.164394)
			(xy 83.541883 -154.123203) (xy 83.512417 -154.077353) (xy 83.489775 -154.027776) (xy 83.47442 -153.975481)
			(xy 83.466664 -153.921533) (xy 83.466178 -153.894282) (xy 82.975196 -153.894282) (xy 82.975196 -153.896314)
			(xy 82.974725 -153.916314) (xy 82.966963 -153.955553) (xy 82.951701 -153.992525) (xy 82.929523 -154.025813)
			(xy 82.91576 -154.040332) (xy 81.127405 -155.828495) (xy 83.791294 -155.828495) (xy 83.795025 -155.775242)
			(xy 83.806143 -155.72303) (xy 83.824431 -155.672877) (xy 83.849532 -155.625763) (xy 83.880955 -155.582608)
			(xy 83.918088 -155.544255) (xy 83.938872 -155.527502) (xy 83.947641 -155.519947) (xy 83.957817 -155.499183)
			(xy 83.95843 -155.487624) (xy 83.95843 -155.40736) (xy 83.957849 -155.395793) (xy 83.947664 -155.37502)
			(xy 83.938872 -155.367482) (xy 83.916374 -155.349308) (xy 83.876641 -155.307284) (xy 83.843705 -155.259745)
			(xy 83.818319 -155.207781) (xy 83.801066 -155.152581) (xy 83.79234 -155.095409) (xy 83.791806 -155.066492)
			(xy 83.792248 -155.039238) (xy 83.800006 -154.985286) (xy 83.815364 -154.932987) (xy 83.838009 -154.883406)
			(xy 83.867479 -154.837552) (xy 83.903175 -154.796359) (xy 83.94437 -154.760666) (xy 83.990225 -154.731198)
			(xy 84.039807 -154.708556) (xy 84.092107 -154.693202) (xy 84.14606 -154.685446) (xy 84.173314 -154.684984)
			(xy 84.202588 -154.685536) (xy 84.260445 -154.694503) (xy 84.316252 -154.712208) (xy 84.368696 -154.738236)
			(xy 84.416546 -154.771974) (xy 84.437982 -154.791918) (xy 84.445348 -154.798776) (xy 84.463382 -154.806142)
			(xy 84.553806 -154.806142) (xy 84.57184 -154.798776) (xy 84.579206 -154.791918) (xy 84.600664 -154.772)
			(xy 84.648515 -154.738272) (xy 84.700954 -154.712245) (xy 84.756753 -154.694529) (xy 84.814603 -154.685541)
			(xy 84.843874 -154.684984) (xy 84.872792 -154.685489) (xy 84.929965 -154.694216) (xy 84.985166 -154.711475)
			(xy 85.037128 -154.736869) (xy 85.084661 -154.769816) (xy 85.126676 -154.809562) (xy 85.144864 -154.83205)
			(xy 85.152437 -154.8408) (xy 85.173188 -154.850988) (xy 85.184742 -154.851608) (xy 85.265006 -154.851608)
			(xy 85.276574 -154.851038) (xy 85.297344 -154.840843) (xy 85.304884 -154.83205) (xy 85.319664 -154.813652)
			(xy 85.353034 -154.780281) (xy 85.371432 -154.765502) (xy 85.380194 -154.75794) (xy 85.390376 -154.737181)
			(xy 85.39099 -154.725624) (xy 85.39099 -154.64536) (xy 85.390389 -154.633796) (xy 85.380216 -154.613025)
			(xy 85.371432 -154.605482) (xy 85.348947 -154.587293) (xy 85.30921 -154.545274) (xy 85.27627 -154.497739)
			(xy 85.250882 -154.445777) (xy 85.233627 -154.390579) (xy 85.2249 -154.333408) (xy 85.224366 -154.304492)
			(xy 85.22487 -154.277242) (xy 85.232627 -154.223296) (xy 85.247982 -154.171003) (xy 85.270622 -154.121428)
			(xy 85.300087 -154.075579) (xy 85.335776 -154.034389) (xy 85.376964 -153.998698) (xy 85.422812 -153.969231)
			(xy 85.472386 -153.946588) (xy 85.524678 -153.931231) (xy 85.578624 -153.923472) (xy 85.605874 -153.922984)
			(xy 85.634792 -153.923489) (xy 85.691965 -153.932216) (xy 85.747166 -153.949475) (xy 85.799128 -153.974869)
			(xy 85.846661 -154.007816) (xy 85.888676 -154.047562) (xy 85.906864 -154.07005) (xy 85.914437 -154.0788)
			(xy 85.935188 -154.088988) (xy 85.946742 -154.089608) (xy 86.027006 -154.089608) (xy 86.038574 -154.089038)
			(xy 86.059344 -154.078843) (xy 86.066884 -154.07005) (xy 86.081664 -154.051652) (xy 86.115034 -154.018281)
			(xy 86.133432 -154.003502) (xy 86.142194 -153.99594) (xy 86.152376 -153.975181) (xy 86.15299 -153.963624)
			(xy 86.15299 -153.88336) (xy 86.152389 -153.871796) (xy 86.142216 -153.851025) (xy 86.133432 -153.843482)
			(xy 86.110947 -153.825293) (xy 86.07121 -153.783274) (xy 86.03827 -153.735739) (xy 86.012882 -153.683777)
			(xy 85.995627 -153.628579) (xy 85.9869 -153.571408) (xy 85.986366 -153.542492) (xy 85.98687 -153.515242)
			(xy 85.994627 -153.461296) (xy 86.009982 -153.409003) (xy 86.032622 -153.359428) (xy 86.062087 -153.313579)
			(xy 86.097776 -153.272389) (xy 86.138964 -153.236698) (xy 86.184812 -153.207231) (xy 86.234386 -153.184588)
			(xy 86.286678 -153.169231) (xy 86.340624 -153.161472) (xy 86.367874 -153.160984) (xy 86.396792 -153.161489)
			(xy 86.453965 -153.170216) (xy 86.509166 -153.187475) (xy 86.561128 -153.212869) (xy 86.608661 -153.245816)
			(xy 86.650676 -153.285562) (xy 86.668864 -153.30805) (xy 86.676437 -153.3168) (xy 86.697188 -153.326988)
			(xy 86.708742 -153.327608) (xy 86.789006 -153.327608) (xy 86.800574 -153.327038) (xy 86.821344 -153.316843)
			(xy 86.828884 -153.30805) (xy 86.845637 -153.287267) (xy 86.883991 -153.250137) (xy 86.927145 -153.218715)
			(xy 86.974259 -153.193616) (xy 87.024411 -153.17533) (xy 87.076622 -153.164213) (xy 87.129874 -153.160483)
			(xy 87.183126 -153.164213) (xy 87.235337 -153.17533) (xy 87.285489 -153.193616) (xy 87.332603 -153.218715)
			(xy 87.375757 -153.250137) (xy 87.414111 -153.287267) (xy 87.430864 -153.30805) (xy 87.438437 -153.3168)
			(xy 87.459188 -153.326988) (xy 87.470742 -153.327608) (xy 87.551006 -153.327608) (xy 87.562574 -153.327038)
			(xy 87.583344 -153.316843) (xy 87.590884 -153.30805) (xy 87.607637 -153.287267) (xy 87.645991 -153.250137)
			(xy 87.689145 -153.218715) (xy 87.736259 -153.193616) (xy 87.786411 -153.17533) (xy 87.838622 -153.164213)
			(xy 87.891874 -153.160483) (xy 87.945126 -153.164213) (xy 87.997337 -153.17533) (xy 88.047489 -153.193616)
			(xy 88.094603 -153.218715) (xy 88.137757 -153.250137) (xy 88.176111 -153.287267) (xy 88.192864 -153.30805)
			(xy 88.200437 -153.3168) (xy 88.221188 -153.326988) (xy 88.232742 -153.327608) (xy 88.313006 -153.327608)
			(xy 88.324574 -153.327038) (xy 88.345344 -153.316843) (xy 88.352884 -153.30805) (xy 88.369637 -153.287267)
			(xy 88.407991 -153.250137) (xy 88.451145 -153.218715) (xy 88.498259 -153.193616) (xy 88.548411 -153.17533)
			(xy 88.600622 -153.164213) (xy 88.653874 -153.160483) (xy 88.707126 -153.164213) (xy 88.759337 -153.17533)
			(xy 88.809489 -153.193616) (xy 88.856603 -153.218715) (xy 88.899757 -153.250137) (xy 88.938111 -153.287267)
			(xy 88.954864 -153.30805) (xy 88.962437 -153.3168) (xy 88.983188 -153.326988) (xy 88.994742 -153.327608)
			(xy 89.075006 -153.327608) (xy 89.086574 -153.327038) (xy 89.107344 -153.316843) (xy 89.114884 -153.30805)
			(xy 89.131637 -153.287267) (xy 89.169991 -153.250137) (xy 89.213145 -153.218715) (xy 89.260259 -153.193616)
			(xy 89.310411 -153.17533) (xy 89.362622 -153.164213) (xy 89.415874 -153.160483) (xy 89.469126 -153.164213)
			(xy 89.521337 -153.17533) (xy 89.571489 -153.193616) (xy 89.618603 -153.218715) (xy 89.661757 -153.250137)
			(xy 89.700111 -153.287267) (xy 89.716864 -153.30805) (xy 89.724437 -153.3168) (xy 89.745188 -153.326988)
			(xy 89.756742 -153.327608) (xy 89.837006 -153.327608) (xy 89.848574 -153.327038) (xy 89.869344 -153.316843)
			(xy 89.876884 -153.30805) (xy 89.893637 -153.287267) (xy 89.931991 -153.250137) (xy 89.975145 -153.218715)
			(xy 90.022259 -153.193616) (xy 90.072411 -153.17533) (xy 90.124622 -153.164213) (xy 90.177874 -153.160483)
			(xy 90.231126 -153.164213) (xy 90.283337 -153.17533) (xy 90.333489 -153.193616) (xy 90.380603 -153.218715)
			(xy 90.423757 -153.250137) (xy 90.462111 -153.287267) (xy 90.478864 -153.30805) (xy 90.486437 -153.3168)
			(xy 90.507188 -153.326988) (xy 90.518742 -153.327608) (xy 90.599006 -153.327608) (xy 90.610574 -153.327038)
			(xy 90.631344 -153.316843) (xy 90.638884 -153.30805) (xy 90.657071 -153.285564) (xy 90.699093 -153.245831)
			(xy 90.74663 -153.212894) (xy 90.798591 -153.187506) (xy 90.853789 -153.17025) (xy 90.910958 -153.16152)
			(xy 90.939874 -153.160984) (xy 90.967126 -153.161479) (xy 91.021075 -153.169233) (xy 91.073372 -153.184585)
			(xy 91.122951 -153.207224) (xy 91.168804 -153.236688) (xy 91.209997 -153.272379) (xy 91.245691 -153.313568)
			(xy 91.27516 -153.359419) (xy 91.297803 -153.408996) (xy 91.31316 -153.461292) (xy 91.320918 -153.51524)
			(xy 91.321382 -153.542492) (xy 91.320865 -153.571409) (xy 91.312136 -153.628581) (xy 91.294879 -153.68378)
			(xy 91.269487 -153.735741) (xy 91.236543 -153.783275) (xy 91.196802 -153.825292) (xy 91.174316 -153.843482)
			(xy 91.165552 -153.851041) (xy 91.155373 -153.871803) (xy 91.154758 -153.88336) (xy 91.154758 -153.963624)
			(xy 91.155352 -153.975189) (xy 91.165528 -153.995962) (xy 91.174316 -154.003502) (xy 91.192712 -154.018284)
			(xy 91.226085 -154.051652) (xy 91.240864 -154.07005) (xy 91.248437 -154.0788) (xy 91.269188 -154.088988)
			(xy 91.280742 -154.089608) (xy 91.361006 -154.089608) (xy 91.372574 -154.089038) (xy 91.393344 -154.078843)
			(xy 91.400884 -154.07005) (xy 91.419071 -154.047564) (xy 91.461093 -154.007831) (xy 91.50863 -153.974894)
			(xy 91.560591 -153.949506) (xy 91.615789 -153.93225) (xy 91.672958 -153.92352) (xy 91.701874 -153.922984)
			(xy 91.729126 -153.923479) (xy 91.783075 -153.931233) (xy 91.835372 -153.946585) (xy 91.884951 -153.969224)
			(xy 91.930804 -153.998688) (xy 91.971997 -154.034379) (xy 92.007691 -154.075568) (xy 92.03716 -154.121419)
			(xy 92.059803 -154.170996) (xy 92.07516 -154.223292) (xy 92.082918 -154.27724) (xy 92.083382 -154.304492)
			(xy 92.082865 -154.333409) (xy 92.074136 -154.390581) (xy 92.056879 -154.44578) (xy 92.031487 -154.497741)
			(xy 91.998543 -154.545275) (xy 91.958802 -154.587292) (xy 91.936316 -154.605482) (xy 91.927552 -154.613041)
			(xy 91.917373 -154.633803) (xy 91.916758 -154.64536) (xy 91.916758 -154.725624) (xy 91.917352 -154.737189)
			(xy 91.927528 -154.757962) (xy 91.936316 -154.765502) (xy 91.957092 -154.782264) (xy 91.994224 -154.820615)
			(xy 92.025648 -154.863768) (xy 92.050749 -154.910881) (xy 92.069037 -154.961032) (xy 92.080155 -155.013244)
			(xy 92.083885 -155.066495) (xy 92.080156 -155.119747) (xy 92.06904 -155.171958) (xy 92.050753 -155.22211)
			(xy 92.025653 -155.269223) (xy 91.994231 -155.312377) (xy 91.957099 -155.350729) (xy 91.936316 -155.367482)
			(xy 91.927552 -155.375041) (xy 91.917373 -155.395803) (xy 91.916758 -155.40736) (xy 91.916758 -155.487624)
			(xy 91.917352 -155.499189) (xy 91.927528 -155.519962) (xy 91.936316 -155.527502) (xy 91.957092 -155.544264)
			(xy 91.994224 -155.582615) (xy 92.025648 -155.625768) (xy 92.050749 -155.672881) (xy 92.069037 -155.723032)
			(xy 92.080155 -155.775244) (xy 92.083885 -155.828495) (xy 92.080156 -155.881747) (xy 92.06904 -155.933958)
			(xy 92.050753 -155.98411) (xy 92.025653 -156.031223) (xy 91.994231 -156.074377) (xy 91.957099 -156.112729)
			(xy 91.936316 -156.129482) (xy 91.927552 -156.137041) (xy 91.917373 -156.157803) (xy 91.916758 -156.16936)
			(xy 91.916758 -156.249624) (xy 91.917352 -156.261189) (xy 91.927528 -156.281962) (xy 91.936316 -156.289502)
			(xy 91.958804 -156.307688) (xy 91.998538 -156.349709) (xy 92.031476 -156.397245) (xy 92.056863 -156.449207)
			(xy 92.074119 -156.504406) (xy 92.082847 -156.561576) (xy 92.083382 -156.590492) (xy 92.082917 -156.618067)
			(xy 92.074965 -156.67264) (xy 92.059241 -156.7255) (xy 92.03607 -156.775546) (xy 92.005937 -156.821736)
			(xy 91.969469 -156.863106) (xy 91.948762 -156.881322) (xy 91.940632 -156.888914) (xy 91.931286 -156.909074)
			(xy 91.930728 -156.920184) (xy 91.930728 -156.9974) (xy 91.931271 -157.008513) (xy 91.940626 -157.028672)
			(xy 91.948762 -157.036262) (xy 91.96945 -157.054498) (xy 92.005924 -157.095861) (xy 92.03606 -157.142045)
			(xy 92.05923 -157.192088) (xy 92.074951 -157.244947) (xy 92.082895 -157.299519) (xy 92.083382 -157.327092)
			(xy 92.082937 -157.354346) (xy 92.075181 -157.408299) (xy 92.059824 -157.460599) (xy 92.037181 -157.51018)
			(xy 92.007711 -157.556035) (xy 91.972015 -157.597228) (xy 91.93082 -157.632922) (xy 91.884965 -157.662389)
			(xy 91.835382 -157.685031) (xy 91.783081 -157.700384) (xy 91.729128 -157.708138) (xy 91.701874 -157.7086)
			(xy 91.672959 -157.708029) (xy 91.61579 -157.699311) (xy 91.560593 -157.682063) (xy 91.508631 -157.656682)
			(xy 91.461095 -157.623747) (xy 91.419076 -157.584015) (xy 91.400884 -157.561534) (xy 91.393336 -157.552758)
			(xy 91.372566 -157.542585) (xy 91.361006 -157.541976) (xy 91.280742 -157.541976) (xy 91.269173 -157.542544)
			(xy 91.248401 -157.552738) (xy 91.240864 -157.561534) (xy 91.224111 -157.582317) (xy 91.185757 -157.619447)
			(xy 91.142603 -157.650869) (xy 91.095489 -157.675968) (xy 91.045337 -157.694254) (xy 90.993126 -157.705371)
			(xy 90.939874 -157.709101) (xy 90.886622 -157.705371) (xy 90.834411 -157.694254) (xy 90.784259 -157.675968)
			(xy 90.737145 -157.650869) (xy 90.693991 -157.619447) (xy 90.655637 -157.582317) (xy 90.638884 -157.561534)
			(xy 90.631336 -157.552758) (xy 90.610566 -157.542585) (xy 90.599006 -157.541976) (xy 90.518742 -157.541976)
			(xy 90.507173 -157.542544) (xy 90.486401 -157.552738) (xy 90.478864 -157.561534) (xy 90.460702 -157.584042)
			(xy 90.418675 -157.623774) (xy 90.371134 -157.656709) (xy 90.319167 -157.682093) (xy 90.263965 -157.699344)
			(xy 90.206792 -157.708068) (xy 90.177874 -157.7086) (xy 90.15153 -157.708154) (xy 90.099341 -157.700917)
			(xy 90.048644 -157.686571) (xy 90.000402 -157.665389) (xy 89.955532 -157.637772) (xy 89.914886 -157.604247)
			(xy 89.879239 -157.565449) (xy 89.849266 -157.522118) (xy 89.837006 -157.498796) (xy 89.830656 -157.485588)
			(xy 89.806272 -157.470856) (xy 86.739476 -157.470856) (xy 86.715092 -157.485588) (xy 86.708742 -157.498796)
			(xy 86.696496 -157.522125) (xy 86.666517 -157.565453) (xy 86.630865 -157.604247) (xy 86.590217 -157.63777)
			(xy 86.545346 -157.665386) (xy 86.497103 -157.686569) (xy 86.446407 -157.700918) (xy 86.394218 -157.708159)
			(xy 86.367874 -157.7086) (xy 86.338959 -157.708029) (xy 86.28179 -157.699311) (xy 86.226593 -157.682063)
			(xy 86.174631 -157.656682) (xy 86.127095 -157.623747) (xy 86.085076 -157.584015) (xy 86.066884 -157.561534)
			(xy 86.059336 -157.552758) (xy 86.038566 -157.542585) (xy 86.027006 -157.541976) (xy 85.946742 -157.541976)
			(xy 85.935173 -157.542544) (xy 85.914401 -157.552738) (xy 85.906864 -157.561534) (xy 85.890111 -157.582317)
			(xy 85.851757 -157.619447) (xy 85.808603 -157.650869) (xy 85.761489 -157.675968) (xy 85.711337 -157.694254)
			(xy 85.659126 -157.705371) (xy 85.605874 -157.709101) (xy 85.552622 -157.705371) (xy 85.500411 -157.694254)
			(xy 85.450259 -157.675968) (xy 85.403145 -157.650869) (xy 85.359991 -157.619447) (xy 85.321637 -157.582317)
			(xy 85.304884 -157.561534) (xy 85.297336 -157.552758) (xy 85.276566 -157.542585) (xy 85.265006 -157.541976)
			(xy 85.184742 -157.541976) (xy 85.173173 -157.542544) (xy 85.152401 -157.552738) (xy 85.144864 -157.561534)
			(xy 85.126702 -157.584042) (xy 85.084675 -157.623774) (xy 85.037134 -157.656709) (xy 84.985167 -157.682093)
			(xy 84.929965 -157.699344) (xy 84.872792 -157.708068) (xy 84.843874 -157.7086) (xy 84.8146 -157.70806)
			(xy 84.756742 -157.699091) (xy 84.700935 -157.681383) (xy 84.64849 -157.655352) (xy 84.600641 -157.621611)
			(xy 84.579206 -157.601666) (xy 84.57184 -157.594808) (xy 84.553806 -157.587442) (xy 84.463382 -157.587442)
			(xy 84.445348 -157.594808) (xy 84.437982 -157.601666) (xy 84.416527 -157.621587) (xy 84.368676 -157.655316)
			(xy 84.316235 -157.681342) (xy 84.260436 -157.699057) (xy 84.202586 -157.708044) (xy 84.173314 -157.7086)
			(xy 84.146061 -157.708132) (xy 84.09211 -157.700376) (xy 84.039812 -157.685022) (xy 83.990231 -157.66238)
			(xy 83.944378 -157.632913) (xy 83.903185 -157.59722) (xy 83.867491 -157.556027) (xy 83.838023 -157.510174)
			(xy 83.81538 -157.460594) (xy 83.800025 -157.408296) (xy 83.792269 -157.354345) (xy 83.791806 -157.327092)
			(xy 83.792333 -157.29952) (xy 83.800273 -157.244949) (xy 83.815985 -157.192091) (xy 83.839144 -157.142044)
			(xy 83.869266 -157.095853) (xy 83.905723 -157.054479) (xy 83.926426 -157.036262) (xy 83.934561 -157.028675)
			(xy 83.943905 -157.008512) (xy 83.94446 -156.9974) (xy 83.94446 -156.920184) (xy 83.94393 -156.909069)
			(xy 83.934566 -156.88891) (xy 83.926426 -156.881322) (xy 83.905727 -156.863097) (xy 83.869255 -156.821732)
			(xy 83.839121 -156.775545) (xy 83.815953 -156.7255) (xy 83.800234 -156.672639) (xy 83.792292 -156.618066)
			(xy 83.791806 -156.590492) (xy 83.792388 -156.561577) (xy 83.801103 -156.504409) (xy 83.818349 -156.449211)
			(xy 83.843728 -156.397249) (xy 83.876661 -156.349714) (xy 83.916391 -156.307694) (xy 83.938872 -156.289502)
			(xy 83.947641 -156.281947) (xy 83.957817 -156.261183) (xy 83.95843 -156.249624) (xy 83.95843 -156.16936)
			(xy 83.957849 -156.157793) (xy 83.947664 -156.13702) (xy 83.938872 -156.129482) (xy 83.91808 -156.112738)
			(xy 83.880949 -156.074385) (xy 83.849526 -156.031229) (xy 83.824427 -155.984115) (xy 83.80614 -155.933961)
			(xy 83.795023 -155.881748) (xy 83.791294 -155.828495) (xy 81.127405 -155.828495) (xy 80.551274 -156.404564)
			(xy 80.54443 -156.411963) (xy 80.536707 -156.430562) (xy 80.536288 -156.440632) (xy 80.536288 -164.097716)
			(xy 86.637622 -164.097716) (xy 86.638123 -164.068308) (xy 86.647149 -164.010189) (xy 86.66499 -163.954145)
			(xy 86.691223 -163.901503) (xy 86.725225 -163.853512) (xy 86.745318 -163.832032) (xy 86.751922 -163.825428)
			(xy 86.759288 -163.807902) (xy 86.762082 -163.720526) (xy 86.755732 -163.702746) (xy 86.749382 -163.69538)
			(xy 86.732199 -163.674557) (xy 86.703277 -163.62897) (xy 86.681067 -163.579764) (xy 86.66601 -163.527919)
			(xy 86.658407 -163.47447) (xy 86.657942 -163.447476) (xy 86.658384 -163.420105) (xy 86.666206 -163.365924)
			(xy 86.6817 -163.31342) (xy 86.704547 -163.263674) (xy 86.734278 -163.217709) (xy 86.751922 -163.196778)
			(xy 86.758018 -163.189666) (xy 86.764368 -163.172648) (xy 86.764368 -163.087304) (xy 86.758018 -163.070286)
			(xy 86.751922 -163.063174) (xy 86.734308 -163.042222) (xy 86.704591 -162.996255) (xy 86.68175 -162.946513)
			(xy 86.666253 -162.894016) (xy 86.658419 -162.839844) (xy 86.657942 -162.812476) (xy 86.658333 -162.78522)
			(xy 86.666094 -162.731264) (xy 86.681456 -162.678962) (xy 86.704105 -162.629378) (xy 86.73358 -162.583523)
			(xy 86.769281 -162.542329) (xy 86.810482 -162.506636) (xy 86.856343 -162.477169) (xy 86.905931 -162.45453)
			(xy 86.958236 -162.439178) (xy 87.012194 -162.431427) (xy 87.03945 -162.430968) (xy 87.06682 -162.431447)
			(xy 87.120999 -162.439259) (xy 87.173503 -162.454744) (xy 87.22325 -162.477584) (xy 87.269217 -162.507307)
			(xy 87.290148 -162.524948) (xy 87.29726 -162.531044) (xy 87.314278 -162.537394) (xy 87.399622 -162.537394)
			(xy 87.41664 -162.531044) (xy 87.423752 -162.524948) (xy 87.444685 -162.507307) (xy 87.490653 -162.477583)
			(xy 87.540399 -162.454737) (xy 87.592901 -162.439241) (xy 87.647079 -162.431412) (xy 87.701821 -162.431412)
			(xy 87.755999 -162.439241) (xy 87.808501 -162.454737) (xy 87.858247 -162.477583) (xy 87.904215 -162.507307)
			(xy 87.925148 -162.524948) (xy 87.93226 -162.531044) (xy 87.949278 -162.537394) (xy 88.034622 -162.537394)
			(xy 88.05164 -162.531044) (xy 88.058752 -162.524948) (xy 88.079685 -162.507307) (xy 88.125653 -162.477583)
			(xy 88.175399 -162.454737) (xy 88.227901 -162.439241) (xy 88.282079 -162.431412) (xy 88.336821 -162.431412)
			(xy 88.390999 -162.439241) (xy 88.443501 -162.454737) (xy 88.493247 -162.477583) (xy 88.539215 -162.507307)
			(xy 88.560148 -162.524948) (xy 88.56726 -162.531044) (xy 88.584278 -162.537394) (xy 88.669622 -162.537394)
			(xy 88.68664 -162.531044) (xy 88.693752 -162.524948) (xy 88.714685 -162.507307) (xy 88.760653 -162.477583)
			(xy 88.810399 -162.454737) (xy 88.862901 -162.439241) (xy 88.917079 -162.431412) (xy 88.971821 -162.431412)
			(xy 89.025999 -162.439241) (xy 89.078501 -162.454737) (xy 89.128247 -162.477583) (xy 89.174215 -162.507307)
			(xy 89.195148 -162.524948) (xy 89.20226 -162.531044) (xy 89.219278 -162.537394) (xy 89.304622 -162.537394)
			(xy 89.32164 -162.531044) (xy 89.328752 -162.524948) (xy 89.349698 -162.507325) (xy 89.395666 -162.477609)
			(xy 89.44541 -162.45477) (xy 89.497908 -162.439275) (xy 89.552082 -162.431443) (xy 89.57945 -162.430968)
			(xy 89.60876 -162.431511) (xy 89.666686 -162.440505) (xy 89.722554 -162.458257) (xy 89.775046 -162.48435)
			(xy 89.822928 -162.518168) (xy 89.844372 -162.538156) (xy 89.851738 -162.545014) (xy 89.86901 -162.552126)
			(xy 89.958418 -162.55365) (xy 89.975944 -162.546792) (xy 89.98331 -162.540188) (xy 90.004476 -162.521627)
			(xy 90.051268 -162.490328) (xy 90.102149 -162.466241) (xy 90.156017 -162.449889) (xy 90.211702 -162.441627)
			(xy 90.23985 -162.441128) (xy 90.267103 -162.441602) (xy 90.321056 -162.449353) (xy 90.373356 -162.464705)
			(xy 90.422938 -162.487344) (xy 90.468793 -162.51681) (xy 90.509987 -162.552503) (xy 90.545682 -162.593696)
			(xy 90.575149 -162.63955) (xy 90.597791 -162.689131) (xy 90.613144 -162.741431) (xy 90.620897 -162.795383)
			(xy 90.621358 -162.822636) (xy 90.620923 -162.850007) (xy 90.613099 -162.904188) (xy 90.597604 -162.956692)
			(xy 90.574755 -163.006439) (xy 90.545023 -163.052404) (xy 90.527378 -163.073334) (xy 90.521282 -163.080446)
			(xy 90.514932 -163.097464) (xy 90.514932 -163.182808) (xy 90.521282 -163.199826) (xy 90.527378 -163.206938)
			(xy 90.544998 -163.227885) (xy 90.574714 -163.273854) (xy 90.597553 -163.323597) (xy 90.613049 -163.376095)
			(xy 90.620882 -163.430268) (xy 90.621358 -163.457636) (xy 90.620806 -163.487042) (xy 90.611789 -163.545157)
			(xy 90.593959 -163.601201) (xy 90.567738 -163.653843) (xy 90.533749 -163.701837) (xy 90.513662 -163.72332)
			(xy 90.507058 -163.729924) (xy 90.499692 -163.74745) (xy 90.496898 -163.834826) (xy 90.503248 -163.852606)
			(xy 90.509598 -163.859972) (xy 90.526755 -163.880815) (xy 90.555682 -163.926396) (xy 90.577898 -163.975598)
			(xy 90.592961 -164.027438) (xy 90.60057 -164.080884) (xy 90.601038 -164.107876) (xy 90.6005 -164.135125)
			(xy 90.592747 -164.189069) (xy 90.577396 -164.241361) (xy 90.55476 -164.290936) (xy 90.525299 -164.336785)
			(xy 90.489613 -164.377975) (xy 90.448429 -164.413667) (xy 90.402584 -164.443134) (xy 90.353012 -164.465778)
			(xy 90.300722 -164.481136) (xy 90.246779 -164.488896) (xy 90.21953 -164.489384) (xy 90.19022 -164.488839)
			(xy 90.132295 -164.479843) (xy 90.076428 -164.462091) (xy 90.023935 -164.435999) (xy 89.976053 -164.402183)
			(xy 89.954608 -164.382196) (xy 89.947242 -164.375338) (xy 89.92997 -164.368226) (xy 89.840562 -164.366702)
			(xy 89.823036 -164.37356) (xy 89.81567 -164.380164) (xy 89.794479 -164.398695) (xy 89.747694 -164.429997)
			(xy 89.696818 -164.454089) (xy 89.642956 -164.470448) (xy 89.587276 -164.478719) (xy 89.55913 -164.479224)
			(xy 89.53176 -164.478759) (xy 89.47758 -164.470944) (xy 89.425076 -164.455455) (xy 89.375329 -164.432613)
			(xy 89.329363 -164.402887) (xy 89.308432 -164.385244) (xy 89.30132 -164.379148) (xy 89.284302 -164.372798)
			(xy 89.198958 -164.372798) (xy 89.18194 -164.379148) (xy 89.174828 -164.385244) (xy 89.153895 -164.402885)
			(xy 89.107927 -164.432609) (xy 89.058181 -164.455455) (xy 89.005679 -164.470951) (xy 88.951501 -164.47878)
			(xy 88.896759 -164.47878) (xy 88.842581 -164.470951) (xy 88.790079 -164.455455) (xy 88.740333 -164.432609)
			(xy 88.694365 -164.402885) (xy 88.673432 -164.385244) (xy 88.66632 -164.379148) (xy 88.649302 -164.372798)
			(xy 88.563958 -164.372798) (xy 88.54694 -164.379148) (xy 88.539828 -164.385244) (xy 88.518895 -164.402885)
			(xy 88.472927 -164.432609) (xy 88.423181 -164.455455) (xy 88.370679 -164.470951) (xy 88.316501 -164.47878)
			(xy 88.261759 -164.47878) (xy 88.207581 -164.470951) (xy 88.155079 -164.455455) (xy 88.105333 -164.432609)
			(xy 88.059365 -164.402885) (xy 88.038432 -164.385244) (xy 88.03132 -164.379148) (xy 88.014302 -164.372798)
			(xy 87.928958 -164.372798) (xy 87.91194 -164.379148) (xy 87.904828 -164.385244) (xy 87.883895 -164.402885)
			(xy 87.837927 -164.432609) (xy 87.788181 -164.455455) (xy 87.735679 -164.470951) (xy 87.681501 -164.47878)
			(xy 87.626759 -164.47878) (xy 87.572581 -164.470951) (xy 87.520079 -164.455455) (xy 87.470333 -164.432609)
			(xy 87.424365 -164.402885) (xy 87.403432 -164.385244) (xy 87.39632 -164.379148) (xy 87.379302 -164.372798)
			(xy 87.293958 -164.372798) (xy 87.27694 -164.379148) (xy 87.269828 -164.385244) (xy 87.248902 -164.402891)
			(xy 87.202927 -164.4326) (xy 87.153178 -164.455434) (xy 87.100676 -164.470923) (xy 87.046499 -164.478751)
			(xy 87.01913 -164.479224) (xy 86.991879 -164.478717) (xy 86.93793 -164.470964) (xy 86.885634 -164.455613)
			(xy 86.836055 -164.432975) (xy 86.790203 -164.403512) (xy 86.74901 -164.367823) (xy 86.713316 -164.326634)
			(xy 86.683847 -164.280785) (xy 86.661203 -164.231209) (xy 86.645845 -164.178915) (xy 86.638086 -164.124967)
			(xy 86.637622 -164.097716) (xy 80.536288 -164.097716) (xy 80.536288 -166.004424) (xy 82.10067 -166.004424)
			(xy 82.10067 -165.919728) (xy 82.108721 -165.835414) (xy 82.12475 -165.752248) (xy 82.148611 -165.670981)
			(xy 82.18009 -165.592351) (xy 82.218901 -165.51707) (xy 82.264691 -165.445818) (xy 82.317047 -165.379242)
			(xy 82.375495 -165.317944) (xy 82.439505 -165.262479) (xy 82.508497 -165.21335) (xy 82.581847 -165.171001)
			(xy 82.65889 -165.135817) (xy 82.738929 -165.108115) (xy 82.821238 -165.088147) (xy 82.905073 -165.076094)
			(xy 82.989674 -165.072064) (xy 83.074275 -165.076094) (xy 83.15811 -165.088147) (xy 83.240419 -165.108115)
			(xy 83.320458 -165.135817) (xy 83.397501 -165.171001) (xy 83.470851 -165.21335) (xy 83.539843 -165.262479)
			(xy 83.603853 -165.317944) (xy 83.662301 -165.379242) (xy 83.714657 -165.445818) (xy 83.760447 -165.51707)
			(xy 83.799258 -165.592351) (xy 83.830737 -165.670981) (xy 83.854598 -165.752248) (xy 83.870627 -165.835414)
			(xy 83.878678 -165.919728) (xy 83.879182 -165.962076) (xy 83.878678 -166.004424) (xy 91.49867 -166.004424)
			(xy 91.49867 -165.919728) (xy 91.506721 -165.835414) (xy 91.52275 -165.752248) (xy 91.546611 -165.670981)
			(xy 91.57809 -165.592351) (xy 91.616901 -165.51707) (xy 91.662691 -165.445818) (xy 91.715047 -165.379242)
			(xy 91.773495 -165.317944) (xy 91.837505 -165.262479) (xy 91.906497 -165.21335) (xy 91.979847 -165.171001)
			(xy 92.05689 -165.135817) (xy 92.136929 -165.108115) (xy 92.219238 -165.088147) (xy 92.303073 -165.076094)
			(xy 92.387674 -165.072064) (xy 92.472275 -165.076094) (xy 92.55611 -165.088147) (xy 92.638419 -165.108115)
			(xy 92.718458 -165.135817) (xy 92.795501 -165.171001) (xy 92.868851 -165.21335) (xy 92.937843 -165.262479)
			(xy 93.001853 -165.317944) (xy 93.060301 -165.379242) (xy 93.112657 -165.445818) (xy 93.158447 -165.51707)
			(xy 93.197258 -165.592351) (xy 93.228737 -165.670981) (xy 93.252598 -165.752248) (xy 93.268627 -165.835414)
			(xy 93.276678 -165.919728) (xy 93.277182 -165.962076) (xy 93.276678 -166.004424) (xy 93.268627 -166.088738)
			(xy 93.252598 -166.171904) (xy 93.228737 -166.253171) (xy 93.197258 -166.331801) (xy 93.158447 -166.407082)
			(xy 93.112657 -166.478334) (xy 93.060301 -166.54491) (xy 93.001853 -166.606208) (xy 92.937843 -166.661673)
			(xy 92.868851 -166.710802) (xy 92.795501 -166.753151) (xy 92.718458 -166.788335) (xy 92.638419 -166.816037)
			(xy 92.55611 -166.836005) (xy 92.472275 -166.848058) (xy 92.387674 -166.852089) (xy 92.303073 -166.848058)
			(xy 92.219238 -166.836005) (xy 92.136929 -166.816037) (xy 92.05689 -166.788335) (xy 91.979847 -166.753151)
			(xy 91.906497 -166.710802) (xy 91.837505 -166.661673) (xy 91.773495 -166.606208) (xy 91.715047 -166.54491)
			(xy 91.662691 -166.478334) (xy 91.616901 -166.407082) (xy 91.57809 -166.331801) (xy 91.546611 -166.253171)
			(xy 91.52275 -166.171904) (xy 91.506721 -166.088738) (xy 91.49867 -166.004424) (xy 83.878678 -166.004424)
			(xy 83.870627 -166.088738) (xy 83.854598 -166.171904) (xy 83.830737 -166.253171) (xy 83.799258 -166.331801)
			(xy 83.760447 -166.407082) (xy 83.714657 -166.478334) (xy 83.662301 -166.54491) (xy 83.603853 -166.606208)
			(xy 83.539843 -166.661673) (xy 83.470851 -166.710802) (xy 83.397501 -166.753151) (xy 83.320458 -166.788335)
			(xy 83.240419 -166.816037) (xy 83.15811 -166.836005) (xy 83.074275 -166.848058) (xy 82.989674 -166.852089)
			(xy 82.905073 -166.848058) (xy 82.821238 -166.836005) (xy 82.738929 -166.816037) (xy 82.65889 -166.788335)
			(xy 82.581847 -166.753151) (xy 82.508497 -166.710802) (xy 82.439505 -166.661673) (xy 82.375495 -166.606208)
			(xy 82.317047 -166.54491) (xy 82.264691 -166.478334) (xy 82.218901 -166.407082) (xy 82.18009 -166.331801)
			(xy 82.148611 -166.253171) (xy 82.12475 -166.171904) (xy 82.108721 -166.088738) (xy 82.10067 -166.004424)
			(xy 80.536288 -166.004424) (xy 80.536288 -168.504546) (xy 82.10067 -168.504546) (xy 82.10067 -168.41985)
			(xy 82.108721 -168.335536) (xy 82.12475 -168.25237) (xy 82.148611 -168.171103) (xy 82.18009 -168.092473)
			(xy 82.218901 -168.017192) (xy 82.264691 -167.94594) (xy 82.317047 -167.879364) (xy 82.375495 -167.818066)
			(xy 82.439505 -167.762601) (xy 82.508497 -167.713472) (xy 82.581847 -167.671123) (xy 82.65889 -167.635939)
			(xy 82.738929 -167.608237) (xy 82.821238 -167.588269) (xy 82.905073 -167.576216) (xy 82.989674 -167.572186)
			(xy 83.074275 -167.576216) (xy 83.15811 -167.588269) (xy 83.240419 -167.608237) (xy 83.320458 -167.635939)
			(xy 83.397501 -167.671123) (xy 83.470851 -167.713472) (xy 83.539843 -167.762601) (xy 83.603853 -167.818066)
			(xy 83.662301 -167.879364) (xy 83.714657 -167.94594) (xy 83.760447 -168.017192) (xy 83.799258 -168.092473)
			(xy 83.830737 -168.171103) (xy 83.854598 -168.25237) (xy 83.870627 -168.335536) (xy 83.878678 -168.41985)
			(xy 83.879182 -168.462198) (xy 83.878678 -168.504546) (xy 91.49867 -168.504546) (xy 91.49867 -168.41985)
			(xy 91.506721 -168.335536) (xy 91.52275 -168.25237) (xy 91.546611 -168.171103) (xy 91.57809 -168.092473)
			(xy 91.616901 -168.017192) (xy 91.662691 -167.94594) (xy 91.715047 -167.879364) (xy 91.773495 -167.818066)
			(xy 91.837505 -167.762601) (xy 91.906497 -167.713472) (xy 91.979847 -167.671123) (xy 92.05689 -167.635939)
			(xy 92.136929 -167.608237) (xy 92.219238 -167.588269) (xy 92.303073 -167.576216) (xy 92.387674 -167.572186)
			(xy 92.472275 -167.576216) (xy 92.55611 -167.588269) (xy 92.638419 -167.608237) (xy 92.718458 -167.635939)
			(xy 92.795501 -167.671123) (xy 92.868851 -167.713472) (xy 92.937843 -167.762601) (xy 93.001853 -167.818066)
			(xy 93.060301 -167.879364) (xy 93.112657 -167.94594) (xy 93.158447 -168.017192) (xy 93.197258 -168.092473)
			(xy 93.228737 -168.171103) (xy 93.252598 -168.25237) (xy 93.268627 -168.335536) (xy 93.276678 -168.41985)
			(xy 93.277182 -168.462198) (xy 93.276678 -168.504546) (xy 93.268627 -168.58886) (xy 93.252598 -168.672026)
			(xy 93.228737 -168.753293) (xy 93.197258 -168.831923) (xy 93.158447 -168.907204) (xy 93.112657 -168.978456)
			(xy 93.060301 -169.045032) (xy 93.001853 -169.10633) (xy 92.937843 -169.161795) (xy 92.868851 -169.210924)
			(xy 92.795501 -169.253273) (xy 92.718458 -169.288457) (xy 92.638419 -169.316159) (xy 92.55611 -169.336127)
			(xy 92.472275 -169.34818) (xy 92.387674 -169.352211) (xy 92.303073 -169.34818) (xy 92.219238 -169.336127)
			(xy 92.136929 -169.316159) (xy 92.05689 -169.288457) (xy 91.979847 -169.253273) (xy 91.906497 -169.210924)
			(xy 91.837505 -169.161795) (xy 91.773495 -169.10633) (xy 91.715047 -169.045032) (xy 91.662691 -168.978456)
			(xy 91.616901 -168.907204) (xy 91.57809 -168.831923) (xy 91.546611 -168.753293) (xy 91.52275 -168.672026)
			(xy 91.506721 -168.58886) (xy 91.49867 -168.504546) (xy 83.878678 -168.504546) (xy 83.870627 -168.58886)
			(xy 83.854598 -168.672026) (xy 83.830737 -168.753293) (xy 83.799258 -168.831923) (xy 83.760447 -168.907204)
			(xy 83.714657 -168.978456) (xy 83.662301 -169.045032) (xy 83.603853 -169.10633) (xy 83.539843 -169.161795)
			(xy 83.470851 -169.210924) (xy 83.397501 -169.253273) (xy 83.320458 -169.288457) (xy 83.240419 -169.316159)
			(xy 83.15811 -169.336127) (xy 83.074275 -169.34818) (xy 82.989674 -169.352211) (xy 82.905073 -169.34818)
			(xy 82.821238 -169.336127) (xy 82.738929 -169.316159) (xy 82.65889 -169.288457) (xy 82.581847 -169.253273)
			(xy 82.508497 -169.210924) (xy 82.439505 -169.161795) (xy 82.375495 -169.10633) (xy 82.317047 -169.045032)
			(xy 82.264691 -168.978456) (xy 82.218901 -168.907204) (xy 82.18009 -168.831923) (xy 82.148611 -168.753293)
			(xy 82.12475 -168.672026) (xy 82.108721 -168.58886) (xy 82.10067 -168.504546) (xy 80.536288 -168.504546)
			(xy 80.536288 -170.998642) (xy 80.536718 -171.008709) (xy 80.544442 -171.027304) (xy 80.551274 -171.03471)
			(xy 82.000852 -172.484034) (xy 82.01467 -172.498512) (xy 82.03688 -172.531799) (xy 82.052156 -172.568785)
			(xy 82.059909 -172.608043) (xy 82.060288 -172.628052) (xy 82.060288 -177.795682) (xy 82.060726 -177.805746)
			(xy 82.06846 -177.82433) (xy 82.075274 -177.83175) (xy 82.265266 -178.021742) (xy 82.288126 -178.029108)
			(xy 82.300318 -178.027076) (xy 82.315081 -178.024915) (xy 82.344834 -178.022628) (xy 82.359754 -178.022504)
			(xy 82.387009 -178.022964) (xy 82.440964 -178.030716) (xy 82.493267 -178.046068) (xy 82.542852 -178.068708)
			(xy 82.58871 -178.098175) (xy 82.629907 -178.133869) (xy 82.665605 -178.175063) (xy 82.695076 -178.220918)
			(xy 82.71772 -178.270501) (xy 82.733077 -178.322803) (xy 82.740833 -178.376757) (xy 82.741262 -178.404012)
			(xy 82.74061 -178.435575) (xy 82.73022 -178.49784) (xy 82.709727 -178.557547) (xy 82.695288 -178.585622)
			(xy 82.690462 -178.594512) (xy 82.68843 -178.61407) (xy 82.714084 -178.702208) (xy 82.72653 -178.717702)
			(xy 82.73542 -178.722782) (xy 82.742786 -178.726846) (xy 82.752438 -178.732688) (xy 82.774536 -178.73472)
			(xy 82.869024 -178.701192) (xy 82.885026 -178.685698) (xy 82.88909 -178.675284) (xy 82.89978 -178.648503)
			(xy 82.928061 -178.598251) (xy 82.963588 -178.552832) (xy 83.005549 -178.513281) (xy 83.052987 -178.4805)
			(xy 83.104822 -178.455238) (xy 83.159869 -178.438069) (xy 83.216875 -178.429386) (xy 83.245706 -178.428904)
			(xy 83.272956 -178.429391) (xy 83.326901 -178.437148) (xy 83.379194 -178.452503) (xy 83.428769 -178.475144)
			(xy 83.474617 -178.504609) (xy 83.515805 -178.540299) (xy 83.551495 -178.581488) (xy 83.580959 -178.627337)
			(xy 83.603599 -178.676912) (xy 83.618954 -178.729204) (xy 83.62671 -178.78315) (xy 83.62671 -178.83765)
			(xy 83.618954 -178.891596) (xy 83.609603 -178.923442) (xy 83.868514 -178.923442) (xy 83.869022 -178.895968)
			(xy 83.876908 -178.841589) (xy 83.892523 -178.788907) (xy 83.915543 -178.739014) (xy 83.94549 -178.692944)
			(xy 83.963256 -178.671982) (xy 83.969352 -178.66487) (xy 83.975702 -178.647852) (xy 83.975702 -178.562)
			(xy 83.969352 -178.544982) (xy 83.963256 -178.53787) (xy 83.94549 -178.51691) (xy 83.915567 -178.470827)
			(xy 83.892555 -178.420932) (xy 83.87693 -178.368255) (xy 83.869013 -178.313882) (xy 83.868514 -178.28641)
			(xy 83.869 -178.259159) (xy 83.876756 -178.205211) (xy 83.892111 -178.152916) (xy 83.914753 -178.103339)
			(xy 83.944219 -178.057489) (xy 83.97991 -178.016298) (xy 84.021101 -177.980607) (xy 84.066951 -177.951141)
			(xy 84.116528 -177.928499) (xy 84.168823 -177.913144) (xy 84.222771 -177.905388) (xy 84.277273 -177.905388)
			(xy 84.331221 -177.913144) (xy 84.383516 -177.928499) (xy 84.433093 -177.951141) (xy 84.478943 -177.980607)
			(xy 84.515864 -178.012598) (xy 90.229944 -178.012598) (xy 90.229944 -176.243234) (xy 90.230411 -176.22322)
			(xy 90.238245 -176.183965) (xy 90.253579 -176.14699) (xy 90.275826 -176.113713) (xy 90.289634 -176.099216)
			(xy 95.437198 -170.951906) (xy 95.444028 -170.944498) (xy 95.451754 -170.925905) (xy 95.452184 -170.915838)
			(xy 95.452184 -153.187908) (xy 95.451759 -153.177839) (xy 95.444038 -153.159241) (xy 95.437198 -153.15184)
			(xy 93.788738 -151.503634) (xy 93.774885 -151.489176) (xy 93.75263 -151.455893) (xy 93.737305 -151.418905)
			(xy 93.7295 -151.379635) (xy 93.729048 -151.359616) (xy 93.729048 -150.315168) (xy 93.729563 -150.295157)
			(xy 93.737387 -150.255906) (xy 93.752707 -150.218932) (xy 93.774939 -150.185651) (xy 93.788738 -150.17115)
			(xy 94.302834 -149.657308) (xy 94.309668 -149.649903) (xy 94.31739 -149.631307) (xy 94.31782 -149.62124)
			(xy 94.31782 -148.97989) (xy 94.317421 -148.969817) (xy 94.309684 -148.951219) (xy 94.302834 -148.943822)
			(xy 92.939616 -147.580858) (xy 92.925861 -147.566332) (xy 92.903683 -147.533046) (xy 92.888418 -147.496076)
			(xy 92.880653 -147.456839) (xy 92.88018 -147.43684) (xy 92.88018 -141.79042) (xy 92.879753 -141.780771)
			(xy 92.872599 -141.762849) (xy 92.859306 -141.74886) (xy 92.850716 -141.744446) (xy 92.753942 -141.699234)
			(xy 92.724478 -141.703044) (xy 92.713048 -141.712696) (xy 92.692334 -141.729437) (xy 92.64716 -141.757645)
			(xy 92.598502 -141.779298) (xy 92.547306 -141.793972) (xy 92.494567 -141.801384) (xy 92.467938 -141.80185)
			(xy 92.440686 -141.801305) (xy 92.386737 -141.793554) (xy 92.334441 -141.778203) (xy 92.284861 -141.755565)
			(xy 92.239008 -141.726101) (xy 92.197816 -141.690411) (xy 92.162122 -141.649222) (xy 92.132653 -141.603372)
			(xy 92.110011 -141.553795) (xy 92.094654 -141.5015) (xy 92.086897 -141.447552) (xy 92.086897 -141.393048)
			(xy 92.094654 -141.3391) (xy 92.110011 -141.286805) (xy 92.132653 -141.237228) (xy 92.162122 -141.191378)
			(xy 92.197816 -141.150189) (xy 92.239008 -141.114499) (xy 92.284861 -141.085035) (xy 92.334441 -141.062397)
			(xy 92.386737 -141.047046) (xy 92.440686 -141.039295) (xy 92.467938 -141.038834) (xy 92.494569 -141.039264)
			(xy 92.547312 -141.046678) (xy 92.598511 -141.061357) (xy 92.647171 -141.083015) (xy 92.692345 -141.11123)
			(xy 92.713048 -141.127988) (xy 92.724478 -141.13764) (xy 92.753942 -141.14145) (xy 92.850716 -141.096238)
			(xy 92.859274 -141.091788) (xy 92.872517 -141.077782) (xy 92.879706 -141.059898) (xy 92.88018 -141.050264)
			(xy 92.88018 -140.954252) (xy 92.880568 -140.934244) (xy 92.88832 -140.894986) (xy 92.903593 -140.858001)
			(xy 92.9258 -140.824713) (xy 92.939616 -140.810234) (xy 93.183964 -140.56614) (xy 93.19133 -140.54328)
			(xy 93.189298 -140.531088) (xy 93.187143 -140.516324) (xy 93.184852 -140.486572) (xy 93.184726 -140.471652)
			(xy 93.185197 -140.444014) (xy 93.193157 -140.389315) (xy 93.208932 -140.336339) (xy 93.232191 -140.286196)
			(xy 93.262446 -140.239937) (xy 93.299065 -140.198531) (xy 93.319854 -140.180314) (xy 93.327474 -140.173964)
			(xy 93.336618 -140.156946) (xy 93.346016 -140.06703) (xy 93.340682 -140.048488) (xy 93.334586 -140.040614)
			(xy 93.31952 -140.020498) (xy 93.294254 -139.977053) (xy 93.274912 -139.930666) (xy 93.261828 -139.88214)
			(xy 93.25523 -139.832317) (xy 93.25483 -139.807188) (xy 93.255316 -139.779937) (xy 93.263072 -139.725989)
			(xy 93.278427 -139.673694) (xy 93.301069 -139.624117) (xy 93.330535 -139.578267) (xy 93.366226 -139.537076)
			(xy 93.407417 -139.501385) (xy 93.453267 -139.471919) (xy 93.502844 -139.449277) (xy 93.555139 -139.433922)
			(xy 93.609087 -139.426166) (xy 93.663589 -139.426166) (xy 93.717537 -139.433922) (xy 93.769832 -139.449277)
			(xy 93.819409 -139.471919) (xy 93.865259 -139.501385) (xy 93.90645 -139.537076) (xy 93.942141 -139.578267)
			(xy 93.971607 -139.624117) (xy 93.994249 -139.673694) (xy 94.009604 -139.725989) (xy 94.01736 -139.779937)
			(xy 94.017846 -139.807188) (xy 94.017377 -139.834825) (xy 94.009413 -139.889523) (xy 93.993637 -139.942498)
			(xy 93.970377 -139.992641) (xy 93.940122 -140.0389) (xy 93.903506 -140.080307) (xy 93.882718 -140.098526)
			(xy 93.875098 -140.104876) (xy 93.865954 -140.121894) (xy 93.856556 -140.21181) (xy 93.86189 -140.230352)
			(xy 93.867986 -140.238226) (xy 93.883066 -140.258332) (xy 93.908331 -140.30178) (xy 93.927671 -140.348169)
			(xy 93.940751 -140.396697) (xy 93.947345 -140.446522) (xy 93.947742 -140.471652) (xy 93.947234 -140.49121)
			(xy 93.946726 -140.501878) (xy 93.953838 -140.521182) (xy 94.019116 -140.590016) (xy 94.038166 -140.598144)
			(xy 94.048834 -140.598144) (xy 94.050866 -140.598144) (xy 94.086934 -140.557758) (xy 94.093281 -140.549951)
			(xy 94.099945 -140.530989) (xy 94.099888 -140.520928) (xy 94.099126 -140.497052) (xy 94.099612 -140.469801)
			(xy 94.107368 -140.415853) (xy 94.122723 -140.363558) (xy 94.145365 -140.313981) (xy 94.174831 -140.268131)
			(xy 94.210522 -140.22694) (xy 94.251713 -140.191249) (xy 94.297563 -140.161783) (xy 94.34714 -140.139141)
			(xy 94.399435 -140.123786) (xy 94.453383 -140.11603) (xy 94.507885 -140.11603) (xy 94.561833 -140.123786)
			(xy 94.614128 -140.139141) (xy 94.663705 -140.161783) (xy 94.709555 -140.191249) (xy 94.750746 -140.22694)
			(xy 94.786437 -140.268131) (xy 94.815903 -140.313981) (xy 94.838545 -140.363558) (xy 94.8539 -140.415853)
			(xy 94.861656 -140.469801) (xy 94.862142 -140.497052) (xy 94.862019 -140.511972) (xy 94.859732 -140.541725)
			(xy 94.85757 -140.556488) (xy 94.855538 -140.56868) (xy 94.862904 -140.59154) (xy 95.540576 -141.269212)
			(xy 95.548044 -141.275923) (xy 95.566613 -141.283504) (xy 95.576644 -141.283944) (xy 97.325434 -141.283944)
			(xy 97.345447 -141.284431) (xy 97.384701 -141.292259) (xy 97.421676 -141.307587) (xy 97.454954 -141.329829)
			(xy 97.469452 -141.343634) (xy 98.22942 -142.103602) (xy 99.991416 -142.103602) (xy 99.995487 -142.04798)
			(xy 100.007613 -141.993543) (xy 100.027536 -141.941452) (xy 100.054832 -141.892817) (xy 100.088918 -141.848674)
			(xy 100.129067 -141.809965) (xy 100.174425 -141.777514) (xy 100.224025 -141.752013) (xy 100.276809 -141.734006)
			(xy 100.331652 -141.723876) (xy 100.387386 -141.721839) (xy 100.442823 -141.727939) (xy 100.49678 -141.742045)
			(xy 100.548109 -141.763857) (xy 100.595715 -141.792911) (xy 100.638583 -141.828586) (xy 100.6758 -141.870123)
			(xy 100.706573 -141.916636) (xy 100.730245 -141.967133) (xy 100.746313 -142.02054) (xy 100.754433 -142.075716)
			(xy 100.754942 -142.103602) (xy 100.754433 -142.131488) (xy 100.746313 -142.186664) (xy 100.730245 -142.240071)
			(xy 100.706573 -142.290568) (xy 100.6758 -142.337081) (xy 100.638583 -142.378618) (xy 100.595715 -142.414293)
			(xy 100.548109 -142.443347) (xy 100.49678 -142.465159) (xy 100.442823 -142.479265) (xy 100.387386 -142.485365)
			(xy 100.331652 -142.483328) (xy 100.276809 -142.473198) (xy 100.224025 -142.455191) (xy 100.174425 -142.42969)
			(xy 100.129067 -142.397239) (xy 100.088918 -142.35853) (xy 100.054832 -142.314387) (xy 100.027536 -142.265752)
			(xy 100.007613 -142.213661) (xy 99.995487 -142.159224) (xy 99.991416 -142.103602) (xy 98.22942 -142.103602)
			(xy 98.917252 -142.791434) (xy 98.931045 -142.805926) (xy 98.953218 -142.839223) (xy 98.968472 -142.876204)
			(xy 98.976224 -142.91545) (xy 98.976688 -142.935452) (xy 98.976688 -143.085312) (xy 100.117908 -143.085312)
			(xy 100.121979 -143.02969) (xy 100.134105 -142.975253) (xy 100.154028 -142.923162) (xy 100.181324 -142.874527)
			(xy 100.21541 -142.830384) (xy 100.255559 -142.791675) (xy 100.300917 -142.759224) (xy 100.350517 -142.733723)
			(xy 100.403301 -142.715716) (xy 100.458144 -142.705586) (xy 100.513878 -142.703549) (xy 100.569315 -142.709649)
			(xy 100.623272 -142.723755) (xy 100.674601 -142.745567) (xy 100.722207 -142.774621) (xy 100.765075 -142.810296)
			(xy 100.802292 -142.851833) (xy 100.833065 -142.898346) (xy 100.856737 -142.948843) (xy 100.872805 -143.00225)
			(xy 100.880925 -143.057426) (xy 100.881434 -143.085312) (xy 100.880925 -143.113198) (xy 100.872805 -143.168374)
			(xy 100.856737 -143.221781) (xy 100.833065 -143.272278) (xy 100.802292 -143.318791) (xy 100.765075 -143.360328)
			(xy 100.722207 -143.396003) (xy 100.674601 -143.425057) (xy 100.623272 -143.446869) (xy 100.569315 -143.460975)
			(xy 100.513878 -143.467075) (xy 100.458144 -143.465038) (xy 100.403301 -143.454908) (xy 100.350517 -143.436901)
			(xy 100.300917 -143.4114) (xy 100.255559 -143.378949) (xy 100.21541 -143.34024) (xy 100.181324 -143.296097)
			(xy 100.154028 -143.247462) (xy 100.134105 -143.195371) (xy 100.121979 -143.140934) (xy 100.117908 -143.085312)
			(xy 98.976688 -143.085312) (xy 98.976688 -145.094706) (xy 99.562666 -145.094706) (xy 99.563113 -145.068765)
			(xy 99.570142 -145.017363) (xy 99.584073 -144.967387) (xy 99.604648 -144.919759) (xy 99.631486 -144.875359)
			(xy 99.664094 -144.835006) (xy 99.70187 -144.799444) (xy 99.744116 -144.769329) (xy 99.766882 -144.756886)
			(xy 99.776788 -144.751806) (xy 99.789996 -144.735042) (xy 99.813618 -144.639792) (xy 99.809808 -144.61871)
			(xy 99.803712 -144.609566) (xy 99.788026 -144.585661) (xy 99.763183 -144.534166) (xy 99.746289 -144.479544)
			(xy 99.737722 -144.423015) (xy 99.737164 -144.394428) (xy 99.73765 -144.367177) (xy 99.745406 -144.313229)
			(xy 99.760761 -144.260934) (xy 99.783403 -144.211357) (xy 99.812869 -144.165507) (xy 99.84856 -144.124316)
			(xy 99.889751 -144.088625) (xy 99.935601 -144.059159) (xy 99.985178 -144.036517) (xy 100.037473 -144.021162)
			(xy 100.091421 -144.013406) (xy 100.145923 -144.013406) (xy 100.199871 -144.021162) (xy 100.252166 -144.036517)
			(xy 100.301743 -144.059159) (xy 100.347593 -144.088625) (xy 100.365166 -144.103852) (xy 102.455216 -144.103852)
			(xy 102.459287 -144.04823) (xy 102.471413 -143.993793) (xy 102.491336 -143.941702) (xy 102.518632 -143.893067)
			(xy 102.552718 -143.848924) (xy 102.592867 -143.810215) (xy 102.638225 -143.777764) (xy 102.687825 -143.752263)
			(xy 102.740609 -143.734256) (xy 102.795452 -143.724126) (xy 102.851186 -143.722089) (xy 102.906623 -143.728189)
			(xy 102.96058 -143.742295) (xy 103.011909 -143.764107) (xy 103.059515 -143.793161) (xy 103.102383 -143.828836)
			(xy 103.1396 -143.870373) (xy 103.170373 -143.916886) (xy 103.194045 -143.967383) (xy 103.210113 -144.02079)
			(xy 103.218233 -144.075966) (xy 103.218742 -144.103852) (xy 103.218233 -144.131738) (xy 103.210113 -144.186914)
			(xy 103.194045 -144.240321) (xy 103.170373 -144.290818) (xy 103.1396 -144.337331) (xy 103.102383 -144.378868)
			(xy 103.059515 -144.414543) (xy 103.011909 -144.443597) (xy 102.96058 -144.465409) (xy 102.906623 -144.479515)
			(xy 102.851186 -144.485615) (xy 102.795452 -144.483578) (xy 102.740609 -144.473448) (xy 102.687825 -144.455441)
			(xy 102.638225 -144.42994) (xy 102.592867 -144.397489) (xy 102.552718 -144.35878) (xy 102.518632 -144.314637)
			(xy 102.491336 -144.266002) (xy 102.471413 -144.213911) (xy 102.459287 -144.159474) (xy 102.455216 -144.103852)
			(xy 100.365166 -144.103852) (xy 100.388784 -144.124316) (xy 100.424475 -144.165507) (xy 100.453941 -144.211357)
			(xy 100.476583 -144.260934) (xy 100.491938 -144.313229) (xy 100.499694 -144.367177) (xy 100.50018 -144.394428)
			(xy 100.49979 -144.420371) (xy 100.492755 -144.471777) (xy 100.478818 -144.521756) (xy 100.458236 -144.569385)
			(xy 100.431389 -144.613785) (xy 100.398773 -144.654138) (xy 100.360989 -144.689697) (xy 100.318734 -144.719808)
			(xy 100.295964 -144.732248) (xy 100.286058 -144.737328) (xy 100.27285 -144.754092) (xy 100.249228 -144.849342)
			(xy 100.253038 -144.870424) (xy 100.259134 -144.879568) (xy 100.274797 -144.903487) (xy 100.299645 -144.954978)
			(xy 100.316544 -145.009595) (xy 100.325119 -145.06612) (xy 100.325682 -145.094706) (xy 100.325346 -145.117825)
			(xy 100.31978 -145.163725) (xy 100.308693 -145.208614) (xy 100.30079 -145.230342) (xy 100.296218 -145.242026)
			(xy 100.298758 -145.265902) (xy 100.357178 -145.35531) (xy 100.378006 -145.367502) (xy 100.390198 -145.36801)
			(xy 100.419095 -145.370045) (xy 100.475808 -145.38185) (xy 100.530086 -145.402092) (xy 100.58068 -145.430305)
			(xy 100.626428 -145.465842) (xy 100.66628 -145.507885) (xy 100.699318 -145.555469) (xy 100.724785 -145.6075)
			(xy 100.742094 -145.662782) (xy 100.743666 -145.673064) (xy 102.076756 -145.673064) (xy 102.080827 -145.617442)
			(xy 102.092953 -145.563005) (xy 102.112876 -145.510914) (xy 102.140172 -145.462279) (xy 102.174258 -145.418136)
			(xy 102.214407 -145.379427) (xy 102.259765 -145.346976) (xy 102.309365 -145.321475) (xy 102.362149 -145.303468)
			(xy 102.416992 -145.293338) (xy 102.472726 -145.291301) (xy 102.528163 -145.297401) (xy 102.58212 -145.311507)
			(xy 102.633449 -145.333319) (xy 102.681055 -145.362373) (xy 102.723923 -145.398048) (xy 102.76114 -145.439585)
			(xy 102.763024 -145.442432) (xy 103.786176 -145.442432) (xy 103.790247 -145.38681) (xy 103.802373 -145.332373)
			(xy 103.822296 -145.280282) (xy 103.849592 -145.231647) (xy 103.883678 -145.187504) (xy 103.923827 -145.148795)
			(xy 103.969185 -145.116344) (xy 104.018785 -145.090843) (xy 104.071569 -145.072836) (xy 104.126412 -145.062706)
			(xy 104.182146 -145.060669) (xy 104.237583 -145.066769) (xy 104.29154 -145.080875) (xy 104.342869 -145.102687)
			(xy 104.390475 -145.131741) (xy 104.433343 -145.167416) (xy 104.47056 -145.208953) (xy 104.501333 -145.255466)
			(xy 104.525005 -145.305963) (xy 104.541073 -145.35937) (xy 104.549193 -145.414546) (xy 104.549702 -145.442432)
			(xy 104.549193 -145.470318) (xy 104.541073 -145.525494) (xy 104.525005 -145.578901) (xy 104.501333 -145.629398)
			(xy 104.47056 -145.675911) (xy 104.433343 -145.717448) (xy 104.390475 -145.753123) (xy 104.342869 -145.782177)
			(xy 104.29154 -145.803989) (xy 104.237583 -145.818095) (xy 104.182146 -145.824195) (xy 104.126412 -145.822158)
			(xy 104.071569 -145.812028) (xy 104.018785 -145.794021) (xy 103.969185 -145.76852) (xy 103.923827 -145.736069)
			(xy 103.883678 -145.69736) (xy 103.849592 -145.653217) (xy 103.822296 -145.604582) (xy 103.802373 -145.552491)
			(xy 103.790247 -145.498054) (xy 103.786176 -145.442432) (xy 102.763024 -145.442432) (xy 102.791913 -145.486098)
			(xy 102.815585 -145.536595) (xy 102.831653 -145.590002) (xy 102.839773 -145.645178) (xy 102.840282 -145.673064)
			(xy 102.839773 -145.70095) (xy 102.831653 -145.756126) (xy 102.815585 -145.809533) (xy 102.791913 -145.86003)
			(xy 102.76114 -145.906543) (xy 102.723923 -145.94808) (xy 102.681055 -145.983755) (xy 102.633449 -146.012809)
			(xy 102.58212 -146.034621) (xy 102.528163 -146.048727) (xy 102.472726 -146.054827) (xy 102.416992 -146.05279)
			(xy 102.362149 -146.04266) (xy 102.309365 -146.024653) (xy 102.259765 -145.999152) (xy 102.214407 -145.966701)
			(xy 102.174258 -145.927992) (xy 102.140172 -145.883849) (xy 102.112876 -145.835214) (xy 102.092953 -145.783123)
			(xy 102.080827 -145.728686) (xy 102.076756 -145.673064) (xy 100.743666 -145.673064) (xy 100.750849 -145.720046)
			(xy 100.751386 -145.74901) (xy 100.7509 -145.776261) (xy 100.743144 -145.830209) (xy 100.727789 -145.882504)
			(xy 100.705147 -145.932081) (xy 100.675681 -145.977931) (xy 100.63999 -146.019122) (xy 100.598799 -146.054813)
			(xy 100.552949 -146.084279) (xy 100.503372 -146.106921) (xy 100.451077 -146.122276) (xy 100.397129 -146.130032)
			(xy 100.342627 -146.130032) (xy 100.288679 -146.122276) (xy 100.236384 -146.106921) (xy 100.186807 -146.084279)
			(xy 100.140957 -146.054813) (xy 100.099766 -146.019122) (xy 100.064075 -145.977931) (xy 100.034609 -145.932081)
			(xy 100.011967 -145.882504) (xy 99.996612 -145.830209) (xy 99.988856 -145.776261) (xy 99.98837 -145.74901)
			(xy 99.988678 -145.72589) (xy 99.994255 -145.679989) (xy 100.005353 -145.635101) (xy 100.013262 -145.613374)
			(xy 100.017834 -145.60169) (xy 100.015294 -145.577814) (xy 99.956874 -145.488406) (xy 99.936046 -145.476214)
			(xy 99.923854 -145.475706) (xy 99.894962 -145.47361) (xy 99.838252 -145.461813) (xy 99.783976 -145.441579)
			(xy 99.733382 -145.413373) (xy 99.687633 -145.377844) (xy 99.647781 -145.335808) (xy 99.614741 -145.28823)
			(xy 99.589273 -145.236205) (xy 99.571961 -145.180927) (xy 99.563204 -145.123668) (xy 99.562666 -145.094706)
			(xy 98.976688 -145.094706) (xy 98.976688 -147.44446) (xy 103.134414 -147.44446) (xy 103.134842 -147.418796)
			(xy 103.14171 -147.367929) (xy 103.155345 -147.318446) (xy 103.175498 -147.27124) (xy 103.201806 -147.227166)
			(xy 103.233791 -147.187023) (xy 103.270876 -147.151537) (xy 103.291386 -147.136104) (xy 103.302172 -147.127651)
			(xy 103.319255 -147.106243) (xy 103.330025 -147.081061) (xy 103.333708 -147.053921) (xy 103.330036 -147.026779)
			(xy 103.319276 -147.001593) (xy 103.302202 -146.980177) (xy 103.291386 -146.971766) (xy 103.267495 -146.953705)
			(xy 103.225182 -146.911322) (xy 103.190012 -146.862847) (xy 103.162849 -146.809472) (xy 103.14436 -146.752508)
			(xy 103.135 -146.693355) (xy 103.134414 -146.66341) (xy 103.1349 -146.636159) (xy 103.142656 -146.582211)
			(xy 103.158011 -146.529916) (xy 103.180653 -146.480339) (xy 103.210119 -146.434489) (xy 103.24581 -146.393298)
			(xy 103.287001 -146.357607) (xy 103.332851 -146.328141) (xy 103.382428 -146.305499) (xy 103.434723 -146.290144)
			(xy 103.488671 -146.282388) (xy 103.543173 -146.282388) (xy 103.597121 -146.290144) (xy 103.649416 -146.305499)
			(xy 103.698993 -146.328141) (xy 103.744843 -146.357607) (xy 103.786034 -146.393298) (xy 103.821725 -146.434489)
			(xy 103.851191 -146.480339) (xy 103.873833 -146.529916) (xy 103.889188 -146.582211) (xy 103.896944 -146.636159)
			(xy 103.89743 -146.66341) (xy 103.897037 -146.689075) (xy 103.89016 -146.739942) (xy 103.876518 -146.789426)
			(xy 103.856359 -146.836632) (xy 103.830046 -146.880705) (xy 103.798057 -146.920847) (xy 103.760969 -146.956334)
			(xy 103.740458 -146.971766) (xy 103.729652 -146.980167) (xy 103.712661 -147.001617) (xy 103.701957 -147.026801)
			(xy 103.698306 -147.053921) (xy 103.701968 -147.081039) (xy 103.712682 -147.106219) (xy 103.729682 -147.127662)
			(xy 103.740458 -147.136104) (xy 103.764322 -147.154199) (xy 103.806639 -147.196573) (xy 103.841814 -147.24504)
			(xy 103.868982 -147.298409) (xy 103.887476 -147.355368) (xy 103.896841 -147.414517) (xy 103.89743 -147.44446)
			(xy 103.896944 -147.471711) (xy 103.889188 -147.525659) (xy 103.873833 -147.577954) (xy 103.851191 -147.627531)
			(xy 103.821725 -147.673381) (xy 103.786034 -147.714572) (xy 103.744843 -147.750263) (xy 103.698993 -147.779729)
			(xy 103.649416 -147.802371) (xy 103.597121 -147.817726) (xy 103.543173 -147.825482) (xy 103.488671 -147.825482)
			(xy 103.434723 -147.817726) (xy 103.382428 -147.802371) (xy 103.332851 -147.779729) (xy 103.287001 -147.750263)
			(xy 103.24581 -147.714572) (xy 103.210119 -147.673381) (xy 103.180653 -147.627531) (xy 103.158011 -147.577954)
			(xy 103.142656 -147.525659) (xy 103.1349 -147.471711) (xy 103.134414 -147.44446) (xy 98.976688 -147.44446)
			(xy 98.976688 -147.55749) (xy 98.977095 -147.567562) (xy 98.984826 -147.586161) (xy 98.991674 -147.593558)
			(xy 103.336852 -151.938482) (xy 103.350621 -151.952996) (xy 103.372798 -151.986286) (xy 103.388059 -152.02326)
			(xy 103.395819 -152.0625) (xy 103.396288 -152.0825) (xy 103.396288 -169.388282) (xy 103.396699 -169.398353)
			(xy 103.404427 -169.416952) (xy 103.411274 -169.42435) (xy 103.844598 -169.857674) (xy 111.593122 -169.857674)
			(xy 111.593631 -169.830101) (xy 111.601574 -169.77553) (xy 111.61729 -169.72267) (xy 111.640451 -169.672624)
			(xy 111.670577 -169.626433) (xy 111.707038 -169.585061) (xy 111.727742 -169.566844) (xy 111.735843 -169.559226)
			(xy 111.745205 -169.539086) (xy 111.745776 -169.527982) (xy 111.745776 -169.450766) (xy 111.745251 -169.439651)
			(xy 111.735883 -169.419492) (xy 111.727742 -169.411904) (xy 111.707009 -169.393718) (xy 111.670541 -169.352344)
			(xy 111.640412 -169.306151) (xy 111.617248 -169.2561) (xy 111.601533 -169.203235) (xy 111.593593 -169.148659)
			(xy 111.593596 -169.093508) (xy 111.60154 -169.038932) (xy 111.61726 -168.986069) (xy 111.640428 -168.93602)
			(xy 111.670562 -168.889829) (xy 111.707033 -168.848459) (xy 111.727742 -168.830244) (xy 111.735843 -168.822626)
			(xy 111.745205 -168.802486) (xy 111.745776 -168.791382) (xy 111.745776 -168.714166) (xy 111.745251 -168.703051)
			(xy 111.735883 -168.682892) (xy 111.727742 -168.675304) (xy 111.707038 -168.657085) (xy 111.670565 -168.615719)
			(xy 111.640431 -168.569531) (xy 111.617264 -168.519484) (xy 111.601547 -168.466623) (xy 111.593607 -168.412048)
			(xy 111.593122 -168.384474) (xy 111.593531 -168.357219) (xy 111.601292 -168.303265) (xy 111.616653 -168.250964)
			(xy 111.639301 -168.201382) (xy 111.668774 -168.155527) (xy 111.704474 -168.114334) (xy 111.745672 -168.078641)
			(xy 111.791531 -168.049174) (xy 111.841116 -168.026533) (xy 111.893419 -168.01118) (xy 111.947375 -168.003427)
			(xy 111.97463 -168.002966) (xy 112.002485 -168.003487) (xy 112.057599 -168.011614) (xy 112.110948 -168.027662)
			(xy 112.1614 -168.05129) (xy 112.207883 -168.081997) (xy 112.249412 -168.119132) (xy 112.285106 -168.161906)
			(xy 112.314206 -168.209412) (xy 112.336096 -168.260642) (xy 112.343692 -168.287446) (xy 112.345978 -168.296336)
			(xy 112.356646 -168.311576) (xy 112.428528 -168.359328) (xy 112.446562 -168.363392) (xy 112.455706 -168.362122)
			(xy 112.468723 -168.360454) (xy 112.494907 -168.358673) (xy 112.50803 -168.358566) (xy 112.522179 -168.358657)
			(xy 112.550402 -168.360693) (xy 112.564418 -168.36263) (xy 112.574578 -168.364154) (xy 112.594136 -168.359328)
			(xy 112.668558 -168.303448) (xy 112.678718 -168.285922) (xy 112.679988 -168.275762) (xy 112.684077 -168.248608)
			(xy 112.699049 -168.195778) (xy 112.72144 -168.145639) (xy 112.750787 -168.099228) (xy 112.786485 -168.057504)
			(xy 112.827794 -168.021327) (xy 112.873863 -167.991446) (xy 112.92374 -167.968477) (xy 112.976394 -167.952896)
			(xy 113.030738 -167.945024) (xy 113.058194 -167.944546) (xy 113.085443 -167.945083) (xy 113.139387 -167.952838)
			(xy 113.191677 -167.96819) (xy 113.241252 -167.990827) (xy 113.2871 -168.020288) (xy 113.328289 -168.055974)
			(xy 113.363981 -168.097158) (xy 113.393448 -168.143003) (xy 113.416092 -168.192574) (xy 113.431451 -168.244863)
			(xy 113.439213 -168.298805) (xy 113.439702 -168.326054) (xy 113.439204 -168.353627) (xy 113.431258 -168.408199)
			(xy 113.415539 -168.461058) (xy 113.392375 -168.511104) (xy 113.362249 -168.557294) (xy 113.325787 -168.598667)
			(xy 113.305082 -168.616884) (xy 113.296973 -168.624495) (xy 113.287614 -168.64464) (xy 113.287048 -168.655746)
			(xy 113.287048 -168.732962) (xy 113.287606 -168.744073) (xy 113.29695 -168.764233) (xy 113.305082 -168.771824)
			(xy 113.325804 -168.790023) (xy 113.362275 -168.831394) (xy 113.392406 -168.877586) (xy 113.41557 -168.927637)
			(xy 113.431283 -168.980502) (xy 113.439219 -169.035078) (xy 113.439253 -169.037) (xy 118.02821 -169.037)
			(xy 118.032281 -168.981378) (xy 118.044407 -168.926941) (xy 118.06433 -168.87485) (xy 118.091626 -168.826215)
			(xy 118.125712 -168.782072) (xy 118.165861 -168.743363) (xy 118.211219 -168.710912) (xy 118.260819 -168.685411)
			(xy 118.313603 -168.667404) (xy 118.368446 -168.657274) (xy 118.42418 -168.655237) (xy 118.479617 -168.661337)
			(xy 118.533574 -168.675443) (xy 118.584903 -168.697255) (xy 118.632509 -168.726309) (xy 118.675377 -168.761984)
			(xy 118.712594 -168.803521) (xy 118.743367 -168.850034) (xy 118.767039 -168.900531) (xy 118.783107 -168.953938)
			(xy 118.791227 -169.009114) (xy 118.791736 -169.037) (xy 118.791227 -169.064886) (xy 118.783107 -169.120062)
			(xy 118.767039 -169.173469) (xy 118.743367 -169.223966) (xy 118.712594 -169.270479) (xy 118.675377 -169.312016)
			(xy 118.632509 -169.347691) (xy 118.584903 -169.376745) (xy 118.533574 -169.398557) (xy 118.479617 -169.412663)
			(xy 118.42418 -169.418763) (xy 118.368446 -169.416726) (xy 118.313603 -169.406596) (xy 118.260819 -169.388589)
			(xy 118.211219 -169.363088) (xy 118.165861 -169.330637) (xy 118.125712 -169.291928) (xy 118.091626 -169.247785)
			(xy 118.06433 -169.19915) (xy 118.044407 -169.147059) (xy 118.032281 -169.092622) (xy 118.02821 -169.037)
			(xy 113.439253 -169.037) (xy 113.439702 -169.062654) (xy 113.439202 -169.089906) (xy 113.431451 -169.143856)
			(xy 113.416101 -169.196153) (xy 113.393463 -169.245734) (xy 113.363999 -169.291587) (xy 113.328309 -169.332781)
			(xy 113.28712 -169.368475) (xy 113.241269 -169.397944) (xy 113.191691 -169.420587) (xy 113.139395 -169.435943)
			(xy 113.085446 -169.443699) (xy 113.058194 -169.444162) (xy 113.023904 -169.442638) (xy 113.013744 -169.441622)
			(xy 112.99444 -169.447718) (xy 112.923828 -169.5069) (xy 112.91443 -169.524934) (xy 112.913414 -169.535094)
			(xy 112.910502 -169.563272) (xy 112.897321 -169.618365) (xy 112.876137 -169.670902) (xy 112.847414 -169.719728)
			(xy 112.811785 -169.763768) (xy 112.770033 -169.802054) (xy 112.723078 -169.833742) (xy 112.671952 -169.858137)
			(xy 112.61778 -169.874701) (xy 112.561754 -169.88307) (xy 112.53343 -169.883582) (xy 112.515411 -169.883366)
			(xy 112.479536 -169.879928) (xy 112.461802 -169.876724) (xy 112.452404 -169.874946) (xy 112.433354 -169.878756)
			(xy 112.35817 -169.926508) (xy 112.34674 -169.942256) (xy 112.344454 -169.951654) (xy 112.337089 -169.978708)
			(xy 112.315456 -170.030436) (xy 112.286488 -170.078442) (xy 112.250809 -170.121694) (xy 112.209185 -170.159261)
			(xy 112.162513 -170.190334) (xy 112.111798 -170.214244) (xy 112.05813 -170.230478) (xy 112.002665 -170.238685)
			(xy 111.97463 -170.239182) (xy 111.947377 -170.238717) (xy 111.893424 -170.230963) (xy 111.841125 -170.21561)
			(xy 111.791543 -170.192969) (xy 111.745689 -170.163501) (xy 111.704495 -170.127808) (xy 111.668801 -170.086614)
			(xy 111.639333 -170.04076) (xy 111.616692 -169.991179) (xy 111.601338 -169.938879) (xy 111.593584 -169.884927)
			(xy 111.593122 -169.857674) (xy 103.844598 -169.857674) (xy 105.320084 -171.33316) (xy 113.21034 -171.33316)
			(xy 113.210833 -171.305586) (xy 113.218778 -171.251014) (xy 113.234497 -171.198154) (xy 113.257662 -171.148108)
			(xy 113.28779 -171.101917) (xy 113.324254 -171.060546) (xy 113.34496 -171.04233) (xy 113.35307 -171.03472)
			(xy 113.362426 -171.014574) (xy 113.362994 -171.003468) (xy 113.362994 -170.926252) (xy 113.362414 -170.915144)
			(xy 113.353084 -170.894985) (xy 113.34496 -170.88739) (xy 113.324233 -170.869197) (xy 113.287765 -170.827823)
			(xy 113.257636 -170.781629) (xy 113.234474 -170.731578) (xy 113.21876 -170.678713) (xy 113.210824 -170.624136)
			(xy 113.21034 -170.59656) (xy 113.210869 -170.567888) (xy 113.219469 -170.511192) (xy 113.236454 -170.456421)
			(xy 113.261442 -170.404807) (xy 113.293871 -170.357513) (xy 113.333011 -170.315602) (xy 113.37798 -170.280019)
			(xy 113.402618 -170.265344) (xy 113.411762 -170.26001) (xy 113.423954 -170.244008) (xy 113.44783 -170.154092)
			(xy 113.445036 -170.134026) (xy 113.439702 -170.125136) (xy 113.42735 -170.103476) (xy 113.407872 -170.057577)
			(xy 113.394688 -170.00949) (xy 113.388033 -169.960075) (xy 113.387632 -169.935144) (xy 113.388075 -169.908525)
			(xy 113.395647 -169.855828) (xy 113.410642 -169.804746) (xy 113.432755 -169.756318) (xy 113.461537 -169.71153)
			(xy 113.4964 -169.671296) (xy 113.536635 -169.636433) (xy 113.581423 -169.607652) (xy 113.629851 -169.58554)
			(xy 113.680934 -169.570545) (xy 113.733631 -169.562975) (xy 113.76025 -169.562526) (xy 113.786672 -169.562972)
			(xy 113.838987 -169.570428) (xy 113.889725 -169.585196) (xy 113.937869 -169.606982) (xy 113.982454 -169.635348)
			(xy 114.00282 -169.652188) (xy 114.009678 -169.658284) (xy 114.026696 -169.66438) (xy 114.111024 -169.66438)
			(xy 114.128042 -169.658284) (xy 114.1349 -169.652188) (xy 114.155266 -169.635349) (xy 114.199852 -169.606984)
			(xy 114.247996 -169.585197) (xy 114.298733 -169.570426) (xy 114.351048 -169.562966) (xy 114.403892 -169.562966)
			(xy 114.456207 -169.570426) (xy 114.506944 -169.585197) (xy 114.555088 -169.606984) (xy 114.599674 -169.635349)
			(xy 114.62004 -169.652188) (xy 114.626898 -169.658284) (xy 114.643916 -169.66438) (xy 114.728244 -169.66438)
			(xy 114.745262 -169.658284) (xy 114.75212 -169.652188) (xy 114.772477 -169.635339) (xy 114.817069 -169.606986)
			(xy 114.865216 -169.585209) (xy 114.915954 -169.570444) (xy 114.968269 -169.562986) (xy 114.99469 -169.562526)
			(xy 115.022581 -169.562932) (xy 115.077739 -169.571245) (xy 115.131042 -169.587685) (xy 115.181299 -169.611887)
			(xy 115.227388 -169.643309) (xy 115.268279 -169.681249) (xy 115.303059 -169.72486) (xy 115.33095 -169.773167)
			(xy 115.351329 -169.825092) (xy 115.363742 -169.879475) (xy 115.367911 -169.9351) (xy 115.363742 -169.990725)
			(xy 115.351329 -170.045108) (xy 115.33095 -170.097033) (xy 115.303059 -170.14534) (xy 115.268279 -170.188951)
			(xy 115.227388 -170.226891) (xy 115.181299 -170.258313) (xy 115.131042 -170.282515) (xy 115.077739 -170.298955)
			(xy 115.022581 -170.307268) (xy 114.99469 -170.307762) (xy 114.968269 -170.307295) (xy 114.915954 -170.299845)
			(xy 114.865216 -170.285082) (xy 114.817072 -170.2633) (xy 114.772486 -170.234938) (xy 114.75212 -170.2181)
			(xy 114.745262 -170.212004) (xy 114.728244 -170.205908) (xy 114.643916 -170.205908) (xy 114.626898 -170.212004)
			(xy 114.62004 -170.2181) (xy 114.599674 -170.234939) (xy 114.555088 -170.263304) (xy 114.506944 -170.285091)
			(xy 114.456207 -170.299862) (xy 114.403892 -170.307322) (xy 114.351048 -170.307322) (xy 114.298733 -170.299862)
			(xy 114.247996 -170.285091) (xy 114.199852 -170.263304) (xy 114.155266 -170.234939) (xy 114.1349 -170.2181)
			(xy 114.128042 -170.212004) (xy 114.111024 -170.205908) (xy 114.026696 -170.205908) (xy 114.009678 -170.212004)
			(xy 114.00282 -170.2181) (xy 113.990525 -170.228404) (xy 113.964455 -170.247101) (xy 113.95075 -170.255438)
			(xy 113.94186 -170.260518) (xy 113.929922 -170.276774) (xy 113.907824 -170.367198) (xy 113.910872 -170.387264)
			(xy 113.91646 -170.3959) (xy 113.929948 -170.41862) (xy 113.951247 -170.466974) (xy 113.965664 -170.517806)
			(xy 113.972924 -170.570141) (xy 113.973356 -170.59656) (xy 113.972878 -170.624134) (xy 113.96493 -170.678707)
			(xy 113.949209 -170.731568) (xy 113.926041 -170.781614) (xy 113.89591 -170.827804) (xy 113.859443 -170.869175)
			(xy 113.838736 -170.88739) (xy 113.830616 -170.894991) (xy 113.821265 -170.915144) (xy 113.820702 -170.926252)
			(xy 113.820702 -171.003468) (xy 113.821271 -171.014578) (xy 113.830609 -171.034736) (xy 113.838736 -171.04233)
			(xy 113.859472 -171.060514) (xy 113.895939 -171.101889) (xy 113.926067 -171.148085) (xy 113.949228 -171.198138)
			(xy 113.96494 -171.251005) (xy 113.972874 -171.305584) (xy 113.973356 -171.33316) (xy 113.97287 -171.360411)
			(xy 113.965114 -171.414359) (xy 113.949759 -171.466654) (xy 113.927117 -171.516231) (xy 113.897651 -171.562081)
			(xy 113.86196 -171.603272) (xy 113.820769 -171.638963) (xy 113.774919 -171.668429) (xy 113.725342 -171.691071)
			(xy 113.673047 -171.706426) (xy 113.619099 -171.714182) (xy 113.564597 -171.714182) (xy 113.510649 -171.706426)
			(xy 113.458354 -171.691071) (xy 113.408777 -171.668429) (xy 113.362927 -171.638963) (xy 113.321736 -171.603272)
			(xy 113.286045 -171.562081) (xy 113.256579 -171.516231) (xy 113.233937 -171.466654) (xy 113.218582 -171.414359)
			(xy 113.210826 -171.360411) (xy 113.21034 -171.33316) (xy 105.320084 -171.33316) (xy 107.436666 -173.449742)
			(xy 107.459526 -173.457108) (xy 107.471718 -173.455076) (xy 107.486482 -173.45292) (xy 107.516234 -173.45063)
			(xy 107.531154 -173.450504) (xy 107.558406 -173.450998) (xy 107.612357 -173.458749) (xy 107.664655 -173.4741)
			(xy 107.714235 -173.496738) (xy 107.760089 -173.526202) (xy 107.801283 -173.561893) (xy 107.836977 -173.603083)
			(xy 107.866446 -173.648935) (xy 107.889088 -173.698513) (xy 107.904444 -173.75081) (xy 107.912199 -173.80476)
			(xy 107.912662 -173.832012) (xy 107.911996 -173.863575) (xy 107.901612 -173.92584) (xy 107.881129 -173.985549)
			(xy 107.866688 -174.013622) (xy 107.861862 -174.022512) (xy 107.85983 -174.04207) (xy 107.885484 -174.130208)
			(xy 107.89793 -174.145702) (xy 107.90682 -174.150782) (xy 107.914186 -174.154846) (xy 107.923838 -174.160688)
			(xy 107.945936 -174.16272) (xy 108.040424 -174.129192) (xy 108.056426 -174.113698) (xy 108.06049 -174.103284)
			(xy 108.071169 -174.0765) (xy 108.099459 -174.026258) (xy 108.134992 -173.980849) (xy 108.176956 -173.941307)
			(xy 108.224396 -173.908534) (xy 108.276229 -173.883277) (xy 108.331274 -173.866113) (xy 108.388276 -173.857432)
			(xy 108.417106 -173.856904) (xy 108.444358 -173.857366) (xy 108.498307 -173.865124) (xy 108.550602 -173.88048)
			(xy 108.60018 -173.903122) (xy 108.646031 -173.932589) (xy 108.687222 -173.968282) (xy 108.722914 -174.009473)
			(xy 108.752381 -174.055325) (xy 108.775022 -174.104903) (xy 108.790378 -174.157199) (xy 108.798134 -174.211148)
			(xy 108.798134 -174.265652) (xy 108.790378 -174.319601) (xy 108.781028 -174.351442) (xy 109.039914 -174.351442)
			(xy 109.040422 -174.323968) (xy 109.048308 -174.269589) (xy 109.063923 -174.216907) (xy 109.086943 -174.167014)
			(xy 109.11689 -174.120944) (xy 109.134656 -174.099982) (xy 109.140752 -174.09287) (xy 109.147102 -174.075852)
			(xy 109.147102 -173.99) (xy 109.140752 -173.972982) (xy 109.134656 -173.96587) (xy 109.11689 -173.94491)
			(xy 109.086967 -173.898827) (xy 109.063955 -173.848932) (xy 109.04833 -173.796255) (xy 109.040413 -173.741882)
			(xy 109.039914 -173.71441) (xy 109.0404 -173.687159) (xy 109.048156 -173.633211) (xy 109.063511 -173.580916)
			(xy 109.086153 -173.531339) (xy 109.115619 -173.485489) (xy 109.15131 -173.444298) (xy 109.192501 -173.408607)
			(xy 109.238351 -173.379141) (xy 109.287928 -173.356499) (xy 109.340223 -173.341144) (xy 109.394171 -173.333388)
			(xy 109.448673 -173.333388) (xy 109.502621 -173.341144) (xy 109.554916 -173.356499) (xy 109.604493 -173.379141)
			(xy 109.650343 -173.408607) (xy 109.691534 -173.444298) (xy 109.727225 -173.485489) (xy 109.756691 -173.531339)
			(xy 109.779333 -173.580916) (xy 109.794688 -173.633211) (xy 109.802444 -173.687159) (xy 109.80293 -173.71441)
			(xy 109.802442 -173.741884) (xy 109.79455 -173.796264) (xy 109.778929 -173.848946) (xy 109.755905 -173.898839)
			(xy 109.725955 -173.944908) (xy 109.708188 -173.96587) (xy 109.702092 -173.972982) (xy 109.695742 -173.99)
			(xy 109.695742 -174.075852) (xy 109.702092 -174.09287) (xy 109.708188 -174.099982) (xy 109.725923 -174.120968)
			(xy 109.755852 -174.167043) (xy 109.778871 -174.216931) (xy 109.794504 -174.269603) (xy 109.802427 -174.323971)
			(xy 109.80293 -174.351442) (xy 109.802444 -174.378693) (xy 109.800811 -174.39005) (xy 110.37773 -174.39005)
			(xy 110.381801 -174.334428) (xy 110.393927 -174.279991) (xy 110.41385 -174.2279) (xy 110.441146 -174.179265)
			(xy 110.475232 -174.135122) (xy 110.515381 -174.096413) (xy 110.560739 -174.063962) (xy 110.610339 -174.038461)
			(xy 110.663123 -174.020454) (xy 110.717966 -174.010324) (xy 110.7737 -174.008287) (xy 110.829137 -174.014387)
			(xy 110.883094 -174.028493) (xy 110.934423 -174.050305) (xy 110.982029 -174.079359) (xy 111.024897 -174.115034)
			(xy 111.062114 -174.156571) (xy 111.092887 -174.203084) (xy 111.116559 -174.253581) (xy 111.132627 -174.306988)
			(xy 111.140747 -174.362164) (xy 111.141256 -174.39005) (xy 111.140747 -174.417936) (xy 111.132627 -174.473112)
			(xy 111.116559 -174.526519) (xy 111.092887 -174.577016) (xy 111.062114 -174.623529) (xy 111.024897 -174.665066)
			(xy 110.982029 -174.700741) (xy 110.934423 -174.729795) (xy 110.883094 -174.751607) (xy 110.829137 -174.765713)
			(xy 110.7737 -174.771813) (xy 110.717966 -174.769776) (xy 110.663123 -174.759646) (xy 110.610339 -174.741639)
			(xy 110.560739 -174.716138) (xy 110.515381 -174.683687) (xy 110.475232 -174.644978) (xy 110.441146 -174.600835)
			(xy 110.41385 -174.5522) (xy 110.393927 -174.500109) (xy 110.381801 -174.445672) (xy 110.37773 -174.39005)
			(xy 109.800811 -174.39005) (xy 109.794688 -174.432641) (xy 109.779333 -174.484936) (xy 109.756691 -174.534513)
			(xy 109.727225 -174.580363) (xy 109.691534 -174.621554) (xy 109.650343 -174.657245) (xy 109.604493 -174.686711)
			(xy 109.554916 -174.709353) (xy 109.502621 -174.724708) (xy 109.448673 -174.732464) (xy 109.394171 -174.732464)
			(xy 109.340223 -174.724708) (xy 109.287928 -174.709353) (xy 109.238351 -174.686711) (xy 109.192501 -174.657245)
			(xy 109.15131 -174.621554) (xy 109.115619 -174.580363) (xy 109.086153 -174.534513) (xy 109.063511 -174.484936)
			(xy 109.048156 -174.432641) (xy 109.0404 -174.378693) (xy 109.039914 -174.351442) (xy 108.781028 -174.351442)
			(xy 108.775022 -174.371897) (xy 108.752381 -174.421475) (xy 108.722914 -174.467327) (xy 108.687222 -174.508518)
			(xy 108.646031 -174.544211) (xy 108.60018 -174.573678) (xy 108.550602 -174.59632) (xy 108.498307 -174.611676)
			(xy 108.444358 -174.619434) (xy 108.417106 -174.61992) (xy 108.391871 -174.619518) (xy 108.341837 -174.612901)
			(xy 108.293117 -174.599729) (xy 108.246565 -174.580234) (xy 108.224574 -174.56785) (xy 108.214922 -174.562008)
			(xy 108.192824 -174.559976) (xy 108.098336 -174.593504) (xy 108.082334 -174.608998) (xy 108.07827 -174.619412)
			(xy 108.067539 -174.646173) (xy 108.039255 -174.696413) (xy 108.00373 -174.741822) (xy 107.961773 -174.781365)
			(xy 107.914341 -174.81414) (xy 107.862515 -174.839401) (xy 107.807477 -174.856571) (xy 107.750481 -174.865259)
			(xy 107.721654 -174.865792) (xy 107.694401 -174.865365) (xy 107.64045 -174.857602) (xy 107.588153 -174.84224)
			(xy 107.538575 -174.819592) (xy 107.492724 -174.79012) (xy 107.451534 -174.754422) (xy 107.415843 -174.713226)
			(xy 107.386378 -174.667371) (xy 107.363738 -174.617788) (xy 107.348385 -174.565489) (xy 107.340631 -174.511537)
			(xy 107.340146 -174.484284) (xy 107.340809 -174.452721) (xy 107.351194 -174.390456) (xy 107.371679 -174.330747)
			(xy 107.38612 -174.302674) (xy 107.390946 -174.293784) (xy 107.392978 -174.274226) (xy 107.367324 -174.186088)
			(xy 107.354878 -174.170594) (xy 107.345988 -174.165514) (xy 107.320862 -174.151006) (xy 107.27498 -174.115496)
			(xy 107.235007 -174.073445) (xy 107.201865 -174.025824) (xy 107.176318 -173.973733) (xy 107.158957 -173.918372)
			(xy 107.150182 -173.861021) (xy 107.149646 -173.832012) (xy 107.149765 -173.817092) (xy 107.152055 -173.787339)
			(xy 107.154218 -173.772576) (xy 107.15625 -173.760384) (xy 107.148884 -173.737524) (xy 103.048816 -169.63771)
			(xy 103.035038 -169.623204) (xy 103.012864 -169.589911) (xy 102.997606 -169.552935) (xy 102.989848 -169.513693)
			(xy 102.98938 -169.493692) (xy 102.98938 -152.18791) (xy 102.988955 -152.177841) (xy 102.981235 -152.159243)
			(xy 102.974394 -152.151842) (xy 98.629216 -147.806918) (xy 98.615442 -147.792408) (xy 98.593268 -147.759117)
			(xy 98.578008 -147.722141) (xy 98.570249 -147.682901) (xy 98.56978 -147.6629) (xy 98.56978 -143.040862)
			(xy 98.56938 -143.03079) (xy 98.561642 -143.012192) (xy 98.554794 -143.004794) (xy 97.256092 -141.706092)
			(xy 97.2486 -141.699412) (xy 97.230049 -141.691812) (xy 97.220024 -141.69136) (xy 95.471234 -141.69136)
			(xy 95.45122 -141.690892) (xy 95.411965 -141.683058) (xy 95.37499 -141.667724) (xy 95.341713 -141.645477)
			(xy 95.327216 -141.63167) (xy 94.575122 -140.879322) (xy 94.552262 -140.871956) (xy 94.54007 -140.873988)
			(xy 94.52102 -140.876528) (xy 94.511622 -140.877544) (xy 94.495112 -140.885926) (xy 94.436946 -140.95095)
			(xy 94.430342 -140.968222) (xy 94.430342 -140.979652) (xy 94.430219 -140.994572) (xy 94.427932 -141.024325)
			(xy 94.42577 -141.039088) (xy 94.423738 -141.05128) (xy 94.431104 -141.07414) (xy 95.261176 -141.904212)
			(xy 95.268644 -141.910923) (xy 95.287213 -141.918504) (xy 95.297244 -141.918944) (xy 95.979488 -141.918944)
			(xy 95.9995 -141.919459) (xy 96.038752 -141.927278) (xy 96.075727 -141.942598) (xy 96.109007 -141.964833)
			(xy 96.123506 -141.978634) (xy 96.692212 -142.54734) (xy 96.705971 -142.561863) (xy 96.728147 -142.59515)
			(xy 96.74341 -142.632122) (xy 96.751175 -142.671359) (xy 96.751648 -142.691358) (xy 96.751648 -147.612862)
			(xy 96.752081 -147.622931) (xy 96.759795 -147.641529) (xy 96.766634 -147.64893) (xy 97.492058 -148.3741)
			(xy 97.505879 -148.388587) (xy 97.52814 -148.421859) (xy 97.543474 -148.458839) (xy 97.544606 -148.464524)
			(xy 97.942144 -148.464524) (xy 97.946215 -148.408902) (xy 97.958341 -148.354465) (xy 97.978264 -148.302374)
			(xy 98.00556 -148.253739) (xy 98.039646 -148.209596) (xy 98.079795 -148.170887) (xy 98.125153 -148.138436)
			(xy 98.174753 -148.112935) (xy 98.227537 -148.094928) (xy 98.28238 -148.084798) (xy 98.338114 -148.082761)
			(xy 98.393551 -148.088861) (xy 98.447508 -148.102967) (xy 98.498837 -148.124779) (xy 98.546443 -148.153833)
			(xy 98.589311 -148.189508) (xy 98.626528 -148.231045) (xy 98.657301 -148.277558) (xy 98.680973 -148.328055)
			(xy 98.697041 -148.381462) (xy 98.705161 -148.436638) (xy 98.70567 -148.464524) (xy 98.705161 -148.49241)
			(xy 98.697041 -148.547586) (xy 98.680973 -148.600993) (xy 98.657301 -148.65149) (xy 98.626528 -148.698003)
			(xy 98.589311 -148.73954) (xy 98.546443 -148.775215) (xy 98.498837 -148.804269) (xy 98.447508 -148.826081)
			(xy 98.393551 -148.840187) (xy 98.338114 -148.846287) (xy 98.28238 -148.84425) (xy 98.227537 -148.83412)
			(xy 98.174753 -148.816113) (xy 98.125153 -148.790612) (xy 98.079795 -148.758161) (xy 98.039646 -148.719452)
			(xy 98.00556 -148.675309) (xy 97.978264 -148.626674) (xy 97.958341 -148.574583) (xy 97.946215 -148.520146)
			(xy 97.942144 -148.464524) (xy 97.544606 -148.464524) (xy 97.55129 -148.498102) (xy 97.551748 -148.518118)
			(xy 97.551748 -149.552152) (xy 98.937316 -149.552152) (xy 98.941387 -149.49653) (xy 98.953513 -149.442093)
			(xy 98.973436 -149.390002) (xy 99.000732 -149.341367) (xy 99.034818 -149.297224) (xy 99.074967 -149.258515)
			(xy 99.120325 -149.226064) (xy 99.169925 -149.200563) (xy 99.222709 -149.182556) (xy 99.277552 -149.172426)
			(xy 99.333286 -149.170389) (xy 99.388723 -149.176489) (xy 99.44268 -149.190595) (xy 99.494009 -149.212407)
			(xy 99.541615 -149.241461) (xy 99.584483 -149.277136) (xy 99.6217 -149.318673) (xy 99.652473 -149.365186)
			(xy 99.676145 -149.415683) (xy 99.692213 -149.46909) (xy 99.700333 -149.524266) (xy 99.700842 -149.552152)
			(xy 99.700333 -149.580038) (xy 99.692213 -149.635214) (xy 99.676145 -149.688621) (xy 99.652473 -149.739118)
			(xy 99.6217 -149.785631) (xy 99.584483 -149.827168) (xy 99.541615 -149.862843) (xy 99.494009 -149.891897)
			(xy 99.44268 -149.913709) (xy 99.388723 -149.927815) (xy 99.333286 -149.933915) (xy 99.277552 -149.931878)
			(xy 99.222709 -149.921748) (xy 99.169925 -149.903741) (xy 99.120325 -149.87824) (xy 99.074967 -149.845789)
			(xy 99.034818 -149.80708) (xy 99.000732 -149.762937) (xy 98.973436 -149.714302) (xy 98.953513 -149.662211)
			(xy 98.941387 -149.607774) (xy 98.937316 -149.552152) (xy 97.551748 -149.552152) (xy 97.551748 -151.634952)
			(xy 99.305616 -151.634952) (xy 99.309687 -151.57933) (xy 99.321813 -151.524893) (xy 99.341736 -151.472802)
			(xy 99.369032 -151.424167) (xy 99.403118 -151.380024) (xy 99.443267 -151.341315) (xy 99.488625 -151.308864)
			(xy 99.538225 -151.283363) (xy 99.591009 -151.265356) (xy 99.645852 -151.255226) (xy 99.701586 -151.253189)
			(xy 99.757023 -151.259289) (xy 99.81098 -151.273395) (xy 99.862309 -151.295207) (xy 99.909915 -151.324261)
			(xy 99.952783 -151.359936) (xy 99.99 -151.401473) (xy 100.020773 -151.447986) (xy 100.044445 -151.498483)
			(xy 100.060513 -151.55189) (xy 100.068633 -151.607066) (xy 100.069142 -151.634952) (xy 100.068633 -151.662838)
			(xy 100.060513 -151.718014) (xy 100.044445 -151.771421) (xy 100.020773 -151.821918) (xy 99.99 -151.868431)
			(xy 99.952783 -151.909968) (xy 99.909915 -151.945643) (xy 99.862309 -151.974697) (xy 99.81098 -151.996509)
			(xy 99.757023 -152.010615) (xy 99.701586 -152.016715) (xy 99.645852 -152.014678) (xy 99.591009 -152.004548)
			(xy 99.538225 -151.986541) (xy 99.488625 -151.96104) (xy 99.443267 -151.928589) (xy 99.403118 -151.88988)
			(xy 99.369032 -151.845737) (xy 99.341736 -151.797102) (xy 99.321813 -151.745011) (xy 99.309687 -151.690574)
			(xy 99.305616 -151.634952) (xy 97.551748 -151.634952) (xy 97.551748 -153.977848) (xy 97.552105 -153.987895)
			(xy 97.559702 -154.006491) (xy 97.56648 -154.013916) (xy 97.850452 -154.297634) (xy 97.864245 -154.312126)
			(xy 97.886418 -154.345423) (xy 97.901672 -154.382404) (xy 97.909424 -154.42165) (xy 97.909888 -154.441652)
			(xy 97.909888 -175.086264) (xy 97.910309 -175.096334) (xy 97.91803 -175.114933) (xy 97.924874 -175.122332)
			(xy 98.908855 -176.106074) (xy 103.363522 -176.106074) (xy 103.364031 -176.078501) (xy 103.371974 -176.02393)
			(xy 103.38769 -175.97107) (xy 103.410851 -175.921024) (xy 103.440977 -175.874833) (xy 103.477438 -175.833461)
			(xy 103.498142 -175.815244) (xy 103.506243 -175.807626) (xy 103.515605 -175.787486) (xy 103.516176 -175.776382)
			(xy 103.516176 -175.699166) (xy 103.515651 -175.688051) (xy 103.506283 -175.667892) (xy 103.498142 -175.660304)
			(xy 103.477409 -175.642118) (xy 103.440941 -175.600744) (xy 103.410812 -175.554551) (xy 103.387648 -175.5045)
			(xy 103.371933 -175.451635) (xy 103.363993 -175.397059) (xy 103.363996 -175.341908) (xy 103.37194 -175.287332)
			(xy 103.38766 -175.234469) (xy 103.410828 -175.18442) (xy 103.440962 -175.138229) (xy 103.477433 -175.096859)
			(xy 103.498142 -175.078644) (xy 103.506243 -175.071026) (xy 103.515605 -175.050886) (xy 103.516176 -175.039782)
			(xy 103.516176 -174.962566) (xy 103.515651 -174.951451) (xy 103.506283 -174.931292) (xy 103.498142 -174.923704)
			(xy 103.477438 -174.905485) (xy 103.440965 -174.864119) (xy 103.410831 -174.817931) (xy 103.387664 -174.767884)
			(xy 103.371947 -174.715023) (xy 103.364007 -174.660448) (xy 103.363522 -174.632874) (xy 103.363931 -174.605619)
			(xy 103.371692 -174.551665) (xy 103.387053 -174.499364) (xy 103.409701 -174.449782) (xy 103.439174 -174.403927)
			(xy 103.474874 -174.362734) (xy 103.516072 -174.327041) (xy 103.561931 -174.297574) (xy 103.611516 -174.274933)
			(xy 103.663819 -174.25958) (xy 103.717775 -174.251827) (xy 103.74503 -174.251366) (xy 103.772885 -174.251887)
			(xy 103.827999 -174.260014) (xy 103.881348 -174.276062) (xy 103.9318 -174.29969) (xy 103.978283 -174.330397)
			(xy 104.019812 -174.367532) (xy 104.055506 -174.410306) (xy 104.084606 -174.457812) (xy 104.106496 -174.509042)
			(xy 104.114092 -174.535846) (xy 104.116378 -174.544736) (xy 104.127046 -174.559976) (xy 104.198928 -174.607728)
			(xy 104.216962 -174.611792) (xy 104.226106 -174.610522) (xy 104.239123 -174.608854) (xy 104.265307 -174.607073)
			(xy 104.27843 -174.606966) (xy 104.292579 -174.607057) (xy 104.320802 -174.609093) (xy 104.334818 -174.61103)
			(xy 104.344978 -174.612554) (xy 104.364536 -174.607728) (xy 104.438958 -174.551848) (xy 104.449118 -174.534322)
			(xy 104.450388 -174.524162) (xy 104.454477 -174.497008) (xy 104.469449 -174.444178) (xy 104.49184 -174.394039)
			(xy 104.521187 -174.347628) (xy 104.556885 -174.305904) (xy 104.598194 -174.269727) (xy 104.644263 -174.239846)
			(xy 104.69414 -174.216877) (xy 104.746794 -174.201296) (xy 104.801138 -174.193424) (xy 104.828594 -174.192946)
			(xy 104.855843 -174.193483) (xy 104.909787 -174.201238) (xy 104.962077 -174.21659) (xy 105.011652 -174.239227)
			(xy 105.0575 -174.268688) (xy 105.098689 -174.304374) (xy 105.134381 -174.345558) (xy 105.163848 -174.391403)
			(xy 105.186492 -174.440974) (xy 105.201851 -174.493263) (xy 105.209613 -174.547205) (xy 105.210102 -174.574454)
			(xy 105.209604 -174.602027) (xy 105.201658 -174.656599) (xy 105.185939 -174.709458) (xy 105.162775 -174.759504)
			(xy 105.132649 -174.805694) (xy 105.096187 -174.847067) (xy 105.075482 -174.865284) (xy 105.067373 -174.872895)
			(xy 105.058014 -174.89304) (xy 105.057448 -174.904146) (xy 105.057448 -174.981362) (xy 105.058006 -174.992473)
			(xy 105.06735 -175.012633) (xy 105.075482 -175.020224) (xy 105.096204 -175.038423) (xy 105.132675 -175.079794)
			(xy 105.162806 -175.125986) (xy 105.18597 -175.176037) (xy 105.201683 -175.228902) (xy 105.209619 -175.283478)
			(xy 105.209653 -175.2854) (xy 109.79861 -175.2854) (xy 109.802681 -175.229778) (xy 109.814807 -175.175341)
			(xy 109.83473 -175.12325) (xy 109.862026 -175.074615) (xy 109.896112 -175.030472) (xy 109.936261 -174.991763)
			(xy 109.981619 -174.959312) (xy 110.031219 -174.933811) (xy 110.084003 -174.915804) (xy 110.138846 -174.905674)
			(xy 110.19458 -174.903637) (xy 110.250017 -174.909737) (xy 110.303974 -174.923843) (xy 110.355303 -174.945655)
			(xy 110.402909 -174.974709) (xy 110.445777 -175.010384) (xy 110.482994 -175.051921) (xy 110.513767 -175.098434)
			(xy 110.537439 -175.148931) (xy 110.553507 -175.202338) (xy 110.561627 -175.257514) (xy 110.562136 -175.2854)
			(xy 110.561627 -175.313286) (xy 110.553507 -175.368462) (xy 110.537439 -175.421869) (xy 110.513767 -175.472366)
			(xy 110.482994 -175.518879) (xy 110.445777 -175.560416) (xy 110.402909 -175.596091) (xy 110.355303 -175.625145)
			(xy 110.303974 -175.646957) (xy 110.250017 -175.661063) (xy 110.19458 -175.667163) (xy 110.138846 -175.665126)
			(xy 110.084003 -175.654996) (xy 110.031219 -175.636989) (xy 109.981619 -175.611488) (xy 109.936261 -175.579037)
			(xy 109.896112 -175.540328) (xy 109.862026 -175.496185) (xy 109.83473 -175.44755) (xy 109.814807 -175.395459)
			(xy 109.802681 -175.341022) (xy 109.79861 -175.2854) (xy 105.209653 -175.2854) (xy 105.210102 -175.311054)
			(xy 105.209602 -175.338306) (xy 105.201851 -175.392256) (xy 105.186501 -175.444553) (xy 105.163863 -175.494134)
			(xy 105.134399 -175.539987) (xy 105.098709 -175.581181) (xy 105.05752 -175.616875) (xy 105.011669 -175.646344)
			(xy 104.962091 -175.668987) (xy 104.909795 -175.684343) (xy 104.855846 -175.692099) (xy 104.828594 -175.692562)
			(xy 104.794304 -175.691038) (xy 104.784144 -175.690022) (xy 104.76484 -175.696118) (xy 104.694228 -175.7553)
			(xy 104.68483 -175.773334) (xy 104.683814 -175.783494) (xy 104.680902 -175.811672) (xy 104.667721 -175.866765)
			(xy 104.646537 -175.919302) (xy 104.617814 -175.968128) (xy 104.582185 -176.012168) (xy 104.540433 -176.050454)
			(xy 104.493478 -176.082142) (xy 104.442352 -176.106537) (xy 104.38818 -176.123101) (xy 104.332154 -176.13147)
			(xy 104.30383 -176.131982) (xy 104.285811 -176.131766) (xy 104.249936 -176.128328) (xy 104.232202 -176.125124)
			(xy 104.222804 -176.123346) (xy 104.203754 -176.127156) (xy 104.12857 -176.174908) (xy 104.11714 -176.190656)
			(xy 104.114854 -176.200054) (xy 104.107489 -176.227108) (xy 104.085856 -176.278836) (xy 104.056888 -176.326842)
			(xy 104.021209 -176.370094) (xy 103.979585 -176.407661) (xy 103.932913 -176.438734) (xy 103.882198 -176.462644)
			(xy 103.82853 -176.478878) (xy 103.773065 -176.487085) (xy 103.74503 -176.487582) (xy 103.717777 -176.487117)
			(xy 103.663824 -176.479363) (xy 103.611525 -176.46401) (xy 103.561943 -176.441369) (xy 103.516089 -176.411901)
			(xy 103.474895 -176.376208) (xy 103.439201 -176.335014) (xy 103.409733 -176.28916) (xy 103.387092 -176.239579)
			(xy 103.371738 -176.187279) (xy 103.363984 -176.133327) (xy 103.363522 -176.106074) (xy 98.908855 -176.106074)
			(xy 98.96983 -176.167034) (xy 98.983662 -176.181511) (xy 99.005923 -176.214786) (xy 99.021254 -176.251769)
			(xy 99.029065 -176.291035) (xy 99.02952 -176.311052) (xy 99.02952 -177.65776) (xy 104.95534 -177.65776)
			(xy 104.955833 -177.630186) (xy 104.963778 -177.575614) (xy 104.979497 -177.522754) (xy 105.002662 -177.472708)
			(xy 105.03279 -177.426517) (xy 105.069254 -177.385146) (xy 105.08996 -177.36693) (xy 105.09807 -177.35932)
			(xy 105.107426 -177.339174) (xy 105.107994 -177.328068) (xy 105.107994 -177.250852) (xy 105.107414 -177.239744)
			(xy 105.098084 -177.219585) (xy 105.08996 -177.21199) (xy 105.069233 -177.193797) (xy 105.032765 -177.152423)
			(xy 105.002636 -177.106229) (xy 104.979474 -177.056178) (xy 104.96376 -177.003313) (xy 104.955824 -176.948736)
			(xy 104.95534 -176.92116) (xy 104.955873 -176.892873) (xy 104.964232 -176.836919) (xy 104.980763 -176.782814)
			(xy 105.005102 -176.731742) (xy 105.036715 -176.684824) (xy 105.07491 -176.643089) (xy 105.118849 -176.607451)
			(xy 105.167569 -176.578693) (xy 105.193592 -176.567592) (xy 105.204768 -176.56302) (xy 105.220262 -176.545494)
			(xy 105.247694 -176.444148) (xy 105.243122 -176.42078) (xy 105.235756 -176.411382) (xy 105.217491 -176.38675)
			(xy 105.188467 -176.332735) (xy 105.168676 -176.274697) (xy 105.158649 -176.214204) (xy 105.158032 -176.183544)
			(xy 105.158475 -176.156925) (xy 105.166047 -176.104228) (xy 105.181042 -176.053146) (xy 105.203155 -176.004718)
			(xy 105.231937 -175.95993) (xy 105.2668 -175.919696) (xy 105.307035 -175.884833) (xy 105.351823 -175.856052)
			(xy 105.400251 -175.83394) (xy 105.451334 -175.818945) (xy 105.504031 -175.811375) (xy 105.53065 -175.810926)
			(xy 105.557072 -175.811372) (xy 105.609387 -175.818828) (xy 105.660125 -175.833596) (xy 105.708269 -175.855382)
			(xy 105.752854 -175.883748) (xy 105.77322 -175.900588) (xy 105.780078 -175.906684) (xy 105.797096 -175.91278)
			(xy 105.881424 -175.91278) (xy 105.898442 -175.906684) (xy 105.9053 -175.900588) (xy 105.925666 -175.883749)
			(xy 105.970252 -175.855384) (xy 106.018396 -175.833597) (xy 106.069133 -175.818826) (xy 106.121448 -175.811366)
			(xy 106.174292 -175.811366) (xy 106.226607 -175.818826) (xy 106.277344 -175.833597) (xy 106.325488 -175.855384)
			(xy 106.370074 -175.883749) (xy 106.39044 -175.900588) (xy 106.397298 -175.906684) (xy 106.414316 -175.91278)
			(xy 106.498644 -175.91278) (xy 106.515662 -175.906684) (xy 106.52252 -175.900588) (xy 106.542877 -175.883739)
			(xy 106.587469 -175.855386) (xy 106.635616 -175.833609) (xy 106.686354 -175.818844) (xy 106.738669 -175.811386)
			(xy 106.76509 -175.810926) (xy 106.792981 -175.811332) (xy 106.848139 -175.819645) (xy 106.901442 -175.836085)
			(xy 106.951699 -175.860287) (xy 106.997788 -175.891709) (xy 107.038679 -175.929649) (xy 107.073459 -175.97326)
			(xy 107.10135 -176.021567) (xy 107.121729 -176.073492) (xy 107.134142 -176.127875) (xy 107.138311 -176.1835)
			(xy 107.134142 -176.239125) (xy 107.121729 -176.293508) (xy 107.10135 -176.345433) (xy 107.073459 -176.39374)
			(xy 107.038679 -176.437351) (xy 106.997788 -176.475291) (xy 106.951699 -176.506713) (xy 106.901442 -176.530915)
			(xy 106.848139 -176.547355) (xy 106.792981 -176.555668) (xy 106.76509 -176.556162) (xy 106.738669 -176.555695)
			(xy 106.686354 -176.548245) (xy 106.635616 -176.533482) (xy 106.587472 -176.5117) (xy 106.542886 -176.483338)
			(xy 106.52252 -176.4665) (xy 106.515662 -176.460404) (xy 106.498644 -176.454308) (xy 106.414316 -176.454308)
			(xy 106.397298 -176.460404) (xy 106.39044 -176.4665) (xy 106.370074 -176.483339) (xy 106.325488 -176.511704)
			(xy 106.277344 -176.533491) (xy 106.226607 -176.548262) (xy 106.174292 -176.555722) (xy 106.121448 -176.555722)
			(xy 106.069133 -176.548262) (xy 106.018396 -176.533491) (xy 105.970252 -176.511704) (xy 105.925666 -176.483339)
			(xy 105.9053 -176.4665) (xy 105.898442 -176.460404) (xy 105.881424 -176.454308) (xy 105.797096 -176.454308)
			(xy 105.780078 -176.460404) (xy 105.77322 -176.4665) (xy 105.750945 -176.484878) (xy 105.701825 -176.515237)
			(xy 105.67543 -176.526952) (xy 105.664508 -176.531524) (xy 105.649014 -176.549558) (xy 105.623106 -176.651158)
			(xy 105.627932 -176.674272) (xy 105.635552 -176.68367) (xy 105.651203 -176.703987) (xy 105.677447 -176.748049)
			(xy 105.697545 -176.795234) (xy 105.711132 -176.844687) (xy 105.717962 -176.895517) (xy 105.718356 -176.92116)
			(xy 105.717878 -176.948734) (xy 105.70993 -177.003307) (xy 105.694209 -177.056168) (xy 105.671041 -177.106214)
			(xy 105.64091 -177.152404) (xy 105.604443 -177.193775) (xy 105.583736 -177.21199) (xy 105.575616 -177.219591)
			(xy 105.566265 -177.239744) (xy 105.565702 -177.250852) (xy 105.565702 -177.328068) (xy 105.566271 -177.339178)
			(xy 105.575609 -177.359336) (xy 105.583736 -177.36693) (xy 105.604472 -177.385114) (xy 105.640939 -177.426489)
			(xy 105.671067 -177.472685) (xy 105.694228 -177.522738) (xy 105.70994 -177.575605) (xy 105.717874 -177.630184)
			(xy 105.718356 -177.65776) (xy 105.71787 -177.685011) (xy 105.710114 -177.738959) (xy 105.694759 -177.791254)
			(xy 105.672117 -177.840831) (xy 105.642651 -177.886681) (xy 105.60696 -177.927872) (xy 105.565769 -177.963563)
			(xy 105.519919 -177.993029) (xy 105.470342 -178.015671) (xy 105.418047 -178.031026) (xy 105.364099 -178.038782)
			(xy 105.309597 -178.038782) (xy 105.255649 -178.031026) (xy 105.203354 -178.015671) (xy 105.153777 -177.993029)
			(xy 105.107927 -177.963563) (xy 105.066736 -177.927872) (xy 105.031045 -177.886681) (xy 105.001579 -177.840831)
			(xy 104.978937 -177.791254) (xy 104.963582 -177.738959) (xy 104.955826 -177.685011) (xy 104.95534 -177.65776)
			(xy 99.02952 -177.65776) (xy 99.02952 -177.92446) (xy 99.029879 -177.934507) (xy 99.037475 -177.953103)
			(xy 99.044252 -177.960528) (xy 99.054666 -177.970942) (xy 99.077526 -177.978308) (xy 99.089718 -177.976276)
			(xy 99.104482 -177.97412) (xy 99.134234 -177.97183) (xy 99.149154 -177.971704) (xy 99.176406 -177.972198)
			(xy 99.230357 -177.979949) (xy 99.282655 -177.9953) (xy 99.332235 -178.017938) (xy 99.378089 -178.047402)
			(xy 99.419283 -178.083093) (xy 99.454977 -178.124283) (xy 99.484446 -178.170135) (xy 99.507088 -178.219713)
			(xy 99.522444 -178.27201) (xy 99.530199 -178.32596) (xy 99.530662 -178.353212) (xy 99.529996 -178.384775)
			(xy 99.519612 -178.44704) (xy 99.499129 -178.506749) (xy 99.484688 -178.534822) (xy 99.479862 -178.543712)
			(xy 99.47783 -178.56327) (xy 99.503484 -178.651408) (xy 99.51593 -178.666902) (xy 99.52482 -178.671982)
			(xy 99.532186 -178.676046) (xy 99.541838 -178.681888) (xy 99.563936 -178.68392) (xy 99.658424 -178.650392)
			(xy 99.674426 -178.634898) (xy 99.67849 -178.624484) (xy 99.689169 -178.5977) (xy 99.717459 -178.547458)
			(xy 99.752992 -178.502049) (xy 99.794956 -178.462507) (xy 99.842396 -178.429734) (xy 99.894229 -178.404477)
			(xy 99.949274 -178.387313) (xy 100.006276 -178.378632) (xy 100.035106 -178.378104) (xy 100.062358 -178.378566)
			(xy 100.116307 -178.386324) (xy 100.168602 -178.40168) (xy 100.21818 -178.424322) (xy 100.264031 -178.453789)
			(xy 100.305222 -178.489482) (xy 100.340914 -178.530673) (xy 100.370381 -178.576525) (xy 100.393022 -178.626103)
			(xy 100.408378 -178.678399) (xy 100.416134 -178.732348) (xy 100.416134 -178.786852) (xy 100.408378 -178.840801)
			(xy 100.399028 -178.872642) (xy 100.657914 -178.872642) (xy 100.658422 -178.845168) (xy 100.666308 -178.790789)
			(xy 100.681923 -178.738107) (xy 100.704943 -178.688214) (xy 100.73489 -178.642144) (xy 100.752656 -178.621182)
			(xy 100.758752 -178.61407) (xy 100.765102 -178.597052) (xy 100.765102 -178.5112) (xy 100.758752 -178.494182)
			(xy 100.752656 -178.48707) (xy 100.73489 -178.46611) (xy 100.704967 -178.420027) (xy 100.681955 -178.370132)
			(xy 100.66633 -178.317455) (xy 100.658413 -178.263082) (xy 100.657914 -178.23561) (xy 100.6584 -178.208359)
			(xy 100.666156 -178.154411) (xy 100.681511 -178.102116) (xy 100.704153 -178.052539) (xy 100.733619 -178.006689)
			(xy 100.76931 -177.965498) (xy 100.810501 -177.929807) (xy 100.856351 -177.900341) (xy 100.905928 -177.877699)
			(xy 100.958223 -177.862344) (xy 101.012171 -177.854588) (xy 101.066673 -177.854588) (xy 101.120621 -177.862344)
			(xy 101.172916 -177.877699) (xy 101.222493 -177.900341) (xy 101.268343 -177.929807) (xy 101.309534 -177.965498)
			(xy 101.345225 -178.006689) (xy 101.374691 -178.052539) (xy 101.397333 -178.102116) (xy 101.412688 -178.154411)
			(xy 101.420444 -178.208359) (xy 101.42093 -178.23561) (xy 101.420442 -178.263084) (xy 101.41255 -178.317464)
			(xy 101.396929 -178.370146) (xy 101.373905 -178.420039) (xy 101.343955 -178.466108) (xy 101.326188 -178.48707)
			(xy 101.320092 -178.494182) (xy 101.313742 -178.5112) (xy 101.313742 -178.597052) (xy 101.320092 -178.61407)
			(xy 101.326188 -178.621182) (xy 101.343923 -178.642168) (xy 101.373852 -178.688243) (xy 101.396871 -178.738131)
			(xy 101.412504 -178.790803) (xy 101.420427 -178.845171) (xy 101.42093 -178.872642) (xy 101.420444 -178.899893)
			(xy 101.418811 -178.91125) (xy 101.99573 -178.91125) (xy 101.999801 -178.855628) (xy 102.011927 -178.801191)
			(xy 102.03185 -178.7491) (xy 102.059146 -178.700465) (xy 102.093232 -178.656322) (xy 102.133381 -178.617613)
			(xy 102.178739 -178.585162) (xy 102.228339 -178.559661) (xy 102.281123 -178.541654) (xy 102.335966 -178.531524)
			(xy 102.3917 -178.529487) (xy 102.447137 -178.535587) (xy 102.501094 -178.549693) (xy 102.552423 -178.571505)
			(xy 102.600029 -178.600559) (xy 102.642897 -178.636234) (xy 102.680114 -178.677771) (xy 102.710887 -178.724284)
			(xy 102.734559 -178.774781) (xy 102.750627 -178.828188) (xy 102.758747 -178.883364) (xy 102.759256 -178.91125)
			(xy 102.758747 -178.939136) (xy 102.750627 -178.994312) (xy 102.734559 -179.047719) (xy 102.710887 -179.098216)
			(xy 102.680114 -179.144729) (xy 102.642897 -179.186266) (xy 102.600029 -179.221941) (xy 102.552423 -179.250995)
			(xy 102.501094 -179.272807) (xy 102.447137 -179.286913) (xy 102.3917 -179.293013) (xy 102.335966 -179.290976)
			(xy 102.281123 -179.280846) (xy 102.228339 -179.262839) (xy 102.178739 -179.237338) (xy 102.133381 -179.204887)
			(xy 102.093232 -179.166178) (xy 102.059146 -179.122035) (xy 102.03185 -179.0734) (xy 102.011927 -179.021309)
			(xy 101.999801 -178.966872) (xy 101.99573 -178.91125) (xy 101.418811 -178.91125) (xy 101.412688 -178.953841)
			(xy 101.397333 -179.006136) (xy 101.374691 -179.055713) (xy 101.345225 -179.101563) (xy 101.309534 -179.142754)
			(xy 101.268343 -179.178445) (xy 101.222493 -179.207911) (xy 101.172916 -179.230553) (xy 101.120621 -179.245908)
			(xy 101.066673 -179.253664) (xy 101.012171 -179.253664) (xy 100.958223 -179.245908) (xy 100.905928 -179.230553)
			(xy 100.856351 -179.207911) (xy 100.810501 -179.178445) (xy 100.76931 -179.142754) (xy 100.733619 -179.101563)
			(xy 100.704153 -179.055713) (xy 100.681511 -179.006136) (xy 100.666156 -178.953841) (xy 100.6584 -178.899893)
			(xy 100.657914 -178.872642) (xy 100.399028 -178.872642) (xy 100.393022 -178.893097) (xy 100.370381 -178.942675)
			(xy 100.340914 -178.988527) (xy 100.305222 -179.029718) (xy 100.264031 -179.065411) (xy 100.21818 -179.094878)
			(xy 100.168602 -179.11752) (xy 100.116307 -179.132876) (xy 100.062358 -179.140634) (xy 100.035106 -179.14112)
			(xy 100.009871 -179.140718) (xy 99.959837 -179.134101) (xy 99.911117 -179.120929) (xy 99.864565 -179.101434)
			(xy 99.842574 -179.08905) (xy 99.832922 -179.083208) (xy 99.810824 -179.081176) (xy 99.716336 -179.114704)
			(xy 99.700334 -179.130198) (xy 99.69627 -179.140612) (xy 99.685539 -179.167373) (xy 99.657255 -179.217613)
			(xy 99.62173 -179.263022) (xy 99.579773 -179.302565) (xy 99.532341 -179.33534) (xy 99.480515 -179.360601)
			(xy 99.425477 -179.377771) (xy 99.368481 -179.386459) (xy 99.339654 -179.386992) (xy 99.312401 -179.386565)
			(xy 99.25845 -179.378802) (xy 99.206153 -179.36344) (xy 99.156575 -179.340792) (xy 99.110724 -179.31132)
			(xy 99.069534 -179.275622) (xy 99.033843 -179.234426) (xy 99.004378 -179.188571) (xy 98.981738 -179.138988)
			(xy 98.966385 -179.086689) (xy 98.958631 -179.032737) (xy 98.958146 -179.005484) (xy 98.958809 -178.973921)
			(xy 98.969194 -178.911656) (xy 98.989679 -178.851947) (xy 99.00412 -178.823874) (xy 99.008946 -178.814984)
			(xy 99.010978 -178.795426) (xy 98.985324 -178.707288) (xy 98.972878 -178.691794) (xy 98.963988 -178.686714)
			(xy 98.938862 -178.672206) (xy 98.89298 -178.636696) (xy 98.853007 -178.594645) (xy 98.819865 -178.547024)
			(xy 98.794318 -178.494933) (xy 98.776957 -178.439572) (xy 98.768182 -178.382221) (xy 98.767646 -178.353212)
			(xy 98.767765 -178.338292) (xy 98.770055 -178.308539) (xy 98.772218 -178.293776) (xy 98.77425 -178.281584)
			(xy 98.766884 -178.258724) (xy 98.681794 -178.173888) (xy 98.667959 -178.159414) (xy 98.645703 -178.126136)
			(xy 98.630373 -178.089152) (xy 98.622561 -178.049887) (xy 98.622104 -178.02987) (xy 98.622104 -176.416462)
			(xy 98.621754 -176.406414) (xy 98.614154 -176.387817) (xy 98.607372 -176.380394) (xy 97.562416 -175.335692)
			(xy 97.54863 -175.321193) (xy 97.526457 -175.287898) (xy 97.511201 -175.250919) (xy 97.503447 -175.211676)
			(xy 97.50298 -175.191674) (xy 97.50298 -154.547062) (xy 97.50258 -154.53699) (xy 97.494842 -154.518392)
			(xy 97.487994 -154.510994) (xy 97.204022 -154.227276) (xy 97.190186 -154.212802) (xy 97.167929 -154.179525)
			(xy 97.152599 -154.142541) (xy 97.144788 -154.103276) (xy 97.144332 -154.083258) (xy 97.144332 -148.623528)
			(xy 97.143992 -148.613479) (xy 97.136384 -148.594882) (xy 97.1296 -148.58746) (xy 96.404176 -147.86229)
			(xy 96.390399 -147.847783) (xy 96.368223 -147.814492) (xy 96.352963 -147.777515) (xy 96.345207 -147.738273)
			(xy 96.34474 -147.718272) (xy 96.34474 -142.796768) (xy 96.344347 -142.786695) (xy 96.336605 -142.768096)
			(xy 96.329754 -142.7607) (xy 95.910146 -142.341092) (xy 95.90267 -142.334391) (xy 95.884107 -142.326804)
			(xy 95.874078 -142.32636) (xy 95.191834 -142.32636) (xy 95.17182 -142.325892) (xy 95.132565 -142.318058)
			(xy 95.09559 -142.302724) (xy 95.062313 -142.280477) (xy 95.047816 -142.26667) (xy 94.143322 -141.361922)
			(xy 94.120462 -141.354556) (xy 94.10827 -141.356588) (xy 94.093506 -141.358745) (xy 94.063754 -141.361035)
			(xy 94.048834 -141.36116) (xy 94.02158 -141.360713) (xy 93.967626 -141.352959) (xy 93.915325 -141.337605)
			(xy 93.865742 -141.314963) (xy 93.819886 -141.285494) (xy 93.778692 -141.249799) (xy 93.742997 -141.208603)
			(xy 93.71353 -141.162746) (xy 93.69089 -141.113162) (xy 93.675538 -141.060861) (xy 93.667786 -141.006906)
			(xy 93.667326 -140.979652) (xy 93.667834 -140.960094) (xy 93.668342 -140.949426) (xy 93.66123 -140.930122)
			(xy 93.595952 -140.861288) (xy 93.576902 -140.85316) (xy 93.566234 -140.85316) (xy 93.551314 -140.853039)
			(xy 93.521561 -140.85075) (xy 93.506798 -140.848588) (xy 93.494606 -140.846556) (xy 93.471746 -140.853922)
			(xy 93.302074 -141.023594) (xy 93.29524 -141.030999) (xy 93.287518 -141.049595) (xy 93.287088 -141.059662)
			(xy 93.287088 -147.33143) (xy 93.287475 -147.341504) (xy 93.29522 -147.360103) (xy 93.302074 -147.367498)
			(xy 94.665292 -148.730462) (xy 94.679058 -148.744979) (xy 94.701233 -148.778268) (xy 94.716495 -148.815241)
			(xy 94.724194 -148.85416) (xy 96.058988 -148.85416) (xy 96.063059 -148.798538) (xy 96.075185 -148.744101)
			(xy 96.095108 -148.69201) (xy 96.122404 -148.643375) (xy 96.15649 -148.599232) (xy 96.196639 -148.560523)
			(xy 96.241997 -148.528072) (xy 96.291597 -148.502571) (xy 96.344381 -148.484564) (xy 96.399224 -148.474434)
			(xy 96.454958 -148.472397) (xy 96.510395 -148.478497) (xy 96.564352 -148.492603) (xy 96.615681 -148.514415)
			(xy 96.663287 -148.543469) (xy 96.706155 -148.579144) (xy 96.743372 -148.620681) (xy 96.774145 -148.667194)
			(xy 96.797817 -148.717691) (xy 96.813885 -148.771098) (xy 96.822005 -148.826274) (xy 96.822514 -148.85416)
			(xy 96.822005 -148.882046) (xy 96.813885 -148.937222) (xy 96.797817 -148.990629) (xy 96.774145 -149.041126)
			(xy 96.743372 -149.087639) (xy 96.706155 -149.129176) (xy 96.663287 -149.164851) (xy 96.615681 -149.193905)
			(xy 96.564352 -149.215717) (xy 96.510395 -149.229823) (xy 96.454958 -149.235923) (xy 96.399224 -149.233886)
			(xy 96.344381 -149.223756) (xy 96.291597 -149.205749) (xy 96.241997 -149.180248) (xy 96.196639 -149.147797)
			(xy 96.15649 -149.109088) (xy 96.122404 -149.064945) (xy 96.095108 -149.01631) (xy 96.075185 -148.964219)
			(xy 96.063059 -148.909782) (xy 96.058988 -148.85416) (xy 94.724194 -148.85416) (xy 94.724257 -148.85448)
			(xy 94.724728 -148.87448) (xy 94.724728 -149.72665) (xy 94.724339 -149.746658) (xy 94.716587 -149.785915)
			(xy 94.701314 -149.822901) (xy 94.679108 -149.856189) (xy 94.665292 -149.870668) (xy 94.643945 -149.892004)
			(xy 95.52305 -149.892004) (xy 95.523536 -149.864753) (xy 95.531292 -149.810805) (xy 95.546647 -149.75851)
			(xy 95.569289 -149.708933) (xy 95.598755 -149.663083) (xy 95.634446 -149.621892) (xy 95.675637 -149.586201)
			(xy 95.721487 -149.556735) (xy 95.771064 -149.534093) (xy 95.823359 -149.518738) (xy 95.877307 -149.510982)
			(xy 95.931809 -149.510982) (xy 95.985757 -149.518738) (xy 96.038052 -149.534093) (xy 96.087629 -149.556735)
			(xy 96.133479 -149.586201) (xy 96.17467 -149.621892) (xy 96.210361 -149.663083) (xy 96.239827 -149.708933)
			(xy 96.262469 -149.75851) (xy 96.277824 -149.810805) (xy 96.28558 -149.864753) (xy 96.286066 -149.892004)
			(xy 96.285543 -149.920929) (xy 96.276862 -149.978124) (xy 96.25964 -150.033351) (xy 96.234273 -150.085342)
			(xy 96.218248 -150.109428) (xy 96.210868 -150.120879) (xy 96.201847 -150.146571) (xy 96.199948 -150.173736)
			(xy 96.205307 -150.200434) (xy 96.217541 -150.224761) (xy 96.235777 -150.244983) (xy 96.258715 -150.259658)
			(xy 96.271588 -150.264114) (xy 96.297187 -150.272507) (xy 96.345882 -150.295554) (xy 96.390851 -150.325221)
			(xy 96.4312 -150.360919) (xy 96.466126 -150.401936) (xy 96.494936 -150.447459) (xy 96.517056 -150.496582)
			(xy 96.532047 -150.548327) (xy 96.53961 -150.601667) (xy 96.540066 -150.628604) (xy 96.53958 -150.655855)
			(xy 96.531824 -150.709803) (xy 96.516469 -150.762098) (xy 96.493827 -150.811675) (xy 96.464361 -150.857525)
			(xy 96.42867 -150.898716) (xy 96.387479 -150.934407) (xy 96.341629 -150.963873) (xy 96.292052 -150.986515)
			(xy 96.239757 -151.00187) (xy 96.185809 -151.009626) (xy 96.131307 -151.009626) (xy 96.077359 -151.00187)
			(xy 96.025064 -150.986515) (xy 95.975487 -150.963873) (xy 95.929637 -150.934407) (xy 95.888446 -150.898716)
			(xy 95.852755 -150.857525) (xy 95.823289 -150.811675) (xy 95.800647 -150.762098) (xy 95.785292 -150.709803)
			(xy 95.777536 -150.655855) (xy 95.77705 -150.628604) (xy 95.777543 -150.599678) (xy 95.786235 -150.542482)
			(xy 95.803466 -150.487256) (xy 95.828841 -150.435266) (xy 95.844868 -150.41118) (xy 95.85223 -150.399719)
			(xy 95.861249 -150.37403) (xy 95.863149 -150.346869) (xy 95.857793 -150.320174) (xy 95.845563 -150.295849)
			(xy 95.827331 -150.275627) (xy 95.804398 -150.260952) (xy 95.791528 -150.256494) (xy 95.765935 -150.248084)
			(xy 95.71724 -150.22504) (xy 95.672271 -150.195375) (xy 95.631922 -150.15968) (xy 95.596994 -150.118664)
			(xy 95.568184 -150.073144) (xy 95.546063 -150.024023) (xy 95.531071 -149.972279) (xy 95.523506 -149.91894)
			(xy 95.52305 -149.892004) (xy 94.643945 -149.892004) (xy 94.151196 -150.38451) (xy 94.144502 -150.39199)
			(xy 94.136914 -150.410551) (xy 94.136464 -150.420578) (xy 94.136464 -150.707852) (xy 94.48114 -150.707852)
			(xy 94.485211 -150.65223) (xy 94.497337 -150.597793) (xy 94.51726 -150.545702) (xy 94.544556 -150.497067)
			(xy 94.578642 -150.452924) (xy 94.618791 -150.414215) (xy 94.664149 -150.381764) (xy 94.713749 -150.356263)
			(xy 94.766533 -150.338256) (xy 94.821376 -150.328126) (xy 94.87711 -150.326089) (xy 94.932547 -150.332189)
			(xy 94.986504 -150.346295) (xy 95.037833 -150.368107) (xy 95.085439 -150.397161) (xy 95.128307 -150.432836)
			(xy 95.165524 -150.474373) (xy 95.196297 -150.520886) (xy 95.219969 -150.571383) (xy 95.236037 -150.62479)
			(xy 95.244157 -150.679966) (xy 95.244666 -150.707852) (xy 95.244157 -150.735738) (xy 95.236037 -150.790914)
			(xy 95.219969 -150.844321) (xy 95.196297 -150.894818) (xy 95.165524 -150.941331) (xy 95.128307 -150.982868)
			(xy 95.085439 -151.018543) (xy 95.037833 -151.047597) (xy 94.986504 -151.069409) (xy 94.932547 -151.083515)
			(xy 94.87711 -151.089615) (xy 94.821376 -151.087578) (xy 94.766533 -151.077448) (xy 94.713749 -151.059441)
			(xy 94.664149 -151.03394) (xy 94.618791 -151.001489) (xy 94.578642 -150.96278) (xy 94.544556 -150.918637)
			(xy 94.51726 -150.870002) (xy 94.497337 -150.817911) (xy 94.485211 -150.763474) (xy 94.48114 -150.707852)
			(xy 94.136464 -150.707852) (xy 94.136464 -151.254206) (xy 94.136839 -151.264251) (xy 94.144423 -151.282848)
			(xy 94.151196 -151.290274) (xy 95.799656 -152.93848) (xy 95.813424 -152.952995) (xy 95.835601 -152.986284)
			(xy 95.850862 -153.023258) (xy 95.858623 -153.062498) (xy 95.859092 -153.082498) (xy 95.859092 -171.021248)
			(xy 95.858712 -171.041257) (xy 95.850959 -171.080515) (xy 95.835683 -171.117501) (xy 95.813474 -171.150788)
			(xy 95.799656 -171.165266) (xy 90.652092 -176.312576) (xy 90.645382 -176.320044) (xy 90.6378 -176.338613)
			(xy 90.63736 -176.348644) (xy 90.63736 -177.907188) (xy 90.637694 -177.917237) (xy 90.645306 -177.935834)
			(xy 90.652092 -177.943256) (xy 90.662506 -177.95367) (xy 90.685366 -177.961036) (xy 90.697558 -177.959004)
			(xy 90.712322 -177.956844) (xy 90.742074 -177.954556) (xy 90.756994 -177.954432) (xy 90.784249 -177.954861)
			(xy 90.838203 -177.962618) (xy 90.890504 -177.977976) (xy 90.940086 -178.00062) (xy 90.985942 -178.030091)
			(xy 91.027135 -178.065789) (xy 91.062829 -178.106986) (xy 91.092296 -178.152843) (xy 91.114936 -178.202428)
			(xy 91.130289 -178.254731) (xy 91.138041 -178.308685) (xy 91.138502 -178.33594) (xy 91.137843 -178.367503)
			(xy 91.127455 -178.429768) (xy 91.106969 -178.489477) (xy 91.092528 -178.51755) (xy 91.087702 -178.52644)
			(xy 91.08567 -178.545998) (xy 91.111324 -178.634136) (xy 91.12377 -178.64963) (xy 91.13266 -178.65471)
			(xy 91.140026 -178.658774) (xy 91.149678 -178.664616) (xy 91.171776 -178.666648) (xy 91.266264 -178.63312)
			(xy 91.282266 -178.617626) (xy 91.28633 -178.607212) (xy 91.297074 -178.580456) (xy 91.325355 -178.530215)
			(xy 91.360878 -178.484806) (xy 91.402832 -178.445262) (xy 91.450263 -178.412485) (xy 91.502087 -178.387224)
			(xy 91.557124 -178.370053) (xy 91.614119 -178.361365) (xy 91.642946 -178.360832) (xy 91.670198 -178.361241)
			(xy 91.724146 -178.369004) (xy 91.776441 -178.384364) (xy 91.826018 -178.407011) (xy 91.871867 -178.436481)
			(xy 91.913056 -178.472176) (xy 91.948746 -178.51337) (xy 91.978212 -178.559223) (xy 92.000852 -178.608802)
			(xy 92.016206 -178.661099) (xy 92.023962 -178.715048) (xy 92.023962 -178.769552) (xy 92.016206 -178.823501)
			(xy 92.00685 -178.85537) (xy 92.265754 -178.85537) (xy 92.266209 -178.827894) (xy 92.274107 -178.773513)
			(xy 92.289733 -178.720829) (xy 92.312765 -178.670937) (xy 92.342725 -178.62487) (xy 92.360496 -178.60391)
			(xy 92.366592 -178.596798) (xy 92.372942 -178.57978) (xy 92.372942 -178.493928) (xy 92.366592 -178.47691)
			(xy 92.360496 -178.469798) (xy 92.34275 -178.448822) (xy 92.312822 -178.402744) (xy 92.289806 -178.352853)
			(xy 92.274176 -178.300179) (xy 92.266255 -178.245809) (xy 92.265754 -178.218338) (xy 92.26624 -178.191087)
			(xy 92.273996 -178.137139) (xy 92.289351 -178.084844) (xy 92.311993 -178.035267) (xy 92.341459 -177.989417)
			(xy 92.37715 -177.948226) (xy 92.418341 -177.912535) (xy 92.464191 -177.883069) (xy 92.513768 -177.860427)
			(xy 92.566063 -177.845072) (xy 92.620011 -177.837316) (xy 92.674513 -177.837316) (xy 92.728461 -177.845072)
			(xy 92.780756 -177.860427) (xy 92.830333 -177.883069) (xy 92.876183 -177.912535) (xy 92.917374 -177.948226)
			(xy 92.953065 -177.989417) (xy 92.982531 -178.035267) (xy 93.005173 -178.084844) (xy 93.020528 -178.137139)
			(xy 93.028284 -178.191087) (xy 93.02877 -178.218338) (xy 93.028313 -178.245814) (xy 93.020415 -178.300195)
			(xy 93.004789 -178.352878) (xy 92.981757 -178.40277) (xy 92.951799 -178.448837) (xy 92.934028 -178.469798)
			(xy 92.927932 -178.47691) (xy 92.921582 -178.493928) (xy 92.921582 -178.57978) (xy 92.927932 -178.596798)
			(xy 92.934028 -178.60391) (xy 92.951782 -178.62488) (xy 92.981707 -178.67096) (xy 93.004722 -178.720852)
			(xy 93.02035 -178.773527) (xy 93.028269 -178.827898) (xy 93.02877 -178.85537) (xy 93.028284 -178.882621)
			(xy 93.026651 -178.893978) (xy 93.60357 -178.893978) (xy 93.607641 -178.838356) (xy 93.619767 -178.783919)
			(xy 93.63969 -178.731828) (xy 93.666986 -178.683193) (xy 93.701072 -178.63905) (xy 93.741221 -178.600341)
			(xy 93.786579 -178.56789) (xy 93.836179 -178.542389) (xy 93.888963 -178.524382) (xy 93.943806 -178.514252)
			(xy 93.99954 -178.512215) (xy 94.054977 -178.518315) (xy 94.108934 -178.532421) (xy 94.160263 -178.554233)
			(xy 94.207869 -178.583287) (xy 94.250737 -178.618962) (xy 94.287954 -178.660499) (xy 94.318727 -178.707012)
			(xy 94.342399 -178.757509) (xy 94.358467 -178.810916) (xy 94.366587 -178.866092) (xy 94.367096 -178.893978)
			(xy 94.366587 -178.921864) (xy 94.358467 -178.97704) (xy 94.342399 -179.030447) (xy 94.318727 -179.080944)
			(xy 94.287954 -179.127457) (xy 94.250737 -179.168994) (xy 94.207869 -179.204669) (xy 94.160263 -179.233723)
			(xy 94.108934 -179.255535) (xy 94.054977 -179.269641) (xy 93.99954 -179.275741) (xy 93.943806 -179.273704)
			(xy 93.888963 -179.263574) (xy 93.836179 -179.245567) (xy 93.786579 -179.220066) (xy 93.741221 -179.187615)
			(xy 93.701072 -179.148906) (xy 93.666986 -179.104763) (xy 93.63969 -179.056128) (xy 93.619767 -179.004037)
			(xy 93.607641 -178.9496) (xy 93.60357 -178.893978) (xy 93.026651 -178.893978) (xy 93.020528 -178.936569)
			(xy 93.005173 -178.988864) (xy 92.982531 -179.038441) (xy 92.953065 -179.084291) (xy 92.917374 -179.125482)
			(xy 92.876183 -179.161173) (xy 92.830333 -179.190639) (xy 92.780756 -179.213281) (xy 92.728461 -179.228636)
			(xy 92.674513 -179.236392) (xy 92.620011 -179.236392) (xy 92.566063 -179.228636) (xy 92.513768 -179.213281)
			(xy 92.464191 -179.190639) (xy 92.418341 -179.161173) (xy 92.37715 -179.125482) (xy 92.341459 -179.084291)
			(xy 92.311993 -179.038441) (xy 92.289351 -178.988864) (xy 92.273996 -178.936569) (xy 92.26624 -178.882621)
			(xy 92.265754 -178.85537) (xy 92.00685 -178.85537) (xy 92.000852 -178.875798) (xy 91.978212 -178.925377)
			(xy 91.948746 -178.97123) (xy 91.913056 -179.012424) (xy 91.871867 -179.048119) (xy 91.826018 -179.077589)
			(xy 91.776441 -179.100236) (xy 91.724146 -179.115596) (xy 91.670198 -179.123359) (xy 91.642946 -179.123848)
			(xy 91.61771 -179.123468) (xy 91.567676 -179.116844) (xy 91.518956 -179.103666) (xy 91.472404 -179.084165)
			(xy 91.450414 -179.071778) (xy 91.440762 -179.065936) (xy 91.418664 -179.063904) (xy 91.324176 -179.097432)
			(xy 91.308174 -179.112926) (xy 91.30411 -179.12334) (xy 91.293443 -179.150129) (xy 91.26515 -179.20037)
			(xy 91.229616 -179.245779) (xy 91.187649 -179.28532) (xy 91.140208 -179.318092) (xy 91.088373 -179.343348)
			(xy 91.033327 -179.360511) (xy 90.976324 -179.369192) (xy 90.947494 -179.36972) (xy 90.920243 -179.369228)
			(xy 90.866296 -179.361471) (xy 90.814002 -179.346116) (xy 90.764426 -179.323475) (xy 90.718576 -179.294009)
			(xy 90.677386 -179.258318) (xy 90.641695 -179.217129) (xy 90.612228 -179.171279) (xy 90.589587 -179.121703)
			(xy 90.57423 -179.06941) (xy 90.566473 -179.015463) (xy 90.565986 -178.988212) (xy 90.566628 -178.956648)
			(xy 90.577023 -178.894383) (xy 90.597515 -178.834674) (xy 90.61196 -178.806602) (xy 90.616786 -178.797712)
			(xy 90.618818 -178.778154) (xy 90.593164 -178.690016) (xy 90.580718 -178.674522) (xy 90.571828 -178.669442)
			(xy 90.546724 -178.654899) (xy 90.50084 -178.619396) (xy 90.460864 -178.577351) (xy 90.427719 -178.529737)
			(xy 90.402168 -178.477651) (xy 90.384803 -178.422295) (xy 90.376024 -178.364948) (xy 90.375486 -178.33594)
			(xy 90.375608 -178.32102) (xy 90.377896 -178.291267) (xy 90.380058 -178.276504) (xy 90.38209 -178.264312)
			(xy 90.374724 -178.241452) (xy 90.289634 -178.156616) (xy 90.275819 -178.142123) (xy 90.253557 -178.108853)
			(xy 90.238222 -178.071875) (xy 90.230404 -178.032614) (xy 90.229944 -178.012598) (xy 84.515864 -178.012598)
			(xy 84.520134 -178.016298) (xy 84.555825 -178.057489) (xy 84.585291 -178.103339) (xy 84.607933 -178.152916)
			(xy 84.623288 -178.205211) (xy 84.631044 -178.259159) (xy 84.63153 -178.28641) (xy 84.631042 -178.313884)
			(xy 84.62315 -178.368264) (xy 84.607529 -178.420946) (xy 84.584505 -178.470839) (xy 84.554555 -178.516908)
			(xy 84.536788 -178.53787) (xy 84.530692 -178.544982) (xy 84.524342 -178.562) (xy 84.524342 -178.647852)
			(xy 84.530692 -178.66487) (xy 84.536788 -178.671982) (xy 84.554523 -178.692968) (xy 84.584452 -178.739043)
			(xy 84.607471 -178.788931) (xy 84.623104 -178.841603) (xy 84.631027 -178.895971) (xy 84.63153 -178.923442)
			(xy 84.631044 -178.950693) (xy 84.629411 -178.96205) (xy 85.20633 -178.96205) (xy 85.210401 -178.906428)
			(xy 85.222527 -178.851991) (xy 85.24245 -178.7999) (xy 85.269746 -178.751265) (xy 85.303832 -178.707122)
			(xy 85.343981 -178.668413) (xy 85.389339 -178.635962) (xy 85.438939 -178.610461) (xy 85.491723 -178.592454)
			(xy 85.546566 -178.582324) (xy 85.6023 -178.580287) (xy 85.657737 -178.586387) (xy 85.711694 -178.600493)
			(xy 85.763023 -178.622305) (xy 85.810629 -178.651359) (xy 85.853497 -178.687034) (xy 85.890714 -178.728571)
			(xy 85.921487 -178.775084) (xy 85.945159 -178.825581) (xy 85.961227 -178.878988) (xy 85.969347 -178.934164)
			(xy 85.969856 -178.96205) (xy 85.969347 -178.989936) (xy 85.961227 -179.045112) (xy 85.945159 -179.098519)
			(xy 85.921487 -179.149016) (xy 85.890714 -179.195529) (xy 85.853497 -179.237066) (xy 85.810629 -179.272741)
			(xy 85.763023 -179.301795) (xy 85.711694 -179.323607) (xy 85.657737 -179.337713) (xy 85.6023 -179.343813)
			(xy 85.546566 -179.341776) (xy 85.491723 -179.331646) (xy 85.438939 -179.313639) (xy 85.389339 -179.288138)
			(xy 85.343981 -179.255687) (xy 85.303832 -179.216978) (xy 85.269746 -179.172835) (xy 85.24245 -179.1242)
			(xy 85.222527 -179.072109) (xy 85.210401 -179.017672) (xy 85.20633 -178.96205) (xy 84.629411 -178.96205)
			(xy 84.623288 -179.004641) (xy 84.607933 -179.056936) (xy 84.585291 -179.106513) (xy 84.555825 -179.152363)
			(xy 84.520134 -179.193554) (xy 84.478943 -179.229245) (xy 84.433093 -179.258711) (xy 84.383516 -179.281353)
			(xy 84.331221 -179.296708) (xy 84.277273 -179.304464) (xy 84.222771 -179.304464) (xy 84.168823 -179.296708)
			(xy 84.116528 -179.281353) (xy 84.066951 -179.258711) (xy 84.021101 -179.229245) (xy 83.97991 -179.193554)
			(xy 83.944219 -179.152363) (xy 83.914753 -179.106513) (xy 83.892111 -179.056936) (xy 83.876756 -179.004641)
			(xy 83.869 -178.950693) (xy 83.868514 -178.923442) (xy 83.609603 -178.923442) (xy 83.603599 -178.943888)
			(xy 83.580959 -178.993463) (xy 83.551495 -179.039312) (xy 83.515805 -179.080501) (xy 83.474617 -179.116191)
			(xy 83.428769 -179.145656) (xy 83.379194 -179.168297) (xy 83.326901 -179.183652) (xy 83.272956 -179.191409)
			(xy 83.245706 -179.19192) (xy 83.220473 -179.191509) (xy 83.170447 -179.184859) (xy 83.121731 -179.171687)
			(xy 83.07517 -179.152221) (xy 83.053174 -179.13985) (xy 83.043522 -179.134008) (xy 83.021424 -179.131976)
			(xy 82.926936 -179.165504) (xy 82.910934 -179.180998) (xy 82.90687 -179.191412) (xy 82.896179 -179.218192)
			(xy 82.867897 -179.26844) (xy 82.83237 -179.313856) (xy 82.790409 -179.353403) (xy 82.74297 -179.38618)
			(xy 82.691135 -179.411438) (xy 82.636088 -179.428601) (xy 82.579084 -179.437278) (xy 82.550254 -179.437792)
			(xy 82.523005 -179.437303) (xy 82.469064 -179.429541) (xy 82.416775 -179.414181) (xy 82.367205 -179.391537)
			(xy 82.321361 -179.36207) (xy 82.280178 -179.326378) (xy 82.244493 -179.285189) (xy 82.215033 -179.239341)
			(xy 82.192397 -179.189767) (xy 82.177046 -179.137476) (xy 82.169293 -179.083533) (xy 82.168746 -179.056284)
			(xy 82.169398 -179.024721) (xy 82.179789 -178.962456) (xy 82.200283 -178.90275) (xy 82.21472 -178.874674)
			(xy 82.219546 -178.865784) (xy 82.221578 -178.846226) (xy 82.195924 -178.758088) (xy 82.183478 -178.742594)
			(xy 82.174588 -178.737514) (xy 82.149496 -178.722958) (xy 82.103633 -178.68744) (xy 82.063673 -178.64539)
			(xy 82.030538 -178.597777) (xy 82.00499 -178.545698) (xy 81.987618 -178.490353) (xy 81.978823 -178.433016)
			(xy 81.978246 -178.404012) (xy 81.97837 -178.389092) (xy 81.980656 -178.359339) (xy 81.982818 -178.344576)
			(xy 81.98485 -178.332384) (xy 81.977484 -178.309524) (xy 81.712816 -178.04511) (xy 81.699004 -178.03063)
			(xy 81.676807 -177.99734) (xy 81.661543 -177.960354) (xy 81.653803 -177.921099) (xy 81.65338 -177.901092)
			(xy 81.65338 -172.733462) (xy 81.652949 -172.723395) (xy 81.645223 -172.704803) (xy 81.638394 -172.697394)
			(xy 80.188816 -171.24807) (xy 80.175007 -171.233589) (xy 80.152816 -171.200298) (xy 80.13756 -171.163312)
			(xy 80.129827 -171.124057) (xy 80.12938 -171.104052) (xy 80.12938 -156.335222) (xy 80.129849 -156.315133)
			(xy 80.13771 -156.275731) (xy 80.153115 -156.238623) (xy 80.163924 -156.221684) (xy 80.174084 -156.206444)
			(xy 80.170528 -156.17063) (xy 80.157574 -156.157422) (xy 80.150127 -156.150734) (xy 80.131631 -156.143138)
			(xy 80.111635 -156.143138) (xy 80.093139 -156.150734) (xy 80.085692 -156.157422) (xy 79.408274 -156.83484)
			(xy 79.401426 -156.842237) (xy 79.393694 -156.860836) (xy 79.393288 -156.870908) (xy 79.393288 -166.446454)
			(xy 79.392823 -166.466456) (xy 79.385071 -166.505701) (xy 79.369815 -166.542681) (xy 79.347642 -166.575977)
			(xy 79.333852 -166.590472) (xy 73.92924 -171.99483) (xy 73.923397 -172.002097) (xy 73.916874 -172.019549)
			(xy 73.91654 -172.028866) (xy 73.91654 -172.857414) (xy 73.917081 -172.867399) (xy 73.924803 -172.885824)
			(xy 73.931526 -172.893228) (xy 73.941686 -172.903388) (xy 73.964546 -172.911008) (xy 73.976738 -172.908976)
			(xy 73.991501 -172.906816) (xy 74.021254 -172.90453) (xy 74.036174 -172.904404) (xy 74.063428 -172.904866)
			(xy 74.117381 -172.91262) (xy 74.169681 -172.927974) (xy 74.219264 -172.950615) (xy 74.265119 -172.980082)
			(xy 74.306314 -173.015776) (xy 74.342009 -173.056969) (xy 74.371479 -173.102824) (xy 74.394122 -173.152406)
			(xy 74.409477 -173.204705) (xy 74.417233 -173.258658) (xy 74.417682 -173.285912) (xy 74.41701 -173.317432)
			(xy 74.406605 -173.379609) (xy 74.38613 -173.439233) (xy 74.371708 -173.467268) (xy 74.366882 -173.476412)
			(xy 74.36485 -173.49597) (xy 74.390504 -173.584108) (xy 74.40295 -173.599602) (xy 74.41184 -173.604682)
			(xy 74.414888 -173.606206) (xy 74.415396 -173.60646) (xy 74.419714 -173.609) (xy 74.42962 -173.614588)
			(xy 74.45121 -173.61662) (xy 74.545698 -173.583092) (xy 74.561446 -173.567598) (xy 74.56551 -173.55693)
			(xy 74.576231 -173.530177) (xy 74.604557 -173.479986) (xy 74.640108 -173.434625) (xy 74.682075 -173.395125)
			(xy 74.729505 -173.362385) (xy 74.781318 -173.337148) (xy 74.836337 -173.319988) (xy 74.89331 -173.311297)
			(xy 74.922126 -173.310804) (xy 74.949375 -173.311292) (xy 75.003318 -173.319051) (xy 75.055608 -173.334408)
			(xy 75.105181 -173.35705) (xy 75.151026 -173.386516) (xy 75.192212 -173.422206) (xy 75.2279 -173.463395)
			(xy 75.257362 -173.509242) (xy 75.280001 -173.558816) (xy 75.295354 -173.611107) (xy 75.30311 -173.665051)
			(xy 75.30311 -173.719549) (xy 75.295354 -173.773493) (xy 75.286003 -173.805342) (xy 75.544934 -173.805342)
			(xy 75.545437 -173.777868) (xy 75.553323 -173.723489) (xy 75.568939 -173.670806) (xy 75.59196 -173.620913)
			(xy 75.621909 -173.574844) (xy 75.639676 -173.553882) (xy 75.645772 -173.54677) (xy 75.652122 -173.529752)
			(xy 75.652122 -173.4439) (xy 75.645772 -173.426882) (xy 75.639676 -173.41977) (xy 75.621913 -173.398807)
			(xy 75.591989 -173.352725) (xy 75.568976 -173.302831) (xy 75.55335 -173.250154) (xy 75.545433 -173.195782)
			(xy 75.544934 -173.16831) (xy 75.54542 -173.141059) (xy 75.553176 -173.087111) (xy 75.568531 -173.034816)
			(xy 75.591173 -172.985239) (xy 75.620639 -172.939389) (xy 75.65633 -172.898198) (xy 75.697521 -172.862507)
			(xy 75.743371 -172.833041) (xy 75.792948 -172.810399) (xy 75.845243 -172.795044) (xy 75.899191 -172.787288)
			(xy 75.953693 -172.787288) (xy 76.007641 -172.795044) (xy 76.059936 -172.810399) (xy 76.109513 -172.833041)
			(xy 76.155363 -172.862507) (xy 76.196554 -172.898198) (xy 76.232245 -172.939389) (xy 76.261711 -172.985239)
			(xy 76.284353 -173.034816) (xy 76.299708 -173.087111) (xy 76.307464 -173.141059) (xy 76.30795 -173.16831)
			(xy 76.307482 -173.195785) (xy 76.299587 -173.250166) (xy 76.283964 -173.302849) (xy 76.260935 -173.352742)
			(xy 76.230978 -173.398809) (xy 76.213208 -173.41977) (xy 76.207112 -173.426882) (xy 76.200762 -173.4439)
			(xy 76.200762 -173.529752) (xy 76.207112 -173.54677) (xy 76.213208 -173.553882) (xy 76.230946 -173.574865)
			(xy 76.260874 -173.620941) (xy 76.283892 -173.67083) (xy 76.299524 -173.723502) (xy 76.307447 -173.777871)
			(xy 76.30795 -173.805342) (xy 76.307464 -173.832593) (xy 76.305831 -173.84395) (xy 76.88275 -173.84395)
			(xy 76.886821 -173.788328) (xy 76.898947 -173.733891) (xy 76.91887 -173.6818) (xy 76.946166 -173.633165)
			(xy 76.980252 -173.589022) (xy 77.020401 -173.550313) (xy 77.065759 -173.517862) (xy 77.115359 -173.492361)
			(xy 77.168143 -173.474354) (xy 77.222986 -173.464224) (xy 77.27872 -173.462187) (xy 77.334157 -173.468287)
			(xy 77.388114 -173.482393) (xy 77.439443 -173.504205) (xy 77.487049 -173.533259) (xy 77.529917 -173.568934)
			(xy 77.567134 -173.610471) (xy 77.597907 -173.656984) (xy 77.621579 -173.707481) (xy 77.637647 -173.760888)
			(xy 77.645767 -173.816064) (xy 77.646276 -173.84395) (xy 77.645767 -173.871836) (xy 77.637647 -173.927012)
			(xy 77.621579 -173.980419) (xy 77.597907 -174.030916) (xy 77.567134 -174.077429) (xy 77.529917 -174.118966)
			(xy 77.487049 -174.154641) (xy 77.439443 -174.183695) (xy 77.388114 -174.205507) (xy 77.334157 -174.219613)
			(xy 77.27872 -174.225713) (xy 77.222986 -174.223676) (xy 77.168143 -174.213546) (xy 77.115359 -174.195539)
			(xy 77.065759 -174.170038) (xy 77.020401 -174.137587) (xy 76.980252 -174.098878) (xy 76.946166 -174.054735)
			(xy 76.91887 -174.0061) (xy 76.898947 -173.954009) (xy 76.886821 -173.899572) (xy 76.88275 -173.84395)
			(xy 76.305831 -173.84395) (xy 76.299708 -173.886541) (xy 76.284353 -173.938836) (xy 76.261711 -173.988413)
			(xy 76.232245 -174.034263) (xy 76.196554 -174.075454) (xy 76.155363 -174.111145) (xy 76.109513 -174.140611)
			(xy 76.059936 -174.163253) (xy 76.007641 -174.178608) (xy 75.953693 -174.186364) (xy 75.899191 -174.186364)
			(xy 75.845243 -174.178608) (xy 75.792948 -174.163253) (xy 75.743371 -174.140611) (xy 75.697521 -174.111145)
			(xy 75.65633 -174.075454) (xy 75.620639 -174.034263) (xy 75.591173 -173.988413) (xy 75.568531 -173.938836)
			(xy 75.553176 -173.886541) (xy 75.54542 -173.832593) (xy 75.544934 -173.805342) (xy 75.286003 -173.805342)
			(xy 75.280001 -173.825784) (xy 75.257362 -173.875358) (xy 75.2279 -173.921205) (xy 75.192212 -173.962394)
			(xy 75.151026 -173.998084) (xy 75.105181 -174.02755) (xy 75.055608 -174.050192) (xy 75.003318 -174.065549)
			(xy 74.949375 -174.073308) (xy 74.922126 -174.07382) (xy 74.896895 -174.073404) (xy 74.846873 -174.066744)
			(xy 74.798161 -174.053563) (xy 74.751607 -174.03409) (xy 74.729594 -174.02175) (xy 74.719688 -174.015908)
			(xy 74.697844 -174.013876) (xy 74.603102 -174.047404) (xy 74.587354 -174.062898) (xy 74.58329 -174.073566)
			(xy 74.572569 -174.100319) (xy 74.544243 -174.15051) (xy 74.508693 -174.195872) (xy 74.466725 -174.235372)
			(xy 74.419296 -174.268113) (xy 74.367483 -174.293351) (xy 74.312464 -174.31051) (xy 74.25549 -174.319202)
			(xy 74.226674 -174.319692) (xy 74.199424 -174.319204) (xy 74.14548 -174.311444) (xy 74.09319 -174.296087)
			(xy 74.043617 -174.273444) (xy 73.997771 -174.243977) (xy 73.956585 -174.208285) (xy 73.920898 -174.167095)
			(xy 73.891436 -174.121246) (xy 73.868798 -174.071671) (xy 73.853447 -174.019378) (xy 73.845693 -173.965434)
			(xy 73.845166 -173.938184) (xy 73.845839 -173.906664) (xy 73.856245 -173.844488) (xy 73.876723 -173.784866)
			(xy 73.89114 -173.756828) (xy 73.895966 -173.747684) (xy 73.897998 -173.728126) (xy 73.872344 -173.639988)
			(xy 73.859898 -173.624494) (xy 73.851008 -173.619414) (xy 73.825914 -173.604858) (xy 73.780049 -173.569342)
			(xy 73.740088 -173.527293) (xy 73.706951 -173.47968) (xy 73.681402 -173.427601) (xy 73.664029 -173.372254)
			(xy 73.655232 -173.314916) (xy 73.654666 -173.285912) (xy 73.65479 -173.270992) (xy 73.657075 -173.241239)
			(xy 73.659238 -173.226476) (xy 73.66127 -173.214284) (xy 73.65365 -173.191424) (xy 73.573386 -173.110906)
			(xy 73.568814 -173.106588) (xy 73.555007 -173.09209) (xy 73.532762 -173.058813) (xy 73.517428 -173.021838)
			(xy 73.509594 -172.982584) (xy 73.509124 -172.96257) (xy 73.509124 -171.923456) (xy 73.509579 -171.903438)
			(xy 73.517387 -171.864171) (xy 73.532714 -171.827185) (xy 73.55497 -171.793904) (xy 73.568814 -171.779438)
			(xy 73.569068 -171.779438) (xy 78.973426 -166.374826) (xy 78.978774 -166.368357) (xy 78.98537 -166.352934)
			(xy 78.98638 -166.3446) (xy 78.98638 -156.765498) (xy 78.98638 -156.49829) (xy 78.986893 -156.478354)
			(xy 78.994701 -156.439252) (xy 79.009958 -156.402413) (xy 79.032083 -156.369241) (xy 79.045816 -156.35478)
			(xy 82.116422 -153.284174) (xy 82.123237 -153.276831) (xy 82.130972 -153.258368) (xy 82.131408 -153.24836)
			(xy 82.131408 -152.47112) (xy 82.131875 -152.451119) (xy 82.139632 -152.411877) (xy 82.15489 -152.3749)
			(xy 82.177065 -152.341607) (xy 82.190844 -152.327102) (xy 83.707732 -150.810214) (xy 83.72223 -150.796409)
			(xy 83.755508 -150.774166) (xy 83.792483 -150.758836) (xy 83.831737 -150.751006) (xy 83.85175 -150.750524)
			(xy 84.72805 -150.750524) (xy 89.059512 -150.750524) (xy 89.069499 -150.749985) (xy 89.08793 -150.742271)
			(xy 89.095326 -150.735538) (xy 89.313004 -150.518114) (xy 89.319997 -150.51036) (xy 89.327619 -150.490943)
			(xy 89.326924 -150.470094) (xy 89.32291 -150.460456) (xy 89.282016 -150.374096) (xy 89.277124 -150.364879)
			(xy 89.261478 -150.351104) (xy 89.241644 -150.344689) (xy 89.231216 -150.34514) (xy 89.193878 -150.346918)
			(xy 89.166626 -150.346431) (xy 89.112678 -150.338671) (xy 89.060383 -150.323313) (xy 89.010806 -150.300668)
			(xy 88.964956 -150.271199) (xy 88.923767 -150.235505) (xy 88.888077 -150.194312) (xy 88.858613 -150.148459)
			(xy 88.835973 -150.098879) (xy 88.820621 -150.046583) (xy 88.812867 -149.992634) (xy 88.812869 -149.93813)
			(xy 88.820628 -149.884182) (xy 88.835986 -149.831887) (xy 88.85863 -149.78231) (xy 88.888099 -149.73646)
			(xy 88.923793 -149.69527) (xy 88.964985 -149.659579) (xy 89.010838 -149.630114) (xy 89.060417 -149.607475)
			(xy 89.112713 -149.592121) (xy 89.166662 -149.584367) (xy 89.221166 -149.584369) (xy 89.275114 -149.592127)
			(xy 89.32741 -149.607485) (xy 89.376987 -149.630128) (xy 89.422837 -149.659596) (xy 89.464027 -149.69529)
			(xy 89.499718 -149.736482) (xy 89.529184 -149.782334) (xy 89.551824 -149.831913) (xy 89.567178 -149.884209)
			(xy 89.574933 -149.938158) (xy 89.575386 -149.96541) (xy 89.574768 -149.996158) (xy 89.564907 -150.056857)
			(xy 89.545441 -150.11519) (xy 89.531698 -150.142702) (xy 89.526784 -150.153295) (xy 89.526116 -150.176611)
			(xy 89.535744 -150.197857) (xy 89.544398 -150.205694) (xy 89.553288 -150.21306) (xy 89.560798 -150.218674)
			(xy 89.578584 -150.224554) (xy 89.597295 -150.223647) (xy 89.614429 -150.216072) (xy 89.62136 -150.209758)
			(xy 89.745566 -150.085298) (xy 89.750929 -150.078835) (xy 89.757554 -150.063414) (xy 89.75852 -150.055072)
			(xy 89.75852 -140.96238) (xy 89.758991 -140.94238) (xy 89.766755 -140.903143) (xy 89.782019 -140.866172)
			(xy 89.804198 -140.832886) (xy 89.817956 -140.818362) (xy 92.678504 -137.957814) (xy 92.685329 -137.95045)
			(xy 92.693067 -137.93194) (xy 92.69311 -137.911878) (xy 92.68968 -137.902442) (xy 92.683584 -137.888218)
			(xy 92.658438 -137.8712) (xy 90.572336 -137.8712) (xy 90.562773 -137.87156) (xy 90.544952 -137.878494)
			(xy 90.530918 -137.891483) (xy 90.526362 -137.899902) (xy 90.480388 -137.995914) (xy 90.48369 -138.02487)
			(xy 90.493088 -138.0363) (xy 90.508885 -138.056706) (xy 90.535427 -138.100962) (xy 90.55577 -138.148389)
			(xy 90.569543 -138.198122) (xy 90.576495 -138.249257) (xy 90.576908 -138.27506) (xy 90.576447 -138.302315)
			(xy 90.568695 -138.35627) (xy 90.553342 -138.408573) (xy 90.530702 -138.458158) (xy 90.501235 -138.504016)
			(xy 90.465542 -138.545213) (xy 90.424348 -138.580911) (xy 90.378493 -138.610383) (xy 90.32891 -138.633028)
			(xy 90.276609 -138.648387) (xy 90.222655 -138.656145) (xy 90.1954 -138.656568) (xy 90.166705 -138.656043)
			(xy 90.109965 -138.647436) (xy 90.055153 -138.630431) (xy 90.003504 -138.60541) (xy 89.956184 -138.572939)
			(xy 89.914259 -138.533749) (xy 89.878674 -138.488724) (xy 89.850231 -138.438879) (xy 89.829572 -138.385336)
			(xy 89.817162 -138.329305) (xy 89.814654 -138.300714) (xy 89.813638 -138.285474) (xy 89.796112 -138.261852)
			(xy 89.695274 -138.224006) (xy 89.68604 -138.221001) (xy 89.666644 -138.22145) (xy 89.648818 -138.229107)
			(xy 89.64168 -138.23569) (xy 88.5317 -139.345416) (xy 88.524925 -139.352841) (xy 88.517337 -139.371438)
			(xy 88.516968 -139.381484) (xy 88.516968 -139.80541) (xy 88.81186 -139.80541) (xy 88.815931 -139.749788)
			(xy 88.828057 -139.695351) (xy 88.84798 -139.64326) (xy 88.875276 -139.594625) (xy 88.909362 -139.550482)
			(xy 88.949511 -139.511773) (xy 88.994869 -139.479322) (xy 89.044469 -139.453821) (xy 89.097253 -139.435814)
			(xy 89.152096 -139.425684) (xy 89.20783 -139.423647) (xy 89.263267 -139.429747) (xy 89.317224 -139.443853)
			(xy 89.368553 -139.465665) (xy 89.416159 -139.494719) (xy 89.459027 -139.530394) (xy 89.496244 -139.571931)
			(xy 89.527017 -139.618444) (xy 89.550689 -139.668941) (xy 89.566757 -139.722348) (xy 89.574877 -139.777524)
			(xy 89.575386 -139.80541) (xy 89.574877 -139.833296) (xy 89.566757 -139.888472) (xy 89.550689 -139.941879)
			(xy 89.527017 -139.992376) (xy 89.496244 -140.038889) (xy 89.459027 -140.080426) (xy 89.416159 -140.116101)
			(xy 89.368553 -140.145155) (xy 89.317224 -140.166967) (xy 89.263267 -140.181073) (xy 89.20783 -140.187173)
			(xy 89.152096 -140.185136) (xy 89.097253 -140.175006) (xy 89.044469 -140.156999) (xy 88.994869 -140.131498)
			(xy 88.949511 -140.099047) (xy 88.909362 -140.060338) (xy 88.875276 -140.016195) (xy 88.84798 -139.96756)
			(xy 88.828057 -139.915469) (xy 88.815931 -139.861032) (xy 88.81186 -139.80541) (xy 88.516968 -139.80541)
			(xy 88.516968 -140.943584) (xy 88.776554 -140.943584) (xy 88.780625 -140.887962) (xy 88.792751 -140.833525)
			(xy 88.812674 -140.781434) (xy 88.83997 -140.732799) (xy 88.874056 -140.688656) (xy 88.914205 -140.649947)
			(xy 88.959563 -140.617496) (xy 89.009163 -140.591995) (xy 89.061947 -140.573988) (xy 89.11679 -140.563858)
			(xy 89.172524 -140.561821) (xy 89.227961 -140.567921) (xy 89.281918 -140.582027) (xy 89.333247 -140.603839)
			(xy 89.380853 -140.632893) (xy 89.423721 -140.668568) (xy 89.460938 -140.710105) (xy 89.491711 -140.756618)
			(xy 89.515383 -140.807115) (xy 89.531451 -140.860522) (xy 89.539571 -140.915698) (xy 89.54008 -140.943584)
			(xy 89.539571 -140.97147) (xy 89.531451 -141.026646) (xy 89.515383 -141.080053) (xy 89.491711 -141.13055)
			(xy 89.460938 -141.177063) (xy 89.423721 -141.2186) (xy 89.380853 -141.254275) (xy 89.333247 -141.283329)
			(xy 89.281918 -141.305141) (xy 89.227961 -141.319247) (xy 89.172524 -141.325347) (xy 89.11679 -141.32331)
			(xy 89.061947 -141.31318) (xy 89.009163 -141.295173) (xy 88.959563 -141.269672) (xy 88.914205 -141.237221)
			(xy 88.874056 -141.198512) (xy 88.83997 -141.154369) (xy 88.812674 -141.105734) (xy 88.792751 -141.053643)
			(xy 88.780625 -140.999206) (xy 88.776554 -140.943584) (xy 88.516968 -140.943584) (xy 88.516968 -141.198346)
			(xy 88.516513 -141.218364) (xy 88.508704 -141.257631) (xy 88.493376 -141.294616) (xy 88.471119 -141.327895)
			(xy 88.457278 -141.342364) (xy 87.946992 -141.85265) (xy 87.932493 -141.866453) (xy 87.899213 -141.888693)
			(xy 87.862239 -141.904022) (xy 87.822987 -141.911854) (xy 87.802974 -141.91234) (xy 85.449664 -141.91234)
			(xy 85.439631 -141.912776) (xy 85.421055 -141.92035) (xy 85.413596 -141.927072) (xy 83.986116 -143.354552)
			(xy 87.380316 -143.354552) (xy 87.384387 -143.29893) (xy 87.396513 -143.244493) (xy 87.416436 -143.192402)
			(xy 87.443732 -143.143767) (xy 87.477818 -143.099624) (xy 87.517967 -143.060915) (xy 87.563325 -143.028464)
			(xy 87.612925 -143.002963) (xy 87.665709 -142.984956) (xy 87.720552 -142.974826) (xy 87.776286 -142.972789)
			(xy 87.831723 -142.978889) (xy 87.88568 -142.992995) (xy 87.937009 -143.014807) (xy 87.984615 -143.043861)
			(xy 88.027483 -143.079536) (xy 88.0647 -143.121073) (xy 88.095473 -143.167586) (xy 88.119145 -143.218083)
			(xy 88.135213 -143.27149) (xy 88.143333 -143.326666) (xy 88.143842 -143.354552) (xy 88.143513 -143.372586)
			(xy 88.36533 -143.372586) (xy 88.365816 -143.345335) (xy 88.373572 -143.291387) (xy 88.388927 -143.239092)
			(xy 88.411569 -143.189515) (xy 88.441035 -143.143665) (xy 88.476726 -143.102474) (xy 88.517917 -143.066783)
			(xy 88.563767 -143.037317) (xy 88.613344 -143.014675) (xy 88.665639 -142.99932) (xy 88.719587 -142.991564)
			(xy 88.774089 -142.991564) (xy 88.828037 -142.99932) (xy 88.880332 -143.014675) (xy 88.929909 -143.037317)
			(xy 88.975759 -143.066783) (xy 89.01695 -143.102474) (xy 89.052641 -143.143665) (xy 89.082107 -143.189515)
			(xy 89.104749 -143.239092) (xy 89.120104 -143.291387) (xy 89.12786 -143.345335) (xy 89.128346 -143.372586)
			(xy 89.127829 -143.40195) (xy 89.118904 -143.459996) (xy 89.110566 -143.488156) (xy 89.106877 -143.501104)
			(xy 89.105692 -143.527992) (xy 89.111581 -143.554253) (xy 89.124133 -143.578061) (xy 89.142474 -143.597757)
			(xy 89.165329 -143.61197) (xy 89.191105 -143.619711) (xy 89.204546 -143.62049) (xy 89.231285 -143.621742)
			(xy 89.28406 -143.630677) (xy 89.335067 -143.646906) (xy 89.383303 -143.670109) (xy 89.42782 -143.69983)
			(xy 89.467742 -143.735484) (xy 89.502285 -143.776372) (xy 89.53077 -143.82169) (xy 89.552638 -143.870546)
			(xy 89.567457 -143.92198) (xy 89.574937 -143.974981) (xy 89.575386 -144.001744) (xy 89.5749 -144.028995)
			(xy 89.567144 -144.082943) (xy 89.551789 -144.135238) (xy 89.529147 -144.184815) (xy 89.499681 -144.230665)
			(xy 89.46399 -144.271856) (xy 89.422799 -144.307547) (xy 89.376949 -144.337013) (xy 89.327372 -144.359655)
			(xy 89.275077 -144.37501) (xy 89.221129 -144.382766) (xy 89.166627 -144.382766) (xy 89.112679 -144.37501)
			(xy 89.060384 -144.359655) (xy 89.010807 -144.337013) (xy 88.964957 -144.307547) (xy 88.923766 -144.271856)
			(xy 88.888075 -144.230665) (xy 88.858609 -144.184815) (xy 88.835967 -144.135238) (xy 88.820612 -144.082943)
			(xy 88.812856 -144.028995) (xy 88.81237 -144.001744) (xy 88.812875 -143.972379) (xy 88.821808 -143.914334)
			(xy 88.83015 -143.886174) (xy 88.833789 -143.873214) (xy 88.83498 -143.846333) (xy 88.829098 -143.820077)
			(xy 88.816555 -143.796273) (xy 88.798221 -143.776579) (xy 88.775375 -143.762365) (xy 88.749607 -143.754621)
			(xy 88.73617 -143.75384) (xy 88.709422 -143.752733) (xy 88.656639 -143.743785) (xy 88.605625 -143.727542)
			(xy 88.557385 -143.704324) (xy 88.512866 -143.674588) (xy 88.472943 -143.638918) (xy 88.438402 -143.598015)
			(xy 88.40992 -143.552684) (xy 88.388058 -143.503814) (xy 88.373246 -143.452367) (xy 88.365774 -143.399354)
			(xy 88.36533 -143.372586) (xy 88.143513 -143.372586) (xy 88.143333 -143.382438) (xy 88.135213 -143.437614)
			(xy 88.119145 -143.491021) (xy 88.095473 -143.541518) (xy 88.0647 -143.588031) (xy 88.027483 -143.629568)
			(xy 87.984615 -143.665243) (xy 87.937009 -143.694297) (xy 87.88568 -143.716109) (xy 87.831723 -143.730215)
			(xy 87.776286 -143.736315) (xy 87.720552 -143.734278) (xy 87.665709 -143.724148) (xy 87.612925 -143.706141)
			(xy 87.563325 -143.68064) (xy 87.517967 -143.648189) (xy 87.477818 -143.60948) (xy 87.443732 -143.565337)
			(xy 87.416436 -143.516702) (xy 87.396513 -143.464611) (xy 87.384387 -143.410174) (xy 87.380316 -143.354552)
			(xy 83.986116 -143.354552) (xy 83.777074 -143.563594) (xy 83.770218 -143.570988) (xy 83.76247 -143.589587)
			(xy 83.762088 -143.599662) (xy 83.762088 -144.874488) (xy 83.761832 -144.88541) (xy 88.81186 -144.88541)
			(xy 88.815931 -144.829788) (xy 88.828057 -144.775351) (xy 88.84798 -144.72326) (xy 88.875276 -144.674625)
			(xy 88.909362 -144.630482) (xy 88.949511 -144.591773) (xy 88.994869 -144.559322) (xy 89.044469 -144.533821)
			(xy 89.097253 -144.515814) (xy 89.152096 -144.505684) (xy 89.20783 -144.503647) (xy 89.263267 -144.509747)
			(xy 89.317224 -144.523853) (xy 89.368553 -144.545665) (xy 89.416159 -144.574719) (xy 89.459027 -144.610394)
			(xy 89.496244 -144.651931) (xy 89.527017 -144.698444) (xy 89.550689 -144.748941) (xy 89.566757 -144.802348)
			(xy 89.574877 -144.857524) (xy 89.575386 -144.88541) (xy 89.574877 -144.913296) (xy 89.566757 -144.968472)
			(xy 89.550689 -145.021879) (xy 89.527017 -145.072376) (xy 89.496244 -145.118889) (xy 89.459027 -145.160426)
			(xy 89.416159 -145.196101) (xy 89.368553 -145.225155) (xy 89.317224 -145.246967) (xy 89.263267 -145.261073)
			(xy 89.20783 -145.267173) (xy 89.152096 -145.265136) (xy 89.097253 -145.255006) (xy 89.044469 -145.236999)
			(xy 88.994869 -145.211498) (xy 88.949511 -145.179047) (xy 88.909362 -145.140338) (xy 88.875276 -145.096195)
			(xy 88.84798 -145.04756) (xy 88.828057 -144.995469) (xy 88.815931 -144.941032) (xy 88.81186 -144.88541)
			(xy 83.761832 -144.88541) (xy 83.76162 -144.894489) (xy 83.753862 -144.93373) (xy 83.738602 -144.970706)
			(xy 83.716426 -145.003997) (xy 83.702652 -145.018506) (xy 82.798076 -145.923) (xy 85.577172 -145.923)
			(xy 85.577678 -145.89575) (xy 85.585434 -145.841804) (xy 85.600788 -145.789511) (xy 85.623428 -145.739935)
			(xy 85.652892 -145.694085) (xy 85.688581 -145.652895) (xy 85.729769 -145.617204) (xy 85.775617 -145.587737)
			(xy 85.825192 -145.565095) (xy 85.877484 -145.549738) (xy 85.93143 -145.541979) (xy 85.95868 -145.541492)
			(xy 85.987972 -145.542003) (xy 86.045868 -145.550951) (xy 86.101717 -145.568638) (xy 86.154208 -145.594651)
			(xy 86.202109 -145.628378) (xy 86.244295 -145.669028) (xy 86.279774 -145.715645) (xy 86.294214 -145.741136)
			(xy 86.295983 -145.744384) (xy 86.30032 -145.750375) (xy 86.30285 -145.753074) (xy 86.317328 -145.767552)
			(xy 86.324762 -145.774268) (xy 86.343262 -145.781904) (xy 86.363276 -145.781904) (xy 86.381776 -145.774268)
			(xy 86.38921 -145.767552) (xy 86.395306 -145.76171) (xy 86.398862 -145.75409) (xy 86.410976 -145.73048)
			(xy 86.440853 -145.686623) (xy 86.476518 -145.647327) (xy 86.517281 -145.61335) (xy 86.562359 -145.585348)
			(xy 86.610881 -145.563859) (xy 86.661911 -145.549299) (xy 86.714466 -145.541948) (xy 86.741 -145.541492)
			(xy 86.770292 -145.541987) (xy 86.828189 -145.550938) (xy 86.884039 -145.568628) (xy 86.93653 -145.594644)
			(xy 86.98443 -145.628373) (xy 87.026615 -145.669025) (xy 87.062095 -145.715644) (xy 87.076534 -145.741136)
			(xy 87.078301 -145.744386) (xy 87.08264 -145.750376) (xy 87.08517 -145.753074) (xy 87.760048 -146.427952)
			(xy 87.7799 -146.448514) (xy 87.813528 -146.494728) (xy 87.83951 -146.545634) (xy 87.857206 -146.599979)
			(xy 87.866181 -146.656424) (xy 87.866728 -146.685) (xy 87.866728 -147.447) (xy 87.866154 -147.475573)
			(xy 87.857161 -147.532007) (xy 87.839457 -147.586341) (xy 87.813479 -147.637242) (xy 87.779865 -147.683456)
			(xy 87.760048 -147.704048) (xy 87.333836 -148.13026) (xy 87.330534 -148.136864) (xy 87.316102 -148.162358)
			(xy 87.280616 -148.208968) (xy 87.238426 -148.249611) (xy 87.190524 -148.283332) (xy 87.138033 -148.309341)
			(xy 87.082185 -148.327027) (xy 87.024291 -148.335975) (xy 86.995 -148.336508) (xy 86.967749 -148.336022)
			(xy 86.913801 -148.328266) (xy 86.861506 -148.312911) (xy 86.811929 -148.290269) (xy 86.766079 -148.260803)
			(xy 86.724888 -148.225112) (xy 86.689197 -148.183921) (xy 86.659731 -148.138071) (xy 86.637089 -148.088494)
			(xy 86.621734 -148.036199) (xy 86.613978 -147.982251) (xy 86.613492 -147.955) (xy 86.613987 -147.925708)
			(xy 86.622938 -147.867811) (xy 86.640628 -147.811961) (xy 86.666644 -147.75947) (xy 86.700373 -147.71157)
			(xy 86.741025 -147.669385) (xy 86.787644 -147.633905) (xy 86.813136 -147.619466) (xy 86.81974 -147.616164)
			(xy 86.954868 -147.480782) (xy 86.961036 -147.474178) (xy 86.968609 -147.457783) (xy 86.969973 -147.439776)
			(xy 86.967822 -147.430998) (xy 86.940136 -147.332446) (xy 86.92007 -147.313396) (xy 86.906608 -147.310094)
			(xy 86.881478 -147.303669) (xy 86.833104 -147.284954) (xy 86.787716 -147.259849) (xy 86.746154 -147.228818)
			(xy 86.709186 -147.192435) (xy 86.692994 -147.172172) (xy 86.688676 -147.167346) (xy 85.788754 -146.26717)
			(xy 85.786061 -146.264634) (xy 85.780068 -146.260297) (xy 85.776816 -146.258534) (xy 85.751317 -146.24411)
			(xy 85.704708 -146.208622) (xy 85.664067 -146.16643) (xy 85.630346 -146.118526) (xy 85.604338 -146.066034)
			(xy 85.586653 -146.010186) (xy 85.577705 -145.952291) (xy 85.577172 -145.923) (xy 82.798076 -145.923)
			(xy 80.896968 -147.823936) (xy 80.890199 -147.831364) (xy 80.882624 -147.84996) (xy 80.882236 -147.860004)
			(xy 80.882236 -148.94941) (xy 88.81186 -148.94941) (xy 88.815931 -148.893788) (xy 88.828057 -148.839351)
			(xy 88.84798 -148.78726) (xy 88.875276 -148.738625) (xy 88.909362 -148.694482) (xy 88.949511 -148.655773)
			(xy 88.994869 -148.623322) (xy 89.044469 -148.597821) (xy 89.097253 -148.579814) (xy 89.152096 -148.569684)
			(xy 89.20783 -148.567647) (xy 89.263267 -148.573747) (xy 89.317224 -148.587853) (xy 89.368553 -148.609665)
			(xy 89.416159 -148.638719) (xy 89.459027 -148.674394) (xy 89.496244 -148.715931) (xy 89.527017 -148.762444)
			(xy 89.550689 -148.812941) (xy 89.566757 -148.866348) (xy 89.574877 -148.921524) (xy 89.575386 -148.94941)
			(xy 89.574877 -148.977296) (xy 89.566757 -149.032472) (xy 89.550689 -149.085879) (xy 89.527017 -149.136376)
			(xy 89.496244 -149.182889) (xy 89.459027 -149.224426) (xy 89.416159 -149.260101) (xy 89.368553 -149.289155)
			(xy 89.317224 -149.310967) (xy 89.263267 -149.325073) (xy 89.20783 -149.331173) (xy 89.152096 -149.329136)
			(xy 89.097253 -149.319006) (xy 89.044469 -149.300999) (xy 88.994869 -149.275498) (xy 88.949511 -149.243047)
			(xy 88.909362 -149.204338) (xy 88.875276 -149.160195) (xy 88.84798 -149.11156) (xy 88.828057 -149.059469)
			(xy 88.815931 -149.005032) (xy 88.81186 -148.94941) (xy 80.882236 -148.94941) (xy 80.882236 -153.968958)
			(xy 80.88178 -153.988975) (xy 80.873968 -154.02824) (xy 80.858636 -154.065222) (xy 80.836376 -154.098497)
			(xy 80.822546 -154.112976) (xy 77.911452 -157.02407) (xy 77.896954 -157.037875) (xy 77.863676 -157.060116)
			(xy 77.8267 -157.075444) (xy 77.787447 -157.083272) (xy 77.767434 -157.08376) (xy 72.013318 -157.08376)
			(xy 72.003289 -157.084205) (xy 71.984727 -157.091793) (xy 71.97725 -157.098492) (xy 65.532254 -163.543488)
			(xy 65.5254 -163.550883) (xy 65.517652 -163.569482) (xy 65.517268 -163.579556) (xy 65.517268 -164.074348)
			(xy 65.517699 -164.084415) (xy 65.525422 -164.10301) (xy 65.532254 -164.110416) (xy 65.628266 -164.206428)
			(xy 65.651126 -164.213794) (xy 65.663318 -164.211762) (xy 65.678081 -164.2096) (xy 65.707834 -164.207313)
			(xy 65.722754 -164.20719) (xy 65.750009 -164.20765) (xy 65.803965 -164.215402) (xy 65.856269 -164.230754)
			(xy 65.905855 -164.253394) (xy 65.951714 -164.28286) (xy 65.992912 -164.318554) (xy 66.028611 -164.359748)
			(xy 66.058083 -164.405603) (xy 66.080729 -164.455186) (xy 66.096088 -164.507488) (xy 66.103846 -164.561443)
			(xy 66.104262 -164.588698) (xy 66.103611 -164.620261) (xy 66.093224 -164.682528) (xy 66.072732 -164.742236)
			(xy 66.058288 -164.770308) (xy 66.053462 -164.779198) (xy 66.05143 -164.798756) (xy 66.077084 -164.886894)
			(xy 66.08953 -164.902388) (xy 66.09842 -164.907468) (xy 66.105786 -164.911532) (xy 66.115438 -164.917374)
			(xy 66.137536 -164.919406) (xy 66.232024 -164.885878) (xy 66.248026 -164.870384) (xy 66.25209 -164.85997)
			(xy 66.262781 -164.833189) (xy 66.291063 -164.78294) (xy 66.32659 -164.737522) (xy 66.368551 -164.697973)
			(xy 66.41599 -164.665193) (xy 66.467824 -164.639931) (xy 66.52287 -164.622763) (xy 66.579875 -164.614081)
			(xy 66.608706 -164.61359) (xy 66.635957 -164.614076) (xy 66.689904 -164.621833) (xy 66.742199 -164.637189)
			(xy 66.791776 -164.659831) (xy 66.837625 -164.689297) (xy 66.878815 -164.724989) (xy 66.914506 -164.766179)
			(xy 66.943972 -164.81203) (xy 66.966613 -164.861607) (xy 66.981968 -164.913901) (xy 66.989724 -164.967849)
			(xy 66.989724 -165.022351) (xy 66.981968 -165.076299) (xy 66.972622 -165.108128) (xy 67.231514 -165.108128)
			(xy 67.232013 -165.080654) (xy 67.239902 -165.026275) (xy 67.255519 -164.973592) (xy 67.27854 -164.923699)
			(xy 67.30849 -164.87763) (xy 67.326256 -164.856668) (xy 67.332352 -164.849556) (xy 67.338702 -164.832538)
			(xy 67.338702 -164.746686) (xy 67.332352 -164.729668) (xy 67.326256 -164.722556) (xy 67.308484 -164.701601)
			(xy 67.278561 -164.655517) (xy 67.255551 -164.60562) (xy 67.239927 -164.552942) (xy 67.232012 -164.498569)
			(xy 67.231514 -164.471096) (xy 67.232 -164.443845) (xy 67.239756 -164.389897) (xy 67.255111 -164.337602)
			(xy 67.277753 -164.288025) (xy 67.307219 -164.242175) (xy 67.34291 -164.200984) (xy 67.384101 -164.165293)
			(xy 67.429951 -164.135827) (xy 67.479528 -164.113185) (xy 67.531823 -164.09783) (xy 67.585771 -164.090074)
			(xy 67.640273 -164.090074) (xy 67.694221 -164.09783) (xy 67.746516 -164.113185) (xy 67.796093 -164.135827)
			(xy 67.841943 -164.165293) (xy 67.883134 -164.200984) (xy 67.918825 -164.242175) (xy 67.948291 -164.288025)
			(xy 67.970933 -164.337602) (xy 67.986288 -164.389897) (xy 67.994044 -164.443845) (xy 67.99453 -164.471096)
			(xy 67.994034 -164.49857) (xy 67.986143 -164.552949) (xy 67.970525 -164.605631) (xy 67.947503 -164.655524)
			(xy 67.917554 -164.701593) (xy 67.899788 -164.722556) (xy 67.893692 -164.729668) (xy 67.887342 -164.746686)
			(xy 67.887342 -164.832538) (xy 67.893692 -164.849556) (xy 67.899788 -164.856668) (xy 67.917516 -164.877659)
			(xy 67.947447 -164.923733) (xy 67.970467 -164.97362) (xy 67.986101 -165.02629) (xy 67.994026 -165.080658)
			(xy 67.99453 -165.108128) (xy 67.994044 -165.135379) (xy 67.992411 -165.146736) (xy 68.56933 -165.146736)
			(xy 68.573401 -165.091114) (xy 68.585527 -165.036677) (xy 68.60545 -164.984586) (xy 68.632746 -164.935951)
			(xy 68.666832 -164.891808) (xy 68.706981 -164.853099) (xy 68.752339 -164.820648) (xy 68.801939 -164.795147)
			(xy 68.854723 -164.77714) (xy 68.909566 -164.76701) (xy 68.9653 -164.764973) (xy 69.020737 -164.771073)
			(xy 69.074694 -164.785179) (xy 69.126023 -164.806991) (xy 69.173629 -164.836045) (xy 69.216497 -164.87172)
			(xy 69.253714 -164.913257) (xy 69.284487 -164.95977) (xy 69.308159 -165.010267) (xy 69.324227 -165.063674)
			(xy 69.332347 -165.11885) (xy 69.332856 -165.146736) (xy 69.332347 -165.174622) (xy 69.324227 -165.229798)
			(xy 69.308159 -165.283205) (xy 69.284487 -165.333702) (xy 69.253714 -165.380215) (xy 69.216497 -165.421752)
			(xy 69.173629 -165.457427) (xy 69.126023 -165.486481) (xy 69.074694 -165.508293) (xy 69.020737 -165.522399)
			(xy 68.9653 -165.528499) (xy 68.909566 -165.526462) (xy 68.854723 -165.516332) (xy 68.801939 -165.498325)
			(xy 68.752339 -165.472824) (xy 68.706981 -165.440373) (xy 68.666832 -165.401664) (xy 68.632746 -165.357521)
			(xy 68.60545 -165.308886) (xy 68.585527 -165.256795) (xy 68.573401 -165.202358) (xy 68.56933 -165.146736)
			(xy 67.992411 -165.146736) (xy 67.986288 -165.189327) (xy 67.970933 -165.241622) (xy 67.948291 -165.291199)
			(xy 67.918825 -165.337049) (xy 67.883134 -165.37824) (xy 67.841943 -165.413931) (xy 67.796093 -165.443397)
			(xy 67.746516 -165.466039) (xy 67.694221 -165.481394) (xy 67.640273 -165.48915) (xy 67.585771 -165.48915)
			(xy 67.531823 -165.481394) (xy 67.479528 -165.466039) (xy 67.429951 -165.443397) (xy 67.384101 -165.413931)
			(xy 67.34291 -165.37824) (xy 67.307219 -165.337049) (xy 67.277753 -165.291199) (xy 67.255111 -165.241622)
			(xy 67.239756 -165.189327) (xy 67.232 -165.135379) (xy 67.231514 -165.108128) (xy 66.972622 -165.108128)
			(xy 66.966613 -165.128593) (xy 66.943972 -165.17817) (xy 66.914506 -165.224021) (xy 66.878815 -165.265211)
			(xy 66.837625 -165.300903) (xy 66.791776 -165.330369) (xy 66.742199 -165.353011) (xy 66.689904 -165.368367)
			(xy 66.635957 -165.376124) (xy 66.608706 -165.376606) (xy 66.583473 -165.376195) (xy 66.533447 -165.369545)
			(xy 66.484731 -165.356372) (xy 66.43817 -165.336906) (xy 66.416174 -165.324536) (xy 66.406522 -165.318694)
			(xy 66.384424 -165.316662) (xy 66.289936 -165.35019) (xy 66.273934 -165.365684) (xy 66.26987 -165.376098)
			(xy 66.25918 -165.402879) (xy 66.230899 -165.453129) (xy 66.195373 -165.498546) (xy 66.153411 -165.538095)
			(xy 66.105972 -165.570873) (xy 66.054137 -165.596132) (xy 65.99909 -165.613296) (xy 65.942085 -165.621973)
			(xy 65.913254 -165.622478) (xy 65.886006 -165.621989) (xy 65.832065 -165.614227) (xy 65.779777 -165.598867)
			(xy 65.730208 -165.576223) (xy 65.684365 -165.546755) (xy 65.643183 -165.511063) (xy 65.607499 -165.469874)
			(xy 65.578041 -165.424026) (xy 65.555406 -165.374452) (xy 65.540057 -165.322161) (xy 65.532306 -165.268218)
			(xy 65.531746 -165.24097) (xy 65.5324 -165.209407) (xy 65.542792 -165.147143) (xy 65.563288 -165.087438)
			(xy 65.57772 -165.05936) (xy 65.582546 -165.05047) (xy 65.584578 -165.030912) (xy 65.558924 -164.942774)
			(xy 65.546478 -164.92728) (xy 65.537588 -164.9222) (xy 65.512496 -164.907643) (xy 65.466635 -164.872125)
			(xy 65.426677 -164.830075) (xy 65.393543 -164.782462) (xy 65.367997 -164.730383) (xy 65.350627 -164.675038)
			(xy 65.341834 -164.617701) (xy 65.341246 -164.588698) (xy 65.34137 -164.573778) (xy 65.343658 -164.544025)
			(xy 65.345818 -164.529262) (xy 65.34785 -164.51707) (xy 65.340484 -164.49421) (xy 65.169796 -164.323776)
			(xy 65.155988 -164.309294) (xy 65.133798 -164.276003) (xy 65.118543 -164.239017) (xy 65.110809 -164.199763)
			(xy 65.11036 -164.179758) (xy 65.11036 -163.474146) (xy 65.110825 -163.454143) (xy 65.118575 -163.414897)
			(xy 65.133828 -163.377915) (xy 65.155997 -163.344615) (xy 65.169796 -163.330128) (xy 71.76389 -156.736034)
			(xy 71.778389 -156.722232) (xy 71.811669 -156.699997) (xy 71.848644 -156.684676) (xy 71.887896 -156.676856)
			(xy 71.907908 -156.676344) (xy 77.662024 -156.676344) (xy 77.672049 -156.675892) (xy 77.690601 -156.668293)
			(xy 77.698092 -156.661612) (xy 80.460088 -153.899616) (xy 80.466869 -153.892193) (xy 80.474471 -153.873596)
			(xy 80.47482 -153.863548) (xy 80.47482 -147.754594) (xy 80.475271 -147.734574) (xy 80.483073 -147.695303)
			(xy 80.498395 -147.658312) (xy 80.520648 -147.625026) (xy 80.53451 -147.610576) (xy 83.340194 -144.805146)
			(xy 83.347033 -144.797745) (xy 83.354748 -144.779147) (xy 83.35518 -144.769078) (xy 83.35518 -143.494252)
			(xy 83.355644 -143.474249) (xy 83.363395 -143.435003) (xy 83.378647 -143.398021) (xy 83.400817 -143.364722)
			(xy 83.414616 -143.350234) (xy 85.200236 -141.564614) (xy 85.214734 -141.550809) (xy 85.248012 -141.528567)
			(xy 85.284987 -141.513238) (xy 85.324241 -141.505409) (xy 85.344254 -141.504924) (xy 87.697564 -141.504924)
			(xy 87.707596 -141.504485) (xy 87.726171 -141.49691) (xy 87.733632 -141.490192) (xy 88.09482 -141.129004)
			(xy 88.101596 -141.121579) (xy 88.109188 -141.102982) (xy 88.109552 -141.092936) (xy 88.109552 -139.276074)
			(xy 88.110005 -139.256055) (xy 88.117811 -139.216787) (xy 88.133138 -139.1798) (xy 88.155394 -139.146519)
			(xy 88.169242 -139.132056) (xy 89.108534 -138.193018) (xy 89.11535 -138.185697) (xy 89.123094 -138.167272)
			(xy 89.123165 -138.147285) (xy 89.11971 -138.1379) (xy 89.078816 -138.037062) (xy 89.05367 -138.01979)
			(xy 89.038176 -138.019536) (xy 89.01168 -138.018696) (xy 88.959294 -138.010591) (xy 88.908535 -137.995304)
			(xy 88.860385 -137.973132) (xy 88.815771 -137.944502) (xy 88.775555 -137.909966) (xy 88.740512 -137.870191)
			(xy 88.725502 -137.84834) (xy 88.717982 -137.838159) (xy 88.695723 -137.826179) (xy 88.683084 -137.82548)
			(xy 87.532464 -137.82548) (xy 87.52246 -137.825974) (xy 87.503977 -137.833639) (xy 87.48983 -137.84779)
			(xy 87.482171 -137.866275) (xy 87.481664 -137.87628) (xy 87.481664 -139.931902) (xy 87.481093 -139.96187)
			(xy 87.471753 -140.021072) (xy 87.453271 -140.078086) (xy 87.426102 -140.131509) (xy 87.390915 -140.180028)
			(xy 87.370158 -140.20165) (xy 86.854538 -140.71727) (xy 86.832943 -140.738063) (xy 86.784432 -140.773278)
			(xy 86.731005 -140.800462) (xy 86.673979 -140.818944) (xy 86.614763 -140.828267) (xy 86.58479 -140.828776)
			(xy 84.996274 -140.828776) (xy 84.987856 -140.829676) (xy 84.972285 -140.836295) (xy 84.965794 -140.84173)
			(xy 82.854546 -142.952978) (xy 82.849162 -142.959499) (xy 82.842564 -142.975056) (xy 82.841592 -142.983458)
			(xy 82.841592 -143.785844) (xy 82.841106 -143.813077) (xy 82.833355 -143.866989) (xy 82.81801 -143.919249)
			(xy 82.795384 -143.968793) (xy 82.765937 -144.014613) (xy 82.73027 -144.055776) (xy 82.689107 -144.091443)
			(xy 82.643287 -144.12089) (xy 82.593743 -144.143516) (xy 82.541483 -144.158861) (xy 82.487571 -144.166612)
			(xy 82.433105 -144.166612) (xy 82.379193 -144.158861) (xy 82.326933 -144.143516) (xy 82.277389 -144.12089)
			(xy 82.231569 -144.091443) (xy 82.190406 -144.055776) (xy 82.154739 -144.014613) (xy 82.125292 -143.968793)
			(xy 82.102666 -143.919249) (xy 82.087321 -143.866989) (xy 82.07957 -143.813077) (xy 82.079084 -143.785844)
			(xy 82.079084 -142.807944) (xy 82.079659 -142.777978) (xy 82.089008 -142.718781) (xy 82.107498 -142.661774)
			(xy 82.134673 -142.608359) (xy 82.169867 -142.55985) (xy 82.19059 -142.538196) (xy 84.551012 -140.177774)
			(xy 84.572609 -140.156987) (xy 84.621123 -140.121783) (xy 84.674552 -140.09461) (xy 84.731576 -140.076139)
			(xy 84.790789 -140.066824) (xy 84.82076 -140.066268) (xy 86.409276 -140.066268) (xy 86.417696 -140.065374)
			(xy 86.433273 -140.058761) (xy 86.439756 -140.053314) (xy 86.706202 -139.786868) (xy 86.711597 -139.780351)
			(xy 86.718216 -139.764795) (xy 86.719156 -139.756388) (xy 86.719156 -137.872724) (xy 86.718037 -137.863214)
			(xy 86.709734 -137.845975) (xy 86.69572 -137.832947) (xy 86.677922 -137.82592) (xy 86.668356 -137.82548)
			(xy 83.240372 -137.82548) (xy 83.230406 -137.825959) (xy 83.21197 -137.833534) (xy 83.204558 -137.840212)
			(xy 83.146392 -137.898124) (xy 83.138772 -137.916412) (xy 83.138772 -137.926572) (xy 83.138183 -137.953752)
			(xy 83.13025 -138.007535) (xy 83.114764 -138.059647) (xy 83.092036 -138.109033) (xy 83.062528 -138.154692)
			(xy 83.026838 -138.195701) (xy 82.985687 -138.231227) (xy 82.93991 -138.260553) (xy 82.890434 -138.283082)
			(xy 82.83826 -138.298361) (xy 82.784446 -138.306078) (xy 82.730082 -138.306078) (xy 82.676268 -138.298361)
			(xy 82.624094 -138.283082) (xy 82.574618 -138.260553) (xy 82.528841 -138.231227) (xy 82.48769 -138.195701)
			(xy 82.452 -138.154692) (xy 82.422492 -138.109033) (xy 82.399764 -138.059647) (xy 82.384278 -138.007535)
			(xy 82.376345 -137.953752) (xy 82.375756 -137.926572) (xy 82.375756 -137.916412) (xy 82.368136 -137.898124)
			(xy 82.30997 -137.840212) (xy 82.302559 -137.833531) (xy 82.284123 -137.825958) (xy 82.274156 -137.82548)
			(xy 73.462896 -137.82548) (xy 73.452887 -137.825968) (xy 73.434393 -137.833628) (xy 73.420237 -137.84778)
			(xy 73.412571 -137.866272) (xy 73.412096 -137.87628) (xy 73.412096 -138.611864) (xy 79.572102 -138.611864)
			(xy 79.576173 -138.556242) (xy 79.588299 -138.501805) (xy 79.608222 -138.449714) (xy 79.635518 -138.401079)
			(xy 79.669604 -138.356936) (xy 79.709753 -138.318227) (xy 79.755111 -138.285776) (xy 79.804711 -138.260275)
			(xy 79.857495 -138.242268) (xy 79.912338 -138.232138) (xy 79.968072 -138.230101) (xy 80.023509 -138.236201)
			(xy 80.077466 -138.250307) (xy 80.128795 -138.272119) (xy 80.176401 -138.301173) (xy 80.219269 -138.336848)
			(xy 80.256486 -138.378385) (xy 80.287259 -138.424898) (xy 80.310931 -138.475395) (xy 80.326999 -138.528802)
			(xy 80.335119 -138.583978) (xy 80.335628 -138.611864) (xy 80.335119 -138.63975) (xy 80.326999 -138.694926)
			(xy 80.310931 -138.748333) (xy 80.287259 -138.79883) (xy 80.256486 -138.845343) (xy 80.219269 -138.88688)
			(xy 80.176401 -138.922555) (xy 80.128795 -138.951609) (xy 80.077466 -138.973421) (xy 80.023509 -138.987527)
			(xy 79.968072 -138.993627) (xy 79.912338 -138.99159) (xy 79.857495 -138.98146) (xy 79.804711 -138.963453)
			(xy 79.755111 -138.937952) (xy 79.709753 -138.905501) (xy 79.669604 -138.866792) (xy 79.635518 -138.822649)
			(xy 79.608222 -138.774014) (xy 79.588299 -138.721923) (xy 79.576173 -138.667486) (xy 79.572102 -138.611864)
			(xy 73.412096 -138.611864) (xy 73.412096 -139.115292) (xy 73.412312 -139.121521) (xy 73.415403 -139.133593)
			(xy 73.418192 -139.139168) (xy 73.432321 -139.166972) (xy 73.452344 -139.226035) (xy 73.462511 -139.287564)
			(xy 73.46315 -139.318746) (xy 73.462661 -139.345996) (xy 73.4549 -139.399941) (xy 73.439541 -139.452233)
			(xy 73.416898 -139.501807) (xy 73.387431 -139.547655) (xy 73.35174 -139.588843) (xy 73.310551 -139.624533)
			(xy 73.264703 -139.654) (xy 73.215129 -139.676642) (xy 73.162837 -139.692) (xy 73.108892 -139.699761)
			(xy 73.081642 -139.700254) (xy 73.06056 -139.699746) (xy 73.044812 -139.69873) (xy 73.017888 -139.71524)
			(xy 72.972676 -139.816332) (xy 72.968949 -139.8259) (xy 72.968646 -139.846414) (xy 72.976399 -139.865409)
			(xy 72.983344 -139.872974) (xy 74.371962 -141.261592) (xy 81.648552 -141.261592) (xy 81.652623 -141.20597)
			(xy 81.664749 -141.151533) (xy 81.684672 -141.099442) (xy 81.711968 -141.050807) (xy 81.746054 -141.006664)
			(xy 81.786203 -140.967955) (xy 81.831561 -140.935504) (xy 81.881161 -140.910003) (xy 81.933945 -140.891996)
			(xy 81.988788 -140.881866) (xy 82.044522 -140.879829) (xy 82.099959 -140.885929) (xy 82.153916 -140.900035)
			(xy 82.205245 -140.921847) (xy 82.252851 -140.950901) (xy 82.295719 -140.986576) (xy 82.332936 -141.028113)
			(xy 82.363709 -141.074626) (xy 82.387381 -141.125123) (xy 82.403449 -141.17853) (xy 82.411569 -141.233706)
			(xy 82.412078 -141.261592) (xy 82.411569 -141.289478) (xy 82.403449 -141.344654) (xy 82.387381 -141.398061)
			(xy 82.363709 -141.448558) (xy 82.332936 -141.495071) (xy 82.295719 -141.536608) (xy 82.252851 -141.572283)
			(xy 82.205245 -141.601337) (xy 82.153916 -141.623149) (xy 82.099959 -141.637255) (xy 82.044522 -141.643355)
			(xy 81.988788 -141.641318) (xy 81.933945 -141.631188) (xy 81.881161 -141.613181) (xy 81.831561 -141.58768)
			(xy 81.786203 -141.555229) (xy 81.746054 -141.51652) (xy 81.711968 -141.472377) (xy 81.684672 -141.423742)
			(xy 81.664749 -141.371651) (xy 81.652623 -141.317214) (xy 81.648552 -141.261592) (xy 74.371962 -141.261592)
			(xy 74.97318 -141.86281) (xy 74.990225 -141.880525) (xy 75.01909 -141.920317) (xy 75.041371 -141.964136)
			(xy 75.056519 -142.010903) (xy 75.06416 -142.059464) (xy 75.06462 -142.084044) (xy 75.06462 -146.371818)
			(xy 75.064892 -146.379141) (xy 75.06902 -146.393194) (xy 75.072748 -146.399504) (xy 75.08711 -146.422674)
			(xy 75.109787 -146.472246) (xy 75.125174 -146.524542) (xy 75.132958 -146.578496) (xy 75.133454 -146.605752)
			(xy 75.132968 -146.633003) (xy 75.125212 -146.686951) (xy 75.109857 -146.739246) (xy 75.087215 -146.788823)
			(xy 75.057749 -146.834673) (xy 75.022058 -146.875864) (xy 74.980867 -146.911555) (xy 74.935017 -146.941021)
			(xy 74.88544 -146.963663) (xy 74.833145 -146.979018) (xy 74.779197 -146.986774) (xy 74.724695 -146.986774)
			(xy 74.670747 -146.979018) (xy 74.618452 -146.963663) (xy 74.568875 -146.941021) (xy 74.523025 -146.911555)
			(xy 74.481834 -146.875864) (xy 74.446143 -146.834673) (xy 74.416677 -146.788823) (xy 74.394035 -146.739246)
			(xy 74.37868 -146.686951) (xy 74.370924 -146.633003) (xy 74.370438 -146.605752) (xy 74.370941 -146.578497)
			(xy 74.378732 -146.524546) (xy 74.39412 -146.472252) (xy 74.416792 -146.422679) (xy 74.431144 -146.399504)
			(xy 74.43493 -146.393222) (xy 74.439048 -146.379151) (xy 74.439272 -146.371818) (xy 74.439272 -142.234666)
			(xy 74.438728 -142.224682) (xy 74.431003 -142.206261) (xy 74.424286 -142.198852) (xy 70.0659 -137.840466)
			(xy 70.058558 -137.833648) (xy 70.040095 -137.825905) (xy 70.030086 -137.82548) (xy 69.86905 -137.82548)
			(xy 69.859048 -137.825967) (xy 69.840553 -137.833591) (xy 69.826345 -137.847674) (xy 69.82206 -137.856722)
			(xy 69.816218 -137.8712) (xy 69.82206 -137.901172) (xy 72.888856 -140.967714) (xy 72.905902 -140.985429)
			(xy 72.934769 -141.02522) (xy 72.957051 -141.069039) (xy 72.972199 -141.115806) (xy 72.97984 -141.164368)
			(xy 72.980296 -141.188948) (xy 72.980296 -146.074892) (xy 73.130916 -146.074892) (xy 73.134987 -146.01927)
			(xy 73.147113 -145.964833) (xy 73.167036 -145.912742) (xy 73.194332 -145.864107) (xy 73.228418 -145.819964)
			(xy 73.268567 -145.781255) (xy 73.313925 -145.748804) (xy 73.363525 -145.723303) (xy 73.416309 -145.705296)
			(xy 73.471152 -145.695166) (xy 73.526886 -145.693129) (xy 73.582323 -145.699229) (xy 73.63628 -145.713335)
			(xy 73.687609 -145.735147) (xy 73.735215 -145.764201) (xy 73.778083 -145.799876) (xy 73.8153 -145.841413)
			(xy 73.846073 -145.887926) (xy 73.869745 -145.938423) (xy 73.885813 -145.99183) (xy 73.893933 -146.047006)
			(xy 73.894442 -146.074892) (xy 73.893933 -146.102778) (xy 73.885813 -146.157954) (xy 73.869745 -146.211361)
			(xy 73.846073 -146.261858) (xy 73.8153 -146.308371) (xy 73.778083 -146.349908) (xy 73.735215 -146.385583)
			(xy 73.687609 -146.414637) (xy 73.63628 -146.436449) (xy 73.582323 -146.450555) (xy 73.526886 -146.456655)
			(xy 73.471152 -146.454618) (xy 73.416309 -146.444488) (xy 73.363525 -146.426481) (xy 73.313925 -146.40098)
			(xy 73.268567 -146.368529) (xy 73.228418 -146.32982) (xy 73.194332 -146.285677) (xy 73.167036 -146.237042)
			(xy 73.147113 -146.184951) (xy 73.134987 -146.130514) (xy 73.130916 -146.074892) (xy 72.980296 -146.074892)
			(xy 72.980296 -146.480784) (xy 72.980831 -146.490773) (xy 72.988539 -146.509209) (xy 72.995282 -146.516598)
			(xy 73.89622 -147.417536) (xy 75.262992 -147.417536) (xy 75.267063 -147.361914) (xy 75.279189 -147.307477)
			(xy 75.299112 -147.255386) (xy 75.326408 -147.206751) (xy 75.360494 -147.162608) (xy 75.400643 -147.123899)
			(xy 75.446001 -147.091448) (xy 75.495601 -147.065947) (xy 75.548385 -147.04794) (xy 75.603228 -147.03781)
			(xy 75.658962 -147.035773) (xy 75.714399 -147.041873) (xy 75.768356 -147.055979) (xy 75.819685 -147.077791)
			(xy 75.867291 -147.106845) (xy 75.910159 -147.14252) (xy 75.947376 -147.184057) (xy 75.978149 -147.23057)
			(xy 76.001821 -147.281067) (xy 76.017889 -147.334474) (xy 76.026009 -147.38965) (xy 76.026518 -147.417536)
			(xy 76.026009 -147.445422) (xy 76.017889 -147.500598) (xy 76.001821 -147.554005) (xy 75.978149 -147.604502)
			(xy 75.947376 -147.651015) (xy 75.910159 -147.692552) (xy 75.867291 -147.728227) (xy 75.819685 -147.757281)
			(xy 75.768356 -147.779093) (xy 75.714399 -147.793199) (xy 75.658962 -147.799299) (xy 75.603228 -147.797262)
			(xy 75.548385 -147.787132) (xy 75.495601 -147.769125) (xy 75.446001 -147.743624) (xy 75.400643 -147.711173)
			(xy 75.360494 -147.672464) (xy 75.326408 -147.628321) (xy 75.299112 -147.579686) (xy 75.279189 -147.527595)
			(xy 75.267063 -147.473158) (xy 75.262992 -147.417536) (xy 73.89622 -147.417536) (xy 74.644758 -148.166074)
			(xy 74.652105 -148.172878) (xy 74.670568 -148.180594) (xy 74.680572 -148.18106) (xy 76.385928 -148.18106)
			(xy 76.398253 -148.180467) (xy 76.420079 -148.169012) (xy 76.427584 -148.159216) (xy 76.442932 -148.137872)
			(xy 76.47855 -148.099206) (xy 76.519139 -148.065795) (xy 76.56393 -148.038271) (xy 76.612075 -148.017156)
			(xy 76.662662 -148.00285) (xy 76.714734 -147.995623) (xy 76.74102 -147.995132) (xy 76.768271 -147.995597)
			(xy 76.822218 -148.003356) (xy 76.874511 -148.018714) (xy 76.924086 -148.041359) (xy 76.969933 -148.070828)
			(xy 77.01112 -148.106522) (xy 77.046808 -148.147715) (xy 77.07627 -148.193567) (xy 77.098907 -148.243146)
			(xy 77.114257 -148.295441) (xy 77.122008 -148.349389) (xy 77.122528 -148.37664) (xy 77.122089 -148.403285)
			(xy 77.114679 -148.456057) (xy 77.099997 -148.507284) (xy 77.078327 -148.555968) (xy 77.050091 -148.601163)
			(xy 77.01584 -148.641987) (xy 76.976239 -148.677646) (xy 76.932061 -148.707446) (xy 76.884164 -148.730807)
			(xy 76.833482 -148.747273) (xy 76.807314 -148.752306) (xy 76.802546 -148.753241) (xy 76.793467 -148.756698)
			(xy 76.78928 -148.759164) (xy 76.764271 -148.773977) (xy 76.710108 -148.795051) (xy 76.652986 -148.805765)
			(xy 76.623926 -148.806408) (xy 74.52995 -148.806408) (xy 74.505371 -148.805946) (xy 74.456813 -148.798295)
			(xy 74.41005 -148.783144) (xy 74.366232 -148.760864) (xy 74.326439 -148.732004) (xy 74.308716 -148.714968)
			(xy 72.446388 -146.85264) (xy 72.429337 -146.834928) (xy 72.400459 -146.795139) (xy 72.378166 -146.751321)
			(xy 72.363008 -146.704553) (xy 72.355357 -146.655988) (xy 72.354948 -146.631406) (xy 72.354948 -141.33957)
			(xy 72.354404 -141.329586) (xy 72.346677 -141.311167) (xy 72.339962 -141.303756) (xy 68.876672 -137.840466)
			(xy 68.869328 -137.833653) (xy 68.850865 -137.82592) (xy 68.840858 -137.82548) (xy 55.171848 -137.82548)
			(xy 55.161782 -137.825912) (xy 55.143189 -137.833637) (xy 55.13578 -137.840466) (xy 49.087532 -143.888714)
			(xy 49.080684 -143.896112) (xy 49.07295 -143.91471) (xy 49.072546 -143.924782) (xy 49.072546 -145.02638)
			(xy 57.174128 -145.02638) (xy 57.178199 -144.970758) (xy 57.190325 -144.916321) (xy 57.210248 -144.86423)
			(xy 57.237544 -144.815595) (xy 57.27163 -144.771452) (xy 57.311779 -144.732743) (xy 57.357137 -144.700292)
			(xy 57.406737 -144.674791) (xy 57.459521 -144.656784) (xy 57.514364 -144.646654) (xy 57.570098 -144.644617)
			(xy 57.625535 -144.650717) (xy 57.679492 -144.664823) (xy 57.730821 -144.686635) (xy 57.778427 -144.715689)
			(xy 57.821295 -144.751364) (xy 57.858512 -144.792901) (xy 57.889285 -144.839414) (xy 57.912957 -144.889911)
			(xy 57.929025 -144.943318) (xy 57.937145 -144.998494) (xy 57.937654 -145.02638) (xy 57.937145 -145.054266)
			(xy 57.929025 -145.109442) (xy 57.912957 -145.162849) (xy 57.889285 -145.213346) (xy 57.858512 -145.259859)
			(xy 57.821295 -145.301396) (xy 57.778427 -145.337071) (xy 57.730821 -145.366125) (xy 57.679492 -145.387937)
			(xy 57.625535 -145.402043) (xy 57.570098 -145.408143) (xy 57.514364 -145.406106) (xy 57.459521 -145.395976)
			(xy 57.406737 -145.377969) (xy 57.357137 -145.352468) (xy 57.311779 -145.320017) (xy 57.27163 -145.281308)
			(xy 57.237544 -145.237165) (xy 57.210248 -145.18853) (xy 57.190325 -145.136439) (xy 57.178199 -145.082002)
			(xy 57.174128 -145.02638) (xy 49.072546 -145.02638) (xy 49.072546 -145.973292) (xy 69.238366 -145.973292)
			(xy 69.242437 -145.91767) (xy 69.254563 -145.863233) (xy 69.274486 -145.811142) (xy 69.301782 -145.762507)
			(xy 69.335868 -145.718364) (xy 69.376017 -145.679655) (xy 69.421375 -145.647204) (xy 69.470975 -145.621703)
			(xy 69.523759 -145.603696) (xy 69.578602 -145.593566) (xy 69.634336 -145.591529) (xy 69.689773 -145.597629)
			(xy 69.74373 -145.611735) (xy 69.795059 -145.633547) (xy 69.842665 -145.662601) (xy 69.885533 -145.698276)
			(xy 69.92275 -145.739813) (xy 69.953523 -145.786326) (xy 69.977195 -145.836823) (xy 69.993263 -145.89023)
			(xy 70.001383 -145.945406) (xy 70.001892 -145.973292) (xy 70.001383 -146.001178) (xy 69.993263 -146.056354)
			(xy 69.977195 -146.109761) (xy 69.953523 -146.160258) (xy 69.92275 -146.206771) (xy 69.885533 -146.248308)
			(xy 69.842665 -146.283983) (xy 69.795059 -146.313037) (xy 69.74373 -146.334849) (xy 69.689773 -146.348955)
			(xy 69.634336 -146.355055) (xy 69.578602 -146.353018) (xy 69.523759 -146.342888) (xy 69.470975 -146.324881)
			(xy 69.421375 -146.29938) (xy 69.376017 -146.266929) (xy 69.335868 -146.22822) (xy 69.301782 -146.184077)
			(xy 69.274486 -146.135442) (xy 69.254563 -146.083351) (xy 69.242437 -146.028914) (xy 69.238366 -145.973292)
			(xy 49.072546 -145.973292) (xy 49.072546 -148.786957) (xy 54.228627 -148.786957) (xy 54.228627 -148.732443)
			(xy 54.236386 -148.678484) (xy 54.251745 -148.626179) (xy 54.274393 -148.576592) (xy 54.303867 -148.530733)
			(xy 54.339569 -148.489536) (xy 54.38077 -148.45384) (xy 54.426632 -148.424371) (xy 54.476222 -148.401729)
			(xy 54.528529 -148.386376) (xy 54.582489 -148.378624) (xy 54.609746 -148.378164) (xy 54.638663 -148.378697)
			(xy 54.695834 -148.38742) (xy 54.751034 -148.404673) (xy 54.802996 -148.430062) (xy 54.85053 -148.463004)
			(xy 54.892546 -148.502745) (xy 54.910736 -148.52523) (xy 54.918281 -148.534009) (xy 54.939053 -148.544182)
			(xy 54.950614 -148.544788) (xy 55.030878 -148.544788) (xy 55.042445 -148.544209) (xy 55.063216 -148.534021)
			(xy 55.070756 -148.52523) (xy 55.087509 -148.504447) (xy 55.125863 -148.467317) (xy 55.169017 -148.435895)
			(xy 55.216131 -148.410796) (xy 55.266283 -148.39251) (xy 55.318494 -148.381393) (xy 55.371746 -148.377663)
			(xy 55.424998 -148.381393) (xy 55.477209 -148.39251) (xy 55.527361 -148.410796) (xy 55.574475 -148.435895)
			(xy 55.617629 -148.467317) (xy 55.655983 -148.504447) (xy 55.672736 -148.52523) (xy 55.680281 -148.534009)
			(xy 55.701053 -148.544182) (xy 55.712614 -148.544788) (xy 55.792878 -148.544788) (xy 55.804445 -148.544209)
			(xy 55.825216 -148.534021) (xy 55.832756 -148.52523) (xy 55.849509 -148.504447) (xy 55.887863 -148.467317)
			(xy 55.931017 -148.435895) (xy 55.978131 -148.410796) (xy 56.028283 -148.39251) (xy 56.080494 -148.381393)
			(xy 56.133746 -148.377663) (xy 56.186998 -148.381393) (xy 56.239209 -148.39251) (xy 56.289361 -148.410796)
			(xy 56.336475 -148.435895) (xy 56.379629 -148.467317) (xy 56.417983 -148.504447) (xy 56.434736 -148.52523)
			(xy 56.442281 -148.534009) (xy 56.463053 -148.544182) (xy 56.474614 -148.544788) (xy 56.554878 -148.544788)
			(xy 56.566445 -148.544209) (xy 56.587216 -148.534021) (xy 56.594756 -148.52523) (xy 56.612979 -148.502774)
			(xy 56.654992 -148.463036) (xy 56.702519 -148.430092) (xy 56.754475 -148.404699) (xy 56.809667 -148.387437)
			(xy 56.866832 -148.378702) (xy 56.895746 -148.378164) (xy 56.922993 -148.378709) (xy 56.976932 -148.386471)
			(xy 57.029217 -148.401829) (xy 57.078785 -148.424471) (xy 57.124626 -148.453936) (xy 57.165808 -148.489625)
			(xy 57.201492 -148.530811) (xy 57.230951 -148.576656) (xy 57.253588 -148.626226) (xy 57.268939 -148.678513)
			(xy 57.276694 -148.732453) (xy 57.276694 -148.786947) (xy 57.268939 -148.840887) (xy 57.253588 -148.893174)
			(xy 57.230951 -148.942744) (xy 57.201492 -148.988589) (xy 57.165808 -149.029775) (xy 57.124626 -149.065464)
			(xy 57.078785 -149.094929) (xy 57.029217 -149.117571) (xy 56.976932 -149.132929) (xy 56.922993 -149.140691)
			(xy 56.895746 -149.14118) (xy 56.86683 -149.140636) (xy 56.80966 -149.131914) (xy 56.754461 -149.114661)
			(xy 56.702499 -149.089274) (xy 56.654964 -149.056335) (xy 56.612947 -149.016598) (xy 56.594756 -148.994114)
			(xy 56.587207 -148.985339) (xy 56.566439 -148.975162) (xy 56.554878 -148.974556) (xy 56.474614 -148.974556)
			(xy 56.463044 -148.975115) (xy 56.442272 -148.985316) (xy 56.434736 -148.994114) (xy 56.417983 -149.014897)
			(xy 56.379629 -149.052027) (xy 56.336475 -149.083449) (xy 56.289361 -149.108548) (xy 56.239209 -149.126834)
			(xy 56.186998 -149.137951) (xy 56.133746 -149.141681) (xy 56.080494 -149.137951) (xy 56.028283 -149.126834)
			(xy 55.978131 -149.108548) (xy 55.931017 -149.083449) (xy 55.887863 -149.052027) (xy 55.849509 -149.014897)
			(xy 55.832756 -148.994114) (xy 55.825207 -148.985339) (xy 55.804439 -148.975162) (xy 55.792878 -148.974556)
			(xy 55.712614 -148.974556) (xy 55.701044 -148.975115) (xy 55.680272 -148.985316) (xy 55.672736 -148.994114)
			(xy 55.655983 -149.014897) (xy 55.617629 -149.052027) (xy 55.574475 -149.083449) (xy 55.527361 -149.108548)
			(xy 55.477209 -149.126834) (xy 55.424998 -149.137951) (xy 55.371746 -149.141681) (xy 55.318494 -149.137951)
			(xy 55.266283 -149.126834) (xy 55.216131 -149.108548) (xy 55.169017 -149.083449) (xy 55.125863 -149.052027)
			(xy 55.087509 -149.014897) (xy 55.070756 -148.994114) (xy 55.063207 -148.985339) (xy 55.042439 -148.975162)
			(xy 55.030878 -148.974556) (xy 54.950614 -148.974556) (xy 54.939044 -148.975115) (xy 54.918272 -148.985316)
			(xy 54.910736 -148.994114) (xy 54.892528 -149.016583) (xy 54.850512 -149.056319) (xy 54.80298 -149.089259)
			(xy 54.751022 -149.11465) (xy 54.695828 -149.131909) (xy 54.638661 -149.140643) (xy 54.609746 -149.14118)
			(xy 54.582489 -149.140776) (xy 54.528529 -149.133024) (xy 54.476222 -149.117671) (xy 54.426632 -149.095029)
			(xy 54.38077 -149.06556) (xy 54.339569 -149.029864) (xy 54.303867 -148.988667) (xy 54.274393 -148.942808)
			(xy 54.251745 -148.893221) (xy 54.236386 -148.840916) (xy 54.228627 -148.786957) (xy 49.072546 -148.786957)
			(xy 49.072546 -149.412198) (xy 69.012814 -149.412198) (xy 69.016885 -149.356576) (xy 69.029011 -149.302139)
			(xy 69.048934 -149.250048) (xy 69.07623 -149.201413) (xy 69.110316 -149.15727) (xy 69.150465 -149.118561)
			(xy 69.195823 -149.08611) (xy 69.245423 -149.060609) (xy 69.298207 -149.042602) (xy 69.35305 -149.032472)
			(xy 69.408784 -149.030435) (xy 69.464221 -149.036535) (xy 69.518178 -149.050641) (xy 69.569507 -149.072453)
			(xy 69.617113 -149.101507) (xy 69.659981 -149.137182) (xy 69.697198 -149.178719) (xy 69.727971 -149.225232)
			(xy 69.751643 -149.275729) (xy 69.767711 -149.329136) (xy 69.775831 -149.384312) (xy 69.77634 -149.412198)
			(xy 69.775831 -149.440084) (xy 69.767711 -149.49526) (xy 69.751643 -149.548667) (xy 69.727971 -149.599164)
			(xy 69.697198 -149.645677) (xy 69.659981 -149.687214) (xy 69.617113 -149.722889) (xy 69.569507 -149.751943)
			(xy 69.518178 -149.773755) (xy 69.464221 -149.787861) (xy 69.408784 -149.793961) (xy 69.35305 -149.791924)
			(xy 69.298207 -149.781794) (xy 69.245423 -149.763787) (xy 69.195823 -149.738286) (xy 69.150465 -149.705835)
			(xy 69.110316 -149.667126) (xy 69.07623 -149.622983) (xy 69.048934 -149.574348) (xy 69.029011 -149.522257)
			(xy 69.016885 -149.46782) (xy 69.012814 -149.412198) (xy 49.072546 -149.412198) (xy 49.072546 -150.921212)
			(xy 49.072119 -150.93128) (xy 49.064396 -150.949876) (xy 49.05756 -150.95728) (xy 49.05756 -151.194051)
			(xy 52.515485 -151.194051) (xy 52.515485 -151.139549) (xy 52.523242 -151.0856) (xy 52.538598 -151.033305)
			(xy 52.56124 -150.983728) (xy 52.590707 -150.937878) (xy 52.626399 -150.896688) (xy 52.667591 -150.860997)
			(xy 52.713442 -150.831532) (xy 52.76302 -150.808892) (xy 52.815316 -150.793539) (xy 52.869265 -150.785784)
			(xy 52.896516 -150.785322) (xy 52.925431 -150.785893) (xy 52.9826 -150.79461) (xy 53.037798 -150.811857)
			(xy 53.08976 -150.837239) (xy 53.137296 -150.870173) (xy 53.179314 -150.909906) (xy 53.197506 -150.932388)
			(xy 53.205072 -150.941146) (xy 53.225827 -150.951332) (xy 53.237384 -150.951946) (xy 53.317648 -150.951946)
			(xy 53.329215 -150.951365) (xy 53.349987 -150.94118) (xy 53.357526 -150.932388) (xy 53.375699 -150.90989)
			(xy 53.417723 -150.870156) (xy 53.465262 -150.837219) (xy 53.517226 -150.811833) (xy 53.572427 -150.79458)
			(xy 53.629599 -150.785855) (xy 53.658516 -150.785322) (xy 53.685769 -150.785749) (xy 53.739719 -150.793508)
			(xy 53.792016 -150.808866) (xy 53.841595 -150.831509) (xy 53.887447 -150.860979) (xy 53.928638 -150.896673)
			(xy 53.964331 -150.937866) (xy 53.993798 -150.983719) (xy 54.01644 -151.033299) (xy 54.031795 -151.085597)
			(xy 54.039552 -151.139547) (xy 54.039552 -151.194053) (xy 54.031795 -151.248003) (xy 54.01644 -151.300301)
			(xy 53.993798 -151.349881) (xy 53.964331 -151.395734) (xy 53.928638 -151.436927) (xy 53.887447 -151.472621)
			(xy 53.841595 -151.502091) (xy 53.792016 -151.524734) (xy 53.739719 -151.540092) (xy 53.685769 -151.547851)
			(xy 53.658516 -151.548338) (xy 53.629598 -151.547832) (xy 53.572426 -151.539104) (xy 53.517225 -151.521845)
			(xy 53.465263 -151.496451) (xy 53.41773 -151.463504) (xy 53.375715 -151.423759) (xy 53.357526 -151.401272)
			(xy 53.349953 -151.392522) (xy 53.329203 -151.382333) (xy 53.317648 -151.381714) (xy 53.237384 -151.381714)
			(xy 53.225814 -151.38227) (xy 53.205043 -151.392474) (xy 53.197506 -151.401272) (xy 53.179305 -151.423747)
			(xy 53.137288 -151.463484) (xy 53.089755 -151.496425) (xy 53.037796 -151.521815) (xy 52.9826 -151.539073)
			(xy 52.925432 -151.547803) (xy 52.896516 -151.548338) (xy 52.869265 -151.547816) (xy 52.815316 -151.540061)
			(xy 52.76302 -151.524708) (xy 52.713442 -151.502068) (xy 52.667591 -151.472603) (xy 52.626399 -151.436912)
			(xy 52.590707 -151.395722) (xy 52.56124 -151.349872) (xy 52.538598 -151.300295) (xy 52.523242 -151.248)
			(xy 52.515485 -151.194051) (xy 49.05756 -151.194051) (xy 49.05756 -153.251451) (xy 52.515485 -153.251451)
			(xy 52.515485 -153.196949) (xy 52.523242 -153.143) (xy 52.538598 -153.090705) (xy 52.56124 -153.041128)
			(xy 52.590707 -152.995278) (xy 52.626399 -152.954088) (xy 52.667591 -152.918397) (xy 52.713442 -152.888932)
			(xy 52.76302 -152.866292) (xy 52.815316 -152.850939) (xy 52.869265 -152.843184) (xy 52.896516 -152.842722)
			(xy 52.925431 -152.843293) (xy 52.9826 -152.85201) (xy 53.037798 -152.869257) (xy 53.08976 -152.894639)
			(xy 53.137296 -152.927573) (xy 53.179314 -152.967306) (xy 53.197506 -152.989788) (xy 53.205072 -152.998546)
			(xy 53.225827 -153.008732) (xy 53.237384 -153.009346) (xy 53.317648 -153.009346) (xy 53.329215 -153.008765)
			(xy 53.349987 -152.99858) (xy 53.357526 -152.989788) (xy 53.375699 -152.96729) (xy 53.417723 -152.927556)
			(xy 53.465262 -152.894619) (xy 53.517226 -152.869233) (xy 53.572427 -152.85198) (xy 53.629599 -152.843255)
			(xy 53.658516 -152.842722) (xy 53.685769 -152.843149) (xy 53.739719 -152.850908) (xy 53.792016 -152.866266)
			(xy 53.841595 -152.888909) (xy 53.887447 -152.918379) (xy 53.928638 -152.954073) (xy 53.964331 -152.995266)
			(xy 53.993798 -153.041119) (xy 54.01644 -153.090699) (xy 54.031795 -153.142997) (xy 54.039552 -153.196947)
			(xy 54.039552 -153.251453) (xy 54.031795 -153.305403) (xy 54.01644 -153.357701) (xy 53.993798 -153.407281)
			(xy 53.964331 -153.453134) (xy 53.928638 -153.494327) (xy 53.887447 -153.530021) (xy 53.841595 -153.559491)
			(xy 53.792016 -153.582134) (xy 53.739719 -153.597492) (xy 53.685769 -153.605251) (xy 53.658516 -153.605738)
			(xy 53.629598 -153.605232) (xy 53.572426 -153.596504) (xy 53.517225 -153.579245) (xy 53.465263 -153.553851)
			(xy 53.41773 -153.520904) (xy 53.375715 -153.481159) (xy 53.357526 -153.458672) (xy 53.349953 -153.449922)
			(xy 53.329203 -153.439733) (xy 53.317648 -153.439114) (xy 53.237384 -153.439114) (xy 53.225814 -153.43967)
			(xy 53.205043 -153.449874) (xy 53.197506 -153.458672) (xy 53.179305 -153.481147) (xy 53.137288 -153.520884)
			(xy 53.089755 -153.553825) (xy 53.037796 -153.579215) (xy 52.9826 -153.596473) (xy 52.925432 -153.605203)
			(xy 52.896516 -153.605738) (xy 52.869265 -153.605216) (xy 52.815316 -153.597461) (xy 52.76302 -153.582108)
			(xy 52.713442 -153.559468) (xy 52.667591 -153.530003) (xy 52.626399 -153.494312) (xy 52.590707 -153.453122)
			(xy 52.56124 -153.407272) (xy 52.538598 -153.357695) (xy 52.523242 -153.3054) (xy 52.515485 -153.251451)
			(xy 49.05756 -153.251451) (xy 49.05756 -154.940254) (xy 52.452778 -154.940254) (xy 52.453308 -154.9115)
			(xy 52.461938 -154.854644) (xy 52.47901 -154.799729) (xy 52.504137 -154.748001) (xy 52.536749 -154.700635)
			(xy 52.576105 -154.658704) (xy 52.621313 -154.62316) (xy 52.646072 -154.60853) (xy 52.656994 -154.60218)
			(xy 52.670202 -154.58186) (xy 52.681124 -154.474672) (xy 52.672234 -154.452066) (xy 52.66309 -154.443684)
			(xy 52.643127 -154.425459) (xy 52.607955 -154.384415) (xy 52.578923 -154.338822) (xy 52.556612 -154.289589)
			(xy 52.541467 -154.237702) (xy 52.533791 -154.184198) (xy 52.533296 -154.157172) (xy 52.533752 -154.12992)
			(xy 52.541512 -154.075971) (xy 52.556871 -154.023675) (xy 52.579516 -153.974098) (xy 52.608985 -153.928247)
			(xy 52.64468 -153.887057) (xy 52.685873 -153.851366) (xy 52.731726 -153.8219) (xy 52.781305 -153.79926)
			(xy 52.833602 -153.783905) (xy 52.887552 -153.776149) (xy 52.914804 -153.775664) (xy 52.943722 -153.776155)
			(xy 53.000896 -153.784886) (xy 53.056096 -153.802148) (xy 53.108058 -153.827545) (xy 53.155591 -153.860494)
			(xy 53.197606 -153.900241) (xy 53.215794 -153.92273) (xy 53.223358 -153.93149) (xy 53.244115 -153.941673)
			(xy 53.255672 -153.942288) (xy 53.335936 -153.942288) (xy 53.3475 -153.941685) (xy 53.368271 -153.931514)
			(xy 53.375814 -153.92273) (xy 53.394005 -153.900246) (xy 53.436024 -153.86051) (xy 53.483558 -153.82757)
			(xy 53.53552 -153.802181) (xy 53.590718 -153.784925) (xy 53.647888 -153.776198) (xy 53.676804 -153.775664)
			(xy 53.704349 -153.776165) (xy 53.758868 -153.78407) (xy 53.811679 -153.799745) (xy 53.861683 -153.822863)
			(xy 53.907836 -153.852941) (xy 53.949177 -153.889352) (xy 53.96738 -153.91003) (xy 53.974746 -153.918666)
			(xy 53.994304 -153.92781) (xy 54.093872 -153.928572) (xy 54.113684 -153.919682) (xy 54.12105 -153.9113)
			(xy 54.139233 -153.89135) (xy 54.180275 -153.856289) (xy 54.225848 -153.827363) (xy 54.275044 -153.805147)
			(xy 54.326879 -153.790086) (xy 54.380319 -153.78248) (xy 54.407308 -153.782014) (xy 54.436223 -153.782593)
			(xy 54.493391 -153.791309) (xy 54.548589 -153.808555) (xy 54.600551 -153.833935) (xy 54.648087 -153.866868)
			(xy 54.690106 -153.906599) (xy 54.708298 -153.92908) (xy 54.715851 -153.93785) (xy 54.736617 -153.948026)
			(xy 54.748176 -153.948638) (xy 54.82844 -153.948638) (xy 54.840007 -153.948055) (xy 54.860779 -153.937871)
			(xy 54.868318 -153.92908) (xy 54.885071 -153.908297) (xy 54.923425 -153.871167) (xy 54.966579 -153.839745)
			(xy 55.013693 -153.814646) (xy 55.063845 -153.79636) (xy 55.116056 -153.785243) (xy 55.169308 -153.781513)
			(xy 55.22256 -153.785243) (xy 55.274771 -153.79636) (xy 55.324923 -153.814646) (xy 55.372037 -153.839745)
			(xy 55.415191 -153.871167) (xy 55.453545 -153.908297) (xy 55.470298 -153.92908) (xy 55.477851 -153.93785)
			(xy 55.498617 -153.948026) (xy 55.510176 -153.948638) (xy 55.59044 -153.948638) (xy 55.602007 -153.948055)
			(xy 55.622779 -153.937871) (xy 55.630318 -153.92908) (xy 55.647801 -153.90749) (xy 55.687963 -153.869107)
			(xy 55.710328 -153.852626) (xy 55.720742 -153.845006) (xy 55.731918 -153.822654) (xy 55.72887 -153.712418)
			(xy 55.716424 -153.690574) (xy 55.705248 -153.683716) (xy 55.682195 -153.668651) (xy 55.640264 -153.632952)
			(xy 55.6039 -153.591597) (xy 55.573857 -153.545444) (xy 55.550761 -153.495452) (xy 55.53509 -153.442659)
			(xy 55.527171 -153.388163) (xy 55.526686 -153.360628) (xy 55.527181 -153.333376) (xy 55.534934 -153.279427)
			(xy 55.550287 -153.22713) (xy 55.572925 -153.17755) (xy 55.60239 -153.131697) (xy 55.63808 -153.090504)
			(xy 55.67927 -153.05481) (xy 55.72512 -153.025342) (xy 55.774698 -153.002698) (xy 55.826993 -152.987342)
			(xy 55.880942 -152.979584) (xy 55.908194 -152.97912) (xy 55.937111 -152.979635) (xy 55.994283 -152.988364)
			(xy 56.049482 -153.005622) (xy 56.101444 -153.031014) (xy 56.148978 -153.063958) (xy 56.190994 -153.1037)
			(xy 56.209184 -153.126186) (xy 56.216759 -153.134934) (xy 56.237508 -153.145126) (xy 56.249062 -153.145744)
			(xy 56.329326 -153.145744) (xy 56.340891 -153.145151) (xy 56.361664 -153.134974) (xy 56.369204 -153.126186)
			(xy 56.387389 -153.103698) (xy 56.429411 -153.063963) (xy 56.476947 -153.031025) (xy 56.528909 -153.005638)
			(xy 56.584108 -152.988383) (xy 56.641278 -152.979655) (xy 56.670194 -152.97912) (xy 56.697448 -152.979561)
			(xy 56.751401 -152.987318) (xy 56.803701 -153.002675) (xy 56.853283 -153.025318) (xy 56.899138 -153.054788)
			(xy 56.940331 -153.090485) (xy 56.976025 -153.13168) (xy 57.005492 -153.177536) (xy 57.028133 -153.22712)
			(xy 57.043487 -153.27942) (xy 57.051241 -153.333374) (xy 57.051702 -153.360628) (xy 57.051259 -153.386603)
			(xy 57.044214 -153.438073) (xy 57.030243 -153.48811) (xy 57.009607 -153.535785) (xy 56.982687 -153.580217)
			(xy 56.949983 -153.62058) (xy 56.9121 -153.656129) (xy 56.891174 -153.671524) (xy 56.88076 -153.679144)
			(xy 56.869584 -153.701496) (xy 56.872632 -153.811732) (xy 56.885078 -153.833576) (xy 56.896254 -153.840434)
			(xy 56.919285 -153.855531) (xy 56.961216 -153.891225) (xy 56.997581 -153.932575) (xy 57.027626 -153.978722)
			(xy 57.050726 -154.028709) (xy 57.066402 -154.081496) (xy 57.074328 -154.135989) (xy 57.074816 -154.163522)
			(xy 57.074448 -154.189074) (xy 57.067633 -154.239722) (xy 57.054115 -154.289006) (xy 57.034136 -154.336044)
			(xy 57.008055 -154.379992) (xy 56.976337 -154.420063) (xy 56.95823 -154.438096) (xy 56.951182 -154.445548)
			(xy 56.943198 -154.464424) (xy 56.942736 -154.474672) (xy 56.942736 -154.547824) (xy 56.943192 -154.558073)
			(xy 56.951179 -154.576949) (xy 56.95823 -154.5844) (xy 56.964326 -154.590496) (xy 56.971438 -154.597862)
			(xy 56.990234 -154.605482) (xy 57.082436 -154.60599) (xy 57.100978 -154.598116) (xy 57.108344 -154.591004)
			(xy 57.129939 -154.570358) (xy 57.178341 -154.53534) (xy 57.231612 -154.508299) (xy 57.288448 -154.489897)
			(xy 57.347459 -154.480584) (xy 57.37733 -154.480006) (xy 57.406245 -154.480572) (xy 57.463414 -154.489291)
			(xy 57.518612 -154.506539) (xy 57.570574 -154.531922) (xy 57.618109 -154.564857) (xy 57.660128 -154.60459)
			(xy 57.67832 -154.627072) (xy 57.685865 -154.63585) (xy 57.706637 -154.646022) (xy 57.718198 -154.64663)
			(xy 57.798462 -154.64663) (xy 57.810031 -154.646062) (xy 57.830804 -154.635868) (xy 57.83834 -154.627072)
			(xy 57.856501 -154.604564) (xy 57.898528 -154.564831) (xy 57.946069 -154.531896) (xy 57.998036 -154.506512)
			(xy 58.053239 -154.489261) (xy 58.110412 -154.480538) (xy 58.13933 -154.480006) (xy 58.166581 -154.480466)
			(xy 58.220527 -154.488226) (xy 58.27282 -154.503584) (xy 58.322396 -154.526228) (xy 58.325172 -154.528012)
			(xy 67.588636 -154.528012) (xy 67.592707 -154.47239) (xy 67.604833 -154.417953) (xy 67.624756 -154.365862)
			(xy 67.652052 -154.317227) (xy 67.686138 -154.273084) (xy 67.726287 -154.234375) (xy 67.771645 -154.201924)
			(xy 67.821245 -154.176423) (xy 67.874029 -154.158416) (xy 67.928872 -154.148286) (xy 67.984606 -154.146249)
			(xy 68.040043 -154.152349) (xy 68.094 -154.166455) (xy 68.145329 -154.188267) (xy 68.192935 -154.217321)
			(xy 68.235803 -154.252996) (xy 68.27302 -154.294533) (xy 68.303793 -154.341046) (xy 68.327465 -154.391543)
			(xy 68.343533 -154.44495) (xy 68.351653 -154.500126) (xy 68.352162 -154.528012) (xy 68.351653 -154.555898)
			(xy 68.343533 -154.611074) (xy 68.327465 -154.664481) (xy 68.303793 -154.714978) (xy 68.27302 -154.761491)
			(xy 68.235803 -154.803028) (xy 68.192935 -154.838703) (xy 68.145329 -154.867757) (xy 68.094 -154.889569)
			(xy 68.040043 -154.903675) (xy 67.984606 -154.909775) (xy 67.928872 -154.907738) (xy 67.874029 -154.897608)
			(xy 67.821245 -154.879601) (xy 67.771645 -154.8541) (xy 67.726287 -154.821649) (xy 67.686138 -154.78294)
			(xy 67.652052 -154.738797) (xy 67.624756 -154.690162) (xy 67.604833 -154.638071) (xy 67.592707 -154.583634)
			(xy 67.588636 -154.528012) (xy 58.325172 -154.528012) (xy 58.368244 -154.555696) (xy 58.409432 -154.591389)
			(xy 58.445122 -154.63258) (xy 58.474586 -154.678431) (xy 58.497226 -154.728008) (xy 58.51258 -154.780302)
			(xy 58.520336 -154.834249) (xy 58.520336 -154.888751) (xy 58.51258 -154.942698) (xy 58.497226 -154.994992)
			(xy 58.474586 -155.044569) (xy 58.445122 -155.09042) (xy 58.409432 -155.131611) (xy 58.368244 -155.167304)
			(xy 58.322396 -155.196772) (xy 58.27282 -155.219416) (xy 58.220527 -155.234774) (xy 58.166581 -155.242534)
			(xy 58.13933 -155.243022) (xy 58.110412 -155.242512) (xy 58.053239 -155.233785) (xy 57.998039 -155.216528)
			(xy 57.946077 -155.191135) (xy 57.898543 -155.158188) (xy 57.856528 -155.118444) (xy 57.83834 -155.095956)
			(xy 57.830764 -155.087209) (xy 57.810016 -155.077019) (xy 57.798462 -155.076398) (xy 57.718198 -155.076398)
			(xy 57.70663 -155.076968) (xy 57.685859 -155.087163) (xy 57.67832 -155.095956) (xy 57.660107 -155.118421)
			(xy 57.618093 -155.158159) (xy 57.570563 -155.191102) (xy 57.518606 -155.216494) (xy 57.463412 -155.233753)
			(xy 57.406245 -155.242486) (xy 57.37733 -155.243022) (xy 57.347171 -155.242439) (xy 57.287605 -155.232939)
			(xy 57.230276 -155.214187) (xy 57.17661 -155.18665) (xy 57.127945 -155.151014) (xy 57.106312 -155.129992)
			(xy 57.0992 -155.122626) (xy 57.080404 -155.115006) (xy 56.988202 -155.114498) (xy 56.96966 -155.122372)
			(xy 56.962294 -155.129484) (xy 56.940697 -155.150127) (xy 56.892294 -155.185142) (xy 56.839023 -155.212182)
			(xy 56.782188 -155.230585) (xy 56.723178 -155.239901) (xy 56.693308 -155.240482) (xy 56.664391 -155.239965)
			(xy 56.607219 -155.231236) (xy 56.55202 -155.213979) (xy 56.500059 -155.188587) (xy 56.452525 -155.155643)
			(xy 56.410508 -155.115902) (xy 56.392318 -155.093416) (xy 56.384759 -155.084652) (xy 56.363997 -155.074473)
			(xy 56.35244 -155.073858) (xy 56.272176 -155.073858) (xy 56.260611 -155.074452) (xy 56.239838 -155.084628)
			(xy 56.232298 -155.093416) (xy 56.215545 -155.114199) (xy 56.177191 -155.151329) (xy 56.134037 -155.182751)
			(xy 56.086923 -155.20785) (xy 56.036771 -155.226136) (xy 55.98456 -155.237253) (xy 55.931308 -155.240983)
			(xy 55.878056 -155.237253) (xy 55.825845 -155.226136) (xy 55.775693 -155.20785) (xy 55.728579 -155.182751)
			(xy 55.685425 -155.151329) (xy 55.647071 -155.114199) (xy 55.630318 -155.093416) (xy 55.622759 -155.084652)
			(xy 55.601997 -155.074473) (xy 55.59044 -155.073858) (xy 55.510176 -155.073858) (xy 55.498611 -155.074452)
			(xy 55.477838 -155.084628) (xy 55.470298 -155.093416) (xy 55.453545 -155.114199) (xy 55.415191 -155.151329)
			(xy 55.372037 -155.182751) (xy 55.324923 -155.20785) (xy 55.274771 -155.226136) (xy 55.22256 -155.237253)
			(xy 55.169308 -155.240983) (xy 55.116056 -155.237253) (xy 55.063845 -155.226136) (xy 55.013693 -155.20785)
			(xy 54.966579 -155.182751) (xy 54.923425 -155.151329) (xy 54.885071 -155.114199) (xy 54.868318 -155.093416)
			(xy 54.860759 -155.084652) (xy 54.839997 -155.074473) (xy 54.82844 -155.073858) (xy 54.748176 -155.073858)
			(xy 54.736611 -155.074452) (xy 54.715838 -155.084628) (xy 54.708298 -155.093416) (xy 54.690112 -155.115904)
			(xy 54.648091 -155.155638) (xy 54.600555 -155.188576) (xy 54.548593 -155.213963) (xy 54.493394 -155.231219)
			(xy 54.436224 -155.239947) (xy 54.407308 -155.240482) (xy 54.378559 -155.239983) (xy 54.321716 -155.231331)
			(xy 54.266813 -155.214251) (xy 54.215093 -155.18913) (xy 54.167725 -155.156535) (xy 54.125782 -155.117206)
			(xy 54.107588 -155.09494) (xy 54.09946 -155.084526) (xy 54.075584 -155.074366) (xy 53.964078 -155.085542)
			(xy 53.942742 -155.100274) (xy 53.9369 -155.111958) (xy 53.924612 -155.135249) (xy 53.894686 -155.178579)
			(xy 53.859083 -155.217378) (xy 53.818478 -155.250907) (xy 53.773646 -155.27853) (xy 53.725438 -155.29972)
			(xy 53.674774 -155.314074) (xy 53.622615 -155.321319) (xy 53.596286 -155.321762) (xy 53.567371 -155.321196)
			(xy 53.510201 -155.312479) (xy 53.455003 -155.295231) (xy 53.40304 -155.269849) (xy 53.355505 -155.236913)
			(xy 53.313487 -155.197178) (xy 53.295296 -155.174696) (xy 53.287732 -155.165936) (xy 53.266975 -155.155752)
			(xy 53.255418 -155.155138) (xy 53.175154 -155.155138) (xy 53.163588 -155.155726) (xy 53.142816 -155.165907)
			(xy 53.135276 -155.174696) (xy 53.117098 -155.19719) (xy 53.075075 -155.236925) (xy 53.027538 -155.269863)
			(xy 52.975574 -155.295249) (xy 52.920374 -155.312503) (xy 52.863203 -155.321229) (xy 52.834286 -155.321762)
			(xy 52.807031 -155.321358) (xy 52.753075 -155.313598) (xy 52.700773 -155.298238) (xy 52.65119 -155.27559)
			(xy 52.605335 -155.246117) (xy 52.564141 -155.210417) (xy 52.528447 -155.169217) (xy 52.498981 -155.123357)
			(xy 52.476341 -155.07377) (xy 52.460989 -155.021466) (xy 52.453238 -154.967509) (xy 52.452778 -154.940254)
			(xy 49.05756 -154.940254) (xy 49.05756 -158.113052) (xy 54.997068 -158.113052) (xy 54.997068 -158.058548)
			(xy 55.004824 -158.004599) (xy 55.02018 -157.952304) (xy 55.042821 -157.902725) (xy 55.072288 -157.856874)
			(xy 55.10798 -157.815683) (xy 55.149171 -157.77999) (xy 55.195022 -157.750523) (xy 55.2446 -157.727881)
			(xy 55.296896 -157.712525) (xy 55.350844 -157.704768) (xy 55.378096 -157.704282) (xy 55.407014 -157.704772)
			(xy 55.464188 -157.713503) (xy 55.519389 -157.730764) (xy 55.571351 -157.756161) (xy 55.618884 -157.789111)
			(xy 55.660898 -157.828859) (xy 55.679086 -157.851348) (xy 55.68665 -157.860107) (xy 55.707407 -157.87029)
			(xy 55.718964 -157.870906) (xy 55.799228 -157.870906) (xy 55.81079 -157.870292) (xy 55.831562 -157.860128)
			(xy 55.839106 -157.851348) (xy 55.855859 -157.830565) (xy 55.894213 -157.793435) (xy 55.937367 -157.762013)
			(xy 55.984481 -157.736914) (xy 56.034633 -157.718628) (xy 56.086844 -157.707511) (xy 56.140096 -157.703781)
			(xy 56.193348 -157.707511) (xy 56.245559 -157.718628) (xy 56.295711 -157.736914) (xy 56.342825 -157.762013)
			(xy 56.385979 -157.793435) (xy 56.424333 -157.830565) (xy 56.441086 -157.851348) (xy 56.44865 -157.860107)
			(xy 56.469407 -157.87029) (xy 56.480964 -157.870906) (xy 56.561228 -157.870906) (xy 56.57279 -157.870292)
			(xy 56.593562 -157.860128) (xy 56.601106 -157.851348) (xy 56.617859 -157.830565) (xy 56.656213 -157.793435)
			(xy 56.699367 -157.762013) (xy 56.746481 -157.736914) (xy 56.796633 -157.718628) (xy 56.848844 -157.707511)
			(xy 56.902096 -157.703781) (xy 56.955348 -157.707511) (xy 57.007559 -157.718628) (xy 57.057711 -157.736914)
			(xy 57.104825 -157.762013) (xy 57.147979 -157.793435) (xy 57.186333 -157.830565) (xy 57.203086 -157.851348)
			(xy 57.21065 -157.860107) (xy 57.231407 -157.87029) (xy 57.242964 -157.870906) (xy 57.323228 -157.870906)
			(xy 57.33479 -157.870292) (xy 57.355562 -157.860128) (xy 57.363106 -157.851348) (xy 57.38128 -157.828851)
			(xy 57.423305 -157.789119) (xy 57.470844 -157.756183) (xy 57.522808 -157.730797) (xy 57.578008 -157.713544)
			(xy 57.635179 -157.704816) (xy 57.664096 -157.704282) (xy 57.691348 -157.704765) (xy 57.745298 -157.712521)
			(xy 57.797595 -157.727877) (xy 57.847175 -157.750518) (xy 57.893027 -157.779985) (xy 57.934219 -157.815678)
			(xy 57.969912 -157.85687) (xy 57.99938 -157.902722) (xy 58.022022 -157.952301) (xy 58.037378 -158.004598)
			(xy 58.045135 -158.058548) (xy 58.045135 -158.113052) (xy 58.037378 -158.167002) (xy 58.022022 -158.219299)
			(xy 57.99938 -158.268878) (xy 57.969912 -158.31473) (xy 57.934219 -158.355922) (xy 57.893027 -158.391615)
			(xy 57.847175 -158.421082) (xy 57.797595 -158.443723) (xy 57.745298 -158.459079) (xy 57.691348 -158.466835)
			(xy 57.664096 -158.467298) (xy 57.635179 -158.466783) (xy 57.578008 -158.458053) (xy 57.522809 -158.440795)
			(xy 57.470847 -158.415403) (xy 57.423313 -158.382458) (xy 57.381296 -158.342717) (xy 57.363106 -158.320232)
			(xy 57.355549 -158.311466) (xy 57.334786 -158.301288) (xy 57.323228 -158.300674) (xy 57.242964 -158.300674)
			(xy 57.231397 -158.301255) (xy 57.210624 -158.31144) (xy 57.203086 -158.320232) (xy 57.186333 -158.341015)
			(xy 57.147979 -158.378145) (xy 57.104825 -158.409567) (xy 57.057711 -158.434666) (xy 57.007559 -158.452952)
			(xy 56.955348 -158.464069) (xy 56.902096 -158.467799) (xy 56.848844 -158.464069) (xy 56.796633 -158.452952)
			(xy 56.746481 -158.434666) (xy 56.699367 -158.409567) (xy 56.656213 -158.378145) (xy 56.617859 -158.341015)
			(xy 56.601106 -158.320232) (xy 56.593549 -158.311466) (xy 56.572786 -158.301288) (xy 56.561228 -158.300674)
			(xy 56.480964 -158.300674) (xy 56.469397 -158.301255) (xy 56.448624 -158.31144) (xy 56.441086 -158.320232)
			(xy 56.424333 -158.341015) (xy 56.385979 -158.378145) (xy 56.342825 -158.409567) (xy 56.295711 -158.434666)
			(xy 56.245559 -158.452952) (xy 56.193348 -158.464069) (xy 56.140096 -158.467799) (xy 56.086844 -158.464069)
			(xy 56.034633 -158.452952) (xy 55.984481 -158.434666) (xy 55.937367 -158.409567) (xy 55.894213 -158.378145)
			(xy 55.855859 -158.341015) (xy 55.839106 -158.320232) (xy 55.831549 -158.311466) (xy 55.810786 -158.301288)
			(xy 55.799228 -158.300674) (xy 55.718964 -158.300674) (xy 55.707397 -158.301255) (xy 55.686624 -158.31144)
			(xy 55.679086 -158.320232) (xy 55.660911 -158.342729) (xy 55.618887 -158.382462) (xy 55.571348 -158.415398)
			(xy 55.519384 -158.440784) (xy 55.464184 -158.458038) (xy 55.407013 -158.466764) (xy 55.378096 -158.467298)
			(xy 55.350844 -158.466832) (xy 55.296896 -158.459075) (xy 55.2446 -158.443719) (xy 55.195022 -158.421077)
			(xy 55.149171 -158.39161) (xy 55.10798 -158.355917) (xy 55.072288 -158.314726) (xy 55.042821 -158.268875)
			(xy 55.02018 -158.219296) (xy 55.004824 -158.167001) (xy 54.997068 -158.113052) (xy 49.05756 -158.113052)
			(xy 49.05756 -160.653052) (xy 54.997068 -160.653052) (xy 54.997068 -160.598548) (xy 55.004824 -160.544599)
			(xy 55.02018 -160.492304) (xy 55.042821 -160.442725) (xy 55.072288 -160.396874) (xy 55.10798 -160.355683)
			(xy 55.149171 -160.31999) (xy 55.195022 -160.290523) (xy 55.2446 -160.267881) (xy 55.296896 -160.252525)
			(xy 55.350844 -160.244768) (xy 55.378096 -160.244282) (xy 55.407014 -160.244772) (xy 55.464188 -160.253503)
			(xy 55.519389 -160.270764) (xy 55.571351 -160.296161) (xy 55.618884 -160.329111) (xy 55.660898 -160.368859)
			(xy 55.679086 -160.391348) (xy 55.68665 -160.400107) (xy 55.707407 -160.41029) (xy 55.718964 -160.410906)
			(xy 55.799228 -160.410906) (xy 55.81079 -160.410292) (xy 55.831562 -160.400128) (xy 55.839106 -160.391348)
			(xy 55.855859 -160.370565) (xy 55.894213 -160.333435) (xy 55.937367 -160.302013) (xy 55.984481 -160.276914)
			(xy 56.034633 -160.258628) (xy 56.086844 -160.247511) (xy 56.140096 -160.243781) (xy 56.193348 -160.247511)
			(xy 56.245559 -160.258628) (xy 56.295711 -160.276914) (xy 56.342825 -160.302013) (xy 56.385979 -160.333435)
			(xy 56.424333 -160.370565) (xy 56.441086 -160.391348) (xy 56.44865 -160.400107) (xy 56.469407 -160.41029)
			(xy 56.480964 -160.410906) (xy 56.561228 -160.410906) (xy 56.57279 -160.410292) (xy 56.593562 -160.400128)
			(xy 56.601106 -160.391348) (xy 56.617859 -160.370565) (xy 56.656213 -160.333435) (xy 56.699367 -160.302013)
			(xy 56.746481 -160.276914) (xy 56.796633 -160.258628) (xy 56.848844 -160.247511) (xy 56.902096 -160.243781)
			(xy 56.955348 -160.247511) (xy 57.007559 -160.258628) (xy 57.057711 -160.276914) (xy 57.104825 -160.302013)
			(xy 57.147979 -160.333435) (xy 57.186333 -160.370565) (xy 57.203086 -160.391348) (xy 57.21065 -160.400107)
			(xy 57.231407 -160.41029) (xy 57.242964 -160.410906) (xy 57.323228 -160.410906) (xy 57.33479 -160.410292)
			(xy 57.355562 -160.400128) (xy 57.363106 -160.391348) (xy 57.38128 -160.368851) (xy 57.423305 -160.329119)
			(xy 57.470844 -160.296183) (xy 57.522808 -160.270797) (xy 57.578008 -160.253544) (xy 57.635179 -160.244816)
			(xy 57.664096 -160.244282) (xy 57.691348 -160.244765) (xy 57.745298 -160.252521) (xy 57.797595 -160.267877)
			(xy 57.847175 -160.290518) (xy 57.893027 -160.319985) (xy 57.934219 -160.355678) (xy 57.969912 -160.39687)
			(xy 57.99938 -160.442722) (xy 58.022022 -160.492301) (xy 58.037378 -160.544598) (xy 58.045135 -160.598548)
			(xy 58.045135 -160.653052) (xy 58.037378 -160.707002) (xy 58.022022 -160.759299) (xy 57.99938 -160.808878)
			(xy 57.969912 -160.85473) (xy 57.934219 -160.895922) (xy 57.893027 -160.931615) (xy 57.847175 -160.961082)
			(xy 57.797595 -160.983723) (xy 57.745298 -160.999079) (xy 57.691348 -161.006835) (xy 57.664096 -161.007298)
			(xy 57.635179 -161.006783) (xy 57.578008 -160.998053) (xy 57.522809 -160.980795) (xy 57.470847 -160.955403)
			(xy 57.423313 -160.922458) (xy 57.381296 -160.882717) (xy 57.363106 -160.860232) (xy 57.355549 -160.851466)
			(xy 57.334786 -160.841288) (xy 57.323228 -160.840674) (xy 57.242964 -160.840674) (xy 57.231397 -160.841255)
			(xy 57.210624 -160.85144) (xy 57.203086 -160.860232) (xy 57.186333 -160.881015) (xy 57.147979 -160.918145)
			(xy 57.104825 -160.949567) (xy 57.057711 -160.974666) (xy 57.007559 -160.992952) (xy 56.955348 -161.004069)
			(xy 56.902096 -161.007799) (xy 56.848844 -161.004069) (xy 56.796633 -160.992952) (xy 56.746481 -160.974666)
			(xy 56.699367 -160.949567) (xy 56.656213 -160.918145) (xy 56.617859 -160.881015) (xy 56.601106 -160.860232)
			(xy 56.593549 -160.851466) (xy 56.572786 -160.841288) (xy 56.561228 -160.840674) (xy 56.480964 -160.840674)
			(xy 56.469397 -160.841255) (xy 56.448624 -160.85144) (xy 56.441086 -160.860232) (xy 56.424333 -160.881015)
			(xy 56.385979 -160.918145) (xy 56.342825 -160.949567) (xy 56.295711 -160.974666) (xy 56.245559 -160.992952)
			(xy 56.193348 -161.004069) (xy 56.140096 -161.007799) (xy 56.086844 -161.004069) (xy 56.034633 -160.992952)
			(xy 55.984481 -160.974666) (xy 55.937367 -160.949567) (xy 55.894213 -160.918145) (xy 55.855859 -160.881015)
			(xy 55.839106 -160.860232) (xy 55.831549 -160.851466) (xy 55.810786 -160.841288) (xy 55.799228 -160.840674)
			(xy 55.718964 -160.840674) (xy 55.707397 -160.841255) (xy 55.686624 -160.85144) (xy 55.679086 -160.860232)
			(xy 55.660911 -160.882729) (xy 55.618887 -160.922462) (xy 55.571348 -160.955398) (xy 55.519384 -160.980784)
			(xy 55.464184 -160.998038) (xy 55.407013 -161.006764) (xy 55.378096 -161.007298) (xy 55.350844 -161.006832)
			(xy 55.296896 -160.999075) (xy 55.2446 -160.983719) (xy 55.195022 -160.961077) (xy 55.149171 -160.93161)
			(xy 55.10798 -160.895917) (xy 55.072288 -160.854726) (xy 55.042821 -160.808875) (xy 55.02018 -160.759296)
			(xy 55.004824 -160.707001) (xy 54.997068 -160.653052) (xy 49.05756 -160.653052) (xy 49.05756 -166.86276)
			(xy 61.555122 -166.86276) (xy 61.555621 -166.835187) (xy 61.563566 -166.780615) (xy 61.579284 -166.727755)
			(xy 61.602447 -166.677709) (xy 61.632574 -166.631519) (xy 61.669037 -166.590146) (xy 61.689742 -166.57193)
			(xy 61.697849 -166.564318) (xy 61.707208 -166.544173) (xy 61.707776 -166.533068) (xy 61.707776 -166.455852)
			(xy 61.707202 -166.444743) (xy 61.697869 -166.424583) (xy 61.689742 -166.41699) (xy 61.668995 -166.398819)
			(xy 61.632527 -166.357443) (xy 61.602398 -166.311248) (xy 61.579235 -166.261195) (xy 61.56352 -166.208329)
			(xy 61.555582 -166.15375) (xy 61.555586 -166.098598) (xy 61.563531 -166.044021) (xy 61.579253 -165.991156)
			(xy 61.602423 -165.941107) (xy 61.632559 -165.894915) (xy 61.669032 -165.853545) (xy 61.689742 -165.83533)
			(xy 61.697849 -165.827718) (xy 61.707208 -165.807573) (xy 61.707776 -165.796468) (xy 61.707776 -165.719252)
			(xy 61.707202 -165.708143) (xy 61.697869 -165.687983) (xy 61.689742 -165.68039) (xy 61.669031 -165.662178)
			(xy 61.632559 -165.620811) (xy 61.602426 -165.574621) (xy 61.57926 -165.524573) (xy 61.563544 -165.47171)
			(xy 61.555606 -165.417135) (xy 61.555122 -165.38956) (xy 61.555541 -165.362306) (xy 61.563303 -165.308355)
			(xy 61.578665 -165.256057) (xy 61.601313 -165.206478) (xy 61.630786 -165.160626) (xy 61.666485 -165.119435)
			(xy 61.707682 -165.083744) (xy 61.753539 -165.05428) (xy 61.803123 -165.031641) (xy 61.855423 -165.016289)
			(xy 61.909376 -165.008536) (xy 61.93663 -165.008052) (xy 61.964488 -165.008509) (xy 62.019608 -165.016639)
			(xy 62.072962 -165.032691) (xy 62.123417 -165.056325) (xy 62.169903 -165.08704) (xy 62.211432 -165.124184)
			(xy 62.247123 -165.166968) (xy 62.276219 -165.214484) (xy 62.298101 -165.265723) (xy 62.305692 -165.292532)
			(xy 62.307978 -165.301422) (xy 62.318646 -165.316662) (xy 62.390528 -165.364414) (xy 62.408562 -165.368478)
			(xy 62.417706 -165.367208) (xy 62.430723 -165.36554) (xy 62.456907 -165.363759) (xy 62.47003 -165.363652)
			(xy 62.484179 -165.363743) (xy 62.512402 -165.365779) (xy 62.526418 -165.367716) (xy 62.536578 -165.36924)
			(xy 62.556136 -165.364414) (xy 62.630558 -165.308534) (xy 62.640718 -165.291008) (xy 62.641988 -165.280848)
			(xy 62.646066 -165.253693) (xy 62.66104 -165.200862) (xy 62.683433 -165.150723) (xy 62.712781 -165.104313)
			(xy 62.74848 -165.062588) (xy 62.789791 -165.026412) (xy 62.835861 -164.996531) (xy 62.885739 -164.973563)
			(xy 62.938393 -164.957982) (xy 62.992738 -164.95011) (xy 63.020194 -164.949632) (xy 63.047449 -164.950061)
			(xy 63.101403 -164.957818) (xy 63.153704 -164.973176) (xy 63.203286 -164.99582) (xy 63.249142 -165.025291)
			(xy 63.290335 -165.060989) (xy 63.326029 -165.102186) (xy 63.355496 -165.148043) (xy 63.378136 -165.197628)
			(xy 63.393489 -165.249931) (xy 63.401241 -165.303885) (xy 63.401702 -165.33114) (xy 63.401194 -165.358713)
			(xy 63.39325 -165.413284) (xy 63.377533 -165.466143) (xy 63.354371 -165.516189) (xy 63.324246 -165.56238)
			(xy 63.287786 -165.603753) (xy 63.267082 -165.62197) (xy 63.258979 -165.629586) (xy 63.249617 -165.649727)
			(xy 63.249048 -165.660832) (xy 63.249048 -165.738048) (xy 63.249614 -165.749159) (xy 63.258952 -165.769318)
			(xy 63.267082 -165.77691) (xy 63.287798 -165.795116) (xy 63.324268 -165.836486) (xy 63.3544 -165.882676)
			(xy 63.377566 -165.932725) (xy 63.393281 -165.985589) (xy 63.401218 -166.040165) (xy 63.401252 -166.042086)
			(xy 67.99021 -166.042086) (xy 67.994281 -165.986464) (xy 68.006407 -165.932027) (xy 68.02633 -165.879936)
			(xy 68.053626 -165.831301) (xy 68.087712 -165.787158) (xy 68.127861 -165.748449) (xy 68.173219 -165.715998)
			(xy 68.222819 -165.690497) (xy 68.275603 -165.67249) (xy 68.330446 -165.66236) (xy 68.38618 -165.660323)
			(xy 68.441617 -165.666423) (xy 68.495574 -165.680529) (xy 68.546903 -165.702341) (xy 68.594509 -165.731395)
			(xy 68.637377 -165.76707) (xy 68.674594 -165.808607) (xy 68.705367 -165.85512) (xy 68.729039 -165.905617)
			(xy 68.745107 -165.959024) (xy 68.753227 -166.0142) (xy 68.753736 -166.042086) (xy 68.753227 -166.069972)
			(xy 68.745107 -166.125148) (xy 68.729039 -166.178555) (xy 68.705367 -166.229052) (xy 68.674594 -166.275565)
			(xy 68.637377 -166.317102) (xy 68.594509 -166.352777) (xy 68.546903 -166.381831) (xy 68.495574 -166.403643)
			(xy 68.441617 -166.417749) (xy 68.38618 -166.423849) (xy 68.330446 -166.421812) (xy 68.275603 -166.411682)
			(xy 68.222819 -166.393675) (xy 68.173219 -166.368174) (xy 68.127861 -166.335723) (xy 68.087712 -166.297014)
			(xy 68.053626 -166.252871) (xy 68.02633 -166.204236) (xy 68.006407 -166.152145) (xy 67.994281 -166.097708)
			(xy 67.99021 -166.042086) (xy 63.401252 -166.042086) (xy 63.401702 -166.06774) (xy 63.401259 -166.094993)
			(xy 63.393497 -166.148942) (xy 63.378137 -166.201238) (xy 63.355491 -166.250816) (xy 63.32602 -166.296666)
			(xy 63.290324 -166.337856) (xy 63.249129 -166.373547) (xy 63.203275 -166.403013) (xy 63.153695 -166.425653)
			(xy 63.101397 -166.441007) (xy 63.047447 -166.448763) (xy 63.020194 -166.449248) (xy 62.985904 -166.447724)
			(xy 62.975744 -166.446708) (xy 62.95644 -166.452804) (xy 62.885828 -166.511986) (xy 62.87643 -166.53002)
			(xy 62.875414 -166.54018) (xy 62.87249 -166.568356) (xy 62.859312 -166.623449) (xy 62.838129 -166.675986)
			(xy 62.809407 -166.724812) (xy 62.77378 -166.768853) (xy 62.73203 -166.807139) (xy 62.685075 -166.838828)
			(xy 62.63395 -166.863223) (xy 62.579779 -166.879787) (xy 62.523754 -166.888156) (xy 62.49543 -166.888668)
			(xy 62.477411 -166.888452) (xy 62.441536 -166.885014) (xy 62.423802 -166.88181) (xy 62.414404 -166.880032)
			(xy 62.395354 -166.883842) (xy 62.32017 -166.931594) (xy 62.30874 -166.947342) (xy 62.306454 -166.95674)
			(xy 62.29908 -166.983791) (xy 62.277449 -167.03552) (xy 62.248482 -167.083526) (xy 62.212804 -167.126779)
			(xy 62.171182 -167.164346) (xy 62.124511 -167.195419) (xy 62.073796 -167.21933) (xy 62.020129 -167.235564)
			(xy 61.964664 -167.243771) (xy 61.93663 -167.244268) (xy 61.909376 -167.243817) (xy 61.855423 -167.236063)
			(xy 61.803122 -167.220708) (xy 61.753539 -167.198067) (xy 61.707684 -167.168598) (xy 61.66649 -167.132903)
			(xy 61.630796 -167.091708) (xy 61.601329 -167.045852) (xy 61.578688 -166.996269) (xy 61.563335 -166.943968)
			(xy 61.555583 -166.890014) (xy 61.555122 -166.86276) (xy 49.05756 -166.86276) (xy 49.05756 -168.42232)
			(xy 63.19774 -168.42232) (xy 63.198205 -168.394745) (xy 63.206156 -168.340172) (xy 63.22188 -168.287311)
			(xy 63.24505 -168.237265) (xy 63.275183 -168.191076) (xy 63.311652 -168.149705) (xy 63.33236 -168.13149)
			(xy 63.340488 -168.123896) (xy 63.349834 -168.103738) (xy 63.350394 -168.092628) (xy 63.350394 -168.015412)
			(xy 63.349837 -168.004301) (xy 63.340491 -167.984142) (xy 63.33236 -167.97655) (xy 63.311662 -167.958325)
			(xy 63.275192 -167.916958) (xy 63.245059 -167.870771) (xy 63.221892 -167.820726) (xy 63.206172 -167.767866)
			(xy 63.198228 -167.713294) (xy 63.19774 -167.68572) (xy 63.198161 -167.659185) (xy 63.205502 -167.606625)
			(xy 63.22006 -167.555591) (xy 63.241552 -167.507068) (xy 63.269564 -167.461993) (xy 63.303555 -167.421238)
			(xy 63.342869 -167.385588) (xy 63.386745 -167.355734) (xy 63.410338 -167.343582) (xy 63.42126 -167.338248)
			(xy 63.43523 -167.31996) (xy 63.455804 -167.21709) (xy 63.449708 -167.194738) (xy 63.441834 -167.185594)
			(xy 63.424552 -167.165109) (xy 63.395397 -167.12014) (xy 63.372986 -167.071458) (xy 63.357783 -167.020066)
			(xy 63.350099 -166.967027) (xy 63.349632 -166.94023) (xy 63.350062 -166.913611) (xy 63.357636 -166.860913)
			(xy 63.372633 -166.809831) (xy 63.394748 -166.761403) (xy 63.423531 -166.716615) (xy 63.458395 -166.676381)
			(xy 63.498631 -166.641519) (xy 63.54342 -166.612738) (xy 63.591849 -166.590626) (xy 63.642933 -166.575631)
			(xy 63.695631 -166.568061) (xy 63.72225 -166.567612) (xy 63.748673 -166.568038) (xy 63.80099 -166.575495)
			(xy 63.851729 -166.590267) (xy 63.899873 -166.612058) (xy 63.944456 -166.640431) (xy 63.96482 -166.657274)
			(xy 63.971678 -166.66337) (xy 63.988696 -166.669466) (xy 64.073024 -166.669466) (xy 64.090042 -166.66337)
			(xy 64.0969 -166.657274) (xy 64.117266 -166.640435) (xy 64.161852 -166.61207) (xy 64.209996 -166.590283)
			(xy 64.260733 -166.575512) (xy 64.313048 -166.568052) (xy 64.365892 -166.568052) (xy 64.418207 -166.575512)
			(xy 64.468944 -166.590283) (xy 64.517088 -166.61207) (xy 64.561674 -166.640435) (xy 64.58204 -166.657274)
			(xy 64.588898 -166.66337) (xy 64.605916 -166.669466) (xy 64.690244 -166.669466) (xy 64.707262 -166.66337)
			(xy 64.71412 -166.657274) (xy 64.734487 -166.640438) (xy 64.779076 -166.61208) (xy 64.82722 -166.590299)
			(xy 64.877956 -166.575531) (xy 64.930269 -166.568072) (xy 64.95669 -166.567612) (xy 64.984579 -166.568046)
			(xy 65.039736 -166.576358) (xy 65.093037 -166.592798) (xy 65.143292 -166.616999) (xy 65.18938 -166.64842)
			(xy 65.230269 -166.686358) (xy 65.265047 -166.729968) (xy 65.292937 -166.778274) (xy 65.313316 -166.830197)
			(xy 65.325728 -166.884577) (xy 65.329897 -166.9402) (xy 65.325728 -166.995823) (xy 65.313316 -167.050203)
			(xy 65.292937 -167.102126) (xy 65.265047 -167.150432) (xy 65.230269 -167.194042) (xy 65.18938 -167.23198)
			(xy 65.143292 -167.263401) (xy 65.093037 -167.287602) (xy 65.039736 -167.304042) (xy 64.984579 -167.312354)
			(xy 64.95669 -167.312848) (xy 64.930269 -167.312385) (xy 64.877954 -167.304934) (xy 64.827216 -167.29017)
			(xy 64.779071 -167.268388) (xy 64.734486 -167.240024) (xy 64.71412 -167.223186) (xy 64.707262 -167.21709)
			(xy 64.690244 -167.210994) (xy 64.605916 -167.210994) (xy 64.588898 -167.21709) (xy 64.58204 -167.223186)
			(xy 64.561674 -167.240025) (xy 64.517088 -167.26839) (xy 64.468944 -167.290177) (xy 64.418207 -167.304948)
			(xy 64.365892 -167.312408) (xy 64.313048 -167.312408) (xy 64.260733 -167.304948) (xy 64.209996 -167.290177)
			(xy 64.161852 -167.26839) (xy 64.117266 -167.240025) (xy 64.0969 -167.223186) (xy 64.090042 -167.21709)
			(xy 64.073024 -167.210994) (xy 63.988696 -167.210994) (xy 63.971678 -167.21709) (xy 63.96482 -167.223186)
			(xy 63.947904 -167.23723) (xy 63.911358 -167.261676) (xy 63.891922 -167.271954) (xy 63.881254 -167.277542)
			(xy 63.867284 -167.296084) (xy 63.848234 -167.398954) (xy 63.854584 -167.421306) (xy 63.862712 -167.43045)
			(xy 63.881107 -167.451542) (xy 63.912082 -167.498155) (xy 63.935914 -167.548794) (xy 63.952091 -167.602371)
			(xy 63.960266 -167.657737) (xy 63.960756 -167.68572) (xy 63.960251 -167.713293) (xy 63.952308 -167.767865)
			(xy 63.936592 -167.820725) (xy 63.91343 -167.870771) (xy 63.883303 -167.916962) (xy 63.846841 -167.958334)
			(xy 63.826136 -167.97655) (xy 63.817989 -167.984126) (xy 63.808653 -168.004298) (xy 63.808102 -168.015412)
			(xy 63.808102 -168.092628) (xy 63.808638 -168.103742) (xy 63.817999 -168.1239) (xy 63.826136 -168.13149)
			(xy 63.846853 -168.149695) (xy 63.883321 -168.191066) (xy 63.913452 -168.237257) (xy 63.936616 -168.287306)
			(xy 63.952332 -168.34017) (xy 63.960271 -168.394745) (xy 63.960756 -168.42232) (xy 63.96027 -168.449571)
			(xy 63.952514 -168.503519) (xy 63.937159 -168.555814) (xy 63.914517 -168.605391) (xy 63.885051 -168.651241)
			(xy 63.84936 -168.692432) (xy 63.808169 -168.728123) (xy 63.762319 -168.757589) (xy 63.712742 -168.780231)
			(xy 63.660447 -168.795586) (xy 63.606499 -168.803342) (xy 63.551997 -168.803342) (xy 63.498049 -168.795586)
			(xy 63.445754 -168.780231) (xy 63.396177 -168.757589) (xy 63.350327 -168.728123) (xy 63.309136 -168.692432)
			(xy 63.273445 -168.651241) (xy 63.243979 -168.605391) (xy 63.221337 -168.555814) (xy 63.205982 -168.503519)
			(xy 63.198226 -168.449571) (xy 63.19774 -168.42232) (xy 49.05756 -168.42232) (xy 49.05756 -179.401978)
			(xy 49.05803 -179.411851) (xy 49.065484 -179.430138) (xy 49.072038 -179.437538) (xy 49.072292 -179.437792)
			(xy 51.009296 -181.374796) (xy 51.992528 -181.374796) (xy 51.996599 -181.319174) (xy 52.008725 -181.264737)
			(xy 52.028648 -181.212646) (xy 52.055944 -181.164011) (xy 52.09003 -181.119868) (xy 52.130179 -181.081159)
			(xy 52.175537 -181.048708) (xy 52.225137 -181.023207) (xy 52.277921 -181.0052) (xy 52.332764 -180.99507)
			(xy 52.388498 -180.993033) (xy 52.443935 -180.999133) (xy 52.497892 -181.013239) (xy 52.549221 -181.035051)
			(xy 52.596827 -181.064105) (xy 52.639695 -181.09978) (xy 52.676912 -181.141317) (xy 52.707685 -181.18783)
			(xy 52.731357 -181.238327) (xy 52.747425 -181.291734) (xy 52.755545 -181.34691) (xy 52.756054 -181.374796)
			(xy 53.008528 -181.374796) (xy 53.012599 -181.319174) (xy 53.024725 -181.264737) (xy 53.044648 -181.212646)
			(xy 53.071944 -181.164011) (xy 53.10603 -181.119868) (xy 53.146179 -181.081159) (xy 53.191537 -181.048708)
			(xy 53.241137 -181.023207) (xy 53.293921 -181.0052) (xy 53.348764 -180.99507) (xy 53.404498 -180.993033)
			(xy 53.459935 -180.999133) (xy 53.513892 -181.013239) (xy 53.565221 -181.035051) (xy 53.612827 -181.064105)
			(xy 53.655695 -181.09978) (xy 53.692912 -181.141317) (xy 53.723685 -181.18783) (xy 53.747357 -181.238327)
			(xy 53.763425 -181.291734) (xy 53.771545 -181.34691) (xy 53.772054 -181.374796) (xy 53.771545 -181.402682)
			(xy 53.763425 -181.457858) (xy 53.747357 -181.511265) (xy 53.723685 -181.561762) (xy 53.692912 -181.608275)
			(xy 53.655695 -181.649812) (xy 53.612827 -181.685487) (xy 53.565221 -181.714541) (xy 53.513892 -181.736353)
			(xy 53.459935 -181.750459) (xy 53.404498 -181.756559) (xy 53.348764 -181.754522) (xy 53.293921 -181.744392)
			(xy 53.241137 -181.726385) (xy 53.191537 -181.700884) (xy 53.146179 -181.668433) (xy 53.10603 -181.629724)
			(xy 53.071944 -181.585581) (xy 53.044648 -181.536946) (xy 53.024725 -181.484855) (xy 53.012599 -181.430418)
			(xy 53.008528 -181.374796) (xy 52.756054 -181.374796) (xy 52.755545 -181.402682) (xy 52.747425 -181.457858)
			(xy 52.731357 -181.511265) (xy 52.707685 -181.561762) (xy 52.676912 -181.608275) (xy 52.639695 -181.649812)
			(xy 52.596827 -181.685487) (xy 52.549221 -181.714541) (xy 52.497892 -181.736353) (xy 52.443935 -181.750459)
			(xy 52.388498 -181.756559) (xy 52.332764 -181.754522) (xy 52.277921 -181.744392) (xy 52.225137 -181.726385)
			(xy 52.175537 -181.700884) (xy 52.130179 -181.668433) (xy 52.09003 -181.629724) (xy 52.055944 -181.585581)
			(xy 52.028648 -181.536946) (xy 52.008725 -181.484855) (xy 51.996599 -181.430418) (xy 51.992528 -181.374796)
			(xy 51.009296 -181.374796) (xy 51.47691 -181.84241) (xy 56.55437 -181.84241) (xy 56.554869 -181.813492)
			(xy 56.563598 -181.756319) (xy 56.580858 -181.701118) (xy 56.606253 -181.649156) (xy 56.639202 -181.601623)
			(xy 56.678948 -181.559608) (xy 56.701436 -181.54142) (xy 56.71019 -181.533851) (xy 56.720376 -181.513097)
			(xy 56.720994 -181.501542) (xy 56.720994 -181.421278) (xy 56.720381 -181.409716) (xy 56.710217 -181.388944)
			(xy 56.701436 -181.3814) (xy 56.67896 -181.3632) (xy 56.639223 -181.321183) (xy 56.606282 -181.27365)
			(xy 56.580892 -181.221691) (xy 56.563634 -181.166494) (xy 56.554905 -181.109326) (xy 56.55437 -181.08041)
			(xy 56.554856 -181.053159) (xy 56.562612 -180.999211) (xy 56.577967 -180.946916) (xy 56.600609 -180.897339)
			(xy 56.630075 -180.851489) (xy 56.665766 -180.810298) (xy 56.706957 -180.774607) (xy 56.752807 -180.745141)
			(xy 56.802384 -180.722499) (xy 56.854679 -180.707144) (xy 56.908627 -180.699388) (xy 56.963129 -180.699388)
			(xy 57.017077 -180.707144) (xy 57.069372 -180.722499) (xy 57.118949 -180.745141) (xy 57.164799 -180.774607)
			(xy 57.20599 -180.810298) (xy 57.241681 -180.851489) (xy 57.271147 -180.897339) (xy 57.293789 -180.946916)
			(xy 57.309144 -180.999211) (xy 57.3169 -181.053159) (xy 57.317386 -181.08041) (xy 57.316809 -181.109325)
			(xy 57.308093 -181.166493) (xy 57.290847 -181.221691) (xy 57.265466 -181.273654) (xy 57.232533 -181.321189)
			(xy 57.192801 -181.363208) (xy 57.17032 -181.3814) (xy 57.161549 -181.388953) (xy 57.151374 -181.409719)
			(xy 57.150762 -181.421278) (xy 57.150762 -181.501542) (xy 57.151344 -181.513109) (xy 57.161528 -181.533881)
			(xy 57.17032 -181.54142) (xy 57.192817 -181.559595) (xy 57.232551 -181.601618) (xy 57.265487 -181.649157)
			(xy 57.290873 -181.701121) (xy 57.308127 -181.756321) (xy 57.316853 -181.813493) (xy 57.317386 -181.84241)
			(xy 57.3169 -181.869661) (xy 57.309144 -181.923609) (xy 57.293789 -181.975904) (xy 57.271147 -182.025481)
			(xy 57.241681 -182.071331) (xy 57.20599 -182.112522) (xy 57.164799 -182.148213) (xy 57.118949 -182.177679)
			(xy 57.069372 -182.200321) (xy 57.017077 -182.215676) (xy 56.963129 -182.223432) (xy 56.908627 -182.223432)
			(xy 56.854679 -182.215676) (xy 56.802384 -182.200321) (xy 56.752807 -182.177679) (xy 56.706957 -182.148213)
			(xy 56.665766 -182.112522) (xy 56.630075 -182.071331) (xy 56.600609 -182.025481) (xy 56.577967 -181.975904)
			(xy 56.562612 -181.923609) (xy 56.554856 -181.869661) (xy 56.55437 -181.84241) (xy 51.47691 -181.84241)
			(xy 52.687474 -183.052974) (xy 52.687982 -183.053482) (xy 52.695366 -183.060057) (xy 52.713665 -183.067492)
			(xy 52.723542 -183.06796) (xy 60.319158 -183.06796) (xy 60.329222 -183.068395) (xy 60.347806 -183.076131)
			(xy 60.355226 -183.082946) (xy 62.422278 -185.149998) (xy 62.430135 -185.15706) (xy 62.449815 -185.16468)
			(xy 62.460378 -185.16473) (xy 62.46241 -185.16473) (xy 62.550802 -185.157364) (xy 62.570106 -185.146442)
			(xy 62.57671 -185.137298) (xy 62.59957 -185.108342) (xy 62.605666 -185.10123) (xy 62.612016 -185.084466)
			(xy 62.612016 -184.998614) (xy 62.605666 -184.98185) (xy 62.59957 -184.974738) (xy 62.581925 -184.953806)
			(xy 62.552191 -184.907838) (xy 62.529337 -184.858091) (xy 62.513834 -184.805586) (xy 62.506 -184.751403)
			(xy 62.505995 -184.696657) (xy 62.513821 -184.642473) (xy 62.529316 -184.589966) (xy 62.552162 -184.540215)
			(xy 62.581888 -184.494242) (xy 62.59957 -184.473342) (xy 62.605666 -184.46623) (xy 62.612016 -184.449466)
			(xy 62.612016 -184.363614) (xy 62.605666 -184.34685) (xy 62.59957 -184.339738) (xy 62.581925 -184.318806)
			(xy 62.552191 -184.272838) (xy 62.529337 -184.223091) (xy 62.513834 -184.170586) (xy 62.506 -184.116403)
			(xy 62.505995 -184.061657) (xy 62.513821 -184.007473) (xy 62.529316 -183.954966) (xy 62.552162 -183.905215)
			(xy 62.581888 -183.859242) (xy 62.59957 -183.838342) (xy 62.605666 -183.83123) (xy 62.612016 -183.814466)
			(xy 62.612016 -183.728614) (xy 62.605666 -183.71185) (xy 62.59957 -183.704738) (xy 62.581925 -183.683806)
			(xy 62.552191 -183.637838) (xy 62.529337 -183.588091) (xy 62.513834 -183.535586) (xy 62.506 -183.481403)
			(xy 62.505995 -183.426657) (xy 62.513821 -183.372473) (xy 62.529316 -183.319966) (xy 62.552162 -183.270215)
			(xy 62.581888 -183.224242) (xy 62.59957 -183.203342) (xy 62.605666 -183.19623) (xy 62.612016 -183.179466)
			(xy 62.612016 -183.093614) (xy 62.605666 -183.07685) (xy 62.59957 -183.069738) (xy 62.581925 -183.048806)
			(xy 62.552191 -183.002838) (xy 62.529337 -182.953091) (xy 62.513834 -182.900586) (xy 62.506 -182.846403)
			(xy 62.505995 -182.791657) (xy 62.513821 -182.737473) (xy 62.529316 -182.684966) (xy 62.552162 -182.635215)
			(xy 62.581888 -182.589242) (xy 62.59957 -182.568342) (xy 62.605666 -182.56123) (xy 62.612016 -182.544466)
			(xy 62.612016 -182.458614) (xy 62.605666 -182.44185) (xy 62.59957 -182.434738) (xy 62.581925 -182.413806)
			(xy 62.552191 -182.367838) (xy 62.529337 -182.318091) (xy 62.513834 -182.265586) (xy 62.506 -182.211403)
			(xy 62.505995 -182.156657) (xy 62.513821 -182.102473) (xy 62.529316 -182.049966) (xy 62.552162 -182.000215)
			(xy 62.581888 -181.954242) (xy 62.59957 -181.933342) (xy 62.605666 -181.92623) (xy 62.612016 -181.909466)
			(xy 62.612016 -181.823614) (xy 62.605666 -181.80685) (xy 62.59957 -181.799738) (xy 62.581933 -181.778805)
			(xy 62.552217 -181.732836) (xy 62.529383 -181.683089) (xy 62.513903 -181.630586) (xy 62.506094 -181.576409)
			(xy 62.50559 -181.54904) (xy 62.506088 -181.521367) (xy 62.514099 -181.466604) (xy 62.529942 -181.413574)
			(xy 62.553285 -181.363392) (xy 62.583638 -181.317112) (xy 62.601602 -181.296056) (xy 62.607698 -181.289198)
			(xy 62.611 -181.280308) (xy 62.612546 -181.275961) (xy 62.614213 -181.266887) (xy 62.614302 -181.262274)
			(xy 62.614302 -181.194964) (xy 62.614199 -181.190352) (xy 62.612535 -181.18128) (xy 62.611 -181.17693)
			(xy 62.607698 -181.16804) (xy 62.601602 -181.161182) (xy 62.583607 -181.14015) (xy 62.553251 -181.093866)
			(xy 62.529907 -181.043678) (xy 62.514067 -180.990642) (xy 62.506062 -180.935873) (xy 62.50559 -180.908198)
			(xy 62.506076 -180.880947) (xy 62.513833 -180.826999) (xy 62.529188 -180.774705) (xy 62.551829 -180.725127)
			(xy 62.581295 -180.679277) (xy 62.616987 -180.638087) (xy 62.658177 -180.602395) (xy 62.704027 -180.572929)
			(xy 62.753605 -180.550288) (xy 62.805899 -180.534933) (xy 62.859847 -180.527176) (xy 62.887098 -180.52669)
			(xy 62.914468 -180.527162) (xy 62.968647 -180.534985) (xy 63.021151 -180.550471) (xy 63.070902 -180.573303)
			(xy 63.11688 -180.603011) (xy 63.137796 -180.62067) (xy 63.144908 -180.626766) (xy 63.161672 -180.633116)
			(xy 63.247524 -180.633116) (xy 63.264288 -180.626766) (xy 63.2714 -180.62067) (xy 63.292333 -180.603029)
			(xy 63.338301 -180.573305) (xy 63.388047 -180.550459) (xy 63.440549 -180.534963) (xy 63.494727 -180.527134)
			(xy 63.549469 -180.527134) (xy 63.603647 -180.534963) (xy 63.656149 -180.550459) (xy 63.705895 -180.573305)
			(xy 63.751863 -180.603029) (xy 63.772796 -180.62067) (xy 63.779908 -180.626766) (xy 63.796672 -180.633116)
			(xy 63.882524 -180.633116) (xy 63.899288 -180.626766) (xy 63.9064 -180.62067) (xy 63.927332 -180.603029)
			(xy 63.973299 -180.573306) (xy 64.023046 -180.550464) (xy 64.075549 -180.534975) (xy 64.129728 -180.527157)
			(xy 64.157098 -180.52669) (xy 64.184349 -180.527176) (xy 64.238297 -180.534932) (xy 64.290593 -180.550287)
			(xy 64.34017 -180.572928) (xy 64.386021 -180.602394) (xy 64.427212 -180.638086) (xy 64.462904 -180.679276)
			(xy 64.49237 -180.725126) (xy 64.515012 -180.774704) (xy 64.530367 -180.826999) (xy 64.538124 -180.880947)
			(xy 64.538606 -180.908198) (xy 64.53814 -180.935497) (xy 64.530359 -180.989538) (xy 64.514956 -181.041919)
			(xy 64.492244 -181.091569) (xy 64.462688 -181.137476) (xy 64.445134 -181.158388) (xy 64.439038 -181.1655)
			(xy 64.432688 -181.182264) (xy 64.432688 -181.267862) (xy 64.439038 -181.28488) (xy 64.445134 -181.291992)
			(xy 64.462854 -181.312948) (xy 64.492721 -181.358986) (xy 64.515683 -181.40883) (xy 64.531264 -181.461449)
			(xy 64.539143 -181.515759) (xy 64.539622 -181.543198) (xy 64.539151 -181.570568) (xy 64.531328 -181.624747)
			(xy 64.515842 -181.677251) (xy 64.493011 -181.727004) (xy 64.463303 -181.772982) (xy 64.445642 -181.793896)
			(xy 64.439546 -181.801008) (xy 64.433196 -181.817772) (xy 64.433196 -181.903624) (xy 64.439546 -181.920388)
			(xy 64.445642 -181.9275) (xy 64.463284 -181.948432) (xy 64.493012 -181.994399) (xy 64.515859 -182.044146)
			(xy 64.531357 -182.096648) (xy 64.539186 -182.150827) (xy 64.539187 -182.20557) (xy 64.531358 -182.259749)
			(xy 64.51586 -182.312252) (xy 64.493013 -182.361998) (xy 64.463286 -182.407965) (xy 64.445642 -182.428896)
			(xy 64.439546 -182.436008) (xy 64.433196 -182.452772) (xy 64.433196 -182.538624) (xy 64.439546 -182.555388)
			(xy 64.445642 -182.5625) (xy 64.463284 -182.583432) (xy 64.493012 -182.629399) (xy 64.515859 -182.679146)
			(xy 64.531357 -182.731648) (xy 64.539186 -182.785827) (xy 64.539187 -182.84057) (xy 64.531358 -182.894749)
			(xy 64.51586 -182.947252) (xy 64.493013 -182.996998) (xy 64.463286 -183.042965) (xy 64.445642 -183.063896)
			(xy 64.439546 -183.071008) (xy 64.433196 -183.087772) (xy 64.433196 -183.173624) (xy 64.439546 -183.190388)
			(xy 64.445642 -183.1975) (xy 64.463286 -183.21843) (xy 64.493017 -183.264395) (xy 64.515864 -183.314142)
			(xy 64.531356 -183.366646) (xy 64.539176 -183.420827) (xy 64.539622 -183.448198) (xy 64.53912 -183.47593)
			(xy 64.531089 -183.530811) (xy 64.51521 -183.583954) (xy 64.491817 -183.634245) (xy 64.461401 -183.680626)
			(xy 64.443356 -183.70169) (xy 64.437006 -183.708548) (xy 64.433704 -183.717438) (xy 64.432162 -183.721786)
			(xy 64.430503 -183.73086) (xy 64.430402 -183.735472) (xy 64.430148 -183.811926) (xy 64.436752 -183.829198)
			(xy 64.442848 -183.83631) (xy 64.460791 -183.857338) (xy 64.491056 -183.903595) (xy 64.514333 -183.953733)
			(xy 64.530135 -184.006705) (xy 64.538131 -184.061401) (xy 64.538606 -184.08904) (xy 64.538131 -184.116409)
			(xy 64.530303 -184.170585) (xy 64.514811 -184.223085) (xy 64.491976 -184.272833) (xy 64.462265 -184.318806)
			(xy 64.444626 -184.339738) (xy 64.43853 -184.34685) (xy 64.43218 -184.363614) (xy 64.43218 -184.449466)
			(xy 64.43853 -184.46623) (xy 64.444626 -184.473342) (xy 64.462266 -184.494274) (xy 64.491988 -184.54024)
			(xy 64.514831 -184.589984) (xy 64.530324 -184.642484) (xy 64.538149 -184.696661) (xy 64.538145 -184.751399)
			(xy 64.530311 -184.805575) (xy 64.51481 -184.858072) (xy 64.491959 -184.907813) (xy 64.462229 -184.953774)
			(xy 64.444626 -184.974738) (xy 64.43853 -184.98185) (xy 64.43218 -184.998614) (xy 64.43218 -185.084466)
			(xy 64.43853 -185.10123) (xy 64.444626 -185.108342) (xy 64.462265 -185.129275) (xy 64.491984 -185.175243)
			(xy 64.51482 -185.22499) (xy 64.530303 -185.277493) (xy 64.538115 -185.331671) (xy 64.538606 -185.35904)
			(xy 64.538117 -185.386289) (xy 64.530356 -185.440233) (xy 64.514998 -185.492522) (xy 64.492354 -185.542095)
			(xy 64.462887 -185.58794) (xy 64.427195 -185.629125) (xy 64.386006 -185.664812) (xy 64.340158 -185.694274)
			(xy 64.290583 -185.716912) (xy 64.238292 -185.732265) (xy 64.184347 -185.74002) (xy 64.157098 -185.740548)
			(xy 64.129728 -185.740076) (xy 64.075551 -185.732251) (xy 64.023049 -185.716762) (xy 63.973299 -185.693927)
			(xy 63.927325 -185.664216) (xy 63.9064 -185.646568) (xy 63.899288 -185.640472) (xy 63.882524 -185.634122)
			(xy 63.796672 -185.634122) (xy 63.779908 -185.640472) (xy 63.772796 -185.646568) (xy 63.751863 -185.664209)
			(xy 63.705895 -185.693933) (xy 63.656149 -185.716779) (xy 63.603647 -185.732275) (xy 63.549469 -185.740104)
			(xy 63.494727 -185.740104) (xy 63.440549 -185.732275) (xy 63.388047 -185.716779) (xy 63.338301 -185.693933)
			(xy 63.292333 -185.664209) (xy 63.2714 -185.646568) (xy 63.264288 -185.640472) (xy 63.247524 -185.634122)
			(xy 63.161672 -185.634122) (xy 63.144908 -185.640472) (xy 63.137796 -185.646568) (xy 63.10884 -185.669428)
			(xy 63.099696 -185.676032) (xy 63.088774 -185.695336) (xy 63.081408 -185.783728) (xy 63.081408 -185.78576)
			(xy 63.081451 -185.796329) (xy 63.08905 -185.816024) (xy 63.09614 -185.82386) (xy 64.53632 -187.26404)
			(xy 66.49339 -187.26404) (xy 66.493882 -187.236671) (xy 66.501694 -187.182493) (xy 66.517177 -187.12999)
			(xy 66.540013 -187.080243) (xy 66.569732 -187.034275) (xy 66.58737 -187.013342) (xy 66.593466 -187.00623)
			(xy 66.599816 -186.989212) (xy 66.599816 -186.903868) (xy 66.593466 -186.88685) (xy 66.58737 -186.879738)
			(xy 66.569767 -186.858774) (xy 66.540037 -186.812813) (xy 66.517187 -186.763072) (xy 66.501685 -186.710574)
			(xy 66.493852 -186.656399) (xy 66.493848 -186.601661) (xy 66.501673 -186.547485) (xy 66.517165 -186.494984)
			(xy 66.540008 -186.44524) (xy 66.56973 -186.399274) (xy 66.58737 -186.378342) (xy 66.593466 -186.37123)
			(xy 66.599816 -186.354212) (xy 66.599816 -186.268868) (xy 66.593466 -186.25185) (xy 66.58737 -186.244738)
			(xy 66.569767 -186.223774) (xy 66.540037 -186.177813) (xy 66.517187 -186.128072) (xy 66.501685 -186.075574)
			(xy 66.493852 -186.021399) (xy 66.493848 -185.966661) (xy 66.501673 -185.912485) (xy 66.517165 -185.859984)
			(xy 66.540008 -185.81024) (xy 66.56973 -185.764274) (xy 66.58737 -185.743342) (xy 66.593466 -185.73623)
			(xy 66.599816 -185.719212) (xy 66.599816 -185.633868) (xy 66.593466 -185.61685) (xy 66.58737 -185.609738)
			(xy 66.569767 -185.588774) (xy 66.540037 -185.542813) (xy 66.517187 -185.493072) (xy 66.501685 -185.440574)
			(xy 66.493852 -185.386399) (xy 66.493848 -185.331661) (xy 66.501673 -185.277485) (xy 66.517165 -185.224984)
			(xy 66.540008 -185.17524) (xy 66.56973 -185.129274) (xy 66.58737 -185.108342) (xy 66.593466 -185.10123)
			(xy 66.599816 -185.084212) (xy 66.599816 -184.998868) (xy 66.593466 -184.98185) (xy 66.58737 -184.974738)
			(xy 66.569767 -184.953774) (xy 66.540037 -184.907813) (xy 66.517187 -184.858072) (xy 66.501685 -184.805574)
			(xy 66.493852 -184.751399) (xy 66.493848 -184.696661) (xy 66.501673 -184.642485) (xy 66.517165 -184.589984)
			(xy 66.540008 -184.54024) (xy 66.56973 -184.494274) (xy 66.58737 -184.473342) (xy 66.593466 -184.46623)
			(xy 66.599816 -184.449212) (xy 66.599816 -184.363868) (xy 66.593466 -184.34685) (xy 66.58737 -184.339738)
			(xy 66.569731 -184.318806) (xy 66.54002 -184.272833) (xy 66.517184 -184.223085) (xy 66.501693 -184.170585)
			(xy 66.493865 -184.116409) (xy 66.49339 -184.08904) (xy 66.493912 -184.059765) (xy 66.502886 -184.001906)
			(xy 66.520598 -183.946099) (xy 66.546633 -183.893655) (xy 66.580377 -183.845807) (xy 66.600324 -183.824372)
			(xy 66.606674 -183.817514) (xy 66.61404 -183.800496) (xy 66.617596 -183.71439) (xy 66.611754 -183.696864)
			(xy 66.605912 -183.689498) (xy 66.589705 -183.668984) (xy 66.562446 -183.624372) (xy 66.541541 -183.576454)
			(xy 66.527383 -183.526127) (xy 66.520237 -183.474338) (xy 66.519806 -183.448198) (xy 66.520269 -183.420828)
			(xy 66.528088 -183.366648) (xy 66.543577 -183.314145) (xy 66.56642 -183.264398) (xy 66.596145 -183.218432)
			(xy 66.613786 -183.1975) (xy 66.619882 -183.190388) (xy 66.626232 -183.17337) (xy 66.626232 -183.088026)
			(xy 66.619882 -183.071008) (xy 66.613786 -183.063896) (xy 66.596145 -183.042964) (xy 66.566423 -182.996995)
			(xy 66.543581 -182.947248) (xy 66.528086 -182.894747) (xy 66.520259 -182.840569) (xy 66.520259 -182.785828)
			(xy 66.528087 -182.73165) (xy 66.543582 -182.679149) (xy 66.566425 -182.629402) (xy 66.596147 -182.583434)
			(xy 66.613786 -182.5625) (xy 66.619882 -182.555388) (xy 66.626232 -182.53837) (xy 66.626232 -182.453026)
			(xy 66.619882 -182.436008) (xy 66.613786 -182.428896) (xy 66.596145 -182.407964) (xy 66.566423 -182.361995)
			(xy 66.543581 -182.312248) (xy 66.528086 -182.259747) (xy 66.520259 -182.205569) (xy 66.520259 -182.150828)
			(xy 66.528087 -182.09665) (xy 66.543582 -182.044149) (xy 66.566425 -181.994402) (xy 66.596147 -181.948434)
			(xy 66.613786 -181.9275) (xy 66.619882 -181.920388) (xy 66.626232 -181.90337) (xy 66.626232 -181.818026)
			(xy 66.619882 -181.801008) (xy 66.613786 -181.793896) (xy 66.596129 -181.772978) (xy 66.566421 -181.727001)
			(xy 66.543588 -181.67725) (xy 66.528101 -181.624746) (xy 66.520278 -181.570568) (xy 66.519806 -181.543198)
			(xy 66.520287 -181.515899) (xy 66.528059 -181.461858) (xy 66.543458 -181.409477) (xy 66.56617 -181.359827)
			(xy 66.595729 -181.313924) (xy 66.613278 -181.293008) (xy 66.619628 -181.285896) (xy 66.625724 -181.268878)
			(xy 66.625724 -181.18328) (xy 66.619374 -181.166516) (xy 66.613278 -181.159404) (xy 66.595563 -181.138444)
			(xy 66.565685 -181.092411) (xy 66.542719 -181.042569) (xy 66.527139 -180.989949) (xy 66.519268 -180.935637)
			(xy 66.51879 -180.908198) (xy 66.519276 -180.880947) (xy 66.527033 -180.826999) (xy 66.542388 -180.774705)
			(xy 66.565029 -180.725127) (xy 66.594495 -180.679277) (xy 66.630187 -180.638087) (xy 66.671377 -180.602395)
			(xy 66.717227 -180.572929) (xy 66.766805 -180.550288) (xy 66.819099 -180.534933) (xy 66.873047 -180.527176)
			(xy 66.900298 -180.52669) (xy 66.927668 -180.52716) (xy 66.981847 -180.534977) (xy 67.03435 -180.550465)
			(xy 67.084097 -180.573306) (xy 67.130064 -180.603029) (xy 67.150996 -180.62067) (xy 67.158108 -180.626766)
			(xy 67.175126 -180.633116) (xy 67.26047 -180.633116) (xy 67.277488 -180.626766) (xy 67.2846 -180.62067)
			(xy 67.305517 -180.603013) (xy 67.351495 -180.573305) (xy 67.401246 -180.550473) (xy 67.45375 -180.534986)
			(xy 67.507928 -180.527162) (xy 67.535298 -180.52669) (xy 67.562549 -180.52718) (xy 67.616497 -180.534936)
			(xy 67.668791 -180.550291) (xy 67.718368 -180.572931) (xy 67.764219 -180.602397) (xy 67.805409 -180.638088)
			(xy 67.8411 -180.679278) (xy 67.870567 -180.725128) (xy 67.893208 -180.774705) (xy 67.908563 -180.826999)
			(xy 67.91632 -180.880947) (xy 67.916806 -180.908198) (xy 67.916319 -180.935497) (xy 67.908548 -180.989538)
			(xy 67.89315 -181.041918) (xy 67.87044 -181.091568) (xy 67.840882 -181.137472) (xy 67.823334 -181.158388)
			(xy 67.816984 -181.1655) (xy 67.810888 -181.182518) (xy 67.810888 -181.268116) (xy 67.817238 -181.28488)
			(xy 67.823334 -181.291992) (xy 67.841049 -181.312952) (xy 67.870927 -181.358985) (xy 67.893892 -181.408827)
			(xy 67.909472 -181.461448) (xy 67.917344 -181.515759) (xy 67.917822 -181.543198) (xy 67.917374 -181.570569)
			(xy 67.909555 -181.62475) (xy 67.894062 -181.677254) (xy 67.871216 -181.727) (xy 67.841486 -181.772966)
			(xy 67.823842 -181.793896) (xy 67.817746 -181.801008) (xy 67.811396 -181.818026) (xy 67.811396 -181.90337)
			(xy 67.817746 -181.920388) (xy 67.823842 -181.9275) (xy 67.841482 -181.948434) (xy 67.871209 -181.994401)
			(xy 67.894057 -182.044146) (xy 67.909554 -182.096649) (xy 67.917384 -182.150828) (xy 67.917384 -182.205569)
			(xy 67.914806 -182.22341) (xy 68.111624 -182.22341) (xy 68.111624 -173.56201) (xy 68.112133 -173.532037)
			(xy 68.121456 -173.472821) (xy 68.139938 -173.415795) (xy 68.167122 -173.362368) (xy 68.202337 -173.313857)
			(xy 68.22313 -173.292262) (xy 69.290438 -172.225208) (xy 69.297272 -172.217804) (xy 69.304994 -172.199208)
			(xy 69.305424 -172.18914) (xy 69.305424 -168.454324) (xy 69.305006 -168.444253) (xy 69.297282 -168.425654)
			(xy 69.290438 -168.418256) (xy 69.060822 -168.188894) (xy 69.040082 -168.167256) (xy 69.004894 -168.118741)
			(xy 68.977722 -168.065322) (xy 68.959236 -168.008312) (xy 68.949891 -167.949112) (xy 68.949316 -167.919146)
			(xy 68.949795 -167.891235) (xy 68.957936 -167.836009) (xy 68.974035 -167.782559) (xy 68.997751 -167.732025)
			(xy 69.028575 -167.685485) (xy 69.046852 -167.664384) (xy 69.053202 -167.657272) (xy 69.059806 -167.64)
			(xy 69.059806 -167.553132) (xy 69.053202 -167.53586) (xy 69.046852 -167.528748) (xy 69.02851 -167.507657)
			(xy 68.997605 -167.461082) (xy 68.973831 -167.410494) (xy 68.957696 -167.356978) (xy 68.949547 -167.30168)
			(xy 68.949062 -167.273732) (xy 68.949548 -167.246481) (xy 68.957304 -167.192533) (xy 68.972659 -167.140238)
			(xy 68.995301 -167.090661) (xy 69.024767 -167.044811) (xy 69.060458 -167.00362) (xy 69.101649 -166.967929)
			(xy 69.147499 -166.938463) (xy 69.197076 -166.915821) (xy 69.249371 -166.900466) (xy 69.303319 -166.89271)
			(xy 69.357821 -166.89271) (xy 69.411769 -166.900466) (xy 69.464064 -166.915821) (xy 69.513641 -166.938463)
			(xy 69.559491 -166.967929) (xy 69.600682 -167.00362) (xy 69.636373 -167.044811) (xy 69.665839 -167.090661)
			(xy 69.688481 -167.140238) (xy 69.703836 -167.192533) (xy 69.711592 -167.246481) (xy 69.712078 -167.273732)
			(xy 69.711519 -167.303856) (xy 69.702034 -167.363352) (xy 69.68332 -167.42062) (xy 69.655842 -167.474237)
			(xy 69.620282 -167.522871) (xy 69.599302 -167.544496) (xy 69.592471 -167.551904) (xy 69.584746 -167.570497)
			(xy 69.584316 -167.580564) (xy 69.584316 -167.612568) (xy 69.584754 -167.622636) (xy 69.592465 -167.641234)
			(xy 69.599302 -167.648636) (xy 69.600318 -167.649398) (xy 69.956426 -168.005506) (xy 69.977157 -168.027153)
			(xy 70.012349 -168.075664) (xy 70.039523 -168.129081) (xy 70.058011 -168.18609) (xy 70.067357 -168.245288)
			(xy 70.067932 -168.275254) (xy 70.067932 -172.36821) (xy 70.06742 -172.398183) (xy 70.058095 -172.457398)
			(xy 70.039613 -172.514423) (xy 70.012431 -172.56785) (xy 69.977218 -172.616363) (xy 69.956426 -172.637958)
			(xy 68.889118 -173.705012) (xy 68.882283 -173.712416) (xy 68.874559 -173.731012) (xy 68.874132 -173.74108)
			(xy 68.874132 -175.559974) (xy 69.868542 -175.559974) (xy 69.869044 -175.532401) (xy 69.876987 -175.477829)
			(xy 69.892704 -175.424969) (xy 69.915867 -175.374922) (xy 69.945994 -175.328732) (xy 69.982457 -175.28736)
			(xy 70.003162 -175.269144) (xy 70.011266 -175.261529) (xy 70.020626 -175.241386) (xy 70.021196 -175.230282)
			(xy 70.021196 -175.153066) (xy 70.020664 -175.141952) (xy 70.0113 -175.121793) (xy 70.003162 -175.114204)
			(xy 69.982428 -175.096018) (xy 69.945959 -175.054645) (xy 69.915827 -175.008452) (xy 69.892662 -174.958401)
			(xy 69.876946 -174.905536) (xy 69.869006 -174.850959) (xy 69.869009 -174.795807) (xy 69.876953 -174.741231)
			(xy 69.892674 -174.688367) (xy 69.915844 -174.638318) (xy 69.945979 -174.592128) (xy 69.982452 -174.550758)
			(xy 70.003162 -174.532544) (xy 70.011266 -174.524929) (xy 70.020626 -174.504786) (xy 70.021196 -174.493682)
			(xy 70.021196 -174.416466) (xy 70.020664 -174.405352) (xy 70.0113 -174.385193) (xy 70.003162 -174.377604)
			(xy 69.982442 -174.359403) (xy 69.945974 -174.318031) (xy 69.915844 -174.271839) (xy 69.89268 -174.221789)
			(xy 69.876965 -174.168925) (xy 69.869027 -174.114349) (xy 69.868542 -174.086774) (xy 69.868931 -174.059518)
			(xy 69.876693 -174.005562) (xy 69.892055 -173.95326) (xy 69.914704 -173.903676) (xy 69.944179 -173.857821)
			(xy 69.979881 -173.816627) (xy 70.021081 -173.780934) (xy 70.066943 -173.751467) (xy 70.116531 -173.728828)
			(xy 70.168836 -173.713476) (xy 70.222794 -173.705725) (xy 70.25005 -173.705266) (xy 70.277905 -173.705769)
			(xy 70.333021 -173.713899) (xy 70.38637 -173.72995) (xy 70.436822 -173.75358) (xy 70.483305 -173.78429)
			(xy 70.524834 -173.821426) (xy 70.560527 -173.864202) (xy 70.589627 -173.91171) (xy 70.611517 -173.962941)
			(xy 70.619112 -173.989746) (xy 70.621398 -173.998636) (xy 70.632066 -174.013876) (xy 70.703948 -174.061628)
			(xy 70.721982 -174.065692) (xy 70.731126 -174.064422) (xy 70.744142 -174.062752) (xy 70.770327 -174.060973)
			(xy 70.78345 -174.060866) (xy 70.797599 -174.060965) (xy 70.825822 -174.062996) (xy 70.839838 -174.06493)
			(xy 70.849998 -174.066454) (xy 70.869556 -174.061628) (xy 70.943978 -174.005748) (xy 70.954138 -173.988222)
			(xy 70.955408 -173.978062) (xy 70.959477 -173.950905) (xy 70.974451 -173.898073) (xy 70.996843 -173.847933)
			(xy 71.026193 -173.801521) (xy 71.061892 -173.759796) (xy 71.103204 -173.72362) (xy 71.149276 -173.693739)
			(xy 71.199155 -173.670772) (xy 71.251811 -173.655192) (xy 71.306158 -173.647322) (xy 71.333614 -173.646846)
			(xy 71.360864 -173.647365) (xy 71.414808 -173.655122) (xy 71.467099 -173.670476) (xy 71.516673 -173.693116)
			(xy 71.562521 -173.722579) (xy 71.60371 -173.758267) (xy 71.639401 -173.799453) (xy 71.668869 -173.845299)
			(xy 71.691512 -173.894871) (xy 71.706871 -173.947161) (xy 71.714633 -174.001105) (xy 71.715122 -174.028354)
			(xy 71.714617 -174.055927) (xy 71.706671 -174.110498) (xy 71.690954 -174.163357) (xy 71.667791 -174.213403)
			(xy 71.637666 -174.259593) (xy 71.601206 -174.300967) (xy 71.580502 -174.319184) (xy 71.572395 -174.326797)
			(xy 71.563034 -174.346941) (xy 71.562468 -174.358046) (xy 71.562468 -174.435262) (xy 71.563019 -174.446374)
			(xy 71.572367 -174.466534) (xy 71.580502 -174.474124) (xy 71.601228 -174.492319) (xy 71.637697 -174.533691)
			(xy 71.667828 -174.579884) (xy 71.690991 -174.629936) (xy 71.706704 -174.682801) (xy 71.714639 -174.737378)
			(xy 71.714673 -174.7393) (xy 76.30363 -174.7393) (xy 76.307701 -174.683678) (xy 76.319827 -174.629241)
			(xy 76.33975 -174.57715) (xy 76.367046 -174.528515) (xy 76.401132 -174.484372) (xy 76.441281 -174.445663)
			(xy 76.486639 -174.413212) (xy 76.536239 -174.387711) (xy 76.589023 -174.369704) (xy 76.643866 -174.359574)
			(xy 76.6996 -174.357537) (xy 76.755037 -174.363637) (xy 76.808994 -174.377743) (xy 76.860323 -174.399555)
			(xy 76.907929 -174.428609) (xy 76.950797 -174.464284) (xy 76.988014 -174.505821) (xy 77.018787 -174.552334)
			(xy 77.042459 -174.602831) (xy 77.058527 -174.656238) (xy 77.066647 -174.711414) (xy 77.067156 -174.7393)
			(xy 77.066647 -174.767186) (xy 77.058527 -174.822362) (xy 77.042459 -174.875769) (xy 77.018787 -174.926266)
			(xy 76.988014 -174.972779) (xy 76.950797 -175.014316) (xy 76.907929 -175.049991) (xy 76.860323 -175.079045)
			(xy 76.808994 -175.100857) (xy 76.755037 -175.114963) (xy 76.6996 -175.121063) (xy 76.643866 -175.119026)
			(xy 76.589023 -175.108896) (xy 76.536239 -175.090889) (xy 76.486639 -175.065388) (xy 76.441281 -175.032937)
			(xy 76.401132 -174.994228) (xy 76.367046 -174.950085) (xy 76.33975 -174.90145) (xy 76.319827 -174.849359)
			(xy 76.307701 -174.794922) (xy 76.30363 -174.7393) (xy 71.714673 -174.7393) (xy 71.715122 -174.764954)
			(xy 71.714602 -174.792205) (xy 71.706852 -174.846153) (xy 71.691502 -174.898449) (xy 71.668866 -174.948028)
			(xy 71.639404 -174.993881) (xy 71.603716 -175.035074) (xy 71.562529 -175.070768) (xy 71.516681 -175.100237)
			(xy 71.467105 -175.122881) (xy 71.414812 -175.138239) (xy 71.360865 -175.145998) (xy 71.333614 -175.146462)
			(xy 71.299324 -175.144938) (xy 71.289164 -175.143922) (xy 71.26986 -175.150018) (xy 71.199248 -175.2092)
			(xy 71.18985 -175.227234) (xy 71.188834 -175.237394) (xy 71.185902 -175.265569) (xy 71.172723 -175.32066)
			(xy 71.151539 -175.373196) (xy 71.122818 -175.422021) (xy 71.087191 -175.466061) (xy 71.045443 -175.504346)
			(xy 70.99849 -175.536036) (xy 70.947366 -175.560432) (xy 70.893197 -175.576997) (xy 70.837173 -175.585369)
			(xy 70.80885 -175.585882) (xy 70.790831 -175.585663) (xy 70.754956 -175.582227) (xy 70.737222 -175.579024)
			(xy 70.727824 -175.577246) (xy 70.708774 -175.581056) (xy 70.63359 -175.628808) (xy 70.62216 -175.644556)
			(xy 70.619874 -175.653954) (xy 70.612491 -175.681002) (xy 70.59086 -175.732729) (xy 70.561894 -175.780735)
			(xy 70.526216 -175.823987) (xy 70.484595 -175.861553) (xy 70.437926 -175.892627) (xy 70.387213 -175.916539)
			(xy 70.333547 -175.932774) (xy 70.278084 -175.940984) (xy 70.25005 -175.941482) (xy 70.222797 -175.940998)
			(xy 70.168846 -175.933247) (xy 70.116547 -175.917896) (xy 70.066965 -175.895258) (xy 70.02111 -175.865792)
			(xy 69.979916 -175.830101) (xy 69.944222 -175.788909) (xy 69.914754 -175.743056) (xy 69.892112 -175.693476)
			(xy 69.876758 -175.641178) (xy 69.869004 -175.587227) (xy 69.868542 -175.559974) (xy 68.874132 -175.559974)
			(xy 68.874132 -177.10912) (xy 71.51116 -177.10912) (xy 71.511618 -177.081545) (xy 71.51957 -177.026971)
			(xy 71.535295 -176.97411) (xy 71.558466 -176.924064) (xy 71.588601 -176.877874) (xy 71.625071 -176.836505)
			(xy 71.64578 -176.81829) (xy 71.653911 -176.8107) (xy 71.663255 -176.790538) (xy 71.663814 -176.779428)
			(xy 71.663814 -176.702212) (xy 71.663283 -176.691097) (xy 71.653921 -176.670937) (xy 71.64578 -176.66335)
			(xy 71.625086 -176.645121) (xy 71.588615 -176.603755) (xy 71.558481 -176.557569) (xy 71.535313 -176.507525)
			(xy 71.519592 -176.454666) (xy 71.511648 -176.400094) (xy 71.51116 -176.37252) (xy 71.51163 -176.346404)
			(xy 71.518765 -176.294662) (xy 71.53289 -176.244376) (xy 71.553741 -176.196487) (xy 71.58093 -176.151889)
			(xy 71.613946 -176.111416) (xy 71.652175 -176.075824) (xy 71.6949 -176.045779) (xy 71.717916 -176.03343)
			(xy 71.72833 -176.028096) (xy 71.7423 -176.009808) (xy 71.76262 -175.909224) (xy 71.757032 -175.886872)
			(xy 71.749666 -175.877982) (xy 71.733387 -175.857795) (xy 71.705983 -175.81377) (xy 71.684951 -175.766368)
			(xy 71.670699 -175.716507) (xy 71.663502 -175.665151) (xy 71.663052 -175.639222) (xy 71.663577 -175.612608)
			(xy 71.671149 -175.55992) (xy 71.686142 -175.508847) (xy 71.708251 -175.460427) (xy 71.737025 -175.415647)
			(xy 71.77188 -175.375417) (xy 71.812105 -175.340557) (xy 71.856881 -175.311776) (xy 71.905298 -175.28966)
			(xy 71.95637 -175.27466) (xy 72.009056 -175.267081) (xy 72.03567 -175.266604) (xy 72.062091 -175.267078)
			(xy 72.114406 -175.274524) (xy 72.165144 -175.289285) (xy 72.213289 -175.311065) (xy 72.257874 -175.339428)
			(xy 72.27824 -175.356266) (xy 72.285098 -175.362362) (xy 72.302116 -175.368458) (xy 72.386444 -175.368458)
			(xy 72.403462 -175.362362) (xy 72.41032 -175.356266) (xy 72.430686 -175.339427) (xy 72.475272 -175.311062)
			(xy 72.523416 -175.289275) (xy 72.574153 -175.274504) (xy 72.626468 -175.267044) (xy 72.679312 -175.267044)
			(xy 72.731627 -175.274504) (xy 72.782364 -175.289275) (xy 72.830508 -175.311062) (xy 72.875094 -175.339427)
			(xy 72.89546 -175.356266) (xy 72.902318 -175.362362) (xy 72.919336 -175.368458) (xy 73.003664 -175.368458)
			(xy 73.020682 -175.362362) (xy 73.02754 -175.356266) (xy 73.047899 -175.339419) (xy 73.09249 -175.311063)
			(xy 73.140636 -175.289285) (xy 73.191374 -175.274519) (xy 73.243688 -175.267063) (xy 73.27011 -175.266604)
			(xy 73.297996 -175.267082) (xy 73.353145 -175.275395) (xy 73.406439 -175.291836) (xy 73.456687 -175.316035)
			(xy 73.502767 -175.347453) (xy 73.543651 -175.385389) (xy 73.578423 -175.428993) (xy 73.606309 -175.477293)
			(xy 73.626684 -175.52921) (xy 73.639095 -175.583584) (xy 73.643263 -175.6392) (xy 73.639095 -175.694816)
			(xy 73.626684 -175.74919) (xy 73.606309 -175.801107) (xy 73.578423 -175.849407) (xy 73.543651 -175.893011)
			(xy 73.502767 -175.930947) (xy 73.456687 -175.962365) (xy 73.406439 -175.986564) (xy 73.353145 -176.003005)
			(xy 73.297996 -176.011318) (xy 73.27011 -176.01184) (xy 73.243689 -176.011367) (xy 73.191374 -176.003919)
			(xy 73.140636 -175.989157) (xy 73.092492 -175.967377) (xy 73.047906 -175.939016) (xy 73.02754 -175.922178)
			(xy 73.020682 -175.916082) (xy 73.003664 -175.909986) (xy 72.919336 -175.909986) (xy 72.902318 -175.916082)
			(xy 72.89546 -175.922178) (xy 72.875094 -175.939017) (xy 72.830508 -175.967382) (xy 72.782364 -175.989169)
			(xy 72.731627 -176.00394) (xy 72.679312 -176.0114) (xy 72.626468 -176.0114) (xy 72.574153 -176.00394)
			(xy 72.523416 -175.989169) (xy 72.475272 -175.967382) (xy 72.430686 -175.939017) (xy 72.41032 -175.922178)
			(xy 72.403462 -175.916082) (xy 72.386444 -175.909986) (xy 72.302116 -175.909986) (xy 72.285098 -175.916082)
			(xy 72.27824 -175.922178) (xy 72.262606 -175.935184) (xy 72.229003 -175.958095) (xy 72.211184 -175.967898)
			(xy 72.20077 -175.973486) (xy 72.187308 -175.992028) (xy 72.168512 -176.092866) (xy 72.174354 -176.114964)
			(xy 72.181974 -176.123854) (xy 72.199282 -176.14471) (xy 72.228443 -176.190393) (xy 72.250844 -176.239745)
			(xy 72.266032 -176.29177) (xy 72.273702 -176.345421) (xy 72.274176 -176.37252) (xy 72.273664 -176.400093)
			(xy 72.265722 -176.454664) (xy 72.250007 -176.507523) (xy 72.226845 -176.55757) (xy 72.196721 -176.603761)
			(xy 72.16026 -176.645133) (xy 72.139556 -176.66335) (xy 72.131413 -176.67093) (xy 72.122074 -176.691099)
			(xy 72.121522 -176.702212) (xy 72.121522 -176.779428) (xy 72.122051 -176.790543) (xy 72.131416 -176.810701)
			(xy 72.139556 -176.81829) (xy 72.160257 -176.836513) (xy 72.19673 -176.877878) (xy 72.226864 -176.924065)
			(xy 72.250032 -176.974111) (xy 72.26575 -177.026972) (xy 72.273691 -177.081546) (xy 72.274176 -177.10912)
			(xy 72.27369 -177.136371) (xy 72.265934 -177.190319) (xy 72.250579 -177.242614) (xy 72.227937 -177.292191)
			(xy 72.198471 -177.338041) (xy 72.16278 -177.379232) (xy 72.121589 -177.414923) (xy 72.075739 -177.444389)
			(xy 72.026162 -177.467031) (xy 71.973867 -177.482386) (xy 71.919919 -177.490142) (xy 71.865417 -177.490142)
			(xy 71.811469 -177.482386) (xy 71.759174 -177.467031) (xy 71.709597 -177.444389) (xy 71.663747 -177.414923)
			(xy 71.622556 -177.379232) (xy 71.586865 -177.338041) (xy 71.557399 -177.292191) (xy 71.534757 -177.242614)
			(xy 71.519402 -177.190319) (xy 71.511646 -177.136371) (xy 71.51116 -177.10912) (xy 68.874132 -177.10912)
			(xy 68.874132 -182.04434) (xy 68.874528 -182.054413) (xy 68.882268 -182.073011) (xy 68.889118 -182.080408)
			(xy 69.14388 -182.33517) (xy 69.151296 -182.341989) (xy 69.169883 -182.349722) (xy 69.179948 -182.350156)
			(xy 76.112878 -182.350156) (xy 76.142851 -182.350663) (xy 76.202068 -182.359985) (xy 76.259094 -182.378467)
			(xy 76.312521 -182.405652) (xy 76.361032 -182.440868) (xy 76.382626 -182.461662) (xy 76.585064 -182.6641)
			(xy 76.592425 -182.670869) (xy 76.610887 -182.678516) (xy 76.630869 -182.678516) (xy 76.649331 -182.670869)
			(xy 76.656692 -182.6641) (xy 76.85913 -182.461662) (xy 76.869533 -182.45147) (xy 76.891655 -182.432527)
			(xy 76.903326 -182.423816) (xy 76.906374 -182.42153) (xy 77.396848 -181.93131) (xy 77.40357 -181.923851)
			(xy 77.411144 -181.905275) (xy 77.41158 -181.895242) (xy 77.41158 -176.944528) (xy 77.411227 -176.934481)
			(xy 77.403627 -176.915885) (xy 77.396848 -176.90846) (xy 77.374242 -176.886108) (xy 77.353465 -176.864504)
			(xy 77.31828 -176.815981) (xy 77.291115 -176.762553) (xy 77.272638 -176.705535) (xy 77.263304 -176.646329)
			(xy 77.262736 -176.61636) (xy 77.263218 -176.588449) (xy 77.271357 -176.533223) (xy 77.287456 -176.479773)
			(xy 77.311171 -176.429238) (xy 77.341995 -176.382698) (xy 77.360272 -176.361598) (xy 77.366622 -176.354486)
			(xy 77.373226 -176.337214) (xy 77.373226 -176.250346) (xy 77.366622 -176.233074) (xy 77.360272 -176.225962)
			(xy 77.34194 -176.204862) (xy 77.311033 -176.15829) (xy 77.287257 -176.107705) (xy 77.27112 -176.05419)
			(xy 77.262968 -175.998893) (xy 77.262482 -175.970946) (xy 77.262968 -175.943695) (xy 77.270724 -175.889747)
			(xy 77.286079 -175.837452) (xy 77.308721 -175.787875) (xy 77.338187 -175.742025) (xy 77.373878 -175.700834)
			(xy 77.415069 -175.665143) (xy 77.460919 -175.635677) (xy 77.510496 -175.613035) (xy 77.562791 -175.59768)
			(xy 77.616739 -175.589924) (xy 77.671241 -175.589924) (xy 77.725189 -175.59768) (xy 77.777484 -175.613035)
			(xy 77.827061 -175.635677) (xy 77.872911 -175.665143) (xy 77.914102 -175.700834) (xy 77.949793 -175.742025)
			(xy 77.979259 -175.787875) (xy 78.001901 -175.837452) (xy 78.017256 -175.889747) (xy 78.025012 -175.943695)
			(xy 78.025498 -175.970946) (xy 78.024908 -176.001069) (xy 78.015434 -176.060565) (xy 77.996728 -176.117833)
			(xy 77.969256 -176.171451) (xy 77.9337 -176.220085) (xy 77.912722 -176.24171) (xy 77.905888 -176.249115)
			(xy 77.898164 -176.26771) (xy 77.897736 -176.277778) (xy 77.897736 -176.309782) (xy 77.898161 -176.319851)
			(xy 77.905881 -176.33845) (xy 77.912722 -176.34585) (xy 77.913738 -176.346612) (xy 78.062836 -176.49571)
			(xy 78.083651 -176.517295) (xy 78.118906 -176.565799) (xy 78.146135 -176.619224) (xy 78.164665 -176.676251)
			(xy 78.174042 -176.735476) (xy 78.174596 -176.765458) (xy 78.174596 -178.798474) (xy 78.471522 -178.798474)
			(xy 78.472085 -178.769559) (xy 78.480804 -178.712389) (xy 78.498052 -178.657191) (xy 78.523435 -178.605229)
			(xy 78.556371 -178.557694) (xy 78.596106 -178.515675) (xy 78.618588 -178.497484) (xy 78.627351 -178.489923)
			(xy 78.637534 -178.469164) (xy 78.638146 -178.457606) (xy 78.638146 -178.377342) (xy 78.63757 -178.365774)
			(xy 78.627381 -178.345002) (xy 78.618588 -178.337464) (xy 78.596085 -178.319296) (xy 78.556351 -178.277271)
			(xy 78.523415 -178.229732) (xy 78.49803 -178.177766) (xy 78.480778 -178.122564) (xy 78.472054 -178.065391)
			(xy 78.471522 -178.036474) (xy 78.471931 -178.009219) (xy 78.479692 -177.955265) (xy 78.495053 -177.902964)
			(xy 78.517701 -177.853382) (xy 78.547174 -177.807527) (xy 78.582874 -177.766334) (xy 78.624072 -177.730641)
			(xy 78.669931 -177.701174) (xy 78.719516 -177.678533) (xy 78.771819 -177.66318) (xy 78.825775 -177.655427)
			(xy 78.85303 -177.654966) (xy 78.880667 -177.655461) (xy 78.935359 -177.663462) (xy 78.988327 -177.679262)
			(xy 79.038464 -177.702533) (xy 79.084723 -177.732788) (xy 79.126137 -177.769395) (xy 79.161843 -177.81159)
			(xy 79.191093 -177.85849) (xy 79.213277 -177.909117) (xy 79.221076 -177.935636) (xy 79.223362 -177.94478)
			(xy 79.234792 -177.96002) (xy 79.308706 -178.006756) (xy 79.327248 -178.010566) (xy 79.336646 -178.008788)
			(xy 79.353146 -178.006047) (xy 79.386469 -178.003125) (xy 79.403194 -178.002946) (xy 79.430443 -178.003483)
			(xy 79.484387 -178.011238) (xy 79.536677 -178.02659) (xy 79.586252 -178.049227) (xy 79.6321 -178.078688)
			(xy 79.673289 -178.114374) (xy 79.708981 -178.155558) (xy 79.738448 -178.201403) (xy 79.761092 -178.250974)
			(xy 79.776451 -178.303263) (xy 79.784213 -178.357205) (xy 79.784702 -178.384454) (xy 79.784272 -178.40964)
			(xy 79.777658 -178.459576) (xy 79.764536 -178.508209) (xy 79.745137 -178.554696) (xy 79.719795 -178.598229)
			(xy 79.704692 -178.618388) (xy 79.696818 -178.628548) (xy 79.6925 -178.653186) (xy 79.727298 -178.757834)
			(xy 79.745586 -178.775106) (xy 79.758032 -178.778408) (xy 79.784565 -178.786174) (xy 79.835211 -178.808337)
			(xy 79.882129 -178.837577) (xy 79.924337 -178.87328) (xy 79.960951 -178.914701) (xy 79.991205 -178.960971)
			(xy 80.014465 -179.011123) (xy 80.030246 -179.064106) (xy 80.038215 -179.118812) (xy 80.038702 -179.146454)
			(xy 80.038204 -179.174027) (xy 80.030258 -179.228599) (xy 80.014539 -179.281458) (xy 79.991375 -179.331504)
			(xy 79.961249 -179.377694) (xy 79.924787 -179.419067) (xy 79.904082 -179.437284) (xy 79.895973 -179.444895)
			(xy 79.886614 -179.46504) (xy 79.886048 -179.476146) (xy 79.886048 -179.553362) (xy 79.886606 -179.564473)
			(xy 79.89595 -179.584633) (xy 79.904082 -179.592224) (xy 79.924804 -179.610423) (xy 79.961275 -179.651794)
			(xy 79.991406 -179.697986) (xy 80.01457 -179.748037) (xy 80.030283 -179.800902) (xy 80.038219 -179.855478)
			(xy 80.038253 -179.8574) (xy 84.62721 -179.8574) (xy 84.631281 -179.801778) (xy 84.643407 -179.747341)
			(xy 84.66333 -179.69525) (xy 84.690626 -179.646615) (xy 84.724712 -179.602472) (xy 84.764861 -179.563763)
			(xy 84.810219 -179.531312) (xy 84.859819 -179.505811) (xy 84.912603 -179.487804) (xy 84.967446 -179.477674)
			(xy 85.02318 -179.475637) (xy 85.078617 -179.481737) (xy 85.132574 -179.495843) (xy 85.183903 -179.517655)
			(xy 85.231509 -179.546709) (xy 85.274377 -179.582384) (xy 85.311594 -179.623921) (xy 85.342367 -179.670434)
			(xy 85.366039 -179.720931) (xy 85.382107 -179.774338) (xy 85.390227 -179.829514) (xy 85.390736 -179.8574)
			(xy 85.390227 -179.885286) (xy 85.382107 -179.940462) (xy 85.366039 -179.993869) (xy 85.342367 -180.044366)
			(xy 85.311594 -180.090879) (xy 85.274377 -180.132416) (xy 85.231509 -180.168091) (xy 85.183903 -180.197145)
			(xy 85.132574 -180.218957) (xy 85.078617 -180.233063) (xy 85.02318 -180.239163) (xy 84.967446 -180.237126)
			(xy 84.912603 -180.226996) (xy 84.859819 -180.208989) (xy 84.810219 -180.183488) (xy 84.764861 -180.151037)
			(xy 84.724712 -180.112328) (xy 84.690626 -180.068185) (xy 84.66333 -180.01955) (xy 84.643407 -179.967459)
			(xy 84.631281 -179.913022) (xy 84.62721 -179.8574) (xy 80.038253 -179.8574) (xy 80.038702 -179.883054)
			(xy 80.038202 -179.910306) (xy 80.030451 -179.964256) (xy 80.015101 -180.016553) (xy 79.992463 -180.066134)
			(xy 79.962999 -180.111987) (xy 79.927309 -180.153181) (xy 79.88612 -180.188875) (xy 79.840269 -180.218344)
			(xy 79.790691 -180.240987) (xy 79.738395 -180.256343) (xy 79.684446 -180.264099) (xy 79.657194 -180.264562)
			(xy 79.622904 -180.263038) (xy 79.612744 -180.262022) (xy 79.59344 -180.268118) (xy 79.522828 -180.3273)
			(xy 79.51343 -180.345334) (xy 79.512414 -180.355494) (xy 79.509502 -180.383672) (xy 79.496321 -180.438765)
			(xy 79.475137 -180.491302) (xy 79.446414 -180.540128) (xy 79.410785 -180.584168) (xy 79.369033 -180.622454)
			(xy 79.322078 -180.654142) (xy 79.270952 -180.678537) (xy 79.21678 -180.695101) (xy 79.160754 -180.70347)
			(xy 79.13243 -180.703982) (xy 79.105177 -180.703517) (xy 79.051224 -180.695763) (xy 78.998925 -180.68041)
			(xy 78.949343 -180.657769) (xy 78.903489 -180.628301) (xy 78.862295 -180.592608) (xy 78.826601 -180.551414)
			(xy 78.797133 -180.50556) (xy 78.774492 -180.455979) (xy 78.759138 -180.403679) (xy 78.751384 -180.349727)
			(xy 78.750922 -180.322474) (xy 78.751409 -180.294612) (xy 78.759514 -180.23948) (xy 78.775547 -180.186112)
			(xy 78.799167 -180.135641) (xy 78.829874 -180.089141) (xy 78.867014 -180.047598) (xy 78.888082 -180.029358)
			(xy 78.897226 -180.021738) (xy 78.906878 -180.000656) (xy 78.903322 -179.89677) (xy 78.8924 -179.876196)
			(xy 78.882748 -179.869084) (xy 78.862203 -179.853655) (xy 78.825069 -179.818144) (xy 78.793037 -179.777969)
			(xy 78.766688 -179.733859) (xy 78.746498 -179.686611) (xy 78.732833 -179.637081) (xy 78.72594 -179.586164)
			(xy 78.725522 -179.560474) (xy 78.725907 -179.535286) (xy 78.732532 -179.485349) (xy 78.745663 -179.436715)
			(xy 78.765073 -179.390229) (xy 78.790424 -179.346698) (xy 78.805532 -179.32654) (xy 78.813406 -179.31638)
			(xy 78.817724 -179.291742) (xy 78.782926 -179.187094) (xy 78.764638 -179.169822) (xy 78.752192 -179.16652)
			(xy 78.725672 -179.158714) (xy 78.675027 -179.136556) (xy 78.628109 -179.107322) (xy 78.585901 -179.071623)
			(xy 78.549286 -179.030208) (xy 78.51903 -178.983943) (xy 78.495767 -178.933795) (xy 78.479984 -178.880816)
			(xy 78.472011 -178.826114) (xy 78.471522 -178.798474) (xy 78.174596 -178.798474) (xy 78.174596 -182.074312)
			(xy 78.173997 -182.104289) (xy 78.164606 -182.163503) (xy 78.146372 -182.2196) (xy 79.86014 -182.2196)
			(xy 79.860592 -182.192025) (xy 79.868545 -182.137451) (xy 79.884272 -182.08459) (xy 79.907445 -182.034544)
			(xy 79.93758 -181.988355) (xy 79.974051 -181.946985) (xy 79.99476 -181.92877) (xy 80.002897 -181.921185)
			(xy 80.012238 -181.90102) (xy 80.012794 -181.889908) (xy 80.012794 -181.812692) (xy 80.012248 -181.801579)
			(xy 80.002894 -181.781421) (xy 79.99476 -181.77383) (xy 79.974052 -181.755616) (xy 79.937583 -181.714246)
			(xy 79.907452 -181.668057) (xy 79.884286 -181.61801) (xy 79.868568 -181.565148) (xy 79.860627 -181.510574)
			(xy 79.86014 -181.483) (xy 79.86071 -181.454477) (xy 79.869217 -181.398068) (xy 79.886025 -181.343553)
			(xy 79.910762 -181.292148) (xy 79.942875 -181.244998) (xy 79.981648 -181.203154) (xy 80.026219 -181.167547)
			(xy 80.05064 -181.1528) (xy 80.060546 -181.146958) (xy 80.073246 -181.128416) (xy 80.090264 -181.028848)
			(xy 80.084168 -181.007258) (xy 80.076802 -180.998622) (xy 80.059877 -180.978237) (xy 80.031365 -180.933582)
			(xy 80.009461 -180.885339) (xy 79.994606 -180.834483) (xy 79.9871 -180.782035) (xy 79.986632 -180.755544)
			(xy 79.987075 -180.728925) (xy 79.994647 -180.676228) (xy 80.009642 -180.625146) (xy 80.031755 -180.576718)
			(xy 80.060537 -180.53193) (xy 80.0954 -180.491696) (xy 80.135635 -180.456833) (xy 80.180423 -180.428052)
			(xy 80.228851 -180.40594) (xy 80.279934 -180.390945) (xy 80.332631 -180.383375) (xy 80.35925 -180.382926)
			(xy 80.385672 -180.383372) (xy 80.437987 -180.390828) (xy 80.488725 -180.405596) (xy 80.536869 -180.427382)
			(xy 80.581454 -180.455748) (xy 80.60182 -180.472588) (xy 80.608678 -180.478684) (xy 80.625696 -180.48478)
			(xy 80.710024 -180.48478) (xy 80.727042 -180.478684) (xy 80.7339 -180.472588) (xy 80.754266 -180.455749)
			(xy 80.798852 -180.427384) (xy 80.846996 -180.405597) (xy 80.897733 -180.390826) (xy 80.950048 -180.383366)
			(xy 81.002892 -180.383366) (xy 81.055207 -180.390826) (xy 81.105944 -180.405597) (xy 81.154088 -180.427384)
			(xy 81.198674 -180.455749) (xy 81.21904 -180.472588) (xy 81.225898 -180.478684) (xy 81.242916 -180.48478)
			(xy 81.327244 -180.48478) (xy 81.344262 -180.478684) (xy 81.35112 -180.472588) (xy 81.371477 -180.455739)
			(xy 81.416069 -180.427386) (xy 81.464216 -180.405609) (xy 81.514954 -180.390844) (xy 81.567269 -180.383386)
			(xy 81.59369 -180.382926) (xy 81.621581 -180.383332) (xy 81.676739 -180.391645) (xy 81.730042 -180.408085)
			(xy 81.780299 -180.432287) (xy 81.826388 -180.463709) (xy 81.867279 -180.501649) (xy 81.902059 -180.54526)
			(xy 81.92995 -180.593567) (xy 81.9364 -180.610002) (xy 86.589362 -180.610002) (xy 86.589807 -180.582426)
			(xy 86.597761 -180.527852) (xy 86.613489 -180.474991) (xy 86.636662 -180.424944) (xy 86.6668 -180.378755)
			(xy 86.703272 -180.337386) (xy 86.723982 -180.319172) (xy 86.732122 -180.311589) (xy 86.741461 -180.291422)
			(xy 86.742016 -180.28031) (xy 86.742016 -180.203094) (xy 86.741494 -180.191978) (xy 86.732126 -180.171818)
			(xy 86.723982 -180.164232) (xy 86.70328 -180.146013) (xy 86.666818 -180.104642) (xy 86.636692 -180.058452)
			(xy 86.613531 -180.008405) (xy 86.597817 -179.955546) (xy 86.589877 -179.900974) (xy 86.589877 -179.845828)
			(xy 86.597816 -179.791257) (xy 86.61353 -179.738397) (xy 86.636691 -179.688351) (xy 86.666816 -179.64216)
			(xy 86.703278 -179.600788) (xy 86.723982 -179.582572) (xy 86.732122 -179.574989) (xy 86.741461 -179.554822)
			(xy 86.742016 -179.54371) (xy 86.742016 -179.466494) (xy 86.741494 -179.455378) (xy 86.732126 -179.435218)
			(xy 86.723982 -179.427632) (xy 86.70328 -179.409412) (xy 86.666809 -179.368044) (xy 86.636677 -179.321856)
			(xy 86.613509 -179.27181) (xy 86.597791 -179.218949) (xy 86.589849 -179.164376) (xy 86.589362 -179.136802)
			(xy 86.58988 -179.109552) (xy 86.597635 -179.055607) (xy 86.612988 -179.003315) (xy 86.635627 -178.95374)
			(xy 86.66509 -178.907891) (xy 86.700778 -178.866701) (xy 86.741965 -178.83101) (xy 86.787811 -178.801542)
			(xy 86.837385 -178.7789) (xy 86.889676 -178.763542) (xy 86.94362 -178.755782) (xy 86.97087 -178.755294)
			(xy 86.998724 -178.755849) (xy 87.053838 -178.763968) (xy 87.107187 -178.780009) (xy 87.15764 -178.803632)
			(xy 87.204124 -178.834335) (xy 87.245654 -178.871466) (xy 87.281348 -178.914238) (xy 87.310448 -178.961742)
			(xy 87.332337 -179.01297) (xy 87.339932 -179.039774) (xy 87.342218 -179.048664) (xy 87.352886 -179.063904)
			(xy 87.424768 -179.111656) (xy 87.442802 -179.11572) (xy 87.451946 -179.11445) (xy 87.464962 -179.112778)
			(xy 87.491147 -179.111) (xy 87.50427 -179.110894) (xy 87.518419 -179.110991) (xy 87.546642 -179.113023)
			(xy 87.560658 -179.114958) (xy 87.570818 -179.116482) (xy 87.590376 -179.111656) (xy 87.664798 -179.055776)
			(xy 87.674958 -179.03825) (xy 87.676228 -179.02809) (xy 87.680396 -179.00095) (xy 87.695362 -178.948124)
			(xy 87.717745 -178.897989) (xy 87.747084 -178.851581) (xy 87.782772 -178.809856) (xy 87.824072 -178.773679)
			(xy 87.870132 -178.743795) (xy 87.92 -178.720823) (xy 87.972645 -178.705236) (xy 88.026982 -178.697356)
			(xy 88.054434 -178.696874) (xy 88.081685 -178.697346) (xy 88.135633 -178.705107) (xy 88.187926 -178.720465)
			(xy 88.237503 -178.743109) (xy 88.283352 -178.772577) (xy 88.324541 -178.80827) (xy 88.360232 -178.849461)
			(xy 88.389699 -178.895311) (xy 88.41234 -178.944889) (xy 88.427697 -178.997183) (xy 88.435455 -179.051131)
			(xy 88.435942 -179.078382) (xy 88.435484 -179.105957) (xy 88.427533 -179.160531) (xy 88.411808 -179.213392)
			(xy 88.388636 -179.263438) (xy 88.358501 -179.309628) (xy 88.322031 -179.350997) (xy 88.301322 -179.369212)
			(xy 88.29319 -179.376802) (xy 88.283846 -179.396963) (xy 88.283288 -179.408074) (xy 88.283288 -179.48529)
			(xy 88.283817 -179.496405) (xy 88.29318 -179.516565) (xy 88.301322 -179.524152) (xy 88.322018 -179.54238)
			(xy 88.358488 -179.583746) (xy 88.388622 -179.629932) (xy 88.41179 -179.679977) (xy 88.42751 -179.732836)
			(xy 88.435454 -179.787408) (xy 88.435488 -179.789328) (xy 93.02445 -179.789328) (xy 93.028521 -179.733706)
			(xy 93.040647 -179.679269) (xy 93.06057 -179.627178) (xy 93.087866 -179.578543) (xy 93.121952 -179.5344)
			(xy 93.162101 -179.495691) (xy 93.207459 -179.46324) (xy 93.257059 -179.437739) (xy 93.309843 -179.419732)
			(xy 93.364686 -179.409602) (xy 93.42042 -179.407565) (xy 93.475857 -179.413665) (xy 93.529814 -179.427771)
			(xy 93.581143 -179.449583) (xy 93.628749 -179.478637) (xy 93.671617 -179.514312) (xy 93.708834 -179.555849)
			(xy 93.739607 -179.602362) (xy 93.763279 -179.652859) (xy 93.779347 -179.706266) (xy 93.787467 -179.761442)
			(xy 93.787976 -179.789328) (xy 93.787467 -179.817214) (xy 93.779347 -179.87239) (xy 93.763279 -179.925797)
			(xy 93.739607 -179.976294) (xy 93.708834 -180.022807) (xy 93.671617 -180.064344) (xy 93.628749 -180.100019)
			(xy 93.581143 -180.129073) (xy 93.529814 -180.150885) (xy 93.475857 -180.164991) (xy 93.42042 -180.171091)
			(xy 93.364686 -180.169054) (xy 93.309843 -180.158924) (xy 93.257059 -180.140917) (xy 93.207459 -180.115416)
			(xy 93.162101 -180.082965) (xy 93.121952 -180.044256) (xy 93.087866 -180.000113) (xy 93.06057 -179.951478)
			(xy 93.040647 -179.899387) (xy 93.028521 -179.84495) (xy 93.02445 -179.789328) (xy 88.435488 -179.789328)
			(xy 88.435942 -179.814982) (xy 88.435405 -179.842231) (xy 88.427652 -179.896175) (xy 88.412301 -179.948467)
			(xy 88.389664 -179.998042) (xy 88.360203 -180.043891) (xy 88.324517 -180.08508) (xy 88.283332 -180.120772)
			(xy 88.237487 -180.150239) (xy 88.187916 -180.172883) (xy 88.135626 -180.188241) (xy 88.081683 -180.196001)
			(xy 88.054434 -180.19649) (xy 88.020144 -180.194966) (xy 88.009984 -180.19395) (xy 87.99068 -180.200046)
			(xy 87.920068 -180.259228) (xy 87.91067 -180.277262) (xy 87.909654 -180.287422) (xy 87.906643 -180.315588)
			(xy 87.893474 -180.370676) (xy 87.872301 -180.423211) (xy 87.84359 -180.472035) (xy 87.807973 -180.516075)
			(xy 87.766233 -180.554363) (xy 87.719288 -180.586054) (xy 87.668172 -180.610452) (xy 87.614008 -180.627021)
			(xy 87.55799 -180.635395) (xy 87.52967 -180.63591) (xy 87.511651 -180.635689) (xy 87.475776 -180.632255)
			(xy 87.458042 -180.629052) (xy 87.448644 -180.627274) (xy 87.429594 -180.631084) (xy 87.35441 -180.678836)
			(xy 87.34298 -180.694584) (xy 87.340694 -180.703982) (xy 87.333311 -180.73103) (xy 87.311678 -180.782756)
			(xy 87.28271 -180.83076) (xy 87.247032 -180.87401) (xy 87.205411 -180.911576) (xy 87.158743 -180.94265)
			(xy 87.10803 -180.966562) (xy 87.054366 -180.982799) (xy 86.998903 -180.99101) (xy 86.97087 -180.99151)
			(xy 86.943618 -180.99105) (xy 86.88967 -180.98329) (xy 86.837374 -180.967931) (xy 86.787797 -180.945286)
			(xy 86.741947 -180.915817) (xy 86.700757 -180.880123) (xy 86.665066 -180.83893) (xy 86.6356 -180.793078)
			(xy 86.612959 -180.743499) (xy 86.597604 -180.691203) (xy 86.589848 -180.637254) (xy 86.589362 -180.610002)
			(xy 81.9364 -180.610002) (xy 81.950329 -180.645492) (xy 81.962742 -180.699875) (xy 81.966911 -180.7555)
			(xy 81.962742 -180.811125) (xy 81.950329 -180.865508) (xy 81.92995 -180.917433) (xy 81.902059 -180.96574)
			(xy 81.867279 -181.009351) (xy 81.826388 -181.047291) (xy 81.780299 -181.078713) (xy 81.730042 -181.102915)
			(xy 81.676739 -181.119355) (xy 81.621581 -181.127668) (xy 81.59369 -181.128162) (xy 81.567269 -181.127695)
			(xy 81.514954 -181.120245) (xy 81.464216 -181.105482) (xy 81.416072 -181.0837) (xy 81.371486 -181.055338)
			(xy 81.35112 -181.0385) (xy 81.344262 -181.032404) (xy 81.327244 -181.026308) (xy 81.242916 -181.026308)
			(xy 81.225898 -181.032404) (xy 81.21904 -181.0385) (xy 81.198674 -181.055339) (xy 81.154088 -181.083704)
			(xy 81.105944 -181.105491) (xy 81.055207 -181.120262) (xy 81.002892 -181.127722) (xy 80.950048 -181.127722)
			(xy 80.897733 -181.120262) (xy 80.846996 -181.105491) (xy 80.798852 -181.083704) (xy 80.754266 -181.055339)
			(xy 80.7339 -181.0385) (xy 80.727042 -181.032404) (xy 80.710024 -181.026308) (xy 80.625696 -181.026308)
			(xy 80.608678 -181.032404) (xy 80.60182 -181.0385) (xy 80.589745 -181.04857) (xy 80.564186 -181.066884)
			(xy 80.550766 -181.075076) (xy 80.54086 -181.081172) (xy 80.528414 -181.099714) (xy 80.51292 -181.199536)
			(xy 80.519524 -181.221126) (xy 80.52689 -181.229762) (xy 80.544916 -181.250813) (xy 80.575348 -181.297128)
			(xy 80.598751 -181.347362) (xy 80.614633 -181.400456) (xy 80.622659 -181.455291) (xy 80.623156 -181.483)
			(xy 80.622706 -181.510575) (xy 80.614752 -181.56515) (xy 80.599025 -181.61801) (xy 80.575852 -181.668057)
			(xy 80.545716 -181.714246) (xy 80.509245 -181.755615) (xy 80.488536 -181.77383) (xy 80.480398 -181.781415)
			(xy 80.471057 -181.80158) (xy 80.470502 -181.812692) (xy 80.470502 -181.889908) (xy 80.471049 -181.90102)
			(xy 80.480402 -181.921179) (xy 80.488536 -181.92877) (xy 80.509243 -181.946985) (xy 80.545712 -181.988354)
			(xy 80.575844 -182.034543) (xy 80.59901 -182.08459) (xy 80.614728 -182.137452) (xy 80.622669 -182.192026)
			(xy 80.623156 -182.2196) (xy 80.62267 -182.246851) (xy 80.614914 -182.300799) (xy 80.599559 -182.353094)
			(xy 80.576917 -182.402671) (xy 80.547451 -182.448521) (xy 80.51176 -182.489712) (xy 80.470569 -182.525403)
			(xy 80.424719 -182.554869) (xy 80.375142 -182.577511) (xy 80.322847 -182.592866) (xy 80.268899 -182.600622)
			(xy 80.214397 -182.600622) (xy 80.160449 -182.592866) (xy 80.108154 -182.577511) (xy 80.058577 -182.554869)
			(xy 80.012727 -182.525403) (xy 79.971536 -182.489712) (xy 79.935845 -182.448521) (xy 79.906379 -182.402671)
			(xy 79.883737 -182.353094) (xy 79.868382 -182.300799) (xy 79.860626 -182.246851) (xy 79.86014 -182.2196)
			(xy 78.146372 -182.2196) (xy 78.146073 -182.22052) (xy 78.118852 -182.273939) (xy 78.083615 -182.322445)
			(xy 78.062836 -182.34406) (xy 77.405738 -183.001158) (xy 77.395333 -183.011348) (xy 77.373212 -183.030292)
			(xy 77.361542 -183.039004) (xy 77.358494 -183.04129) (xy 77.017118 -183.382412) (xy 77.010283 -183.389816)
			(xy 77.002559 -183.408412) (xy 77.002132 -183.41848) (xy 77.002132 -186.87034) (xy 77.002528 -186.880413)
			(xy 77.010268 -186.899011) (xy 77.017118 -186.906408) (xy 78.160626 -188.049662) (xy 78.181383 -188.071284)
			(xy 78.216572 -188.119802) (xy 78.243741 -188.173225) (xy 78.262222 -188.230239) (xy 78.271562 -188.289442)
			(xy 78.272132 -188.31941) (xy 78.272132 -190.04534) (xy 78.272528 -190.055413) (xy 78.280268 -190.074011)
			(xy 78.287118 -190.081408) (xy 78.79588 -190.59017) (xy 78.803296 -190.596989) (xy 78.821883 -190.604722)
			(xy 78.831948 -190.605156) (xy 84.823808 -190.605156) (xy 84.833879 -190.604746) (xy 84.852478 -190.597016)
			(xy 84.859876 -190.59017) (xy 85.241638 -190.208408) (xy 85.248472 -190.201004) (xy 85.256194 -190.182408)
			(xy 85.256624 -190.17234) (xy 85.256624 -186.54141) (xy 85.257133 -186.511437) (xy 85.266456 -186.452221)
			(xy 85.284938 -186.395195) (xy 85.312122 -186.341768) (xy 85.347337 -186.293257) (xy 85.36813 -186.271662)
			(xy 86.054438 -185.585608) (xy 86.061272 -185.578204) (xy 86.068994 -185.559608) (xy 86.069424 -185.54954)
			(xy 86.069424 -182.396638) (xy 86.068999 -182.386568) (xy 86.06128 -182.367969) (xy 86.054438 -182.36057)
			(xy 85.697822 -182.004208) (xy 85.677041 -181.982608) (xy 85.641858 -181.934083) (xy 85.614694 -181.880654)
			(xy 85.596218 -181.823635) (xy 85.586884 -181.764429) (xy 85.586316 -181.73446) (xy 85.586803 -181.706549)
			(xy 85.594942 -181.651324) (xy 85.61104 -181.597874) (xy 85.634753 -181.547339) (xy 85.665576 -181.500799)
			(xy 85.683852 -181.479698) (xy 85.690202 -181.472586) (xy 85.696806 -181.455314) (xy 85.696806 -181.368446)
			(xy 85.690202 -181.351174) (xy 85.683852 -181.344062) (xy 85.665516 -181.322965) (xy 85.634611 -181.276392)
			(xy 85.610836 -181.225805) (xy 85.594699 -181.172291) (xy 85.586548 -181.116993) (xy 85.586062 -181.089046)
			(xy 85.586548 -181.061795) (xy 85.594304 -181.007847) (xy 85.609659 -180.955552) (xy 85.632301 -180.905975)
			(xy 85.661767 -180.860125) (xy 85.697458 -180.818934) (xy 85.738649 -180.783243) (xy 85.784499 -180.753777)
			(xy 85.834076 -180.731135) (xy 85.886371 -180.71578) (xy 85.940319 -180.708024) (xy 85.994821 -180.708024)
			(xy 86.048769 -180.71578) (xy 86.101064 -180.731135) (xy 86.150641 -180.753777) (xy 86.196491 -180.783243)
			(xy 86.237682 -180.818934) (xy 86.273373 -180.860125) (xy 86.302839 -180.905975) (xy 86.325481 -180.955552)
			(xy 86.340836 -181.007847) (xy 86.348592 -181.061795) (xy 86.349078 -181.089046) (xy 86.348465 -181.119168)
			(xy 86.338993 -181.178662) (xy 86.320292 -181.235929) (xy 86.292826 -181.289547) (xy 86.257276 -181.338183)
			(xy 86.236302 -181.35981) (xy 86.229465 -181.367213) (xy 86.221744 -181.38581) (xy 86.221316 -181.395878)
			(xy 86.221316 -181.427882) (xy 86.221747 -181.437951) (xy 86.229463 -181.456549) (xy 86.236302 -181.46395)
			(xy 86.237318 -181.464712) (xy 86.720426 -181.94782) (xy 86.741163 -181.969461) (xy 86.776354 -182.017973)
			(xy 86.803527 -182.071392) (xy 86.822014 -182.128402) (xy 86.822778 -182.13324) (xy 88.110822 -182.13324)
			(xy 88.111308 -182.105666) (xy 88.119255 -182.051094) (xy 88.134976 -181.998234) (xy 88.158142 -181.948188)
			(xy 88.188271 -181.901998) (xy 88.224736 -181.860626) (xy 88.245442 -181.84241) (xy 88.253558 -181.834806)
			(xy 88.262912 -181.814655) (xy 88.263476 -181.803548) (xy 88.263476 -181.726332) (xy 88.262914 -181.715221)
			(xy 88.253572 -181.695062) (xy 88.245442 -181.68747) (xy 88.224722 -181.669269) (xy 88.18825 -181.627899)
			(xy 88.158118 -181.581707) (xy 88.134954 -181.531657) (xy 88.11924 -181.478792) (xy 88.111305 -181.424215)
			(xy 88.110822 -181.39664) (xy 88.111224 -181.36959) (xy 88.118875 -181.316034) (xy 88.134013 -181.264095)
			(xy 88.156336 -181.214816) (xy 88.185396 -181.169184) (xy 88.220611 -181.128114) (xy 88.261273 -181.09243)
			(xy 88.306569 -181.062848) (xy 88.355588 -181.03996) (xy 88.381332 -181.031642) (xy 88.392762 -181.028086)
			(xy 88.40978 -181.012338) (xy 88.446864 -180.914802) (xy 88.444578 -180.891688) (xy 88.438482 -180.881528)
			(xy 88.425555 -180.859512) (xy 88.405154 -180.812712) (xy 88.391321 -180.763568) (xy 88.384314 -180.712998)
			(xy 88.383872 -180.687472) (xy 88.384331 -180.660856) (xy 88.39191 -180.608165) (xy 88.40691 -180.557089)
			(xy 88.429026 -180.508668) (xy 88.457808 -180.463886) (xy 88.492669 -180.423657) (xy 88.532901 -180.388797)
			(xy 88.577683 -180.360018) (xy 88.626106 -180.337904) (xy 88.677183 -180.322906) (xy 88.729874 -180.315329)
			(xy 88.75649 -180.314854) (xy 88.782911 -180.315328) (xy 88.835225 -180.322776) (xy 88.885963 -180.337538)
			(xy 88.934108 -180.359318) (xy 88.978694 -180.387679) (xy 88.99906 -180.404516) (xy 89.005918 -180.410612)
			(xy 89.022936 -180.416708) (xy 89.107264 -180.416708) (xy 89.124282 -180.410612) (xy 89.13114 -180.404516)
			(xy 89.151506 -180.387677) (xy 89.196092 -180.359312) (xy 89.244236 -180.337525) (xy 89.294973 -180.322754)
			(xy 89.347288 -180.315294) (xy 89.400132 -180.315294) (xy 89.452447 -180.322754) (xy 89.503184 -180.337525)
			(xy 89.551328 -180.359312) (xy 89.595914 -180.387677) (xy 89.61628 -180.404516) (xy 89.623138 -180.410612)
			(xy 89.640156 -180.416708) (xy 89.724484 -180.416708) (xy 89.741502 -180.410612) (xy 89.74836 -180.404516)
			(xy 89.768742 -180.387699) (xy 89.813327 -180.35934) (xy 89.861468 -180.337557) (xy 89.912201 -180.322784)
			(xy 89.96451 -180.315318) (xy 89.99093 -180.314854) (xy 90.018811 -180.315433) (xy 90.07395 -180.323748)
			(xy 90.127235 -180.340188) (xy 90.177474 -180.364385) (xy 90.223545 -180.3958) (xy 90.264421 -180.43373)
			(xy 90.299186 -180.477328) (xy 90.327066 -180.52562) (xy 90.347438 -180.577529) (xy 90.358792 -180.627274)
			(xy 94.981522 -180.627274) (xy 94.982031 -180.599701) (xy 94.989974 -180.54513) (xy 95.00569 -180.49227)
			(xy 95.028851 -180.442224) (xy 95.058977 -180.396033) (xy 95.095438 -180.354661) (xy 95.116142 -180.336444)
			(xy 95.124243 -180.328826) (xy 95.133605 -180.308686) (xy 95.134176 -180.297582) (xy 95.134176 -180.220366)
			(xy 95.133651 -180.209251) (xy 95.124283 -180.189092) (xy 95.116142 -180.181504) (xy 95.095409 -180.163318)
			(xy 95.058941 -180.121944) (xy 95.028812 -180.075751) (xy 95.005648 -180.0257) (xy 94.989933 -179.972835)
			(xy 94.981993 -179.918259) (xy 94.981996 -179.863108) (xy 94.98994 -179.808532) (xy 95.00566 -179.755669)
			(xy 95.028828 -179.70562) (xy 95.058962 -179.659429) (xy 95.095433 -179.618059) (xy 95.116142 -179.599844)
			(xy 95.124243 -179.592226) (xy 95.133605 -179.572086) (xy 95.134176 -179.560982) (xy 95.134176 -179.483766)
			(xy 95.133651 -179.472651) (xy 95.124283 -179.452492) (xy 95.116142 -179.444904) (xy 95.095438 -179.426685)
			(xy 95.058965 -179.385319) (xy 95.028831 -179.339131) (xy 95.005664 -179.289084) (xy 94.989947 -179.236223)
			(xy 94.982007 -179.181648) (xy 94.981522 -179.154074) (xy 94.981931 -179.126819) (xy 94.989692 -179.072865)
			(xy 95.005053 -179.020564) (xy 95.027701 -178.970982) (xy 95.057174 -178.925127) (xy 95.092874 -178.883934)
			(xy 95.134072 -178.848241) (xy 95.179931 -178.818774) (xy 95.229516 -178.796133) (xy 95.281819 -178.78078)
			(xy 95.335775 -178.773027) (xy 95.36303 -178.772566) (xy 95.390885 -178.773087) (xy 95.445999 -178.781214)
			(xy 95.499348 -178.797262) (xy 95.5498 -178.82089) (xy 95.596283 -178.851597) (xy 95.637812 -178.888732)
			(xy 95.673506 -178.931506) (xy 95.702606 -178.979012) (xy 95.724496 -179.030242) (xy 95.732092 -179.057046)
			(xy 95.734378 -179.065936) (xy 95.745046 -179.081176) (xy 95.816928 -179.128928) (xy 95.834962 -179.132992)
			(xy 95.844106 -179.131722) (xy 95.857123 -179.130054) (xy 95.883307 -179.128273) (xy 95.89643 -179.128166)
			(xy 95.910579 -179.128257) (xy 95.938802 -179.130293) (xy 95.952818 -179.13223) (xy 95.962978 -179.133754)
			(xy 95.982536 -179.128928) (xy 96.056958 -179.073048) (xy 96.067118 -179.055522) (xy 96.068388 -179.045362)
			(xy 96.072477 -179.018208) (xy 96.087449 -178.965378) (xy 96.10984 -178.915239) (xy 96.139187 -178.868828)
			(xy 96.174885 -178.827104) (xy 96.216194 -178.790927) (xy 96.262263 -178.761046) (xy 96.31214 -178.738077)
			(xy 96.364794 -178.722496) (xy 96.419138 -178.714624) (xy 96.446594 -178.714146) (xy 96.473843 -178.714683)
			(xy 96.527787 -178.722438) (xy 96.580077 -178.73779) (xy 96.629652 -178.760427) (xy 96.6755 -178.789888)
			(xy 96.716689 -178.825574) (xy 96.752381 -178.866758) (xy 96.781848 -178.912603) (xy 96.804492 -178.962174)
			(xy 96.819851 -179.014463) (xy 96.827613 -179.068405) (xy 96.828102 -179.095654) (xy 96.827604 -179.123227)
			(xy 96.819658 -179.177799) (xy 96.803939 -179.230658) (xy 96.780775 -179.280704) (xy 96.750649 -179.326894)
			(xy 96.714187 -179.368267) (xy 96.693482 -179.386484) (xy 96.685373 -179.394095) (xy 96.676014 -179.41424)
			(xy 96.675448 -179.425346) (xy 96.675448 -179.502562) (xy 96.676006 -179.513673) (xy 96.68535 -179.533833)
			(xy 96.693482 -179.541424) (xy 96.714204 -179.559623) (xy 96.750675 -179.600994) (xy 96.780806 -179.647186)
			(xy 96.80397 -179.697237) (xy 96.819683 -179.750102) (xy 96.827619 -179.804678) (xy 96.827653 -179.8066)
			(xy 101.41661 -179.8066) (xy 101.420681 -179.750978) (xy 101.432807 -179.696541) (xy 101.45273 -179.64445)
			(xy 101.480026 -179.595815) (xy 101.514112 -179.551672) (xy 101.554261 -179.512963) (xy 101.599619 -179.480512)
			(xy 101.649219 -179.455011) (xy 101.702003 -179.437004) (xy 101.756846 -179.426874) (xy 101.81258 -179.424837)
			(xy 101.868017 -179.430937) (xy 101.921974 -179.445043) (xy 101.973303 -179.466855) (xy 102.020909 -179.495909)
			(xy 102.063777 -179.531584) (xy 102.100994 -179.573121) (xy 102.131767 -179.619634) (xy 102.155439 -179.670131)
			(xy 102.171507 -179.723538) (xy 102.179627 -179.778714) (xy 102.180136 -179.8066) (xy 102.179627 -179.834486)
			(xy 102.171507 -179.889662) (xy 102.155439 -179.943069) (xy 102.131767 -179.993566) (xy 102.100994 -180.040079)
			(xy 102.063777 -180.081616) (xy 102.020909 -180.117291) (xy 101.973303 -180.146345) (xy 101.921974 -180.168157)
			(xy 101.868017 -180.182263) (xy 101.81258 -180.188363) (xy 101.756846 -180.186326) (xy 101.702003 -180.176196)
			(xy 101.649219 -180.158189) (xy 101.599619 -180.132688) (xy 101.554261 -180.100237) (xy 101.514112 -180.061528)
			(xy 101.480026 -180.017385) (xy 101.45273 -179.96875) (xy 101.432807 -179.916659) (xy 101.420681 -179.862222)
			(xy 101.41661 -179.8066) (xy 96.827653 -179.8066) (xy 96.828102 -179.832254) (xy 96.827602 -179.859506)
			(xy 96.819851 -179.913456) (xy 96.804501 -179.965753) (xy 96.781863 -180.015334) (xy 96.752399 -180.061187)
			(xy 96.716709 -180.102381) (xy 96.67552 -180.138075) (xy 96.629669 -180.167544) (xy 96.580091 -180.190187)
			(xy 96.527795 -180.205543) (xy 96.473846 -180.213299) (xy 96.446594 -180.213762) (xy 96.412304 -180.212238)
			(xy 96.402144 -180.211222) (xy 96.38284 -180.217318) (xy 96.312228 -180.2765) (xy 96.30283 -180.294534)
			(xy 96.301814 -180.304694) (xy 96.298902 -180.332872) (xy 96.285721 -180.387965) (xy 96.264537 -180.440502)
			(xy 96.235814 -180.489328) (xy 96.200185 -180.533368) (xy 96.158433 -180.571654) (xy 96.111478 -180.603342)
			(xy 96.060352 -180.627737) (xy 96.00618 -180.644301) (xy 95.950154 -180.65267) (xy 95.92183 -180.653182)
			(xy 95.903811 -180.652966) (xy 95.867936 -180.649528) (xy 95.850202 -180.646324) (xy 95.840804 -180.644546)
			(xy 95.821754 -180.648356) (xy 95.74657 -180.696108) (xy 95.73514 -180.711856) (xy 95.732854 -180.721254)
			(xy 95.725489 -180.748308) (xy 95.703856 -180.800036) (xy 95.674888 -180.848042) (xy 95.639209 -180.891294)
			(xy 95.597585 -180.928861) (xy 95.550913 -180.959934) (xy 95.500198 -180.983844) (xy 95.44653 -181.000078)
			(xy 95.391065 -181.008285) (xy 95.36303 -181.008782) (xy 95.335777 -181.008317) (xy 95.281824 -181.000563)
			(xy 95.229525 -180.98521) (xy 95.179943 -180.962569) (xy 95.134089 -180.933101) (xy 95.092895 -180.897408)
			(xy 95.057201 -180.856214) (xy 95.027733 -180.81036) (xy 95.005092 -180.760779) (xy 94.989738 -180.708479)
			(xy 94.981984 -180.654527) (xy 94.981522 -180.627274) (xy 90.358792 -180.627274) (xy 90.359846 -180.631893)
			(xy 90.364013 -180.6875) (xy 90.359846 -180.743107) (xy 90.347438 -180.797471) (xy 90.327066 -180.84938)
			(xy 90.299186 -180.897672) (xy 90.264421 -180.94127) (xy 90.223545 -180.9792) (xy 90.177474 -181.010615)
			(xy 90.127235 -181.034812) (xy 90.07395 -181.051252) (xy 90.018811 -181.059567) (xy 89.99093 -181.06009)
			(xy 89.964509 -181.059617) (xy 89.912194 -181.052171) (xy 89.861455 -181.03741) (xy 89.813311 -181.015629)
			(xy 89.768725 -180.987266) (xy 89.74836 -180.970428) (xy 89.741502 -180.964332) (xy 89.724484 -180.958236)
			(xy 89.640156 -180.958236) (xy 89.623138 -180.964332) (xy 89.61628 -180.970428) (xy 89.595914 -180.987267)
			(xy 89.551328 -181.015632) (xy 89.503184 -181.037419) (xy 89.452447 -181.05219) (xy 89.400132 -181.05965)
			(xy 89.347288 -181.05965) (xy 89.294973 -181.05219) (xy 89.244236 -181.037419) (xy 89.196092 -181.015632)
			(xy 89.151506 -180.987267) (xy 89.13114 -180.970428) (xy 89.124282 -180.964332) (xy 89.107264 -180.958236)
			(xy 89.022936 -180.958236) (xy 89.005918 -180.964332) (xy 88.99906 -180.970428) (xy 88.979951 -180.986226)
			(xy 88.938339 -181.013183) (xy 88.893521 -181.034385) (xy 88.870028 -181.04231) (xy 88.858598 -181.04612)
			(xy 88.841834 -181.062122) (xy 88.806274 -181.159912) (xy 88.808814 -181.18328) (xy 88.815164 -181.193186)
			(xy 88.829089 -181.216128) (xy 88.851049 -181.265097) (xy 88.865918 -181.316663) (xy 88.873403 -181.369806)
			(xy 88.873838 -181.39664) (xy 88.873353 -181.424214) (xy 88.865407 -181.478787) (xy 88.849688 -181.531647)
			(xy 88.826521 -181.581694) (xy 88.796391 -181.627884) (xy 88.759925 -181.669255) (xy 88.739218 -181.68747)
			(xy 88.731105 -181.695076) (xy 88.721751 -181.715225) (xy 88.721184 -181.726332) (xy 88.721184 -181.803548)
			(xy 88.721738 -181.81466) (xy 88.731084 -181.834821) (xy 88.739218 -181.84241) (xy 88.759941 -181.860608)
			(xy 88.796409 -181.90198) (xy 88.82654 -181.948173) (xy 88.849703 -181.998223) (xy 88.865417 -182.051088)
			(xy 88.873354 -182.105665) (xy 88.873838 -182.13324) (xy 88.873352 -182.160491) (xy 88.865596 -182.214439)
			(xy 88.850241 -182.266734) (xy 88.827599 -182.316311) (xy 88.798133 -182.362161) (xy 88.762442 -182.403352)
			(xy 88.721251 -182.439043) (xy 88.675401 -182.468509) (xy 88.625824 -182.491151) (xy 88.573529 -182.506506)
			(xy 88.519581 -182.514262) (xy 88.465079 -182.514262) (xy 88.411131 -182.506506) (xy 88.358836 -182.491151)
			(xy 88.309259 -182.468509) (xy 88.263409 -182.439043) (xy 88.222218 -182.403352) (xy 88.186527 -182.362161)
			(xy 88.157061 -182.316311) (xy 88.134419 -182.266734) (xy 88.119064 -182.214439) (xy 88.111308 -182.160491)
			(xy 88.110822 -182.13324) (xy 86.822778 -182.13324) (xy 86.831358 -182.187602) (xy 86.831932 -182.217568)
			(xy 86.831932 -185.72861) (xy 86.83142 -185.758583) (xy 86.822095 -185.817798) (xy 86.803613 -185.874823)
			(xy 86.776431 -185.92825) (xy 86.741218 -185.976763) (xy 86.720426 -185.998358) (xy 86.034118 -186.684412)
			(xy 86.027283 -186.691816) (xy 86.019559 -186.710412) (xy 86.019132 -186.72048) (xy 86.019132 -190.17234)
			(xy 86.019528 -190.182413) (xy 86.027268 -190.201011) (xy 86.034118 -190.208408) (xy 86.41588 -190.59017)
			(xy 86.423296 -190.596989) (xy 86.441883 -190.604722) (xy 86.451948 -190.605156) (xy 92.443808 -190.605156)
			(xy 92.453879 -190.604746) (xy 92.472478 -190.597016) (xy 92.479876 -190.59017) (xy 92.861638 -190.208408)
			(xy 92.868472 -190.201004) (xy 92.876194 -190.182408) (xy 92.876624 -190.17234) (xy 92.876624 -186.54141)
			(xy 92.877133 -186.511437) (xy 92.886456 -186.452221) (xy 92.904938 -186.395195) (xy 92.932122 -186.341768)
			(xy 92.967337 -186.293257) (xy 92.98813 -186.271662) (xy 94.258638 -185.001408) (xy 94.265472 -184.994004)
			(xy 94.273194 -184.975408) (xy 94.273624 -184.96534) (xy 94.273624 -183.156098) (xy 94.27322 -183.146026)
			(xy 94.265486 -183.127427) (xy 94.258638 -183.12003) (xy 94.095062 -182.956708) (xy 94.074288 -182.935101)
			(xy 94.039102 -182.886579) (xy 94.011936 -182.833152) (xy 93.993459 -182.776134) (xy 93.984124 -182.716929)
			(xy 93.983556 -182.68696) (xy 93.983556 -181.666388) (xy 93.98405 -181.638477) (xy 93.992185 -181.583252)
			(xy 94.008281 -181.529801) (xy 94.031993 -181.479267) (xy 94.062816 -181.432727) (xy 94.081092 -181.411626)
			(xy 94.087442 -181.404514) (xy 94.094046 -181.387242) (xy 94.094046 -181.300374) (xy 94.087442 -181.283102)
			(xy 94.081092 -181.27599) (xy 94.062776 -181.254877) (xy 94.031866 -181.208308) (xy 94.008086 -181.157726)
			(xy 93.991946 -181.104215) (xy 93.98379 -181.04892) (xy 93.983302 -181.020974) (xy 93.983788 -180.993723)
			(xy 93.991544 -180.939775) (xy 94.006899 -180.88748) (xy 94.029541 -180.837903) (xy 94.059007 -180.792053)
			(xy 94.094698 -180.750862) (xy 94.135889 -180.715171) (xy 94.181739 -180.685705) (xy 94.231316 -180.663063)
			(xy 94.283611 -180.647708) (xy 94.337559 -180.639952) (xy 94.392061 -180.639952) (xy 94.446009 -180.647708)
			(xy 94.498304 -180.663063) (xy 94.547881 -180.685705) (xy 94.593731 -180.715171) (xy 94.634922 -180.750862)
			(xy 94.670613 -180.792053) (xy 94.700079 -180.837903) (xy 94.722721 -180.88748) (xy 94.738076 -180.939775)
			(xy 94.745832 -180.993723) (xy 94.746318 -181.020974) (xy 94.745795 -181.048918) (xy 94.737634 -181.104208)
			(xy 94.721498 -181.157717) (xy 94.69773 -181.2083) (xy 94.666841 -181.254877) (xy 94.648528 -181.27599)
			(xy 94.642178 -181.283102) (xy 94.635574 -181.300374) (xy 94.635574 -181.387242) (xy 94.642178 -181.404514)
			(xy 94.648528 -181.411626) (xy 94.666797 -181.432733) (xy 94.697625 -181.47927) (xy 94.721341 -181.529803)
			(xy 94.73744 -181.583252) (xy 94.745577 -181.638477) (xy 94.746064 -181.666388) (xy 94.746064 -182.13324)
			(xy 96.59874 -182.13324) (xy 96.599219 -182.105666) (xy 96.607167 -182.051093) (xy 96.622888 -181.998233)
			(xy 96.646056 -181.948186) (xy 96.676187 -181.901997) (xy 96.712653 -181.860626) (xy 96.73336 -181.84241)
			(xy 96.741479 -181.834808) (xy 96.75083 -181.814656) (xy 96.751394 -181.803548) (xy 96.751394 -181.726332)
			(xy 96.750826 -181.715222) (xy 96.741488 -181.695063) (xy 96.73336 -181.68747) (xy 96.712623 -181.669287)
			(xy 96.676157 -181.627911) (xy 96.646029 -181.581715) (xy 96.622868 -181.531662) (xy 96.607156 -181.478795)
			(xy 96.599222 -181.424216) (xy 96.59874 -181.39664) (xy 96.599286 -181.367028) (xy 96.608433 -181.308514)
			(xy 96.626512 -181.252118) (xy 96.653091 -181.199192) (xy 96.68753 -181.151011) (xy 96.729001 -181.10873)
			(xy 96.776508 -181.073367) (xy 96.802448 -181.059074) (xy 96.8121 -181.053994) (xy 96.825308 -181.03723)
			(xy 96.849184 -180.942742) (xy 96.845374 -180.92166) (xy 96.839278 -180.912516) (xy 96.824345 -180.889347)
			(xy 96.800704 -180.839554) (xy 96.784649 -180.786823) (xy 96.77653 -180.732304) (xy 96.776032 -180.704744)
			(xy 96.776475 -180.678125) (xy 96.784047 -180.625428) (xy 96.799042 -180.574346) (xy 96.821155 -180.525918)
			(xy 96.849937 -180.48113) (xy 96.8848 -180.440896) (xy 96.925035 -180.406033) (xy 96.969823 -180.377252)
			(xy 97.018251 -180.35514) (xy 97.069334 -180.340145) (xy 97.122031 -180.332575) (xy 97.14865 -180.332126)
			(xy 97.175072 -180.332572) (xy 97.227387 -180.340028) (xy 97.278125 -180.354796) (xy 97.326269 -180.376582)
			(xy 97.370854 -180.404948) (xy 97.39122 -180.421788) (xy 97.398078 -180.427884) (xy 97.415096 -180.43398)
			(xy 97.499424 -180.43398) (xy 97.516442 -180.427884) (xy 97.5233 -180.421788) (xy 97.543666 -180.404949)
			(xy 97.588252 -180.376584) (xy 97.636396 -180.354797) (xy 97.687133 -180.340026) (xy 97.739448 -180.332566)
			(xy 97.792292 -180.332566) (xy 97.844607 -180.340026) (xy 97.895344 -180.354797) (xy 97.943488 -180.376584)
			(xy 97.988074 -180.404949) (xy 98.00844 -180.421788) (xy 98.015298 -180.427884) (xy 98.032316 -180.43398)
			(xy 98.116644 -180.43398) (xy 98.133662 -180.427884) (xy 98.14052 -180.421788) (xy 98.160877 -180.404939)
			(xy 98.205469 -180.376586) (xy 98.253616 -180.354809) (xy 98.304354 -180.340044) (xy 98.356669 -180.332586)
			(xy 98.38309 -180.332126) (xy 98.410981 -180.332532) (xy 98.466139 -180.340845) (xy 98.519442 -180.357285)
			(xy 98.569699 -180.381487) (xy 98.615788 -180.412909) (xy 98.656679 -180.450849) (xy 98.691459 -180.49446)
			(xy 98.71935 -180.542767) (xy 98.739729 -180.594692) (xy 98.752142 -180.649075) (xy 98.756311 -180.7047)
			(xy 98.752142 -180.760325) (xy 98.739729 -180.814708) (xy 98.71935 -180.866633) (xy 98.691459 -180.91494)
			(xy 98.656679 -180.958551) (xy 98.615788 -180.996491) (xy 98.569699 -181.027913) (xy 98.519442 -181.052115)
			(xy 98.466139 -181.068555) (xy 98.410981 -181.076868) (xy 98.38309 -181.077362) (xy 98.356669 -181.076895)
			(xy 98.304354 -181.069445) (xy 98.253616 -181.054682) (xy 98.205472 -181.0329) (xy 98.160886 -181.004538)
			(xy 98.14052 -180.9877) (xy 98.133662 -180.981604) (xy 98.116644 -180.975508) (xy 98.032316 -180.975508)
			(xy 98.015298 -180.981604) (xy 98.00844 -180.9877) (xy 97.988074 -181.004539) (xy 97.943488 -181.032904)
			(xy 97.895344 -181.054691) (xy 97.844607 -181.069462) (xy 97.792292 -181.076922) (xy 97.739448 -181.076922)
			(xy 97.687133 -181.069462) (xy 97.636396 -181.054691) (xy 97.588252 -181.032904) (xy 97.543666 -181.004539)
			(xy 97.5233 -180.9877) (xy 97.516442 -180.981604) (xy 97.499424 -180.975508) (xy 97.415096 -180.975508)
			(xy 97.398078 -180.981604) (xy 97.39122 -180.9877) (xy 97.376369 -181.000042) (xy 97.344556 -181.021932)
			(xy 97.32772 -181.031388) (xy 97.318322 -181.036722) (xy 97.305368 -181.05374) (xy 97.283016 -181.148736)
			(xy 97.28708 -181.169564) (xy 97.29343 -181.178708) (xy 97.309557 -181.202826) (xy 97.33509 -181.254922)
			(xy 97.352443 -181.310283) (xy 97.361218 -181.367632) (xy 97.361756 -181.39664) (xy 97.361264 -181.424214)
			(xy 97.353319 -181.478786) (xy 97.3376 -181.531646) (xy 97.314435 -181.581693) (xy 97.284307 -181.627883)
			(xy 97.247842 -181.669254) (xy 97.227136 -181.68747) (xy 97.219025 -181.695079) (xy 97.209669 -181.715226)
			(xy 97.209102 -181.726332) (xy 97.209102 -181.803548) (xy 97.209682 -181.814656) (xy 97.219012 -181.834815)
			(xy 97.227136 -181.84241) (xy 97.247862 -181.860604) (xy 97.28433 -181.901978) (xy 97.314459 -181.948171)
			(xy 97.337622 -181.998222) (xy 97.353336 -182.051088) (xy 97.361272 -182.105664) (xy 97.361756 -182.13324)
			(xy 97.36127 -182.160491) (xy 97.353514 -182.214439) (xy 97.338159 -182.266734) (xy 97.315517 -182.316311)
			(xy 97.286051 -182.362161) (xy 97.25036 -182.403352) (xy 97.209169 -182.439043) (xy 97.163319 -182.468509)
			(xy 97.113742 -182.491151) (xy 97.061447 -182.506506) (xy 97.007499 -182.514262) (xy 96.952997 -182.514262)
			(xy 96.899049 -182.506506) (xy 96.846754 -182.491151) (xy 96.797177 -182.468509) (xy 96.751327 -182.439043)
			(xy 96.710136 -182.403352) (xy 96.674445 -182.362161) (xy 96.644979 -182.316311) (xy 96.622337 -182.266734)
			(xy 96.606982 -182.214439) (xy 96.599226 -182.160491) (xy 96.59874 -182.13324) (xy 94.746064 -182.13324)
			(xy 94.746064 -182.50789) (xy 94.746478 -182.517961) (xy 94.754205 -182.53656) (xy 94.76105 -182.543958)
			(xy 94.924626 -182.70728) (xy 94.945392 -182.728894) (xy 94.980579 -182.777414) (xy 95.007747 -182.830839)
			(xy 95.026226 -182.887855) (xy 95.035563 -182.94706) (xy 95.036132 -182.977028) (xy 95.036132 -185.14441)
			(xy 95.03562 -185.174383) (xy 95.026295 -185.233598) (xy 95.007813 -185.290623) (xy 94.980631 -185.34405)
			(xy 94.945418 -185.392563) (xy 94.924626 -185.414158) (xy 93.654118 -186.684412) (xy 93.647283 -186.691816)
			(xy 93.639559 -186.710412) (xy 93.639132 -186.72048) (xy 93.639132 -190.17234) (xy 93.639528 -190.182413)
			(xy 93.647268 -190.201011) (xy 93.654118 -190.208408) (xy 94.03588 -190.59017) (xy 94.043296 -190.596989)
			(xy 94.061883 -190.604722) (xy 94.071948 -190.605156) (xy 101.714808 -190.605156) (xy 101.724879 -190.604746)
			(xy 101.743478 -190.597016) (xy 101.750876 -190.59017) (xy 102.36073 -189.980316) (xy 102.36756 -189.972908)
			(xy 102.375285 -189.954315) (xy 102.375716 -189.944248) (xy 102.375716 -188.091318) (xy 102.376232 -188.061345)
			(xy 102.385554 -188.00213) (xy 102.404034 -187.945104) (xy 102.431216 -187.891677) (xy 102.46643 -187.843165)
			(xy 102.487222 -187.82157) (xy 103.021638 -187.287408) (xy 103.028472 -187.280004) (xy 103.036194 -187.261408)
			(xy 103.036624 -187.25134) (xy 103.036624 -183.037734) (xy 103.036201 -183.027664) (xy 103.028481 -183.009065)
			(xy 103.021638 -183.001666) (xy 102.487222 -182.467504) (xy 102.466487 -182.445861) (xy 102.431298 -182.397348)
			(xy 102.404125 -182.34393) (xy 102.385638 -182.286921) (xy 102.376291 -182.227722) (xy 102.375716 -182.197756)
			(xy 102.375716 -181.68366) (xy 102.376203 -181.655749) (xy 102.384342 -181.600524) (xy 102.40044 -181.547074)
			(xy 102.424153 -181.496539) (xy 102.454976 -181.449999) (xy 102.473252 -181.428898) (xy 102.479602 -181.421786)
			(xy 102.486206 -181.404514) (xy 102.486206 -181.317646) (xy 102.479602 -181.300374) (xy 102.473252 -181.293262)
			(xy 102.454916 -181.272165) (xy 102.424011 -181.225592) (xy 102.400236 -181.175005) (xy 102.384099 -181.121491)
			(xy 102.375948 -181.066193) (xy 102.375462 -181.038246) (xy 102.375948 -181.010995) (xy 102.383704 -180.957047)
			(xy 102.399059 -180.904752) (xy 102.421701 -180.855175) (xy 102.451167 -180.809325) (xy 102.486858 -180.768134)
			(xy 102.528049 -180.732443) (xy 102.573899 -180.702977) (xy 102.623476 -180.680335) (xy 102.675771 -180.66498)
			(xy 102.729719 -180.657224) (xy 102.784221 -180.657224) (xy 102.838169 -180.66498) (xy 102.890464 -180.680335)
			(xy 102.940041 -180.702977) (xy 102.985891 -180.732443) (xy 103.027082 -180.768134) (xy 103.062773 -180.809325)
			(xy 103.092239 -180.855175) (xy 103.114881 -180.904752) (xy 103.130236 -180.957047) (xy 103.137992 -181.010995)
			(xy 103.138478 -181.038246) (xy 103.138008 -181.066192) (xy 103.129836 -181.121485) (xy 103.113687 -181.174994)
			(xy 103.089908 -181.225577) (xy 103.059007 -181.272151) (xy 103.040688 -181.293262) (xy 103.034338 -181.300374)
			(xy 103.027734 -181.317646) (xy 103.027734 -181.404514) (xy 103.034338 -181.421786) (xy 103.040688 -181.428898)
			(xy 103.058937 -181.450021) (xy 103.089769 -181.496553) (xy 103.11349 -181.547081) (xy 103.129594 -181.600528)
			(xy 103.137735 -181.65575) (xy 103.138224 -181.68366) (xy 103.138224 -182.018686) (xy 103.13865 -182.028755)
			(xy 103.14637 -182.047353) (xy 103.15321 -182.054754) (xy 103.687626 -182.588916) (xy 103.708361 -182.610558)
			(xy 103.743553 -182.659071) (xy 103.770726 -182.712489) (xy 103.789213 -182.769499) (xy 103.798558 -182.828698)
			(xy 103.799132 -182.858664) (xy 103.799132 -186.998356) (xy 103.799703 -187.008335) (xy 103.807425 -187.026748)
			(xy 103.821542 -187.040869) (xy 103.839953 -187.048595) (xy 103.849932 -187.049156) (xy 108.4072 -187.049156)
			(xy 108.417271 -187.048742) (xy 108.435869 -187.041015) (xy 108.443268 -187.03417) (xy 110.94593 -184.531508)
			(xy 110.952763 -184.524103) (xy 110.960486 -184.505507) (xy 110.960916 -184.49544) (xy 110.960916 -177.54473)
			(xy 110.960497 -177.534659) (xy 110.952774 -177.51606) (xy 110.94593 -177.508662) (xy 110.869222 -177.432208)
			(xy 110.848441 -177.410608) (xy 110.813258 -177.362083) (xy 110.786094 -177.308654) (xy 110.767618 -177.251635)
			(xy 110.758284 -177.192429) (xy 110.757716 -177.16246) (xy 110.758203 -177.134549) (xy 110.766342 -177.079324)
			(xy 110.78244 -177.025874) (xy 110.806153 -176.975339) (xy 110.836976 -176.928799) (xy 110.855252 -176.907698)
			(xy 110.861602 -176.900586) (xy 110.868206 -176.883314) (xy 110.868206 -176.796446) (xy 110.861602 -176.779174)
			(xy 110.855252 -176.772062) (xy 110.836916 -176.750965) (xy 110.806011 -176.704392) (xy 110.782236 -176.653805)
			(xy 110.766099 -176.600291) (xy 110.757948 -176.544993) (xy 110.757462 -176.517046) (xy 110.757948 -176.489795)
			(xy 110.765704 -176.435847) (xy 110.781059 -176.383552) (xy 110.803701 -176.333975) (xy 110.833167 -176.288125)
			(xy 110.868858 -176.246934) (xy 110.910049 -176.211243) (xy 110.955899 -176.181777) (xy 111.005476 -176.159135)
			(xy 111.057771 -176.14378) (xy 111.111719 -176.136024) (xy 111.166221 -176.136024) (xy 111.220169 -176.14378)
			(xy 111.272464 -176.159135) (xy 111.322041 -176.181777) (xy 111.367891 -176.211243) (xy 111.409082 -176.246934)
			(xy 111.444773 -176.288125) (xy 111.474239 -176.333975) (xy 111.496881 -176.383552) (xy 111.512236 -176.435847)
			(xy 111.519992 -176.489795) (xy 111.520478 -176.517046) (xy 111.519865 -176.547168) (xy 111.510393 -176.606662)
			(xy 111.491692 -176.663929) (xy 111.464226 -176.717547) (xy 111.428676 -176.766183) (xy 111.407702 -176.78781)
			(xy 111.400865 -176.795213) (xy 111.393144 -176.81381) (xy 111.392716 -176.823878) (xy 111.392716 -176.855882)
			(xy 111.393147 -176.865951) (xy 111.400863 -176.884549) (xy 111.407702 -176.89195) (xy 111.408718 -176.892712)
			(xy 111.611918 -177.095912) (xy 111.63265 -177.117557) (xy 111.667842 -177.166069) (xy 111.695016 -177.219486)
			(xy 111.713504 -177.276495) (xy 111.72285 -177.335694) (xy 111.723424 -177.36566) (xy 111.723424 -180.323744)
			(xy 111.723853 -180.333757) (xy 111.731531 -180.352255) (xy 111.745702 -180.366407) (xy 111.76421 -180.374061)
			(xy 111.774224 -180.374544) (xy 118.787164 -180.374544) (xy 118.797212 -180.374197) (xy 118.815809 -180.366594)
			(xy 118.823232 -180.359812) (xy 120.039638 -179.143406) (xy 120.046473 -179.136002) (xy 120.054195 -179.117406)
			(xy 120.054624 -179.107338) (xy 120.054624 -172.852334) (xy 120.054201 -172.842264) (xy 120.046481 -172.823665)
			(xy 120.039638 -172.816266) (xy 119.098822 -171.875704) (xy 119.078087 -171.854061) (xy 119.042898 -171.805548)
			(xy 119.015725 -171.75213) (xy 118.997238 -171.695121) (xy 118.987891 -171.635922) (xy 118.987316 -171.605956)
			(xy 118.987316 -170.91406) (xy 118.987803 -170.886149) (xy 118.995942 -170.830924) (xy 119.01204 -170.777474)
			(xy 119.035753 -170.726939) (xy 119.066576 -170.680399) (xy 119.084852 -170.659298) (xy 119.091202 -170.652186)
			(xy 119.097806 -170.634914) (xy 119.097806 -170.548046) (xy 119.091202 -170.530774) (xy 119.084852 -170.523662)
			(xy 119.066516 -170.502565) (xy 119.035611 -170.455992) (xy 119.011836 -170.405405) (xy 118.995699 -170.351891)
			(xy 118.987548 -170.296593) (xy 118.987062 -170.268646) (xy 118.987548 -170.241395) (xy 118.995304 -170.187447)
			(xy 119.010659 -170.135152) (xy 119.033301 -170.085575) (xy 119.062767 -170.039725) (xy 119.098458 -169.998534)
			(xy 119.139649 -169.962843) (xy 119.185499 -169.933377) (xy 119.235076 -169.910735) (xy 119.287371 -169.89538)
			(xy 119.341319 -169.887624) (xy 119.395821 -169.887624) (xy 119.449769 -169.89538) (xy 119.502064 -169.910735)
			(xy 119.551641 -169.933377) (xy 119.597491 -169.962843) (xy 119.638682 -169.998534) (xy 119.674373 -170.039725)
			(xy 119.703839 -170.085575) (xy 119.726481 -170.135152) (xy 119.741836 -170.187447) (xy 119.749592 -170.241395)
			(xy 119.750078 -170.268646) (xy 119.749428 -170.301369) (xy 119.738323 -170.365864) (xy 119.72798 -170.396916)
			(xy 119.723662 -170.408854) (xy 119.726964 -170.432984) (xy 119.782082 -170.511216) (xy 119.789708 -170.520713)
			(xy 119.811324 -170.531856) (xy 119.823484 -170.532552) (xy 120.429528 -170.532552) (xy 120.459506 -170.533127)
			(xy 120.518722 -170.542521) (xy 120.57574 -170.56106) (xy 120.629158 -170.588286) (xy 120.677662 -170.62353)
			(xy 120.699276 -170.644312) (xy 121.670826 -171.615862) (xy 121.691583 -171.637484) (xy 121.726772 -171.686002)
			(xy 121.753941 -171.739425) (xy 121.772422 -171.796439) (xy 121.781762 -171.855642) (xy 121.782332 -171.88561)
			(xy 121.782332 -173.53534) (xy 121.782728 -173.545413) (xy 121.790468 -173.564011) (xy 121.797318 -173.571408)
			(xy 122.05208 -173.82617) (xy 122.059496 -173.832989) (xy 122.078083 -173.840722) (xy 122.088148 -173.841156)
			(xy 127.114808 -173.841156) (xy 127.124879 -173.840746) (xy 127.143478 -173.833016) (xy 127.150876 -173.82617)
			(xy 127.812038 -173.165008) (xy 127.818872 -173.157604) (xy 127.826594 -173.139008) (xy 127.827024 -173.12894)
			(xy 127.827024 -165.511734) (xy 127.826601 -165.501664) (xy 127.818881 -165.483065) (xy 127.812038 -165.475666)
			(xy 127.379222 -165.043104) (xy 127.358487 -165.021461) (xy 127.323298 -164.972948) (xy 127.296125 -164.91953)
			(xy 127.277638 -164.862521) (xy 127.268291 -164.803322) (xy 127.267716 -164.773356) (xy 127.267716 -164.18306)
			(xy 127.268203 -164.155149) (xy 127.276342 -164.099924) (xy 127.29244 -164.046474) (xy 127.316153 -163.995939)
			(xy 127.346976 -163.949399) (xy 127.365252 -163.928298) (xy 127.371602 -163.921186) (xy 127.378206 -163.903914)
			(xy 127.378206 -163.817046) (xy 127.371602 -163.799774) (xy 127.365252 -163.792662) (xy 127.346916 -163.771565)
			(xy 127.316011 -163.724992) (xy 127.292236 -163.674405) (xy 127.276099 -163.620891) (xy 127.267948 -163.565593)
			(xy 127.267462 -163.537646) (xy 127.267948 -163.510395) (xy 127.275704 -163.456447) (xy 127.291059 -163.404152)
			(xy 127.313701 -163.354575) (xy 127.343167 -163.308725) (xy 127.378858 -163.267534) (xy 127.420049 -163.231843)
			(xy 127.465899 -163.202377) (xy 127.515476 -163.179735) (xy 127.567771 -163.16438) (xy 127.621719 -163.156624)
			(xy 127.676221 -163.156624) (xy 127.730169 -163.16438) (xy 127.782464 -163.179735) (xy 127.832041 -163.202377)
			(xy 127.877891 -163.231843) (xy 127.919082 -163.267534) (xy 127.954773 -163.308725) (xy 127.984239 -163.354575)
			(xy 128.006881 -163.404152) (xy 128.022236 -163.456447) (xy 128.029992 -163.510395) (xy 128.030478 -163.537646)
			(xy 128.029828 -163.570369) (xy 128.018723 -163.634864) (xy 128.00838 -163.665916) (xy 128.004062 -163.677854)
			(xy 128.007364 -163.701984) (xy 128.062482 -163.780216) (xy 128.070108 -163.789713) (xy 128.091724 -163.800856)
			(xy 128.103884 -163.801552) (xy 135.812784 -163.801552) (xy 135.822833 -163.801213) (xy 135.841429 -163.793604)
			(xy 135.848852 -163.78682) (xy 136.676638 -162.959034) (xy 136.683461 -162.951621) (xy 136.69119 -162.933031)
			(xy 136.691624 -162.922966) (xy 136.691624 -154.345132) (xy 136.69211 -154.317899) (xy 136.699861 -154.263987)
			(xy 136.715206 -154.211727) (xy 136.737832 -154.162183) (xy 136.767279 -154.116363) (xy 136.802946 -154.0752)
			(xy 136.844109 -154.039533) (xy 136.889929 -154.010086) (xy 136.939473 -153.98746) (xy 136.991733 -153.972115)
			(xy 137.045645 -153.964364) (xy 137.100111 -153.964364) (xy 137.154023 -153.972115) (xy 137.206283 -153.98746)
			(xy 137.255827 -154.010086) (xy 137.301647 -154.039533) (xy 137.34281 -154.0752) (xy 137.378477 -154.116363)
			(xy 137.407924 -154.162183) (xy 137.43055 -154.211727) (xy 137.445895 -154.263987) (xy 137.453646 -154.317899)
			(xy 137.454132 -154.345132) (xy 137.454132 -163.102036) (xy 137.453573 -163.132007) (xy 137.444259 -163.19122)
			(xy 137.425789 -163.248244) (xy 137.398616 -163.301672) (xy 137.363413 -163.350187) (xy 137.342626 -163.371784)
			(xy 136.261602 -164.452808) (xy 136.240024 -164.47363) (xy 136.191516 -164.508882) (xy 136.13809 -164.536107)
			(xy 136.081062 -164.554637) (xy 136.021836 -164.564014) (xy 135.991854 -164.564568) (xy 128.086358 -164.564568)
			(xy 128.060958 -164.581332) (xy 128.055116 -164.59581) (xy 128.051777 -164.605247) (xy 128.051755 -164.625242)
			(xy 128.059347 -164.643738) (xy 128.066038 -164.651182) (xy 128.478026 -165.062916) (xy 128.498761 -165.084558)
			(xy 128.533953 -165.133071) (xy 128.561126 -165.186489) (xy 128.579613 -165.243499) (xy 128.588958 -165.302698)
			(xy 128.589532 -165.332664) (xy 128.589532 -168.015412) (xy 139.30757 -168.015412) (xy 139.30807 -167.986494)
			(xy 139.316799 -167.929321) (xy 139.334059 -167.874121) (xy 139.359454 -167.822158) (xy 139.392402 -167.774625)
			(xy 139.432148 -167.73261) (xy 139.454636 -167.714422) (xy 139.46339 -167.706852) (xy 139.473576 -167.686099)
			(xy 139.474194 -167.674544) (xy 139.474194 -167.59428) (xy 139.47358 -167.582718) (xy 139.463416 -167.561946)
			(xy 139.454636 -167.554402) (xy 139.432161 -167.536201) (xy 139.392424 -167.494184) (xy 139.359483 -167.446652)
			(xy 139.334092 -167.394692) (xy 139.316835 -167.339496) (xy 139.308105 -167.282328) (xy 139.30757 -167.253412)
			(xy 139.308056 -167.226161) (xy 139.315812 -167.172213) (xy 139.331167 -167.119918) (xy 139.353809 -167.070341)
			(xy 139.383275 -167.024491) (xy 139.418966 -166.9833) (xy 139.460157 -166.947609) (xy 139.506007 -166.918143)
			(xy 139.555584 -166.895501) (xy 139.607879 -166.880146) (xy 139.661827 -166.87239) (xy 139.716329 -166.87239)
			(xy 139.770277 -166.880146) (xy 139.822572 -166.895501) (xy 139.872149 -166.918143) (xy 139.917999 -166.947609)
			(xy 139.95919 -166.9833) (xy 139.994881 -167.024491) (xy 140.024347 -167.070341) (xy 140.046989 -167.119918)
			(xy 140.062344 -167.172213) (xy 140.0701 -167.226161) (xy 140.070586 -167.253412) (xy 140.07001 -167.282327)
			(xy 140.061294 -167.339496) (xy 140.044048 -167.394694) (xy 140.018667 -167.446656) (xy 139.985733 -167.494191)
			(xy 139.946001 -167.53621) (xy 139.92352 -167.554402) (xy 139.914748 -167.561954) (xy 139.904574 -167.582721)
			(xy 139.903962 -167.59428) (xy 139.903962 -167.674544) (xy 139.904543 -167.686111) (xy 139.914728 -167.706884)
			(xy 139.92352 -167.714422) (xy 139.946018 -167.732596) (xy 139.985752 -167.77462) (xy 140.018688 -167.822158)
			(xy 140.044074 -167.874123) (xy 140.061327 -167.929323) (xy 140.070053 -167.986495) (xy 140.070586 -168.015412)
			(xy 140.0701 -168.042663) (xy 140.062344 -168.096611) (xy 140.046989 -168.148906) (xy 140.024347 -168.198483)
			(xy 139.994881 -168.244333) (xy 139.95919 -168.285524) (xy 139.917999 -168.321215) (xy 139.872149 -168.350681)
			(xy 139.822572 -168.373323) (xy 139.770277 -168.388678) (xy 139.716329 -168.396434) (xy 139.661827 -168.396434)
			(xy 139.607879 -168.388678) (xy 139.555584 -168.373323) (xy 139.506007 -168.350681) (xy 139.460157 -168.321215)
			(xy 139.418966 -168.285524) (xy 139.383275 -168.244333) (xy 139.353809 -168.198483) (xy 139.331167 -168.148906)
			(xy 139.315812 -168.096611) (xy 139.308056 -168.042663) (xy 139.30757 -168.015412) (xy 128.589532 -168.015412)
			(xy 128.589532 -173.30801) (xy 128.58902 -173.337983) (xy 128.579695 -173.397198) (xy 128.561213 -173.454223)
			(xy 128.534031 -173.50765) (xy 128.498818 -173.556163) (xy 128.478026 -173.577758) (xy 128.456944 -173.59884)
			(xy 130.214624 -173.59884) (xy 130.215108 -173.57147) (xy 130.22292 -173.517292) (xy 130.238405 -173.464789)
			(xy 130.261243 -173.415041) (xy 130.290964 -173.369074) (xy 130.308604 -173.348142) (xy 130.3147 -173.34103)
			(xy 130.32105 -173.324012) (xy 130.32105 -173.238668) (xy 130.3147 -173.22165) (xy 130.308604 -173.214538)
			(xy 130.291003 -173.193573) (xy 130.261279 -173.14761) (xy 130.238432 -173.097869) (xy 130.222934 -173.045372)
			(xy 130.215102 -172.991199) (xy 130.215098 -172.936462) (xy 130.222921 -172.882287) (xy 130.238411 -172.829787)
			(xy 130.26125 -172.780043) (xy 130.290967 -172.734075) (xy 130.308604 -172.713142) (xy 130.3147 -172.70603)
			(xy 130.32105 -172.689012) (xy 130.32105 -172.603668) (xy 130.3147 -172.58665) (xy 130.308604 -172.579538)
			(xy 130.291003 -172.558573) (xy 130.261279 -172.51261) (xy 130.238432 -172.462869) (xy 130.222934 -172.410372)
			(xy 130.215102 -172.356199) (xy 130.215098 -172.301462) (xy 130.222921 -172.247287) (xy 130.238411 -172.194787)
			(xy 130.26125 -172.145043) (xy 130.290967 -172.099075) (xy 130.308604 -172.078142) (xy 130.3147 -172.07103)
			(xy 130.32105 -172.054012) (xy 130.32105 -171.968668) (xy 130.3147 -171.95165) (xy 130.308604 -171.944538)
			(xy 130.29097 -171.923602) (xy 130.261257 -171.87763) (xy 130.23842 -171.827884) (xy 130.222928 -171.775384)
			(xy 130.215099 -171.721209) (xy 130.214624 -171.69384) (xy 130.215109 -171.665965) (xy 130.22322 -171.610807)
			(xy 130.239275 -171.557418) (xy 130.262932 -171.506936) (xy 130.293686 -171.460435) (xy 130.311906 -171.439332)
			(xy 130.318002 -171.432474) (xy 130.32486 -171.415202) (xy 130.32486 -171.328588) (xy 130.318256 -171.311316)
			(xy 130.31216 -171.304204) (xy 130.294099 -171.283136) (xy 130.263576 -171.236796) (xy 130.240103 -171.186515)
			(xy 130.224177 -171.13336) (xy 130.216135 -171.078457) (xy 130.21564 -171.050712) (xy 130.216103 -171.023342)
			(xy 130.22392 -170.969162) (xy 130.23941 -170.916658) (xy 130.262252 -170.866912) (xy 130.291978 -170.820945)
			(xy 130.30962 -170.800014) (xy 130.315716 -170.792902) (xy 130.322066 -170.775884) (xy 130.322066 -170.69054)
			(xy 130.315716 -170.673522) (xy 130.30962 -170.66641) (xy 130.291991 -170.645468) (xy 130.262267 -170.599501)
			(xy 130.239421 -170.549757) (xy 130.223924 -170.497256) (xy 130.216095 -170.443079) (xy 130.216093 -170.388339)
			(xy 130.22392 -170.334162) (xy 130.239415 -170.28166) (xy 130.262258 -170.231915) (xy 130.29198 -170.185947)
			(xy 130.30962 -170.165014) (xy 130.315716 -170.157902) (xy 130.322066 -170.140884) (xy 130.322066 -170.05554)
			(xy 130.315716 -170.038522) (xy 130.30962 -170.03141) (xy 130.291991 -170.010468) (xy 130.262267 -169.964501)
			(xy 130.239421 -169.914757) (xy 130.223924 -169.862256) (xy 130.216095 -169.808079) (xy 130.216093 -169.753339)
			(xy 130.22392 -169.699162) (xy 130.239415 -169.64666) (xy 130.262258 -169.596915) (xy 130.29198 -169.550947)
			(xy 130.30962 -169.530014) (xy 130.315716 -169.522902) (xy 130.322066 -169.505884) (xy 130.322066 -169.42054)
			(xy 130.315716 -169.403522) (xy 130.30962 -169.39641) (xy 130.291975 -169.375482) (xy 130.262264 -169.329509)
			(xy 130.239428 -169.27976) (xy 130.223939 -169.227258) (xy 130.216113 -169.173082) (xy 130.21564 -169.145712)
			(xy 130.216121 -169.118413) (xy 130.223892 -169.064371) (xy 130.23929 -169.01199) (xy 130.262002 -168.96234)
			(xy 130.291562 -168.916437) (xy 130.309112 -168.895522) (xy 130.315462 -168.88841) (xy 130.321558 -168.871392)
			(xy 130.321558 -168.785794) (xy 130.315208 -168.76903) (xy 130.309112 -168.761918) (xy 130.291409 -168.740948)
			(xy 130.261528 -168.694919) (xy 130.238559 -168.645079) (xy 130.222977 -168.592461) (xy 130.215103 -168.538151)
			(xy 130.214624 -168.510712) (xy 130.215067 -168.483458) (xy 130.222823 -168.429505) (xy 130.238179 -168.377204)
			(xy 130.260822 -168.327622) (xy 130.290292 -168.281768) (xy 130.325988 -168.240574) (xy 130.367184 -168.20488)
			(xy 130.41304 -168.175413) (xy 130.462623 -168.152772) (xy 130.514924 -168.137418) (xy 130.568878 -168.129665)
			(xy 130.596132 -168.129204) (xy 130.623503 -168.12965) (xy 130.677683 -168.137473) (xy 130.730186 -168.152966)
			(xy 130.779933 -168.175813) (xy 130.825899 -168.205541) (xy 130.84683 -168.223184) (xy 130.853942 -168.22928)
			(xy 130.87096 -168.23563) (xy 130.956304 -168.23563) (xy 130.973322 -168.22928) (xy 130.980434 -168.223184)
			(xy 131.001378 -168.20556) (xy 131.047348 -168.175846) (xy 131.097092 -168.153008) (xy 131.14959 -168.137513)
			(xy 131.203764 -168.129681) (xy 131.231132 -168.129204) (xy 131.258385 -168.129648) (xy 131.312334 -168.137409)
			(xy 131.364631 -168.152769) (xy 131.414209 -168.175415) (xy 131.46006 -168.204886) (xy 131.50125 -168.240581)
			(xy 131.536941 -168.281776) (xy 131.566406 -168.32763) (xy 131.589046 -168.377211) (xy 131.6044 -168.429509)
			(xy 131.612155 -168.483459) (xy 131.61264 -168.510712) (xy 131.612153 -168.538011) (xy 131.604381 -168.592051)
			(xy 131.588983 -168.644432) (xy 131.566273 -168.694081) (xy 131.536716 -168.739986) (xy 131.519168 -168.760902)
			(xy 131.512818 -168.768014) (xy 131.506722 -168.785032) (xy 131.506722 -168.87063) (xy 131.513072 -168.887394)
			(xy 131.519168 -168.894506) (xy 131.53688 -168.915469) (xy 131.56676 -168.9615) (xy 131.589727 -169.011341)
			(xy 131.605308 -169.063962) (xy 131.613178 -169.118273) (xy 131.613656 -169.145712) (xy 131.613208 -169.173083)
			(xy 131.605387 -169.227263) (xy 131.589895 -169.279767) (xy 131.567049 -169.329514) (xy 131.53732 -169.375479)
			(xy 131.519676 -169.39641) (xy 131.51358 -169.403522) (xy 131.50723 -169.42054) (xy 131.50723 -169.505884)
			(xy 131.51358 -169.522902) (xy 131.519676 -169.530014) (xy 131.537328 -169.550937) (xy 131.567052 -169.596907)
			(xy 131.589897 -169.646655) (xy 131.605392 -169.699158) (xy 131.61322 -169.753338) (xy 131.613218 -169.80808)
			(xy 131.605388 -169.86226) (xy 131.589891 -169.914762) (xy 131.567044 -169.964509) (xy 131.537317 -170.010477)
			(xy 131.519676 -170.03141) (xy 131.51358 -170.038522) (xy 131.50723 -170.05554) (xy 131.50723 -170.140884)
			(xy 131.51358 -170.157902) (xy 131.519676 -170.165014) (xy 131.537328 -170.185937) (xy 131.567052 -170.231907)
			(xy 131.589897 -170.281655) (xy 131.605392 -170.334158) (xy 131.61322 -170.388338) (xy 131.613218 -170.44308)
			(xy 131.605388 -170.49726) (xy 131.589891 -170.549762) (xy 131.567044 -170.599509) (xy 131.537317 -170.645477)
			(xy 131.519676 -170.66641) (xy 131.51358 -170.673522) (xy 131.50723 -170.69054) (xy 131.50723 -170.775884)
			(xy 131.51358 -170.792902) (xy 131.519676 -170.800014) (xy 131.537285 -170.820971) (xy 131.567002 -170.866936)
			(xy 131.589844 -170.916678) (xy 131.605342 -170.969173) (xy 131.613178 -171.023344) (xy 131.613656 -171.050712)
			(xy 131.613122 -171.078585) (xy 131.60502 -171.13374) (xy 131.588975 -171.187128) (xy 131.56533 -171.237611)
			(xy 131.534587 -171.284114) (xy 131.516374 -171.30522) (xy 131.510278 -171.312078) (xy 131.50342 -171.32935)
			(xy 131.50342 -171.415964) (xy 131.510024 -171.433236) (xy 131.51612 -171.440348) (xy 131.534202 -171.461398)
			(xy 131.564723 -171.507743) (xy 131.588192 -171.558028) (xy 131.604113 -171.611187) (xy 131.612148 -171.666094)
			(xy 131.61264 -171.69384) (xy 131.612153 -171.72121) (xy 131.604343 -171.775388) (xy 131.588859 -171.827892)
			(xy 131.566022 -171.877639) (xy 131.5363 -171.923606) (xy 131.51866 -171.944538) (xy 131.512564 -171.95165)
			(xy 131.506214 -171.968668) (xy 131.506214 -172.054012) (xy 131.512564 -172.07103) (xy 131.51866 -172.078142)
			(xy 131.53634 -172.099043) (xy 131.566065 -172.145016) (xy 131.588908 -172.194767) (xy 131.604402 -172.247274)
			(xy 131.612227 -172.301457) (xy 131.612225 -172.32884) (xy 133.592824 -172.32884) (xy 133.593308 -172.30147)
			(xy 133.60112 -172.247292) (xy 133.616605 -172.194789) (xy 133.639443 -172.145041) (xy 133.669164 -172.099074)
			(xy 133.686804 -172.078142) (xy 133.6929 -172.07103) (xy 133.69925 -172.054012) (xy 133.69925 -171.968668)
			(xy 133.6929 -171.95165) (xy 133.686804 -171.944538) (xy 133.66917 -171.923602) (xy 133.639457 -171.87763)
			(xy 133.61662 -171.827884) (xy 133.601128 -171.775384) (xy 133.593299 -171.721209) (xy 133.592824 -171.69384)
			(xy 133.593309 -171.665965) (xy 133.60142 -171.610807) (xy 133.617475 -171.557418) (xy 133.641132 -171.506936)
			(xy 133.671886 -171.460435) (xy 133.690106 -171.439332) (xy 133.696202 -171.432474) (xy 133.70306 -171.415202)
			(xy 133.70306 -171.328588) (xy 133.696456 -171.311316) (xy 133.69036 -171.304204) (xy 133.672299 -171.283136)
			(xy 133.641776 -171.236796) (xy 133.618303 -171.186515) (xy 133.602377 -171.13336) (xy 133.594335 -171.078457)
			(xy 133.59384 -171.050712) (xy 133.594303 -171.023342) (xy 133.60212 -170.969162) (xy 133.61761 -170.916658)
			(xy 133.640452 -170.866912) (xy 133.670178 -170.820945) (xy 133.68782 -170.800014) (xy 133.693916 -170.792902)
			(xy 133.700266 -170.775884) (xy 133.700266 -170.69054) (xy 133.693916 -170.673522) (xy 133.68782 -170.66641)
			(xy 133.670191 -170.645468) (xy 133.640467 -170.599501) (xy 133.617621 -170.549757) (xy 133.602124 -170.497256)
			(xy 133.594295 -170.443079) (xy 133.594293 -170.388339) (xy 133.60212 -170.334162) (xy 133.617615 -170.28166)
			(xy 133.640458 -170.231915) (xy 133.67018 -170.185947) (xy 133.68782 -170.165014) (xy 133.693916 -170.157902)
			(xy 133.700266 -170.140884) (xy 133.700266 -170.05554) (xy 133.693916 -170.038522) (xy 133.68782 -170.03141)
			(xy 133.670191 -170.010468) (xy 133.640467 -169.964501) (xy 133.617621 -169.914757) (xy 133.602124 -169.862256)
			(xy 133.594295 -169.808079) (xy 133.594293 -169.753339) (xy 133.60212 -169.699162) (xy 133.617615 -169.64666)
			(xy 133.640458 -169.596915) (xy 133.67018 -169.550947) (xy 133.68782 -169.530014) (xy 133.693916 -169.522902)
			(xy 133.700266 -169.505884) (xy 133.700266 -169.42054) (xy 133.693916 -169.403522) (xy 133.68782 -169.39641)
			(xy 133.670175 -169.375482) (xy 133.640464 -169.329509) (xy 133.617628 -169.27976) (xy 133.602139 -169.227258)
			(xy 133.594313 -169.173082) (xy 133.59384 -169.145712) (xy 133.594321 -169.118413) (xy 133.602092 -169.064371)
			(xy 133.61749 -169.01199) (xy 133.640202 -168.96234) (xy 133.669762 -168.916437) (xy 133.687312 -168.895522)
			(xy 133.693662 -168.88841) (xy 133.699758 -168.871392) (xy 133.699758 -168.785794) (xy 133.693408 -168.76903)
			(xy 133.687312 -168.761918) (xy 133.669609 -168.740948) (xy 133.639728 -168.694919) (xy 133.616759 -168.645079)
			(xy 133.601177 -168.592461) (xy 133.593303 -168.538151) (xy 133.592824 -168.510712) (xy 133.593267 -168.483458)
			(xy 133.601023 -168.429505) (xy 133.616379 -168.377204) (xy 133.639022 -168.327622) (xy 133.668492 -168.281768)
			(xy 133.704188 -168.240574) (xy 133.745384 -168.20488) (xy 133.79124 -168.175413) (xy 133.840823 -168.152772)
			(xy 133.893124 -168.137418) (xy 133.947078 -168.129665) (xy 133.974332 -168.129204) (xy 134.001703 -168.12965)
			(xy 134.055883 -168.137473) (xy 134.108386 -168.152966) (xy 134.158133 -168.175813) (xy 134.204099 -168.205541)
			(xy 134.22503 -168.223184) (xy 134.232142 -168.22928) (xy 134.24916 -168.23563) (xy 134.334504 -168.23563)
			(xy 134.351522 -168.22928) (xy 134.358634 -168.223184) (xy 134.379578 -168.20556) (xy 134.425548 -168.175846)
			(xy 134.475292 -168.153008) (xy 134.52779 -168.137513) (xy 134.581964 -168.129681) (xy 134.609332 -168.129204)
			(xy 134.637242 -168.129699) (xy 134.692467 -168.137836) (xy 134.745917 -168.153933) (xy 134.796452 -168.177644)
			(xy 134.842993 -168.208465) (xy 134.864094 -168.22674) (xy 134.871206 -168.23309) (xy 134.88797 -168.239694)
			(xy 134.973822 -168.24071) (xy 134.990586 -168.234614) (xy 134.997952 -168.228518) (xy 135.018731 -168.211373)
			(xy 135.064232 -168.182532) (xy 135.11334 -168.160384) (xy 135.165077 -168.145372) (xy 135.218412 -168.137793)
			(xy 135.245348 -168.137332) (xy 135.272718 -168.137821) (xy 135.326896 -168.145632) (xy 135.379399 -168.161115)
			(xy 135.429146 -168.183952) (xy 135.475114 -168.213673) (xy 135.496046 -168.231312) (xy 135.503158 -168.237408)
			(xy 135.520176 -168.243758) (xy 135.60552 -168.243758) (xy 135.622538 -168.237408) (xy 135.62965 -168.231312)
			(xy 135.650592 -168.213685) (xy 135.696562 -168.183971) (xy 135.746307 -168.161132) (xy 135.798805 -168.145639)
			(xy 135.852979 -168.137807) (xy 135.880348 -168.137332) (xy 135.907602 -168.137733) (xy 135.961555 -168.145497)
			(xy 136.013854 -168.160861) (xy 136.063434 -168.18351) (xy 136.109286 -168.212985) (xy 136.150477 -168.248686)
			(xy 136.186168 -168.289885) (xy 136.215632 -168.335743) (xy 136.23827 -168.385329) (xy 136.253621 -168.437631)
			(xy 136.261373 -168.491586) (xy 136.261856 -168.51884) (xy 136.261365 -168.546209) (xy 136.253555 -168.600388)
			(xy 136.238072 -168.652891) (xy 136.215236 -168.702639) (xy 136.185515 -168.748606) (xy 136.167876 -168.769538)
			(xy 136.16178 -168.77665) (xy 136.15543 -168.793668) (xy 136.15543 -168.879012) (xy 136.16178 -168.89603)
			(xy 136.167876 -168.903142) (xy 136.185556 -168.924043) (xy 136.215279 -168.970016) (xy 136.238122 -169.019768)
			(xy 136.253615 -169.072275) (xy 136.261439 -169.126458) (xy 136.261435 -169.181203) (xy 136.253602 -169.235384)
			(xy 136.2381 -169.287889) (xy 136.21525 -169.337636) (xy 136.185519 -169.383605) (xy 136.167876 -169.404538)
			(xy 136.16178 -169.41165) (xy 136.15543 -169.428668) (xy 136.15543 -169.514012) (xy 136.16178 -169.53103)
			(xy 136.167876 -169.538142) (xy 136.185556 -169.559043) (xy 136.215279 -169.605016) (xy 136.238122 -169.654768)
			(xy 136.253615 -169.707275) (xy 136.261439 -169.761458) (xy 136.261435 -169.816203) (xy 136.253602 -169.870384)
			(xy 136.2381 -169.922889) (xy 136.21525 -169.972636) (xy 136.185519 -170.018605) (xy 136.167876 -170.039538)
			(xy 136.16178 -170.04665) (xy 136.15543 -170.063668) (xy 136.15543 -170.149012) (xy 136.16178 -170.16603)
			(xy 136.167876 -170.173142) (xy 136.185556 -170.194043) (xy 136.215279 -170.240016) (xy 136.238122 -170.289768)
			(xy 136.253615 -170.342275) (xy 136.261439 -170.396458) (xy 136.261435 -170.451203) (xy 136.253602 -170.505384)
			(xy 136.2381 -170.557889) (xy 136.21525 -170.607636) (xy 136.185519 -170.653605) (xy 136.167876 -170.674538)
			(xy 136.16178 -170.68165) (xy 136.15543 -170.698668) (xy 136.15543 -170.784012) (xy 136.16178 -170.80103)
			(xy 136.167876 -170.808142) (xy 136.185556 -170.829043) (xy 136.215279 -170.875016) (xy 136.238122 -170.924768)
			(xy 136.253615 -170.977275) (xy 136.261439 -171.031458) (xy 136.261435 -171.086203) (xy 136.253602 -171.140384)
			(xy 136.2381 -171.192889) (xy 136.21525 -171.242636) (xy 136.185519 -171.288605) (xy 136.167876 -171.309538)
			(xy 136.16178 -171.31665) (xy 136.15543 -171.333668) (xy 136.15543 -171.419012) (xy 136.16178 -171.43603)
			(xy 136.167876 -171.443142) (xy 136.185498 -171.464088) (xy 136.215213 -171.510057) (xy 136.238053 -171.559801)
			(xy 136.253548 -171.612298) (xy 136.26138 -171.666472) (xy 136.261856 -171.69384) (xy 136.26136 -171.72109)
			(xy 136.253599 -171.775035) (xy 136.238241 -171.827326) (xy 136.215599 -171.876901) (xy 136.186133 -171.922749)
			(xy 136.150443 -171.963937) (xy 136.109255 -171.999628) (xy 136.063408 -172.029095) (xy 136.013834 -172.051738)
			(xy 135.961543 -172.067097) (xy 135.907598 -172.074859) (xy 135.880348 -172.075348) (xy 135.852978 -172.074866)
			(xy 135.798799 -172.067054) (xy 135.746296 -172.05157) (xy 135.696549 -172.028731) (xy 135.650582 -171.999009)
			(xy 135.62965 -171.981368) (xy 135.622538 -171.975272) (xy 135.60552 -171.968922) (xy 135.520176 -171.968922)
			(xy 135.503158 -171.975272) (xy 135.496046 -171.981368) (xy 135.475103 -171.998994) (xy 135.429134 -172.028709)
			(xy 135.379389 -172.051548) (xy 135.326891 -172.067042) (xy 135.272717 -172.074873) (xy 135.245348 -172.075348)
			(xy 135.215799 -172.074812) (xy 135.157408 -172.065693) (xy 135.101122 -172.047679) (xy 135.048286 -172.021203)
			(xy 135.000164 -171.986897) (xy 134.978648 -171.966636) (xy 134.971299 -171.96012) (xy 134.953149 -171.952666)
			(xy 134.943342 -171.952158) (xy 134.890002 -171.952158) (xy 134.882636 -171.960032) (xy 134.876086 -171.967354)
			(xy 134.868652 -171.985524) (xy 134.868158 -171.995338) (xy 134.868158 -172.027342) (xy 134.868643 -172.037156)
			(xy 134.87609 -172.05532) (xy 134.882636 -172.062648) (xy 134.90283 -172.084129) (xy 134.936972 -172.132193)
			(xy 134.963315 -172.184937) (xy 134.981232 -172.241106) (xy 134.990294 -172.299362) (xy 134.99084 -172.32884)
			(xy 134.990359 -172.356091) (xy 134.982598 -172.410037) (xy 134.96724 -172.46233) (xy 134.944596 -172.511905)
			(xy 134.915129 -172.557754) (xy 134.879437 -172.598943) (xy 134.838247 -172.634634) (xy 134.792398 -172.6641)
			(xy 134.742822 -172.686743) (xy 134.690529 -172.7021) (xy 134.636583 -172.70986) (xy 134.609332 -172.710348)
			(xy 134.581962 -172.709876) (xy 134.527783 -172.702061) (xy 134.475279 -172.686574) (xy 134.425532 -172.663734)
			(xy 134.379565 -172.634009) (xy 134.358634 -172.616368) (xy 134.351522 -172.610272) (xy 134.334504 -172.603922)
			(xy 134.24916 -172.603922) (xy 134.232142 -172.610272) (xy 134.22503 -172.616368) (xy 134.204093 -172.634002)
			(xy 134.158122 -172.663715) (xy 134.108376 -172.686553) (xy 134.055876 -172.702045) (xy 134.001701 -172.709874)
			(xy 133.974332 -172.710348) (xy 133.947083 -172.709792) (xy 133.89314 -172.702041) (xy 133.840849 -172.686692)
			(xy 133.791275 -172.664057) (xy 133.745426 -172.634598) (xy 133.704237 -172.598914) (xy 133.668545 -172.557731)
			(xy 133.639077 -172.511888) (xy 133.616433 -172.462318) (xy 133.601074 -172.41003) (xy 133.593313 -172.356089)
			(xy 133.592824 -172.32884) (xy 131.612225 -172.32884) (xy 131.612223 -172.356203) (xy 131.604389 -172.410385)
			(xy 131.588887 -172.462889) (xy 131.566036 -172.512637) (xy 131.536304 -172.558605) (xy 131.51866 -172.579538)
			(xy 131.512564 -172.58665) (xy 131.506214 -172.603668) (xy 131.506214 -172.689012) (xy 131.512564 -172.70603)
			(xy 131.51866 -172.713142) (xy 131.53634 -172.734043) (xy 131.566065 -172.780016) (xy 131.588908 -172.829767)
			(xy 131.604402 -172.882274) (xy 131.612227 -172.936457) (xy 131.612223 -172.991203) (xy 131.604389 -173.045385)
			(xy 131.588887 -173.097889) (xy 131.566036 -173.147637) (xy 131.536304 -173.193605) (xy 131.51866 -173.214538)
			(xy 131.512564 -173.22165) (xy 131.506214 -173.238668) (xy 131.506214 -173.324012) (xy 131.512564 -173.34103)
			(xy 131.51866 -173.348142) (xy 131.536279 -173.36909) (xy 131.565995 -173.415058) (xy 131.588836 -173.464801)
			(xy 131.604331 -173.517299) (xy 131.612164 -173.571472) (xy 131.61264 -173.59884) (xy 131.612159 -173.626091)
			(xy 131.604398 -173.680037) (xy 131.58904 -173.73233) (xy 131.566396 -173.781905) (xy 131.536929 -173.827754)
			(xy 131.501237 -173.868943) (xy 131.460047 -173.904634) (xy 131.414198 -173.9341) (xy 131.364622 -173.956743)
			(xy 131.312329 -173.9721) (xy 131.258383 -173.97986) (xy 131.231132 -173.980348) (xy 131.203762 -173.979876)
			(xy 131.149583 -173.972061) (xy 131.097079 -173.956574) (xy 131.047332 -173.933734) (xy 131.001365 -173.904009)
			(xy 130.980434 -173.886368) (xy 130.973322 -173.880272) (xy 130.956304 -173.873922) (xy 130.87096 -173.873922)
			(xy 130.853942 -173.880272) (xy 130.84683 -173.886368) (xy 130.825893 -173.904002) (xy 130.779922 -173.933715)
			(xy 130.730176 -173.956553) (xy 130.677676 -173.972045) (xy 130.623501 -173.979874) (xy 130.596132 -173.980348)
			(xy 130.568883 -173.979792) (xy 130.51494 -173.972041) (xy 130.462649 -173.956692) (xy 130.413075 -173.934057)
			(xy 130.367226 -173.904598) (xy 130.326037 -173.868914) (xy 130.290345 -173.827731) (xy 130.260877 -173.781888)
			(xy 130.238233 -173.732318) (xy 130.222874 -173.68003) (xy 130.215113 -173.626089) (xy 130.214624 -173.59884)
			(xy 128.456944 -173.59884) (xy 127.563626 -174.492158) (xy 127.542014 -174.512927) (xy 127.493493 -174.548112)
			(xy 127.440067 -174.575279) (xy 127.383051 -174.593758) (xy 127.323846 -174.603095) (xy 127.293878 -174.603664)
			(xy 121.909078 -174.603664) (xy 121.879106 -174.603116) (xy 121.819892 -174.593803) (xy 121.762867 -174.57533)
			(xy 121.709439 -174.548155) (xy 121.660926 -174.512948) (xy 121.63933 -174.492158) (xy 121.13133 -173.984158)
			(xy 121.110574 -173.962534) (xy 121.075388 -173.914016) (xy 121.048219 -173.860593) (xy 121.029737 -173.80358)
			(xy 121.020396 -173.744378) (xy 121.019824 -173.71441) (xy 121.019824 -172.06468) (xy 121.019429 -172.054607)
			(xy 121.011689 -172.036008) (xy 121.004838 -172.028612) (xy 120.286526 -171.3103) (xy 120.279067 -171.303578)
			(xy 120.260491 -171.296006) (xy 120.250458 -171.295568) (xy 119.800624 -171.295568) (xy 119.790622 -171.296107)
			(xy 119.772137 -171.303753) (xy 119.757984 -171.31789) (xy 119.750318 -171.336366) (xy 119.749824 -171.346368)
			(xy 119.749824 -171.426886) (xy 119.75025 -171.436955) (xy 119.75797 -171.455553) (xy 119.76481 -171.462954)
			(xy 120.705626 -172.403516) (xy 120.726361 -172.425158) (xy 120.761553 -172.473671) (xy 120.788726 -172.527089)
			(xy 120.807213 -172.584099) (xy 120.816558 -172.643298) (xy 120.817132 -172.673264) (xy 120.817132 -179.286408)
			(xy 120.816619 -179.316381) (xy 120.807294 -179.375596) (xy 120.788813 -179.432621) (xy 120.76163 -179.486048)
			(xy 120.726418 -179.534561) (xy 120.705626 -179.556156) (xy 119.235982 -181.0258) (xy 119.214411 -181.046631)
			(xy 119.165902 -181.081881) (xy 119.112474 -181.109106) (xy 119.055444 -181.127633) (xy 118.996216 -181.137007)
			(xy 118.966234 -181.13756) (xy 111.774224 -181.13756) (xy 111.764223 -181.138107) (xy 111.745739 -181.145751)
			(xy 111.731587 -181.159885) (xy 111.723919 -181.178359) (xy 111.723424 -181.18836) (xy 111.723424 -182.28564)
			(xy 121.299224 -182.28564) (xy 121.299708 -182.25827) (xy 121.30752 -182.204092) (xy 121.323005 -182.151589)
			(xy 121.345843 -182.101841) (xy 121.375564 -182.055874) (xy 121.393204 -182.034942) (xy 121.3993 -182.02783)
			(xy 121.40565 -182.010812) (xy 121.40565 -181.925468) (xy 121.3993 -181.90845) (xy 121.393204 -181.901338)
			(xy 121.375603 -181.880373) (xy 121.345879 -181.83441) (xy 121.323032 -181.784669) (xy 121.307534 -181.732172)
			(xy 121.299702 -181.677999) (xy 121.299698 -181.623262) (xy 121.307521 -181.569087) (xy 121.323011 -181.516587)
			(xy 121.34585 -181.466843) (xy 121.375567 -181.420875) (xy 121.393204 -181.399942) (xy 121.3993 -181.39283)
			(xy 121.40565 -181.375812) (xy 121.40565 -181.290468) (xy 121.3993 -181.27345) (xy 121.393204 -181.266338)
			(xy 121.375603 -181.245373) (xy 121.345879 -181.19941) (xy 121.323032 -181.149669) (xy 121.307534 -181.097172)
			(xy 121.299702 -181.042999) (xy 121.299698 -180.988262) (xy 121.307521 -180.934087) (xy 121.323011 -180.881587)
			(xy 121.34585 -180.831843) (xy 121.375567 -180.785875) (xy 121.393204 -180.764942) (xy 121.3993 -180.75783)
			(xy 121.40565 -180.740812) (xy 121.40565 -180.655468) (xy 121.3993 -180.63845) (xy 121.393204 -180.631338)
			(xy 121.375603 -180.610373) (xy 121.345879 -180.56441) (xy 121.323032 -180.514669) (xy 121.307534 -180.462172)
			(xy 121.299702 -180.407999) (xy 121.299698 -180.353262) (xy 121.307521 -180.299087) (xy 121.323011 -180.246587)
			(xy 121.34585 -180.196843) (xy 121.375567 -180.150875) (xy 121.393204 -180.129942) (xy 121.3993 -180.12283)
			(xy 121.40565 -180.105812) (xy 121.40565 -180.020468) (xy 121.3993 -180.00345) (xy 121.393204 -179.996338)
			(xy 121.375603 -179.975373) (xy 121.345879 -179.92941) (xy 121.323032 -179.879669) (xy 121.307534 -179.827172)
			(xy 121.299702 -179.772999) (xy 121.299698 -179.718262) (xy 121.307521 -179.664087) (xy 121.323011 -179.611587)
			(xy 121.34585 -179.561843) (xy 121.375567 -179.515875) (xy 121.393204 -179.494942) (xy 121.3993 -179.48783)
			(xy 121.40565 -179.470812) (xy 121.40565 -179.385468) (xy 121.3993 -179.36845) (xy 121.393204 -179.361338)
			(xy 121.375603 -179.340373) (xy 121.345879 -179.29441) (xy 121.323032 -179.244669) (xy 121.307534 -179.192172)
			(xy 121.299702 -179.137999) (xy 121.299698 -179.083262) (xy 121.307521 -179.029087) (xy 121.323011 -178.976587)
			(xy 121.34585 -178.926843) (xy 121.375567 -178.880875) (xy 121.393204 -178.859942) (xy 121.3993 -178.85283)
			(xy 121.40565 -178.835812) (xy 121.40565 -178.750468) (xy 121.3993 -178.73345) (xy 121.393204 -178.726338)
			(xy 121.375603 -178.705373) (xy 121.345879 -178.65941) (xy 121.323032 -178.609669) (xy 121.307534 -178.557172)
			(xy 121.299702 -178.502999) (xy 121.299698 -178.448262) (xy 121.307521 -178.394087) (xy 121.323011 -178.341587)
			(xy 121.34585 -178.291843) (xy 121.375567 -178.245875) (xy 121.393204 -178.224942) (xy 121.3993 -178.21783)
			(xy 121.40565 -178.200812) (xy 121.40565 -178.115468) (xy 121.3993 -178.09845) (xy 121.393204 -178.091338)
			(xy 121.37557 -178.070402) (xy 121.345857 -178.02443) (xy 121.32302 -177.974684) (xy 121.307528 -177.922184)
			(xy 121.299699 -177.868009) (xy 121.299224 -177.84064) (xy 121.29977 -177.811474) (xy 121.308667 -177.753823)
			(xy 121.326243 -177.698201) (xy 121.352088 -177.645906) (xy 121.385599 -177.59816) (xy 121.405396 -177.576734)
			(xy 121.412254 -177.569368) (xy 121.419366 -177.551588) (xy 121.419366 -177.461164) (xy 121.412254 -177.443384)
			(xy 121.405396 -177.436018) (xy 121.385611 -177.414586) (xy 121.352127 -177.366827) (xy 121.326295 -177.314532)
			(xy 121.308716 -177.258917) (xy 121.299799 -177.201275) (xy 121.299224 -177.172112) (xy 121.299667 -177.144858)
			(xy 121.307423 -177.090905) (xy 121.322779 -177.038604) (xy 121.345422 -176.989022) (xy 121.374892 -176.943168)
			(xy 121.410588 -176.901974) (xy 121.451784 -176.86628) (xy 121.49764 -176.836813) (xy 121.547223 -176.814172)
			(xy 121.599524 -176.798818) (xy 121.653478 -176.791065) (xy 121.680732 -176.790604) (xy 121.708103 -176.79105)
			(xy 121.762283 -176.798873) (xy 121.814786 -176.814366) (xy 121.864533 -176.837213) (xy 121.910499 -176.866941)
			(xy 121.93143 -176.884584) (xy 121.938542 -176.89068) (xy 121.95556 -176.89703) (xy 122.040904 -176.89703)
			(xy 122.057922 -176.89068) (xy 122.065034 -176.884584) (xy 122.085967 -176.866943) (xy 122.131935 -176.837219)
			(xy 122.181681 -176.814373) (xy 122.234183 -176.798877) (xy 122.288361 -176.791048) (xy 122.343103 -176.791048)
			(xy 122.397281 -176.798877) (xy 122.449783 -176.814373) (xy 122.499529 -176.837219) (xy 122.545497 -176.866943)
			(xy 122.56643 -176.884584) (xy 122.573542 -176.89068) (xy 122.59056 -176.89703) (xy 122.675904 -176.89703)
			(xy 122.692922 -176.89068) (xy 122.700034 -176.884584) (xy 122.720978 -176.86696) (xy 122.766948 -176.837246)
			(xy 122.816692 -176.814408) (xy 122.86919 -176.798913) (xy 122.923364 -176.791081) (xy 122.950732 -176.790604)
			(xy 122.977985 -176.791048) (xy 123.031934 -176.798809) (xy 123.084231 -176.814169) (xy 123.133809 -176.836815)
			(xy 123.17966 -176.866286) (xy 123.22085 -176.901981) (xy 123.256541 -176.943176) (xy 123.286006 -176.98903)
			(xy 123.308646 -177.038611) (xy 123.324 -177.090909) (xy 123.331755 -177.144859) (xy 123.33224 -177.172112)
			(xy 125.312424 -177.172112) (xy 125.312867 -177.144858) (xy 125.320623 -177.090905) (xy 125.335979 -177.038604)
			(xy 125.358622 -176.989022) (xy 125.388092 -176.943168) (xy 125.423788 -176.901974) (xy 125.464984 -176.86628)
			(xy 125.51084 -176.836813) (xy 125.560423 -176.814172) (xy 125.612724 -176.798818) (xy 125.666678 -176.791065)
			(xy 125.693932 -176.790604) (xy 125.721303 -176.79105) (xy 125.775483 -176.798873) (xy 125.827986 -176.814366)
			(xy 125.877733 -176.837213) (xy 125.923699 -176.866941) (xy 125.94463 -176.884584) (xy 125.951742 -176.89068)
			(xy 125.96876 -176.89703) (xy 126.054104 -176.89703) (xy 126.071122 -176.89068) (xy 126.078234 -176.884584)
			(xy 126.099167 -176.866943) (xy 126.145135 -176.837219) (xy 126.194881 -176.814373) (xy 126.247383 -176.798877)
			(xy 126.301561 -176.791048) (xy 126.356303 -176.791048) (xy 126.410481 -176.798877) (xy 126.462983 -176.814373)
			(xy 126.512729 -176.837219) (xy 126.558697 -176.866943) (xy 126.57963 -176.884584) (xy 126.586742 -176.89068)
			(xy 126.60376 -176.89703) (xy 126.689104 -176.89703) (xy 126.706122 -176.89068) (xy 126.713234 -176.884584)
			(xy 126.734178 -176.86696) (xy 126.780148 -176.837246) (xy 126.829892 -176.814408) (xy 126.88239 -176.798913)
			(xy 126.936564 -176.791081) (xy 126.963932 -176.790604) (xy 126.991185 -176.791048) (xy 127.045134 -176.798809)
			(xy 127.097431 -176.814169) (xy 127.147009 -176.836815) (xy 127.19286 -176.866286) (xy 127.23405 -176.901981)
			(xy 127.269741 -176.943176) (xy 127.299206 -176.98903) (xy 127.321846 -177.038611) (xy 127.3372 -177.090909)
			(xy 127.344955 -177.144859) (xy 127.34544 -177.172112) (xy 127.344905 -177.201231) (xy 127.336058 -177.258792)
			(xy 127.31857 -177.314341) (xy 127.292849 -177.366591) (xy 127.25949 -177.414327) (xy 127.239776 -177.435764)
			(xy 127.232918 -177.442876) (xy 127.225806 -177.46091) (xy 127.225806 -177.55108) (xy 127.233172 -177.569114)
			(xy 127.24003 -177.576226) (xy 127.259872 -177.59769) (xy 127.293469 -177.64552) (xy 127.319378 -177.697914)
			(xy 127.336993 -177.753647) (xy 127.345901 -177.811415) (xy 127.346456 -177.84064) (xy 127.345965 -177.868009)
			(xy 127.338155 -177.922188) (xy 127.322672 -177.974691) (xy 127.299836 -178.024439) (xy 127.270115 -178.070406)
			(xy 127.252476 -178.091338) (xy 127.24638 -178.09845) (xy 127.24003 -178.115468) (xy 127.24003 -178.200812)
			(xy 127.24638 -178.21783) (xy 127.252476 -178.224942) (xy 127.270156 -178.245843) (xy 127.299879 -178.291816)
			(xy 127.322722 -178.341568) (xy 127.338215 -178.394075) (xy 127.346039 -178.448258) (xy 127.346035 -178.503003)
			(xy 127.338202 -178.557184) (xy 127.3227 -178.609689) (xy 127.29985 -178.659436) (xy 127.270119 -178.705405)
			(xy 127.252476 -178.726338) (xy 127.24638 -178.73345) (xy 127.24003 -178.750468) (xy 127.24003 -178.835812)
			(xy 127.24638 -178.85283) (xy 127.252476 -178.859942) (xy 127.270098 -178.880888) (xy 127.299813 -178.926857)
			(xy 127.322653 -178.976601) (xy 127.338148 -179.029098) (xy 127.34598 -179.083272) (xy 127.346456 -179.11064)
			(xy 127.34596 -179.13789) (xy 127.338199 -179.191835) (xy 127.322841 -179.244126) (xy 127.300199 -179.293701)
			(xy 127.270733 -179.339549) (xy 127.235043 -179.380737) (xy 127.193855 -179.416428) (xy 127.148008 -179.445895)
			(xy 127.098434 -179.468538) (xy 127.046143 -179.483897) (xy 126.992198 -179.491659) (xy 126.964948 -179.492148)
			(xy 126.935506 -179.4916) (xy 126.877322 -179.482559) (xy 126.821217 -179.464683) (xy 126.768527 -179.438398)
			(xy 126.720501 -179.404329) (xy 126.69901 -179.384198) (xy 126.692406 -179.377594) (xy 126.675642 -179.370482)
			(xy 126.590298 -179.36591) (xy 126.573026 -179.371498) (xy 126.56566 -179.377086) (xy 126.545426 -179.392476)
			(xy 126.501634 -179.418299) (xy 126.454801 -179.438076) (xy 126.405755 -179.451457) (xy 126.355367 -179.458203)
			(xy 126.329948 -179.45862) (xy 126.302578 -179.458145) (xy 126.248398 -179.450333) (xy 126.195895 -179.434847)
			(xy 126.146147 -179.412006) (xy 126.100181 -179.382282) (xy 126.07925 -179.36464) (xy 126.072138 -179.358544)
			(xy 126.05512 -179.352194) (xy 125.969776 -179.352194) (xy 125.952758 -179.358544) (xy 125.945646 -179.36464)
			(xy 125.924713 -179.382278) (xy 125.87874 -179.411988) (xy 125.828992 -179.434824) (xy 125.776492 -179.450316)
			(xy 125.722317 -179.458145) (xy 125.694948 -179.45862) (xy 125.667697 -179.4581) (xy 125.613749 -179.45035)
			(xy 125.561453 -179.435001) (xy 125.511873 -179.412365) (xy 125.466021 -179.382903) (xy 125.424828 -179.347215)
			(xy 125.389133 -179.306028) (xy 125.359664 -179.260179) (xy 125.33702 -179.210604) (xy 125.321663 -179.15831)
			(xy 125.313904 -179.104363) (xy 125.31344 -179.077112) (xy 125.313903 -179.049742) (xy 125.32172 -178.995562)
			(xy 125.33721 -178.943058) (xy 125.360052 -178.893312) (xy 125.389778 -178.847345) (xy 125.40742 -178.826414)
			(xy 125.413516 -178.819302) (xy 125.419866 -178.802284) (xy 125.419866 -178.71694) (xy 125.413516 -178.699922)
			(xy 125.40742 -178.69281) (xy 125.389791 -178.671868) (xy 125.360067 -178.625901) (xy 125.337221 -178.576157)
			(xy 125.321724 -178.523656) (xy 125.313895 -178.469479) (xy 125.313893 -178.414739) (xy 125.32172 -178.360562)
			(xy 125.337215 -178.30806) (xy 125.360058 -178.258315) (xy 125.38978 -178.212347) (xy 125.40742 -178.191414)
			(xy 125.413516 -178.184302) (xy 125.419866 -178.167284) (xy 125.419866 -178.08194) (xy 125.413516 -178.064922)
			(xy 125.40742 -178.05781) (xy 125.389775 -178.036882) (xy 125.360064 -177.990909) (xy 125.337228 -177.94116)
			(xy 125.321739 -177.888658) (xy 125.313913 -177.834482) (xy 125.31344 -177.807112) (xy 125.313921 -177.779813)
			(xy 125.321692 -177.725771) (xy 125.33709 -177.67339) (xy 125.359802 -177.62374) (xy 125.389362 -177.577837)
			(xy 125.406912 -177.556922) (xy 125.413262 -177.54981) (xy 125.419358 -177.532792) (xy 125.419358 -177.447194)
			(xy 125.413008 -177.43043) (xy 125.406912 -177.423318) (xy 125.389209 -177.402348) (xy 125.359328 -177.356319)
			(xy 125.336359 -177.306479) (xy 125.320777 -177.253861) (xy 125.312903 -177.199551) (xy 125.312424 -177.172112)
			(xy 123.33224 -177.172112) (xy 123.331753 -177.199411) (xy 123.323981 -177.253451) (xy 123.308583 -177.305832)
			(xy 123.285873 -177.355481) (xy 123.256316 -177.401386) (xy 123.238768 -177.422302) (xy 123.232418 -177.429414)
			(xy 123.226322 -177.446432) (xy 123.226322 -177.53203) (xy 123.232672 -177.548794) (xy 123.238768 -177.555906)
			(xy 123.25648 -177.576869) (xy 123.28636 -177.6229) (xy 123.309327 -177.672741) (xy 123.324908 -177.725362)
			(xy 123.332778 -177.779673) (xy 123.333256 -177.807112) (xy 123.332808 -177.834483) (xy 123.324987 -177.888663)
			(xy 123.309495 -177.941167) (xy 123.286649 -177.990914) (xy 123.25692 -178.036879) (xy 123.239276 -178.05781)
			(xy 123.23318 -178.064922) (xy 123.22683 -178.08194) (xy 123.22683 -178.167284) (xy 123.23318 -178.184302)
			(xy 123.239276 -178.191414) (xy 123.256928 -178.212337) (xy 123.286652 -178.258307) (xy 123.309497 -178.308055)
			(xy 123.324992 -178.360558) (xy 123.33282 -178.414738) (xy 123.332818 -178.46948) (xy 123.324988 -178.52366)
			(xy 123.309491 -178.576162) (xy 123.286644 -178.625909) (xy 123.256917 -178.671877) (xy 123.239276 -178.69281)
			(xy 123.23318 -178.699922) (xy 123.22683 -178.71694) (xy 123.22683 -178.802284) (xy 123.23318 -178.819302)
			(xy 123.239276 -178.826414) (xy 123.256928 -178.847337) (xy 123.286652 -178.893307) (xy 123.309497 -178.943055)
			(xy 123.324992 -178.995558) (xy 123.33282 -179.049738) (xy 123.332818 -179.10448) (xy 123.324988 -179.15866)
			(xy 123.309491 -179.211162) (xy 123.286644 -179.260909) (xy 123.256917 -179.306877) (xy 123.239276 -179.32781)
			(xy 123.23318 -179.334922) (xy 123.22683 -179.35194) (xy 123.22683 -179.437284) (xy 123.23318 -179.454302)
			(xy 123.239276 -179.461414) (xy 123.256885 -179.482371) (xy 123.286602 -179.528336) (xy 123.309444 -179.578078)
			(xy 123.324942 -179.630573) (xy 123.332778 -179.684744) (xy 123.333256 -179.712112) (xy 123.33272 -179.741337)
			(xy 123.323795 -179.799103) (xy 123.306173 -179.854833) (xy 123.280264 -179.907228) (xy 123.246673 -179.955062)
			(xy 123.22683 -179.976526) (xy 123.219972 -179.983638) (xy 123.212606 -180.001672) (xy 123.212606 -180.091842)
			(xy 123.219718 -180.109876) (xy 123.226576 -180.116988) (xy 123.246304 -180.138413) (xy 123.279658 -180.186153)
			(xy 123.305373 -180.238406) (xy 123.322854 -180.293958) (xy 123.331694 -180.351521) (xy 123.33224 -180.38064)
			(xy 123.331753 -180.40801) (xy 123.323943 -180.462188) (xy 123.308459 -180.514692) (xy 123.285622 -180.564439)
			(xy 123.2559 -180.610406) (xy 123.23826 -180.631338) (xy 123.232164 -180.63845) (xy 123.225814 -180.655468)
			(xy 123.225814 -180.740812) (xy 123.232164 -180.75783) (xy 123.23826 -180.764942) (xy 123.25594 -180.785843)
			(xy 123.285665 -180.831816) (xy 123.308508 -180.881567) (xy 123.324002 -180.934074) (xy 123.331827 -180.988257)
			(xy 123.331823 -181.043003) (xy 123.323989 -181.097185) (xy 123.308487 -181.149689) (xy 123.285636 -181.199437)
			(xy 123.255904 -181.245405) (xy 123.23826 -181.266338) (xy 123.232164 -181.27345) (xy 123.225814 -181.290468)
			(xy 123.225814 -181.375812) (xy 123.232164 -181.39283) (xy 123.23826 -181.399942) (xy 123.255879 -181.42089)
			(xy 123.285595 -181.466858) (xy 123.308436 -181.516601) (xy 123.323931 -181.569099) (xy 123.331764 -181.623272)
			(xy 123.33224 -181.65064) (xy 123.331759 -181.677891) (xy 123.323998 -181.731837) (xy 123.30864 -181.78413)
			(xy 123.285996 -181.833705) (xy 123.256529 -181.879554) (xy 123.220837 -181.920743) (xy 123.179647 -181.956434)
			(xy 123.133798 -181.9859) (xy 123.084222 -182.008543) (xy 123.031929 -182.0239) (xy 122.977983 -182.03166)
			(xy 122.950732 -182.032148) (xy 122.923362 -182.031676) (xy 122.869183 -182.023861) (xy 122.816679 -182.008374)
			(xy 122.766932 -181.985534) (xy 122.720965 -181.955809) (xy 122.700034 -181.938168) (xy 122.692922 -181.932072)
			(xy 122.675904 -181.925722) (xy 122.59056 -181.925722) (xy 122.573542 -181.932072) (xy 122.56643 -181.938168)
			(xy 122.545493 -181.955802) (xy 122.499522 -181.985515) (xy 122.449776 -182.008353) (xy 122.397276 -182.023845)
			(xy 122.343101 -182.031674) (xy 122.315732 -182.032148) (xy 122.286254 -182.031603) (xy 122.228001 -182.022537)
			(xy 122.171836 -182.004617) (xy 122.119096 -181.978268) (xy 122.071039 -181.944119) (xy 122.04954 -181.923944)
			(xy 122.042193 -181.917426) (xy 122.024042 -181.909973) (xy 122.014234 -181.909466) (xy 121.960894 -181.909466)
			(xy 121.954036 -181.916832) (xy 121.947486 -181.924154) (xy 121.940052 -181.942324) (xy 121.939558 -181.952138)
			(xy 121.939558 -181.984142) (xy 121.940043 -181.993956) (xy 121.94749 -182.01212) (xy 121.954036 -182.019448)
			(xy 121.97423 -182.040929) (xy 122.008372 -182.088993) (xy 122.034715 -182.141737) (xy 122.052632 -182.197906)
			(xy 122.061694 -182.256162) (xy 122.06224 -182.28564) (xy 122.061754 -182.312891) (xy 122.053998 -182.366839)
			(xy 122.038643 -182.419134) (xy 122.016001 -182.468711) (xy 121.986535 -182.514561) (xy 121.950844 -182.555752)
			(xy 121.909653 -182.591443) (xy 121.863803 -182.620909) (xy 121.814226 -182.643551) (xy 121.761931 -182.658906)
			(xy 121.707983 -182.666662) (xy 121.653481 -182.666662) (xy 121.599533 -182.658906) (xy 121.547238 -182.643551)
			(xy 121.497661 -182.620909) (xy 121.451811 -182.591443) (xy 121.41062 -182.555752) (xy 121.374929 -182.514561)
			(xy 121.345463 -182.468711) (xy 121.322821 -182.419134) (xy 121.307466 -182.366839) (xy 121.29971 -182.312891)
			(xy 121.299224 -182.28564) (xy 111.723424 -182.28564) (xy 111.723424 -184.67451) (xy 111.722915 -184.704483)
			(xy 111.713589 -184.763698) (xy 111.695107 -184.820723) (xy 111.667924 -184.874151) (xy 111.63271 -184.922663)
			(xy 111.611918 -184.944258) (xy 108.856018 -187.700158) (xy 108.83441 -187.720931) (xy 108.785888 -187.756116)
			(xy 108.732461 -187.783281) (xy 108.675444 -187.801759) (xy 108.616239 -187.811095) (xy 108.58627 -187.811664)
			(xy 103.596948 -187.811664) (xy 103.586879 -187.812097) (xy 103.56828 -187.819811) (xy 103.56088 -187.82665)
			(xy 103.15321 -188.23432) (xy 103.14637 -188.24172) (xy 103.13865 -188.260319) (xy 103.138224 -188.270388)
			(xy 103.138224 -188.38164) (xy 113.076736 -188.38164) (xy 113.077217 -188.35427) (xy 113.08503 -188.300091)
			(xy 113.100515 -188.247588) (xy 113.123354 -188.197841) (xy 113.153076 -188.151874) (xy 113.170716 -188.130942)
			(xy 113.176812 -188.12383) (xy 113.183162 -188.106812) (xy 113.183162 -188.021468) (xy 113.176812 -188.00445)
			(xy 113.170716 -187.997338) (xy 113.153115 -187.976373) (xy 113.123389 -187.930411) (xy 113.100542 -187.88067)
			(xy 113.085043 -187.828173) (xy 113.077211 -187.773999) (xy 113.077207 -187.719262) (xy 113.085031 -187.665086)
			(xy 113.100521 -187.612587) (xy 113.12336 -187.562842) (xy 113.153079 -187.516875) (xy 113.170716 -187.495942)
			(xy 113.176812 -187.48883) (xy 113.183162 -187.471812) (xy 113.183162 -187.386468) (xy 113.176812 -187.36945)
			(xy 113.170716 -187.362338) (xy 113.153115 -187.341373) (xy 113.123389 -187.295411) (xy 113.100542 -187.24567)
			(xy 113.085043 -187.193173) (xy 113.077211 -187.138999) (xy 113.077207 -187.084262) (xy 113.085031 -187.030086)
			(xy 113.100521 -186.977587) (xy 113.12336 -186.927842) (xy 113.153079 -186.881875) (xy 113.170716 -186.860942)
			(xy 113.176812 -186.85383) (xy 113.183162 -186.836812) (xy 113.183162 -186.751468) (xy 113.176812 -186.73445)
			(xy 113.170716 -186.727338) (xy 113.153115 -186.706373) (xy 113.123389 -186.660411) (xy 113.100542 -186.61067)
			(xy 113.085043 -186.558173) (xy 113.077211 -186.503999) (xy 113.077207 -186.449262) (xy 113.085031 -186.395086)
			(xy 113.100521 -186.342587) (xy 113.12336 -186.292842) (xy 113.153079 -186.246875) (xy 113.170716 -186.225942)
			(xy 113.176812 -186.21883) (xy 113.183162 -186.201812) (xy 113.183162 -186.116468) (xy 113.176812 -186.09945)
			(xy 113.170716 -186.092338) (xy 113.153115 -186.071373) (xy 113.123389 -186.025411) (xy 113.100542 -185.97567)
			(xy 113.085043 -185.923173) (xy 113.077211 -185.868999) (xy 113.077207 -185.814262) (xy 113.085031 -185.760086)
			(xy 113.100521 -185.707587) (xy 113.12336 -185.657842) (xy 113.153079 -185.611875) (xy 113.170716 -185.590942)
			(xy 113.176812 -185.58383) (xy 113.183162 -185.566812) (xy 113.183162 -185.481468) (xy 113.176812 -185.46445)
			(xy 113.170716 -185.457338) (xy 113.153115 -185.436373) (xy 113.123389 -185.390411) (xy 113.100542 -185.34067)
			(xy 113.085043 -185.288173) (xy 113.077211 -185.233999) (xy 113.077207 -185.179262) (xy 113.085031 -185.125086)
			(xy 113.100521 -185.072587) (xy 113.12336 -185.022842) (xy 113.153079 -184.976875) (xy 113.170716 -184.955942)
			(xy 113.176812 -184.94883) (xy 113.183162 -184.931812) (xy 113.183162 -184.846468) (xy 113.176812 -184.82945)
			(xy 113.170716 -184.822338) (xy 113.153084 -184.8014) (xy 113.12337 -184.755429) (xy 113.100533 -184.705683)
			(xy 113.08504 -184.653184) (xy 113.077211 -184.599009) (xy 113.076736 -184.57164) (xy 113.077279 -184.542473)
			(xy 113.086176 -184.484823) (xy 113.103752 -184.429201) (xy 113.129598 -184.376906) (xy 113.163111 -184.32916)
			(xy 113.182908 -184.307734) (xy 113.189766 -184.300368) (xy 113.196878 -184.282588) (xy 113.196878 -184.192164)
			(xy 113.189766 -184.174384) (xy 113.182908 -184.167018) (xy 113.163125 -184.145584) (xy 113.12964 -184.097826)
			(xy 113.103808 -184.045531) (xy 113.086229 -183.989916) (xy 113.077311 -183.932275) (xy 113.076736 -183.903112)
			(xy 113.077167 -183.875857) (xy 113.084923 -183.821903) (xy 113.10028 -183.769602) (xy 113.122924 -183.720019)
			(xy 113.152395 -183.674164) (xy 113.188092 -183.63297) (xy 113.229289 -183.597276) (xy 113.275147 -183.567809)
			(xy 113.324732 -183.545169) (xy 113.377034 -183.529816) (xy 113.430989 -183.522064) (xy 113.458244 -183.521604)
			(xy 113.485613 -183.522102) (xy 113.539791 -183.529912) (xy 113.592294 -183.545393) (xy 113.642041 -183.568228)
			(xy 113.688009 -183.597946) (xy 113.708942 -183.615584) (xy 113.716054 -183.62168) (xy 113.733072 -183.62803)
			(xy 113.818416 -183.62803) (xy 113.835434 -183.62168) (xy 113.842546 -183.615584) (xy 113.863479 -183.597943)
			(xy 113.909447 -183.568219) (xy 113.959193 -183.545373) (xy 114.011695 -183.529877) (xy 114.065873 -183.522048)
			(xy 114.120615 -183.522048) (xy 114.174793 -183.529877) (xy 114.227295 -183.545373) (xy 114.277041 -183.568219)
			(xy 114.323009 -183.597943) (xy 114.343942 -183.615584) (xy 114.351054 -183.62168) (xy 114.368072 -183.62803)
			(xy 114.453416 -183.62803) (xy 114.470434 -183.62168) (xy 114.477546 -183.615584) (xy 114.498486 -183.597954)
			(xy 114.544457 -183.568242) (xy 114.594202 -183.545404) (xy 114.646701 -183.529911) (xy 114.700875 -183.52208)
			(xy 114.728244 -183.521604) (xy 114.755497 -183.522037) (xy 114.809447 -183.5298) (xy 114.861744 -183.545161)
			(xy 114.911322 -183.567808) (xy 114.957173 -183.59728) (xy 114.998363 -183.632977) (xy 115.034053 -183.674172)
			(xy 115.063519 -183.720027) (xy 115.086159 -183.769609) (xy 115.101512 -183.821908) (xy 115.109267 -183.875859)
			(xy 115.109752 -183.903112) (xy 117.089936 -183.903112) (xy 117.090367 -183.875857) (xy 117.098123 -183.821903)
			(xy 117.11348 -183.769602) (xy 117.136124 -183.720019) (xy 117.165595 -183.674164) (xy 117.201292 -183.63297)
			(xy 117.242489 -183.597276) (xy 117.288347 -183.567809) (xy 117.337932 -183.545169) (xy 117.390234 -183.529816)
			(xy 117.444189 -183.522064) (xy 117.471444 -183.521604) (xy 117.498813 -183.522102) (xy 117.552991 -183.529912)
			(xy 117.605494 -183.545393) (xy 117.655241 -183.568228) (xy 117.701209 -183.597946) (xy 117.722142 -183.615584)
			(xy 117.729254 -183.62168) (xy 117.746272 -183.62803) (xy 117.831616 -183.62803) (xy 117.848634 -183.62168)
			(xy 117.855746 -183.615584) (xy 117.876679 -183.597943) (xy 117.922647 -183.568219) (xy 117.972393 -183.545373)
			(xy 118.024895 -183.529877) (xy 118.079073 -183.522048) (xy 118.133815 -183.522048) (xy 118.187993 -183.529877)
			(xy 118.240495 -183.545373) (xy 118.290241 -183.568219) (xy 118.336209 -183.597943) (xy 118.357142 -183.615584)
			(xy 118.364254 -183.62168) (xy 118.381272 -183.62803) (xy 118.466616 -183.62803) (xy 118.483634 -183.62168)
			(xy 118.490746 -183.615584) (xy 118.511686 -183.597954) (xy 118.557657 -183.568242) (xy 118.607402 -183.545404)
			(xy 118.659901 -183.529911) (xy 118.714075 -183.52208) (xy 118.741444 -183.521604) (xy 118.768697 -183.522037)
			(xy 118.822647 -183.5298) (xy 118.874944 -183.545161) (xy 118.924522 -183.567808) (xy 118.970373 -183.59728)
			(xy 119.011563 -183.632977) (xy 119.047253 -183.674172) (xy 119.076719 -183.720027) (xy 119.099359 -183.769609)
			(xy 119.114712 -183.821908) (xy 119.122467 -183.875859) (xy 119.122952 -183.903112) (xy 119.122414 -183.93223)
			(xy 119.113567 -183.989791) (xy 119.09608 -184.045341) (xy 119.070359 -184.09759) (xy 119.037002 -184.145327)
			(xy 119.017288 -184.166764) (xy 119.01043 -184.173876) (xy 119.003318 -184.19191) (xy 119.003318 -184.28208)
			(xy 119.010684 -184.300114) (xy 119.017542 -184.307226) (xy 119.037386 -184.328688) (xy 119.070982 -184.376519)
			(xy 119.096891 -184.428914) (xy 119.114505 -184.484647) (xy 119.123413 -184.542415) (xy 119.123968 -184.57164)
			(xy 119.123559 -184.598894) (xy 119.115796 -184.652847) (xy 119.100434 -184.705145) (xy 119.077785 -184.754725)
			(xy 119.048311 -184.800577) (xy 119.012612 -184.841768) (xy 118.971413 -184.877459) (xy 118.925555 -184.906924)
			(xy 118.87597 -184.929562) (xy 118.823668 -184.944913) (xy 118.769714 -184.952665) (xy 118.74246 -184.953148)
			(xy 118.716175 -184.952671) (xy 118.664099 -184.945476) (xy 118.613504 -184.931202) (xy 118.565348 -184.910117)
			(xy 118.520541 -184.882622) (xy 118.479933 -184.849236) (xy 118.46179 -184.830212) (xy 118.454779 -184.823327)
			(xy 118.43702 -184.814961) (xy 118.427246 -184.813956) (xy 118.373906 -184.811162) (xy 118.366286 -184.818274)
			(xy 118.366286 -184.871614) (xy 118.366778 -184.881428) (xy 118.374219 -184.899592) (xy 118.380764 -184.90692)
			(xy 118.400949 -184.928409) (xy 118.435092 -184.976472) (xy 118.461436 -185.029214) (xy 118.479354 -185.08538)
			(xy 118.48842 -185.143634) (xy 118.488968 -185.173112) (xy 118.488556 -185.200367) (xy 118.480797 -185.254322)
			(xy 118.465437 -185.306623) (xy 118.44279 -185.356206) (xy 118.413317 -185.402061) (xy 118.377618 -185.443255)
			(xy 118.336419 -185.478948) (xy 118.29056 -185.508415) (xy 118.240974 -185.531055) (xy 118.188671 -185.546408)
			(xy 118.134715 -185.55416) (xy 118.10746 -185.55462) (xy 118.077984 -185.554037) (xy 118.019733 -185.544978)
			(xy 117.963569 -185.527065) (xy 117.910829 -185.500725) (xy 117.862769 -185.466586) (xy 117.841268 -185.446416)
			(xy 117.833937 -185.439877) (xy 117.815774 -185.432434) (xy 117.805962 -185.431938) (xy 117.752622 -185.431938)
			(xy 117.745764 -185.439304) (xy 117.73923 -185.446639) (xy 117.731786 -185.464799) (xy 117.731286 -185.47461)
			(xy 117.731286 -185.506614) (xy 117.731778 -185.516428) (xy 117.739219 -185.534592) (xy 117.745764 -185.54192)
			(xy 117.765949 -185.563409) (xy 117.800092 -185.611472) (xy 117.826436 -185.664214) (xy 117.844354 -185.72038)
			(xy 117.85342 -185.778634) (xy 117.853968 -185.808112) (xy 117.853482 -185.835363) (xy 117.845726 -185.889311)
			(xy 117.830371 -185.941606) (xy 117.807729 -185.991183) (xy 117.778263 -186.037033) (xy 117.742572 -186.078224)
			(xy 117.701381 -186.113915) (xy 117.655531 -186.143381) (xy 117.605954 -186.166023) (xy 117.553659 -186.181378)
			(xy 117.499711 -186.189134) (xy 117.445209 -186.189134) (xy 117.391261 -186.181378) (xy 117.338966 -186.166023)
			(xy 117.289389 -186.143381) (xy 117.243539 -186.113915) (xy 117.202348 -186.078224) (xy 117.166657 -186.037033)
			(xy 117.137191 -185.991183) (xy 117.114549 -185.941606) (xy 117.099194 -185.889311) (xy 117.091438 -185.835363)
			(xy 117.090952 -185.808112) (xy 117.091412 -185.780741) (xy 117.09923 -185.726562) (xy 117.114719 -185.674058)
			(xy 117.137563 -185.624311) (xy 117.167289 -185.578345) (xy 117.184932 -185.557414) (xy 117.191028 -185.550302)
			(xy 117.197378 -185.533284) (xy 117.197378 -185.44794) (xy 117.191028 -185.430922) (xy 117.184932 -185.42381)
			(xy 117.167303 -185.402868) (xy 117.137577 -185.356902) (xy 117.114731 -185.307157) (xy 117.099233 -185.254656)
			(xy 117.091404 -185.200479) (xy 117.091402 -185.145739) (xy 117.09923 -185.091561) (xy 117.114724 -185.03906)
			(xy 117.137568 -184.989314) (xy 117.167292 -184.943347) (xy 117.184932 -184.922414) (xy 117.191028 -184.915302)
			(xy 117.197378 -184.898284) (xy 117.197378 -184.81294) (xy 117.191028 -184.795922) (xy 117.184932 -184.78881)
			(xy 117.167289 -184.767881) (xy 117.137577 -184.721908) (xy 117.114741 -184.67216) (xy 117.099251 -184.619658)
			(xy 117.091425 -184.565481) (xy 117.090952 -184.538112) (xy 117.091455 -184.510814) (xy 117.099223 -184.456774)
			(xy 117.114618 -184.404394) (xy 117.137324 -184.354744) (xy 117.166878 -184.308839) (xy 117.184424 -184.287922)
			(xy 117.190774 -184.28081) (xy 117.19687 -184.263792) (xy 117.19687 -184.178194) (xy 117.19052 -184.16143)
			(xy 117.184424 -184.154318) (xy 117.166722 -184.133347) (xy 117.136841 -184.087318) (xy 117.113872 -184.037479)
			(xy 117.098289 -183.98486) (xy 117.090415 -183.930551) (xy 117.089936 -183.903112) (xy 115.109752 -183.903112)
			(xy 115.109287 -183.930412) (xy 115.101512 -183.984454) (xy 115.08611 -184.036836) (xy 115.063395 -184.086485)
			(xy 115.033831 -184.132387) (xy 115.01628 -184.153302) (xy 115.00993 -184.160414) (xy 115.003834 -184.177432)
			(xy 115.003834 -184.26303) (xy 115.010184 -184.279794) (xy 115.01628 -184.286906) (xy 115.033993 -184.307868)
			(xy 115.063873 -184.353899) (xy 115.08684 -184.403741) (xy 115.10242 -184.456361) (xy 115.110291 -184.510673)
			(xy 115.110768 -184.538112) (xy 115.110317 -184.565483) (xy 115.102497 -184.619663) (xy 115.087004 -184.672166)
			(xy 115.064159 -184.721913) (xy 115.034431 -184.767879) (xy 115.016788 -184.78881) (xy 115.010692 -184.795922)
			(xy 115.004342 -184.81294) (xy 115.004342 -184.898284) (xy 115.010692 -184.915302) (xy 115.016788 -184.922414)
			(xy 115.03444 -184.943338) (xy 115.064163 -184.989307) (xy 115.087007 -185.039055) (xy 115.102501 -185.091558)
			(xy 115.110329 -185.145738) (xy 115.110327 -185.20048) (xy 115.102498 -185.254659) (xy 115.087 -185.307162)
			(xy 115.064154 -185.356909) (xy 115.034429 -185.402877) (xy 115.016788 -185.42381) (xy 115.010692 -185.430922)
			(xy 115.004342 -185.44794) (xy 115.004342 -185.533284) (xy 115.010692 -185.550302) (xy 115.016788 -185.557414)
			(xy 115.03444 -185.578338) (xy 115.064163 -185.624307) (xy 115.087007 -185.674055) (xy 115.102501 -185.726558)
			(xy 115.110329 -185.780738) (xy 115.110327 -185.83548) (xy 115.102498 -185.889659) (xy 115.087 -185.942162)
			(xy 115.064154 -185.991909) (xy 115.034429 -186.037877) (xy 115.016788 -186.05881) (xy 115.010692 -186.065922)
			(xy 115.004342 -186.08294) (xy 115.004342 -186.168284) (xy 115.010692 -186.185302) (xy 115.016788 -186.192414)
			(xy 115.034398 -186.213369) (xy 115.064115 -186.259335) (xy 115.086957 -186.309077) (xy 115.102454 -186.361573)
			(xy 115.11029 -186.415744) (xy 115.110768 -186.443112) (xy 115.110228 -186.472337) (xy 115.101304 -186.530102)
			(xy 115.083683 -186.585833) (xy 115.057774 -186.638227) (xy 115.024184 -186.686062) (xy 115.004342 -186.707526)
			(xy 114.997484 -186.714638) (xy 114.990118 -186.732672) (xy 114.990118 -186.822842) (xy 114.99723 -186.840876)
			(xy 115.004088 -186.847988) (xy 115.023818 -186.869411) (xy 115.057171 -186.917152) (xy 115.082886 -186.969405)
			(xy 115.100366 -187.024958) (xy 115.109206 -187.082521) (xy 115.109752 -187.11164) (xy 115.109262 -187.13901)
			(xy 115.101452 -187.193188) (xy 115.085969 -187.245691) (xy 115.063132 -187.295439) (xy 115.033412 -187.341406)
			(xy 115.015772 -187.362338) (xy 115.009676 -187.36945) (xy 115.003326 -187.386468) (xy 115.003326 -187.471812)
			(xy 115.009676 -187.48883) (xy 115.015772 -187.495942) (xy 115.033452 -187.516843) (xy 115.063175 -187.562816)
			(xy 115.086018 -187.612568) (xy 115.101511 -187.665075) (xy 115.109336 -187.719258) (xy 115.109332 -187.774003)
			(xy 115.101499 -187.828184) (xy 115.085997 -187.880689) (xy 115.063146 -187.930437) (xy 115.033416 -187.976405)
			(xy 115.015772 -187.997338) (xy 115.009676 -188.00445) (xy 115.003326 -188.021468) (xy 115.003326 -188.106812)
			(xy 115.009676 -188.12383) (xy 115.015772 -188.130942) (xy 115.033393 -188.151889) (xy 115.063109 -188.197857)
			(xy 115.085948 -188.247601) (xy 115.101444 -188.300098) (xy 115.109276 -188.354272) (xy 115.109752 -188.38164)
			(xy 115.10926 -188.40889) (xy 115.101499 -188.462835) (xy 115.086141 -188.515127) (xy 115.063498 -188.564702)
			(xy 115.034032 -188.61055) (xy 114.998341 -188.651738) (xy 114.957153 -188.687429) (xy 114.911305 -188.716896)
			(xy 114.861731 -188.739539) (xy 114.809439 -188.754898) (xy 114.755494 -188.762659) (xy 114.728244 -188.763148)
			(xy 114.700874 -188.762669) (xy 114.646695 -188.754856) (xy 114.594192 -188.739371) (xy 114.544444 -188.716532)
			(xy 114.498478 -188.686809) (xy 114.477546 -188.669168) (xy 114.470434 -188.663072) (xy 114.453416 -188.656722)
			(xy 114.368072 -188.656722) (xy 114.351054 -188.663072) (xy 114.343942 -188.669168) (xy 114.323009 -188.686809)
			(xy 114.277041 -188.716533) (xy 114.227295 -188.739379) (xy 114.174793 -188.754875) (xy 114.120615 -188.762704)
			(xy 114.065873 -188.762704) (xy 114.011695 -188.754875) (xy 113.959193 -188.739379) (xy 113.909447 -188.716533)
			(xy 113.863479 -188.686809) (xy 113.842546 -188.669168) (xy 113.835434 -188.663072) (xy 113.818416 -188.656722)
			(xy 113.733072 -188.656722) (xy 113.716054 -188.663072) (xy 113.708942 -188.669168) (xy 113.688001 -188.686796)
			(xy 113.642031 -188.716511) (xy 113.592286 -188.739349) (xy 113.539787 -188.754843) (xy 113.485613 -188.762673)
			(xy 113.458244 -188.763148) (xy 113.430994 -188.762604) (xy 113.377048 -188.754854) (xy 113.324754 -188.739506)
			(xy 113.275177 -188.716871) (xy 113.229325 -188.687411) (xy 113.188133 -188.651726) (xy 113.152439 -188.610542)
			(xy 113.122969 -188.564697) (xy 113.100324 -188.515125) (xy 113.084964 -188.462834) (xy 113.077202 -188.40889)
			(xy 113.076736 -188.38164) (xy 103.138224 -188.38164) (xy 103.138224 -190.123318) (xy 103.137656 -190.153289)
			(xy 103.128345 -190.212501) (xy 103.109876 -190.269525) (xy 103.082706 -190.322954) (xy 103.047505 -190.371469)
			(xy 103.026718 -190.393066) (xy 102.163626 -191.256158) (xy 102.142014 -191.276927) (xy 102.093493 -191.312112)
			(xy 102.040067 -191.339279) (xy 101.983051 -191.357758) (xy 101.923846 -191.367095) (xy 101.893878 -191.367664)
			(xy 93.892878 -191.367664) (xy 93.862906 -191.367116) (xy 93.803692 -191.357803) (xy 93.746667 -191.33933)
			(xy 93.693239 -191.312155) (xy 93.644726 -191.276948) (xy 93.62313 -191.256158) (xy 93.293692 -190.92672)
			(xy 93.286331 -190.919951) (xy 93.267869 -190.912304) (xy 93.247887 -190.912304) (xy 93.229425 -190.919951)
			(xy 93.222064 -190.92672) (xy 92.892626 -191.256158) (xy 92.871014 -191.276927) (xy 92.822493 -191.312112)
			(xy 92.769067 -191.339279) (xy 92.712051 -191.357758) (xy 92.652846 -191.367095) (xy 92.622878 -191.367664)
			(xy 86.272878 -191.367664) (xy 86.242906 -191.367116) (xy 86.183692 -191.357803) (xy 86.126667 -191.33933)
			(xy 86.073239 -191.312155) (xy 86.024726 -191.276948) (xy 86.00313 -191.256158) (xy 85.673692 -190.92672)
			(xy 85.666331 -190.919951) (xy 85.647869 -190.912304) (xy 85.627887 -190.912304) (xy 85.609425 -190.919951)
			(xy 85.602064 -190.92672) (xy 85.272626 -191.256158) (xy 85.251014 -191.276927) (xy 85.202493 -191.312112)
			(xy 85.149067 -191.339279) (xy 85.092051 -191.357758) (xy 85.032846 -191.367095) (xy 85.002878 -191.367664)
			(xy 78.652878 -191.367664) (xy 78.622906 -191.367116) (xy 78.563692 -191.357803) (xy 78.506667 -191.33933)
			(xy 78.453239 -191.312155) (xy 78.404726 -191.276948) (xy 78.38313 -191.256158) (xy 77.62113 -190.494158)
			(xy 77.600374 -190.472534) (xy 77.565188 -190.424016) (xy 77.538019 -190.370593) (xy 77.519537 -190.31358)
			(xy 77.510196 -190.254378) (xy 77.509624 -190.22441) (xy 77.509624 -188.49848) (xy 77.509229 -188.488407)
			(xy 77.501489 -188.469808) (xy 77.494638 -188.462412) (xy 76.35113 -187.319158) (xy 76.330374 -187.297534)
			(xy 76.295188 -187.249016) (xy 76.268019 -187.195593) (xy 76.249537 -187.13858) (xy 76.240196 -187.079378)
			(xy 76.239624 -187.04941) (xy 76.239624 -183.41848) (xy 76.239229 -183.408407) (xy 76.231489 -183.389808)
			(xy 76.224638 -183.382412) (xy 75.969876 -183.12765) (xy 75.962472 -183.120814) (xy 75.943876 -183.11309)
			(xy 75.933808 -183.112664) (xy 69.000878 -183.112664) (xy 68.970906 -183.112116) (xy 68.911692 -183.102803)
			(xy 68.854667 -183.08433) (xy 68.801239 -183.057155) (xy 68.752726 -183.021948) (xy 68.73113 -183.001158)
			(xy 68.22313 -182.493158) (xy 68.202374 -182.471534) (xy 68.167188 -182.423016) (xy 68.140019 -182.369593)
			(xy 68.121537 -182.31258) (xy 68.112196 -182.253378) (xy 68.111624 -182.22341) (xy 67.914806 -182.22341)
			(xy 67.909555 -182.259748) (xy 67.894058 -182.312251) (xy 67.871211 -182.361997) (xy 67.841484 -182.407964)
			(xy 67.823842 -182.428896) (xy 67.817746 -182.436008) (xy 67.811396 -182.453026) (xy 67.811396 -182.53837)
			(xy 67.817746 -182.555388) (xy 67.823842 -182.5625) (xy 67.841482 -182.583434) (xy 67.871209 -182.629401)
			(xy 67.894057 -182.679146) (xy 67.909554 -182.731649) (xy 67.917384 -182.785828) (xy 67.917384 -182.840569)
			(xy 67.909555 -182.894748) (xy 67.894058 -182.947251) (xy 67.871211 -182.996997) (xy 67.841484 -183.042964)
			(xy 67.823842 -183.063896) (xy 67.817746 -183.071008) (xy 67.811396 -183.088026) (xy 67.811396 -183.17337)
			(xy 67.817746 -183.190388) (xy 67.823842 -183.1975) (xy 67.841501 -183.218416) (xy 67.871209 -183.264394)
			(xy 67.89404 -183.314145) (xy 67.909527 -183.366649) (xy 67.917351 -183.420828) (xy 67.917822 -183.448198)
			(xy 67.917258 -183.477471) (xy 67.908294 -183.535328) (xy 67.890592 -183.591135) (xy 67.864566 -183.643579)
			(xy 67.83083 -183.69143) (xy 67.810888 -183.712866) (xy 67.804538 -183.719724) (xy 67.797172 -183.736742)
			(xy 67.793616 -183.822848) (xy 67.799458 -183.840374) (xy 67.8053 -183.84774) (xy 67.821526 -183.86824)
			(xy 67.848782 -183.912855) (xy 67.869683 -183.960777) (xy 67.883836 -184.011107) (xy 67.890978 -184.062899)
			(xy 67.891406 -184.08904) (xy 67.890903 -184.116409) (xy 67.883094 -184.170586) (xy 67.867613 -184.223089)
			(xy 67.84478 -184.272836) (xy 67.815063 -184.318805) (xy 67.797426 -184.339738) (xy 67.79133 -184.34685)
			(xy 67.78498 -184.363868) (xy 67.78498 -184.449212) (xy 67.79133 -184.46623) (xy 67.797426 -184.473342)
			(xy 67.815108 -184.494242) (xy 67.844835 -184.540214) (xy 67.86768 -184.589966) (xy 67.883176 -184.642473)
			(xy 67.891002 -184.696657) (xy 67.890997 -184.751403) (xy 67.883163 -184.805586) (xy 67.867659 -184.858091)
			(xy 67.844806 -184.907839) (xy 67.815071 -184.953806) (xy 67.797426 -184.974738) (xy 67.79133 -184.98185)
			(xy 67.78498 -184.998868) (xy 67.78498 -185.084212) (xy 67.79133 -185.10123) (xy 67.797426 -185.108342)
			(xy 67.815108 -185.129242) (xy 67.844835 -185.175214) (xy 67.86768 -185.224966) (xy 67.883176 -185.277473)
			(xy 67.891002 -185.331657) (xy 67.890997 -185.386403) (xy 67.883163 -185.440586) (xy 67.867659 -185.493091)
			(xy 67.844806 -185.542839) (xy 67.815071 -185.588806) (xy 67.797426 -185.609738) (xy 67.79133 -185.61685)
			(xy 67.78498 -185.633868) (xy 67.78498 -185.719212) (xy 67.79133 -185.73623) (xy 67.797426 -185.743342)
			(xy 67.815108 -185.764242) (xy 67.844835 -185.810214) (xy 67.86768 -185.859966) (xy 67.883176 -185.912473)
			(xy 67.891002 -185.966657) (xy 67.890997 -186.021403) (xy 67.883163 -186.075586) (xy 67.867659 -186.128091)
			(xy 67.844806 -186.177839) (xy 67.815071 -186.223806) (xy 67.797426 -186.244738) (xy 67.79133 -186.25185)
			(xy 67.78498 -186.268868) (xy 67.78498 -186.354212) (xy 67.79133 -186.37123) (xy 67.797426 -186.378342)
			(xy 67.815108 -186.399242) (xy 67.844835 -186.445214) (xy 67.86768 -186.494966) (xy 67.883176 -186.547473)
			(xy 67.891002 -186.601657) (xy 67.890997 -186.656403) (xy 67.883163 -186.710586) (xy 67.867659 -186.763091)
			(xy 67.844806 -186.812839) (xy 67.815071 -186.858806) (xy 67.797426 -186.879738) (xy 67.79133 -186.88685)
			(xy 67.78498 -186.903868) (xy 67.78498 -186.989212) (xy 67.79133 -187.00623) (xy 67.797426 -187.013342)
			(xy 67.815055 -187.034282) (xy 67.844768 -187.080253) (xy 67.867605 -187.129998) (xy 67.883099 -187.182497)
			(xy 67.89093 -187.236671) (xy 67.891406 -187.26404) (xy 67.890959 -187.291292) (xy 67.883197 -187.345242)
			(xy 67.867837 -187.397537) (xy 67.845191 -187.447115) (xy 67.81572 -187.492965) (xy 67.780025 -187.534155)
			(xy 67.738831 -187.569846) (xy 67.692978 -187.599311) (xy 67.643398 -187.621952) (xy 67.5911 -187.637306)
			(xy 67.53715 -187.645062) (xy 67.509898 -187.645548) (xy 67.482527 -187.645096) (xy 67.428347 -187.637277)
			(xy 67.375843 -187.621785) (xy 67.326096 -187.59894) (xy 67.280131 -187.569211) (xy 67.2592 -187.551568)
			(xy 67.252088 -187.545472) (xy 67.23507 -187.539122) (xy 67.149726 -187.539122) (xy 67.132708 -187.545472)
			(xy 67.125596 -187.551568) (xy 67.104672 -187.569217) (xy 67.058698 -187.598929) (xy 67.008948 -187.621763)
			(xy 66.956445 -187.637252) (xy 66.902268 -187.645076) (xy 66.874898 -187.645548) (xy 66.847649 -187.645024)
			(xy 66.793704 -187.637268) (xy 66.741413 -187.621915) (xy 66.691838 -187.599277) (xy 66.64599 -187.569814)
			(xy 66.6048 -187.534126) (xy 66.569109 -187.492941) (xy 66.539642 -187.447095) (xy 66.516998 -187.397523)
			(xy 66.50164 -187.345233) (xy 66.493879 -187.291289) (xy 66.49339 -187.26404) (xy 64.53632 -187.26404)
			(xy 65.473834 -188.201554) (xy 65.474342 -188.202062) (xy 65.481723 -188.208645) (xy 65.500022 -188.216098)
			(xy 65.509902 -188.21654) (xy 76.285598 -188.21654) (xy 76.295667 -188.216964) (xy 76.314269 -188.224682)
			(xy 76.321666 -188.231526) (xy 77.274674 -189.184534) (xy 77.281518 -189.191933) (xy 77.289244 -189.210531)
			(xy 77.28966 -189.220602) (xy 77.28966 -191.726058) (xy 77.290126 -191.735933) (xy 77.297575 -191.754225)
			(xy 77.304138 -191.761618) (xy 77.304392 -191.761872) (xy 78.547214 -193.004694) (xy 78.547722 -193.005202)
			(xy 78.555099 -193.011795) (xy 78.573399 -193.019264) (xy 78.583282 -193.01968)
		)
		(stroke
			(width 0)
			(type solid)
		)
		(fill yes)
		(layer "In6.Cu")
		(net "GND")
	)
	(gr_poly
		(pts
			(xy 121.842784 -440.718448) (xy 121.852846 -440.718008) (xy 121.871424 -440.710266) (xy 121.878852 -440.703462)
			(xy 122.780044 -439.80227) (xy 122.786892 -439.794872) (xy 122.794624 -439.776274) (xy 122.79503 -439.766202)
			(xy 122.79503 -421.79494) (xy 122.76963 -421.766238) (xy 122.750072 -421.764206) (xy 122.719504 -421.760164)
			(xy 122.659582 -421.745628) (xy 122.601854 -421.723958) (xy 122.547168 -421.695471) (xy 122.496325 -421.660586)
			(xy 122.45007 -421.619812) (xy 122.409081 -421.573748) (xy 122.373958 -421.523068) (xy 122.345216 -421.468516)
			(xy 122.323277 -421.41089) (xy 122.308461 -421.351036) (xy 122.300986 -421.28983) (xy 122.300492 -421.259)
			(xy 122.300492 -421.258746) (xy 122.301221 -421.219428) (xy 122.313334 -421.14173) (xy 122.324622 -421.10406)
			(xy 122.329194 -421.09009) (xy 122.32259 -421.062912) (xy 121.98731 -420.727632) (xy 121.979346 -420.720493)
			(xy 121.959395 -420.712858) (xy 121.948702 -420.7129) (xy 121.862342 -420.717726) (xy 121.843292 -420.727378)
			(xy 121.836434 -420.736014) (xy 121.818203 -420.757837) (xy 121.77638 -420.796364) (xy 121.729306 -420.828263)
			(xy 121.678023 -420.85283) (xy 121.623664 -420.869521) (xy 121.567432 -420.877967) (xy 121.539 -420.878508)
			(xy 121.511749 -420.878022) (xy 121.457801 -420.870266) (xy 121.405506 -420.854911) (xy 121.355929 -420.832269)
			(xy 121.310079 -420.802803) (xy 121.268888 -420.767112) (xy 121.233197 -420.725921) (xy 121.203731 -420.680071)
			(xy 121.181089 -420.630494) (xy 121.165734 -420.578199) (xy 121.157978 -420.524251) (xy 121.157492 -420.497)
			(xy 121.158016 -420.468567) (xy 121.166455 -420.412331) (xy 121.183145 -420.35797) (xy 121.207717 -420.306688)
			(xy 121.239628 -420.259619) (xy 121.278169 -420.217808) (xy 121.299986 -420.199566) (xy 121.308622 -420.192708)
			(xy 121.318274 -420.173658) (xy 121.3231 -420.087298) (xy 121.323214 -420.076592) (xy 121.315572 -420.056612)
			(xy 121.308368 -420.04869) (xy 120.819164 -419.559486) (xy 120.811544 -419.553136) (xy 120.009412 -419.017196)
			(xy 119.982114 -418.9984) (xy 119.931579 -418.955515) (xy 119.886277 -418.907134) (xy 119.866156 -418.880798)
			(xy 119.571008 -418.483034) (xy 119.563393 -418.473816) (xy 119.542055 -418.463098) (xy 119.530114 -418.46246)
			(xy 115.971828 -418.46246) (xy 115.961765 -418.462022) (xy 115.943183 -418.454285) (xy 115.93576 -418.447474)
			(xy 113.497868 -416.009582) (xy 113.490472 -416.002732) (xy 113.471873 -415.994996) (xy 113.4618 -415.994596)
			(xy 107.299252 -415.994596) (xy 107.26674 -416.006534) (xy 107.246055 -416.023199) (xy 107.200946 -416.051249)
			(xy 107.152383 -416.072773) (xy 107.101304 -416.087354) (xy 107.048698 -416.094712) (xy 107.022138 -416.09518)
			(xy 106.994884 -416.094719) (xy 106.940931 -416.086967) (xy 106.88863 -416.071613) (xy 106.839047 -416.048973)
			(xy 106.793191 -416.019505) (xy 106.751996 -415.983811) (xy 106.716301 -415.942617) (xy 106.686832 -415.896762)
			(xy 106.66419 -415.84718) (xy 106.648836 -415.794879) (xy 106.641081 -415.740926) (xy 106.64063 -415.713672)
			(xy 106.64063 -415.713418) (xy 106.641258 -415.682373) (xy 106.651336 -415.621105) (xy 106.660696 -415.591498)
			(xy 106.665522 -415.577528) (xy 106.658918 -415.549588) (xy 106.378248 -415.268918) (xy 106.369954 -415.261475)
			(xy 106.348998 -415.253975) (xy 106.337862 -415.25444) (xy 106.248708 -415.262568) (xy 106.22915 -415.273998)
			(xy 106.2228 -415.283396) (xy 106.205221 -415.307929) (xy 106.163608 -415.351639) (xy 106.115632 -415.388252)
			(xy 106.06249 -415.416856) (xy 106.005508 -415.436737) (xy 105.975912 -415.442654) (xy 105.965498 -415.444686)
			(xy 105.948734 -415.455608) (xy 105.896156 -415.533332) (xy 105.892346 -415.553144) (xy 105.894632 -415.563304)
			(xy 105.898357 -415.582517) (xy 105.9023 -415.621458) (xy 105.902506 -415.641028) (xy 105.90202 -415.668279)
			(xy 105.894264 -415.722227) (xy 105.878909 -415.774522) (xy 105.856267 -415.824099) (xy 105.826801 -415.869949)
			(xy 105.79111 -415.91114) (xy 105.749919 -415.946831) (xy 105.704069 -415.976297) (xy 105.654492 -415.998939)
			(xy 105.602197 -416.014294) (xy 105.548249 -416.02205) (xy 105.493747 -416.02205) (xy 105.439799 -416.014294)
			(xy 105.387504 -415.998939) (xy 105.337927 -415.976297) (xy 105.292077 -415.946831) (xy 105.250886 -415.91114)
			(xy 105.215195 -415.869949) (xy 105.185729 -415.824099) (xy 105.163087 -415.774522) (xy 105.147732 -415.722227)
			(xy 105.139976 -415.668279) (xy 105.13949 -415.641028) (xy 105.139948 -415.614451) (xy 105.147325 -415.561811)
			(xy 105.16194 -415.510706) (xy 105.183509 -415.462125) (xy 105.211615 -415.41701) (xy 105.245713 -415.376234)
			(xy 105.285142 -415.340588) (xy 105.32914 -415.310762) (xy 105.376852 -415.287335) (xy 105.427356 -415.270759)
			(xy 105.453434 -415.265616) (xy 105.463848 -415.263584) (xy 105.480612 -415.252662) (xy 105.53319 -415.174938)
			(xy 105.537 -415.155126) (xy 105.534714 -415.144966) (xy 105.53099 -415.125753) (xy 105.52705 -415.086812)
			(xy 105.52684 -415.067242) (xy 105.527285 -415.040835) (xy 105.534563 -414.988524) (xy 105.548987 -414.937717)
			(xy 105.570279 -414.889385) (xy 105.598034 -414.844451) (xy 105.631721 -414.803775) (xy 105.670696 -414.768133)
			(xy 105.692194 -414.75279) (xy 105.701592 -414.74644) (xy 105.713022 -414.726882) (xy 105.72115 -414.637728)
			(xy 105.721586 -414.6266) (xy 105.71408 -414.605657) (xy 105.706672 -414.597342) (xy 104.977438 -413.868108)
			(xy 104.970586 -413.860712) (xy 104.962843 -413.842113) (xy 104.962452 -413.83204) (xy 104.962452 -412.058358)
			(xy 104.96202 -412.048292) (xy 104.954289 -412.029703) (xy 104.947466 -412.02229) (xy 104.511856 -411.58668)
			(xy 104.504459 -411.579832) (xy 104.48586 -411.572101) (xy 104.475788 -411.571694) (xy 103.515668 -411.571694)
			(xy 103.48722 -411.596586) (xy 103.48468 -411.615636) (xy 103.479881 -411.647594) (xy 103.463244 -411.710041)
			(xy 103.438842 -411.769882) (xy 103.407068 -411.826156) (xy 103.38816 -411.852364) (xy 103.382787 -411.860183)
			(xy 103.377714 -411.878451) (xy 103.378254 -411.887924) (xy 103.381302 -411.918658) (xy 103.382736 -411.927994)
			(xy 103.391341 -411.94479) (xy 103.398066 -411.951424) (xy 103.42062 -411.97213) (xy 103.461114 -412.018056)
			(xy 103.495798 -412.068513) (xy 103.524171 -412.122771) (xy 103.545821 -412.180044) (xy 103.560435 -412.239502)
			(xy 103.567801 -412.300286) (xy 103.568246 -412.3309) (xy 103.567744 -412.362861) (xy 103.559733 -412.426279)
			(xy 103.543836 -412.488193) (xy 103.520304 -412.547626) (xy 103.48951 -412.603641) (xy 103.451937 -412.655356)
			(xy 103.40818 -412.701953) (xy 103.358927 -412.742698) (xy 103.304956 -412.776949) (xy 103.247117 -412.804166)
			(xy 103.186324 -412.823919) (xy 103.123534 -412.835897) (xy 103.059738 -412.839911) (xy 102.995942 -412.835897)
			(xy 102.933152 -412.823919) (xy 102.872359 -412.804166) (xy 102.81452 -412.776949) (xy 102.760549 -412.742698)
			(xy 102.711296 -412.701953) (xy 102.667539 -412.655356) (xy 102.629966 -412.603641) (xy 102.599172 -412.547626)
			(xy 102.57564 -412.488193) (xy 102.559743 -412.426279) (xy 102.551732 -412.362861) (xy 102.55123 -412.3309)
			(xy 102.551731 -412.298266) (xy 102.560081 -412.233535) (xy 102.576644 -412.170404) (xy 102.601147 -412.10991)
			(xy 102.633189 -412.053049) (xy 102.652322 -412.026608) (xy 102.657708 -412.018792) (xy 102.662809 -412.000522)
			(xy 102.662228 -411.991048) (xy 102.65918 -411.960314) (xy 102.657757 -411.950972) (xy 102.649165 -411.934161)
			(xy 102.642416 -411.927548) (xy 102.619864 -411.906841) (xy 102.579374 -411.860914) (xy 102.544694 -411.810456)
			(xy 102.516325 -411.756198) (xy 102.494679 -411.698926) (xy 102.480069 -411.639468) (xy 102.472706 -411.578685)
			(xy 102.472236 -411.548072) (xy 102.472683 -411.517634) (xy 102.479948 -411.457192) (xy 102.494371 -411.398048)
			(xy 102.515746 -411.341047) (xy 102.543768 -411.287003) (xy 102.578037 -411.236688) (xy 102.618063 -411.190819)
			(xy 102.640384 -411.17012) (xy 102.648258 -411.163008) (xy 102.656894 -411.144466) (xy 102.65918 -411.060138)
			(xy 102.658943 -411.049746) (xy 102.651203 -411.030477) (xy 102.644194 -411.0228) (xy 101.69525 -410.073856)
			(xy 101.665532 -410.068014) (xy 101.651054 -410.073602) (xy 101.620535 -410.085474) (xy 101.557217 -410.102181)
			(xy 101.49228 -410.110639) (xy 101.459538 -410.111194) (xy 101.428805 -410.110751) (xy 101.367786 -410.103346)
			(xy 101.308105 -410.088639) (xy 101.250631 -410.066846) (xy 101.196204 -410.038283) (xy 101.145617 -410.003368)
			(xy 101.099607 -409.96261) (xy 101.058847 -409.916602) (xy 101.023929 -409.866016) (xy 100.995364 -409.811591)
			(xy 100.973568 -409.754118) (xy 100.958859 -409.694438) (xy 100.951451 -409.633419) (xy 100.95103 -409.602686)
			(xy 100.95103 -409.600908) (xy 100.950672 -409.591891) (xy 100.94443 -409.574971) (xy 100.938838 -409.567888)
			(xy 100.91928 -409.544774) (xy 100.913042 -409.538072) (xy 100.897032 -409.529215) (xy 100.888038 -409.527502)
			(xy 100.851602 -409.521472) (xy 100.780537 -409.501368) (xy 100.7126 -409.472401) (xy 100.648894 -409.435039)
			(xy 100.590449 -409.389888) (xy 100.563934 -409.36418) (xy 100.088192 -408.888438) (xy 100.065512 -408.865138)
			(xy 100.024969 -408.814298) (xy 99.990376 -408.759237) (xy 99.962168 -408.700647) (xy 99.9407 -408.639267)
			(xy 99.926243 -408.575868) (xy 99.918977 -408.511249) (xy 99.91852 -408.478736) (xy 99.91852 -406.912064)
			(xy 99.918091 -406.901996) (xy 99.91037 -406.883399) (xy 99.903534 -406.875996) (xy 99.437444 -406.41016)
			(xy 99.429539 -406.402934) (xy 99.409546 -406.395308) (xy 99.398836 -406.395428) (xy 99.312476 -406.4)
			(xy 99.293426 -406.409652) (xy 99.286568 -406.418288) (xy 99.265823 -406.443225) (xy 99.219035 -406.488153)
			(xy 99.166913 -406.526767) (xy 99.110303 -406.558437) (xy 99.050125 -406.582651) (xy 98.987356 -406.599015)
			(xy 98.923015 -406.607262) (xy 98.890582 -406.607772) (xy 98.859851 -406.607325) (xy 98.798839 -406.599915)
			(xy 98.739164 -406.585204) (xy 98.681697 -406.563407) (xy 98.627278 -406.534842) (xy 98.576698 -406.499925)
			(xy 98.530695 -406.459166) (xy 98.489942 -406.41316) (xy 98.45503 -406.362576) (xy 98.426471 -406.308153)
			(xy 98.40468 -406.250685) (xy 98.389976 -406.191008) (xy 98.382571 -406.129995) (xy 98.382074 -406.099264)
			(xy 98.382587 -406.066832) (xy 98.39084 -406.002494) (xy 98.407208 -405.939728) (xy 98.431424 -405.879553)
			(xy 98.463096 -405.822946) (xy 98.501709 -405.770826) (xy 98.546636 -405.72404) (xy 98.571558 -405.703278)
			(xy 98.580194 -405.69642) (xy 98.589846 -405.67737) (xy 98.594418 -405.59101) (xy 98.594538 -405.580299)
			(xy 98.586924 -405.560296) (xy 98.579686 -405.552402) (xy 98.32848 -405.301196) (xy 98.321133 -405.294389)
			(xy 98.302671 -405.286665) (xy 98.292666 -405.28621) (xy 97.203006 -405.28621) (xy 97.1804 -405.291544)
			(xy 97.154006 -405.304169) (xy 97.098945 -405.323959) (xy 97.041974 -405.337288) (xy 96.983849 -405.343979)
			(xy 96.954594 -405.344376) (xy 96.925341 -405.343961) (xy 96.867222 -405.337246) (xy 96.810255 -405.323916)
			(xy 96.75519 -405.304148) (xy 96.728788 -405.291544) (xy 96.706182 -405.28621) (xy 95.133668 -405.28621)
			(xy 95.09252 -405.307292) (xy 95.076969 -405.327991) (xy 95.040867 -405.365098) (xy 94.999772 -405.396587)
			(xy 94.954552 -405.421794) (xy 94.906158 -405.440189) (xy 94.855611 -405.451383) (xy 94.803976 -405.455141)
			(xy 94.752341 -405.451383) (xy 94.701794 -405.440189) (xy 94.6534 -405.421794) (xy 94.60818 -405.396587)
			(xy 94.567085 -405.365098) (xy 94.530983 -405.327991) (xy 94.515432 -405.307292) (xy 94.474284 -405.28621)
			(xy 93.874844 -405.28621) (xy 93.833696 -405.307292) (xy 93.818145 -405.327991) (xy 93.782043 -405.365098)
			(xy 93.740948 -405.396587) (xy 93.695728 -405.421794) (xy 93.647334 -405.440189) (xy 93.596787 -405.451383)
			(xy 93.545152 -405.455141) (xy 93.493517 -405.451383) (xy 93.44297 -405.440189) (xy 93.394576 -405.421794)
			(xy 93.349356 -405.396587) (xy 93.308261 -405.365098) (xy 93.272159 -405.327991) (xy 93.256608 -405.307292)
			(xy 93.21546 -405.28621) (xy 92.070428 -405.28621) (xy 92.02928 -405.307292) (xy 92.013729 -405.327991)
			(xy 91.977627 -405.365098) (xy 91.936532 -405.396587) (xy 91.891312 -405.421794) (xy 91.842918 -405.440189)
			(xy 91.792371 -405.451383) (xy 91.740736 -405.455141) (xy 91.689101 -405.451383) (xy 91.638554 -405.440189)
			(xy 91.59016 -405.421794) (xy 91.54494 -405.396587) (xy 91.503845 -405.365098) (xy 91.467743 -405.327991)
			(xy 91.452192 -405.307292) (xy 91.411044 -405.28621) (xy 90.811604 -405.28621) (xy 90.770456 -405.307292)
			(xy 90.754905 -405.327991) (xy 90.718803 -405.365098) (xy 90.677708 -405.396587) (xy 90.632488 -405.421794)
			(xy 90.584094 -405.440189) (xy 90.533547 -405.451383) (xy 90.481912 -405.455141) (xy 90.430277 -405.451383)
			(xy 90.37973 -405.440189) (xy 90.331336 -405.421794) (xy 90.286116 -405.396587) (xy 90.245021 -405.365098)
			(xy 90.208919 -405.327991) (xy 90.193368 -405.307292) (xy 90.15222 -405.28621) (xy 89.007188 -405.28621)
			(xy 88.96604 -405.307292) (xy 88.950489 -405.327991) (xy 88.914387 -405.365098) (xy 88.873292 -405.396587)
			(xy 88.828072 -405.421794) (xy 88.779678 -405.440189) (xy 88.729131 -405.451383) (xy 88.677496 -405.455141)
			(xy 88.625861 -405.451383) (xy 88.575314 -405.440189) (xy 88.52692 -405.421794) (xy 88.4817 -405.396587)
			(xy 88.440605 -405.365098) (xy 88.404503 -405.327991) (xy 88.388952 -405.307292) (xy 88.347804 -405.28621)
			(xy 87.748364 -405.28621) (xy 87.707216 -405.307292) (xy 87.691665 -405.327991) (xy 87.655563 -405.365098)
			(xy 87.614468 -405.396587) (xy 87.569248 -405.421794) (xy 87.520854 -405.440189) (xy 87.470307 -405.451383)
			(xy 87.418672 -405.455141) (xy 87.367037 -405.451383) (xy 87.31649 -405.440189) (xy 87.268096 -405.421794)
			(xy 87.222876 -405.396587) (xy 87.181781 -405.365098) (xy 87.145679 -405.327991) (xy 87.130128 -405.307292)
			(xy 87.08898 -405.28621) (xy 85.943948 -405.28621) (xy 85.9028 -405.307292) (xy 85.887249 -405.327991)
			(xy 85.851147 -405.365098) (xy 85.810052 -405.396587) (xy 85.764832 -405.421794) (xy 85.716438 -405.440189)
			(xy 85.665891 -405.451383) (xy 85.614256 -405.455141) (xy 85.562621 -405.451383) (xy 85.512074 -405.440189)
			(xy 85.46368 -405.421794) (xy 85.41846 -405.396587) (xy 85.377365 -405.365098) (xy 85.341263 -405.327991)
			(xy 85.325712 -405.307292) (xy 85.284564 -405.28621) (xy 84.685124 -405.28621) (xy 84.643976 -405.307292)
			(xy 84.628425 -405.327991) (xy 84.592323 -405.365098) (xy 84.551228 -405.396587) (xy 84.506008 -405.421794)
			(xy 84.457614 -405.440189) (xy 84.407067 -405.451383) (xy 84.355432 -405.455141) (xy 84.303797 -405.451383)
			(xy 84.25325 -405.440189) (xy 84.204856 -405.421794) (xy 84.159636 -405.396587) (xy 84.118541 -405.365098)
			(xy 84.082439 -405.327991) (xy 84.066888 -405.307292) (xy 84.02574 -405.28621) (xy 82.880708 -405.28621)
			(xy 82.83956 -405.307292) (xy 82.824009 -405.327991) (xy 82.787907 -405.365098) (xy 82.746812 -405.396587)
			(xy 82.701592 -405.421794) (xy 82.653198 -405.440189) (xy 82.602651 -405.451383) (xy 82.551016 -405.455141)
			(xy 82.499381 -405.451383) (xy 82.448834 -405.440189) (xy 82.40044 -405.421794) (xy 82.35522 -405.396587)
			(xy 82.314125 -405.365098) (xy 82.278023 -405.327991) (xy 82.262472 -405.307292) (xy 82.221324 -405.28621)
			(xy 81.621884 -405.28621) (xy 81.580736 -405.307292) (xy 81.565185 -405.327991) (xy 81.529083 -405.365098)
			(xy 81.487988 -405.396587) (xy 81.442768 -405.421794) (xy 81.394374 -405.440189) (xy 81.343827 -405.451383)
			(xy 81.292192 -405.455141) (xy 81.240557 -405.451383) (xy 81.19001 -405.440189) (xy 81.141616 -405.421794)
			(xy 81.096396 -405.396587) (xy 81.055301 -405.365098) (xy 81.019199 -405.327991) (xy 81.003648 -405.307292)
			(xy 80.9625 -405.28621) (xy 79.817468 -405.28621) (xy 79.77632 -405.307292) (xy 79.760769 -405.327991)
			(xy 79.724667 -405.365098) (xy 79.683572 -405.396587) (xy 79.638352 -405.421794) (xy 79.589958 -405.440189)
			(xy 79.539411 -405.451383) (xy 79.487776 -405.455141) (xy 79.436141 -405.451383) (xy 79.385594 -405.440189)
			(xy 79.3372 -405.421794) (xy 79.29198 -405.396587) (xy 79.250885 -405.365098) (xy 79.214783 -405.327991)
			(xy 79.199232 -405.307292) (xy 79.158084 -405.28621) (xy 78.558644 -405.28621) (xy 78.517496 -405.307292)
			(xy 78.501945 -405.327991) (xy 78.465843 -405.365098) (xy 78.424748 -405.396587) (xy 78.379528 -405.421794)
			(xy 78.331134 -405.440189) (xy 78.280587 -405.451383) (xy 78.228952 -405.455141) (xy 78.177317 -405.451383)
			(xy 78.12677 -405.440189) (xy 78.078376 -405.421794) (xy 78.033156 -405.396587) (xy 77.992061 -405.365098)
			(xy 77.955959 -405.327991) (xy 77.940408 -405.307292) (xy 77.89926 -405.28621) (xy 76.754228 -405.28621)
			(xy 76.71308 -405.307292) (xy 76.697529 -405.327991) (xy 76.661427 -405.365098) (xy 76.620332 -405.396587)
			(xy 76.575112 -405.421794) (xy 76.526718 -405.440189) (xy 76.476171 -405.451383) (xy 76.424536 -405.455141)
			(xy 76.372901 -405.451383) (xy 76.322354 -405.440189) (xy 76.27396 -405.421794) (xy 76.22874 -405.396587)
			(xy 76.187645 -405.365098) (xy 76.151543 -405.327991) (xy 76.135992 -405.307292) (xy 76.094844 -405.28621)
			(xy 75.495404 -405.28621) (xy 75.454256 -405.307292) (xy 75.438705 -405.327991) (xy 75.402603 -405.365098)
			(xy 75.361508 -405.396587) (xy 75.316288 -405.421794) (xy 75.267894 -405.440189) (xy 75.217347 -405.451383)
			(xy 75.165712 -405.455141) (xy 75.114077 -405.451383) (xy 75.06353 -405.440189) (xy 75.015136 -405.421794)
			(xy 74.969916 -405.396587) (xy 74.928821 -405.365098) (xy 74.892719 -405.327991) (xy 74.877168 -405.307292)
			(xy 74.83602 -405.28621) (xy 73.690988 -405.28621) (xy 73.64984 -405.307292) (xy 73.634289 -405.327991)
			(xy 73.598187 -405.365098) (xy 73.557092 -405.396587) (xy 73.511872 -405.421794) (xy 73.463478 -405.440189)
			(xy 73.412931 -405.451383) (xy 73.361296 -405.455141) (xy 73.309661 -405.451383) (xy 73.259114 -405.440189)
			(xy 73.21072 -405.421794) (xy 73.1655 -405.396587) (xy 73.124405 -405.365098) (xy 73.088303 -405.327991)
			(xy 73.072752 -405.307292) (xy 73.031604 -405.28621) (xy 72.432164 -405.28621) (xy 72.391016 -405.307292)
			(xy 72.375465 -405.327991) (xy 72.339363 -405.365098) (xy 72.298268 -405.396587) (xy 72.253048 -405.421794)
			(xy 72.204654 -405.440189) (xy 72.154107 -405.451383) (xy 72.102472 -405.455141) (xy 72.050837 -405.451383)
			(xy 72.00029 -405.440189) (xy 71.951896 -405.421794) (xy 71.906676 -405.396587) (xy 71.865581 -405.365098)
			(xy 71.829479 -405.327991) (xy 71.813928 -405.307292) (xy 71.77278 -405.28621) (xy 70.627748 -405.28621)
			(xy 70.5866 -405.307292) (xy 70.571049 -405.327991) (xy 70.534947 -405.365098) (xy 70.493852 -405.396587)
			(xy 70.448632 -405.421794) (xy 70.400238 -405.440189) (xy 70.349691 -405.451383) (xy 70.298056 -405.455141)
			(xy 70.246421 -405.451383) (xy 70.195874 -405.440189) (xy 70.14748 -405.421794) (xy 70.10226 -405.396587)
			(xy 70.061165 -405.365098) (xy 70.025063 -405.327991) (xy 70.009512 -405.307292) (xy 69.968364 -405.28621)
			(xy 69.368924 -405.28621) (xy 69.327776 -405.307292) (xy 69.312225 -405.327991) (xy 69.276123 -405.365098)
			(xy 69.235028 -405.396587) (xy 69.189808 -405.421794) (xy 69.141414 -405.440189) (xy 69.090867 -405.451383)
			(xy 69.039232 -405.455141) (xy 68.987597 -405.451383) (xy 68.93705 -405.440189) (xy 68.888656 -405.421794)
			(xy 68.843436 -405.396587) (xy 68.802341 -405.365098) (xy 68.766239 -405.327991) (xy 68.750688 -405.307292)
			(xy 68.70954 -405.28621) (xy 67.564508 -405.28621) (xy 67.52336 -405.307292) (xy 67.507809 -405.327991)
			(xy 67.471707 -405.365098) (xy 67.430612 -405.396587) (xy 67.385392 -405.421794) (xy 67.336998 -405.440189)
			(xy 67.286451 -405.451383) (xy 67.234816 -405.455141) (xy 67.183181 -405.451383) (xy 67.132634 -405.440189)
			(xy 67.08424 -405.421794) (xy 67.03902 -405.396587) (xy 66.997925 -405.365098) (xy 66.961823 -405.327991)
			(xy 66.946272 -405.307292) (xy 66.905124 -405.28621) (xy 66.305684 -405.28621) (xy 66.264536 -405.307292)
			(xy 66.248985 -405.327991) (xy 66.212883 -405.365098) (xy 66.171788 -405.396587) (xy 66.126568 -405.421794)
			(xy 66.078174 -405.440189) (xy 66.027627 -405.451383) (xy 65.975992 -405.455141) (xy 65.924357 -405.451383)
			(xy 65.87381 -405.440189) (xy 65.825416 -405.421794) (xy 65.780196 -405.396587) (xy 65.739101 -405.365098)
			(xy 65.702999 -405.327991) (xy 65.687448 -405.307292) (xy 65.6463 -405.28621) (xy 64.501268 -405.28621)
			(xy 64.46012 -405.307292) (xy 64.444569 -405.327991) (xy 64.408467 -405.365098) (xy 64.367372 -405.396587)
			(xy 64.322152 -405.421794) (xy 64.273758 -405.440189) (xy 64.223211 -405.451383) (xy 64.171576 -405.455141)
			(xy 64.119941 -405.451383) (xy 64.069394 -405.440189) (xy 64.021 -405.421794) (xy 63.97578 -405.396587)
			(xy 63.934685 -405.365098) (xy 63.898583 -405.327991) (xy 63.883032 -405.307292) (xy 63.841884 -405.28621)
			(xy 63.242444 -405.28621) (xy 63.201296 -405.307292) (xy 63.185745 -405.327991) (xy 63.149643 -405.365098)
			(xy 63.108548 -405.396587) (xy 63.063328 -405.421794) (xy 63.014934 -405.440189) (xy 62.964387 -405.451383)
			(xy 62.912752 -405.455141) (xy 62.861117 -405.451383) (xy 62.81057 -405.440189) (xy 62.762176 -405.421794)
			(xy 62.716956 -405.396587) (xy 62.675861 -405.365098) (xy 62.639759 -405.327991) (xy 62.624208 -405.307292)
			(xy 62.58306 -405.28621) (xy 61.438028 -405.28621) (xy 61.39688 -405.307292) (xy 61.381329 -405.327991)
			(xy 61.345227 -405.365098) (xy 61.304132 -405.396587) (xy 61.258912 -405.421794) (xy 61.210518 -405.440189)
			(xy 61.159971 -405.451383) (xy 61.108336 -405.455141) (xy 61.056701 -405.451383) (xy 61.006154 -405.440189)
			(xy 60.95776 -405.421794) (xy 60.91254 -405.396587) (xy 60.871445 -405.365098) (xy 60.835343 -405.327991)
			(xy 60.819792 -405.307292) (xy 60.778644 -405.28621) (xy 60.179204 -405.28621) (xy 60.138056 -405.307292)
			(xy 60.122505 -405.327991) (xy 60.086403 -405.365098) (xy 60.045308 -405.396587) (xy 60.000088 -405.421794)
			(xy 59.951694 -405.440189) (xy 59.901147 -405.451383) (xy 59.849512 -405.455141) (xy 59.797877 -405.451383)
			(xy 59.74733 -405.440189) (xy 59.698936 -405.421794) (xy 59.653716 -405.396587) (xy 59.612621 -405.365098)
			(xy 59.576519 -405.327991) (xy 59.560968 -405.307292) (xy 59.51982 -405.28621) (xy 58.374788 -405.28621)
			(xy 58.33364 -405.307292) (xy 58.318089 -405.327991) (xy 58.281987 -405.365098) (xy 58.240892 -405.396587)
			(xy 58.195672 -405.421794) (xy 58.147278 -405.440189) (xy 58.096731 -405.451383) (xy 58.045096 -405.455141)
			(xy 57.993461 -405.451383) (xy 57.942914 -405.440189) (xy 57.89452 -405.421794) (xy 57.8493 -405.396587)
			(xy 57.808205 -405.365098) (xy 57.772103 -405.327991) (xy 57.756552 -405.307292) (xy 57.715404 -405.28621)
			(xy 57.115964 -405.28621) (xy 57.074816 -405.307292) (xy 57.059265 -405.327991) (xy 57.023163 -405.365098)
			(xy 56.982068 -405.396587) (xy 56.936848 -405.421794) (xy 56.888454 -405.440189) (xy 56.837907 -405.451383)
			(xy 56.786272 -405.455141) (xy 56.734637 -405.451383) (xy 56.68409 -405.440189) (xy 56.635696 -405.421794)
			(xy 56.590476 -405.396587) (xy 56.549381 -405.365098) (xy 56.513279 -405.327991) (xy 56.497728 -405.307292)
			(xy 56.45658 -405.28621) (xy 55.311548 -405.28621) (xy 55.2704 -405.307292) (xy 55.254849 -405.327991)
			(xy 55.218747 -405.365098) (xy 55.177652 -405.396587) (xy 55.132432 -405.421794) (xy 55.084038 -405.440189)
			(xy 55.033491 -405.451383) (xy 54.981856 -405.455141) (xy 54.930221 -405.451383) (xy 54.879674 -405.440189)
			(xy 54.83128 -405.421794) (xy 54.78606 -405.396587) (xy 54.744965 -405.365098) (xy 54.708863 -405.327991)
			(xy 54.693312 -405.307292) (xy 54.652164 -405.28621) (xy 54.052724 -405.28621) (xy 54.011576 -405.307292)
			(xy 53.996025 -405.327991) (xy 53.959923 -405.365098) (xy 53.918828 -405.396587) (xy 53.873608 -405.421794)
			(xy 53.825214 -405.440189) (xy 53.774667 -405.451383) (xy 53.723032 -405.455141) (xy 53.671397 -405.451383)
			(xy 53.62085 -405.440189) (xy 53.572456 -405.421794) (xy 53.527236 -405.396587) (xy 53.486141 -405.365098)
			(xy 53.450039 -405.327991) (xy 53.434488 -405.307292) (xy 53.39334 -405.28621) (xy 52.248308 -405.28621)
			(xy 52.20716 -405.307292) (xy 52.191609 -405.327991) (xy 52.155507 -405.365098) (xy 52.114412 -405.396587)
			(xy 52.069192 -405.421794) (xy 52.020798 -405.440189) (xy 51.970251 -405.451383) (xy 51.918616 -405.455141)
			(xy 51.866981 -405.451383) (xy 51.816434 -405.440189) (xy 51.76804 -405.421794) (xy 51.72282 -405.396587)
			(xy 51.681725 -405.365098) (xy 51.645623 -405.327991) (xy 51.630072 -405.307292) (xy 51.588924 -405.28621)
			(xy 50.989484 -405.28621) (xy 50.948336 -405.307292) (xy 50.932785 -405.327991) (xy 50.896683 -405.365098)
			(xy 50.855588 -405.396587) (xy 50.810368 -405.421794) (xy 50.761974 -405.440189) (xy 50.711427 -405.451383)
			(xy 50.659792 -405.455141) (xy 50.608157 -405.451383) (xy 50.55761 -405.440189) (xy 50.509216 -405.421794)
			(xy 50.463996 -405.396587) (xy 50.422901 -405.365098) (xy 50.386799 -405.327991) (xy 50.371248 -405.307292)
			(xy 50.3301 -405.28621) (xy 49.185068 -405.28621) (xy 49.14392 -405.307292) (xy 49.128369 -405.327991)
			(xy 49.092267 -405.365098) (xy 49.051172 -405.396587) (xy 49.005952 -405.421794) (xy 48.957558 -405.440189)
			(xy 48.907011 -405.451383) (xy 48.855376 -405.455141) (xy 48.803741 -405.451383) (xy 48.753194 -405.440189)
			(xy 48.7048 -405.421794) (xy 48.65958 -405.396587) (xy 48.618485 -405.365098) (xy 48.582383 -405.327991)
			(xy 48.566832 -405.307292) (xy 48.525684 -405.28621) (xy 47.926244 -405.28621) (xy 47.885096 -405.307292)
			(xy 47.869545 -405.327991) (xy 47.833443 -405.365098) (xy 47.792348 -405.396587) (xy 47.747128 -405.421794)
			(xy 47.698734 -405.440189) (xy 47.648187 -405.451383) (xy 47.596552 -405.455141) (xy 47.544917 -405.451383)
			(xy 47.49437 -405.440189) (xy 47.445976 -405.421794) (xy 47.400756 -405.396587) (xy 47.359661 -405.365098)
			(xy 47.323559 -405.327991) (xy 47.308008 -405.307292) (xy 47.26686 -405.28621) (xy 46.876462 -405.28621)
			(xy 46.866395 -405.28664) (xy 46.847802 -405.294366) (xy 46.840394 -405.301196) (xy 45.325538 -406.816052)
			(xy 45.322236 -406.822402) (xy 45.27653 -406.905845) (xy 45.217365 -407.004502) (xy 48.438323 -407.004502)
			(xy 48.442189 -406.954044) (xy 48.453698 -406.904764) (xy 48.472581 -406.857812) (xy 48.498397 -406.814286)
			(xy 48.530543 -406.775201) (xy 48.568269 -406.741471) (xy 48.610694 -406.713882) (xy 48.656827 -406.693079)
			(xy 48.705591 -406.679548) (xy 48.730662 -406.676098) (xy 48.743108 -406.674574) (xy 48.763428 -406.660604)
			(xy 48.814736 -406.565608) (xy 48.815244 -406.54097) (xy 48.809656 -406.529794) (xy 48.797816 -406.504931)
			(xy 48.781062 -406.452477) (xy 48.77258 -406.398069) (xy 48.772064 -406.370536) (xy 48.772562 -406.343887)
			(xy 48.780505 -406.291183) (xy 48.796215 -406.240253) (xy 48.819341 -406.192232) (xy 48.849365 -406.148195)
			(xy 48.885617 -406.109124) (xy 48.927288 -406.075893) (xy 48.973446 -406.049244) (xy 49.02306 -406.029772)
			(xy 49.075022 -406.017912) (xy 49.128172 -406.013929) (xy 49.181322 -406.017912) (xy 49.233284 -406.029772)
			(xy 49.282898 -406.049244) (xy 49.329056 -406.075893) (xy 49.370727 -406.109124) (xy 49.406979 -406.148195)
			(xy 49.437003 -406.192232) (xy 49.460129 -406.240253) (xy 49.475839 -406.291183) (xy 49.483782 -406.343887)
			(xy 49.48428 -406.370536) (xy 49.483809 -406.395712) (xy 49.476675 -406.445556) (xy 49.470056 -406.46985)
			(xy 49.467885 -406.478805) (xy 49.469302 -406.497161) (xy 49.47285 -406.505664) (xy 49.486058 -406.533604)
			(xy 49.490354 -406.541991) (xy 49.503923 -406.555046) (xy 49.512474 -406.559004) (xy 49.53798 -406.570037)
			(xy 49.586486 -406.597162) (xy 49.609248 -406.613106) (xy 49.61587 -406.61756) (xy 49.630996 -406.622614)
			(xy 49.638966 -406.623012) (xy 49.876202 -406.623012) (xy 49.884188 -406.622703) (xy 49.899338 -406.61764)
			(xy 49.90592 -406.613106) (xy 49.928685 -406.597169) (xy 49.977196 -406.570054) (xy 50.002694 -406.559004)
			(xy 50.011166 -406.554924) (xy 50.024717 -406.541916) (xy 50.02911 -406.533604) (xy 50.042318 -406.505664)
			(xy 50.045897 -406.497169) (xy 50.047318 -406.478802) (xy 50.045112 -406.46985) (xy 50.038469 -406.445561)
			(xy 50.031337 -406.395713) (xy 50.030888 -406.370536) (xy 50.031386 -406.343887) (xy 50.039329 -406.291183)
			(xy 50.055039 -406.240253) (xy 50.078165 -406.192232) (xy 50.108189 -406.148195) (xy 50.144441 -406.109124)
			(xy 50.186112 -406.075893) (xy 50.23227 -406.049244) (xy 50.281884 -406.029772) (xy 50.333846 -406.017912)
			(xy 50.386996 -406.013929) (xy 50.440146 -406.017912) (xy 50.492108 -406.029772) (xy 50.541722 -406.049244)
			(xy 50.58788 -406.075893) (xy 50.629551 -406.109124) (xy 50.665803 -406.148195) (xy 50.695827 -406.192232)
			(xy 50.718953 -406.240253) (xy 50.734663 -406.291183) (xy 50.742606 -406.343887) (xy 50.743104 -406.370536)
			(xy 50.742581 -406.398069) (xy 50.734111 -406.45248) (xy 50.717364 -406.504937) (xy 50.705512 -406.529794)
			(xy 50.699924 -406.54097) (xy 50.700432 -406.565608) (xy 50.75174 -406.660604) (xy 50.77206 -406.674574)
			(xy 50.784506 -406.676098) (xy 50.809582 -406.679513) (xy 50.858343 -406.693054) (xy 50.904473 -406.713864)
			(xy 50.946894 -406.741459) (xy 50.984616 -406.775194) (xy 51.016759 -406.814282) (xy 51.042571 -406.85781)
			(xy 51.061452 -406.904763) (xy 51.072959 -406.954044) (xy 51.076825 -407.004502) (xy 51.501616 -407.004502)
			(xy 51.505481 -406.954049) (xy 51.516987 -406.904774) (xy 51.535866 -406.857826) (xy 51.561677 -406.814303)
			(xy 51.593816 -406.775219) (xy 51.631535 -406.741488) (xy 51.673952 -406.713897) (xy 51.720077 -406.69309)
			(xy 51.768834 -406.679552) (xy 51.793902 -406.676098) (xy 51.806348 -406.674574) (xy 51.826668 -406.660604)
			(xy 51.877976 -406.565608) (xy 51.878484 -406.54097) (xy 51.872896 -406.529794) (xy 51.861052 -406.504933)
			(xy 51.8443 -406.452478) (xy 51.83582 -406.398069) (xy 51.835304 -406.370536) (xy 51.835802 -406.343887)
			(xy 51.843745 -406.291183) (xy 51.859455 -406.240253) (xy 51.882581 -406.192232) (xy 51.912605 -406.148195)
			(xy 51.948857 -406.109124) (xy 51.990528 -406.075893) (xy 52.036686 -406.049244) (xy 52.0863 -406.029772)
			(xy 52.138262 -406.017912) (xy 52.191412 -406.013929) (xy 52.244562 -406.017912) (xy 52.296524 -406.029772)
			(xy 52.346138 -406.049244) (xy 52.392296 -406.075893) (xy 52.433967 -406.109124) (xy 52.470219 -406.148195)
			(xy 52.500243 -406.192232) (xy 52.523369 -406.240253) (xy 52.539079 -406.291183) (xy 52.547022 -406.343887)
			(xy 52.54752 -406.370536) (xy 52.547048 -406.395711) (xy 52.539914 -406.445556) (xy 52.533296 -406.46985)
			(xy 52.531122 -406.478805) (xy 52.53254 -406.497162) (xy 52.53609 -406.505664) (xy 52.549298 -406.533604)
			(xy 52.553579 -406.542) (xy 52.567158 -406.555051) (xy 52.575714 -406.559004) (xy 52.601216 -406.570046)
			(xy 52.649725 -406.597165) (xy 52.672488 -406.613106) (xy 52.679101 -406.617576) (xy 52.694234 -406.62262)
			(xy 52.702206 -406.623012) (xy 52.939442 -406.623012) (xy 52.947425 -406.622677) (xy 52.962576 -406.617632)
			(xy 52.96916 -406.613106) (xy 52.99193 -406.597176) (xy 53.040437 -406.570057) (xy 53.065934 -406.559004)
			(xy 53.074412 -406.554937) (xy 53.087959 -406.541919) (xy 53.09235 -406.533604) (xy 53.105558 -406.505664)
			(xy 53.109137 -406.497168) (xy 53.11056 -406.478801) (xy 53.108352 -406.46985) (xy 53.10171 -406.445561)
			(xy 53.094577 -406.395713) (xy 53.094128 -406.370536) (xy 53.094626 -406.343887) (xy 53.102569 -406.291183)
			(xy 53.118279 -406.240253) (xy 53.141405 -406.192232) (xy 53.171429 -406.148195) (xy 53.207681 -406.109124)
			(xy 53.249352 -406.075893) (xy 53.29551 -406.049244) (xy 53.345124 -406.029772) (xy 53.397086 -406.017912)
			(xy 53.450236 -406.013929) (xy 53.503386 -406.017912) (xy 53.555348 -406.029772) (xy 53.604962 -406.049244)
			(xy 53.65112 -406.075893) (xy 53.692791 -406.109124) (xy 53.729043 -406.148195) (xy 53.759067 -406.192232)
			(xy 53.782193 -406.240253) (xy 53.797903 -406.291183) (xy 53.805846 -406.343887) (xy 53.806344 -406.370536)
			(xy 53.805817 -406.398069) (xy 53.797348 -406.452479) (xy 53.780603 -406.504937) (xy 53.768752 -406.529794)
			(xy 53.763164 -406.54097) (xy 53.763672 -406.565608) (xy 53.81498 -406.660604) (xy 53.8353 -406.674574)
			(xy 53.847746 -406.676098) (xy 53.872825 -406.679509) (xy 53.921593 -406.693043) (xy 53.967731 -406.713849)
			(xy 54.01016 -406.741441) (xy 54.047889 -406.775176) (xy 54.080038 -406.814265) (xy 54.105857 -406.857796)
			(xy 54.124741 -406.904753) (xy 54.136251 -406.954039) (xy 54.140118 -407.004502) (xy 54.564821 -407.004502)
			(xy 54.568686 -406.954046) (xy 54.580194 -406.904767) (xy 54.599076 -406.857817) (xy 54.62489 -406.814292)
			(xy 54.657034 -406.775207) (xy 54.694758 -406.741476) (xy 54.73718 -406.713887) (xy 54.78331 -406.693083)
			(xy 54.832072 -406.679549) (xy 54.857142 -406.676098) (xy 54.869588 -406.674574) (xy 54.889908 -406.660604)
			(xy 54.941216 -406.565608) (xy 54.941724 -406.54097) (xy 54.936136 -406.529794) (xy 54.924295 -406.504932)
			(xy 54.907541 -406.452477) (xy 54.89906 -406.398069) (xy 54.898544 -406.370536) (xy 54.899042 -406.343887)
			(xy 54.906985 -406.291183) (xy 54.922695 -406.240253) (xy 54.945821 -406.192232) (xy 54.975845 -406.148195)
			(xy 55.012097 -406.109124) (xy 55.053768 -406.075893) (xy 55.099926 -406.049244) (xy 55.14954 -406.029772)
			(xy 55.201502 -406.017912) (xy 55.254652 -406.013929) (xy 55.307802 -406.017912) (xy 55.359764 -406.029772)
			(xy 55.409378 -406.049244) (xy 55.455536 -406.075893) (xy 55.497207 -406.109124) (xy 55.533459 -406.148195)
			(xy 55.563483 -406.192232) (xy 55.586609 -406.240253) (xy 55.602319 -406.291183) (xy 55.610262 -406.343887)
			(xy 55.61076 -406.370536) (xy 55.61029 -406.395712) (xy 55.603155 -406.445556) (xy 55.596536 -406.46985)
			(xy 55.594366 -406.478806) (xy 55.595783 -406.497161) (xy 55.59933 -406.505664) (xy 55.612538 -406.533604)
			(xy 55.616841 -406.541987) (xy 55.630405 -406.555044) (xy 55.638954 -406.559004) (xy 55.664459 -406.57004)
			(xy 55.712966 -406.597163) (xy 55.735728 -406.613106) (xy 55.742332 -406.617591) (xy 55.757472 -406.622626)
			(xy 55.765446 -406.623012) (xy 56.002682 -406.623012) (xy 56.010667 -406.622695) (xy 56.025818 -406.617638)
			(xy 56.0324 -406.613106) (xy 56.055167 -406.597171) (xy 56.103676 -406.570055) (xy 56.129174 -406.559004)
			(xy 56.137659 -406.55495) (xy 56.151202 -406.541922) (xy 56.15559 -406.533604) (xy 56.168798 -406.505664)
			(xy 56.172377 -406.497169) (xy 56.173799 -406.478802) (xy 56.171592 -406.46985) (xy 56.164949 -406.445561)
			(xy 56.157817 -406.395713) (xy 56.157368 -406.370536) (xy 56.157866 -406.343887) (xy 56.165809 -406.291183)
			(xy 56.181519 -406.240253) (xy 56.204645 -406.192232) (xy 56.234669 -406.148195) (xy 56.270921 -406.109124)
			(xy 56.312592 -406.075893) (xy 56.35875 -406.049244) (xy 56.408364 -406.029772) (xy 56.460326 -406.017912)
			(xy 56.513476 -406.013929) (xy 56.566626 -406.017912) (xy 56.618588 -406.029772) (xy 56.668202 -406.049244)
			(xy 56.71436 -406.075893) (xy 56.756031 -406.109124) (xy 56.792283 -406.148195) (xy 56.822307 -406.192232)
			(xy 56.845433 -406.240253) (xy 56.861143 -406.291183) (xy 56.869086 -406.343887) (xy 56.869584 -406.370536)
			(xy 56.869053 -406.398069) (xy 56.860585 -406.452479) (xy 56.843842 -406.504937) (xy 56.831992 -406.529794)
			(xy 56.826404 -406.54097) (xy 56.826912 -406.565608) (xy 56.87822 -406.660604) (xy 56.89854 -406.674574)
			(xy 56.910986 -406.676098) (xy 56.936063 -406.679512) (xy 56.984827 -406.69305) (xy 57.030959 -406.713859)
			(xy 57.073382 -406.741453) (xy 57.111107 -406.775188) (xy 57.143252 -406.814276) (xy 57.169066 -406.857806)
			(xy 57.187948 -406.90476) (xy 57.199457 -406.954042) (xy 57.203322 -407.004502) (xy 57.628025 -407.004502)
			(xy 57.631892 -406.954042) (xy 57.643401 -406.90476) (xy 57.662286 -406.857808) (xy 57.688104 -406.814281)
			(xy 57.720252 -406.775195) (xy 57.757981 -406.741465) (xy 57.800408 -406.713877) (xy 57.846543 -406.693076)
			(xy 57.895309 -406.679547) (xy 57.920382 -406.676098) (xy 57.932828 -406.674574) (xy 57.953148 -406.660604)
			(xy 58.004456 -406.565608) (xy 58.004964 -406.54097) (xy 57.999376 -406.529794) (xy 57.987531 -406.504934)
			(xy 57.97078 -406.452478) (xy 57.9623 -406.398069) (xy 57.961784 -406.370536) (xy 57.962282 -406.343887)
			(xy 57.970225 -406.291183) (xy 57.985935 -406.240253) (xy 58.009061 -406.192232) (xy 58.039085 -406.148195)
			(xy 58.075337 -406.109124) (xy 58.117008 -406.075893) (xy 58.163166 -406.049244) (xy 58.21278 -406.029772)
			(xy 58.264742 -406.017912) (xy 58.317892 -406.013929) (xy 58.371042 -406.017912) (xy 58.423004 -406.029772)
			(xy 58.472618 -406.049244) (xy 58.518776 -406.075893) (xy 58.560447 -406.109124) (xy 58.596699 -406.148195)
			(xy 58.626723 -406.192232) (xy 58.649849 -406.240253) (xy 58.665559 -406.291183) (xy 58.673502 -406.343887)
			(xy 58.674 -406.370536) (xy 58.673529 -406.395711) (xy 58.666394 -406.445556) (xy 58.659776 -406.46985)
			(xy 58.657603 -406.478805) (xy 58.659021 -406.497161) (xy 58.66257 -406.505664) (xy 58.675778 -406.533604)
			(xy 58.680066 -406.541996) (xy 58.69364 -406.555049) (xy 58.702194 -406.559004) (xy 58.727695 -406.570048)
			(xy 58.776204 -406.597166) (xy 58.798968 -406.613106) (xy 58.805585 -406.617568) (xy 58.820715 -406.622617)
			(xy 58.828686 -406.623012) (xy 59.065922 -406.623012) (xy 59.073908 -406.622712) (xy 59.089059 -406.617643)
			(xy 59.09564 -406.613106) (xy 59.118404 -406.597166) (xy 59.166915 -406.570053) (xy 59.192414 -406.559004)
			(xy 59.200889 -406.554931) (xy 59.214438 -406.541917) (xy 59.21883 -406.533604) (xy 59.232038 -406.505664)
			(xy 59.235617 -406.497169) (xy 59.237037 -406.478802) (xy 59.234832 -406.46985) (xy 59.22819 -406.445561)
			(xy 59.221057 -406.395713) (xy 59.220608 -406.370536) (xy 59.221106 -406.343887) (xy 59.229049 -406.291183)
			(xy 59.244759 -406.240253) (xy 59.267885 -406.192232) (xy 59.297909 -406.148195) (xy 59.334161 -406.109124)
			(xy 59.375832 -406.075893) (xy 59.42199 -406.049244) (xy 59.471604 -406.029772) (xy 59.523566 -406.017912)
			(xy 59.576716 -406.013929) (xy 59.629866 -406.017912) (xy 59.681828 -406.029772) (xy 59.731442 -406.049244)
			(xy 59.7776 -406.075893) (xy 59.819271 -406.109124) (xy 59.855523 -406.148195) (xy 59.885547 -406.192232)
			(xy 59.908673 -406.240253) (xy 59.924383 -406.291183) (xy 59.932326 -406.343887) (xy 59.932824 -406.370536)
			(xy 59.932299 -406.398069) (xy 59.92383 -406.45248) (xy 59.907084 -406.504937) (xy 59.895232 -406.529794)
			(xy 59.889644 -406.54097) (xy 59.890152 -406.565608) (xy 59.94146 -406.660604) (xy 59.96178 -406.674574)
			(xy 59.974226 -406.676098) (xy 59.999306 -406.679508) (xy 60.048077 -406.69304) (xy 60.094217 -406.713844)
			(xy 60.136648 -406.741436) (xy 60.17438 -406.77517) (xy 60.206532 -406.81426) (xy 60.232352 -406.857792)
			(xy 60.251238 -406.90475) (xy 60.262749 -406.954037) (xy 60.266615 -407.004502) (xy 60.691318 -407.004502)
			(xy 60.695184 -406.954047) (xy 60.706691 -406.90477) (xy 60.725571 -406.857821) (xy 60.751383 -406.814297)
			(xy 60.783525 -406.775213) (xy 60.821246 -406.741482) (xy 60.863666 -406.713892) (xy 60.909794 -406.693086)
			(xy 60.958553 -406.679551) (xy 60.983622 -406.676098) (xy 60.996068 -406.674574) (xy 61.016388 -406.660604)
			(xy 61.067696 -406.565608) (xy 61.068204 -406.54097) (xy 61.062616 -406.529794) (xy 61.050774 -406.504933)
			(xy 61.034021 -406.452477) (xy 61.02554 -406.398069) (xy 61.025024 -406.370536) (xy 61.025522 -406.343887)
			(xy 61.033465 -406.291183) (xy 61.049175 -406.240253) (xy 61.072301 -406.192232) (xy 61.102325 -406.148195)
			(xy 61.138577 -406.109124) (xy 61.180248 -406.075893) (xy 61.226406 -406.049244) (xy 61.27602 -406.029772)
			(xy 61.327982 -406.017912) (xy 61.381132 -406.013929) (xy 61.434282 -406.017912) (xy 61.486244 -406.029772)
			(xy 61.535858 -406.049244) (xy 61.582016 -406.075893) (xy 61.623687 -406.109124) (xy 61.659939 -406.148195)
			(xy 61.689963 -406.192232) (xy 61.713089 -406.240253) (xy 61.728799 -406.291183) (xy 61.736742 -406.343887)
			(xy 61.73724 -406.370536) (xy 61.736767 -406.395711) (xy 61.729634 -406.445556) (xy 61.723016 -406.46985)
			(xy 61.720848 -406.478806) (xy 61.722264 -406.497161) (xy 61.72581 -406.505664) (xy 61.739018 -406.533604)
			(xy 61.743328 -406.541983) (xy 61.756887 -406.555042) (xy 61.765434 -406.559004) (xy 61.790938 -406.570043)
			(xy 61.839445 -406.597164) (xy 61.862208 -406.613106) (xy 61.868816 -406.617583) (xy 61.883953 -406.622623)
			(xy 61.891926 -406.623012) (xy 62.129162 -406.623012) (xy 62.137146 -406.622686) (xy 62.152297 -406.617635)
			(xy 62.15888 -406.613106) (xy 62.181649 -406.597174) (xy 62.230157 -406.570056) (xy 62.255654 -406.559004)
			(xy 62.264136 -406.554943) (xy 62.277681 -406.54192) (xy 62.28207 -406.533604) (xy 62.295278 -406.505664)
			(xy 62.298857 -406.497168) (xy 62.300279 -406.478801) (xy 62.298072 -406.46985) (xy 62.29143 -406.44556)
			(xy 62.284297 -406.395713) (xy 62.283848 -406.370536) (xy 62.284346 -406.343887) (xy 62.292289 -406.291183)
			(xy 62.307999 -406.240253) (xy 62.331125 -406.192232) (xy 62.361149 -406.148195) (xy 62.397401 -406.109124)
			(xy 62.439072 -406.075893) (xy 62.48523 -406.049244) (xy 62.534844 -406.029772) (xy 62.586806 -406.017912)
			(xy 62.639956 -406.013929) (xy 62.693106 -406.017912) (xy 62.745068 -406.029772) (xy 62.794682 -406.049244)
			(xy 62.84084 -406.075893) (xy 62.882511 -406.109124) (xy 62.918763 -406.148195) (xy 62.948787 -406.192232)
			(xy 62.971913 -406.240253) (xy 62.987623 -406.291183) (xy 62.995566 -406.343887) (xy 62.996064 -406.370536)
			(xy 62.995535 -406.398069) (xy 62.987067 -406.452479) (xy 62.970323 -406.504937) (xy 62.958472 -406.529794)
			(xy 62.952884 -406.54097) (xy 62.953392 -406.565608) (xy 63.0047 -406.660604) (xy 63.02502 -406.674574)
			(xy 63.037466 -406.676098) (xy 63.062544 -406.679511) (xy 63.11131 -406.693047) (xy 63.157445 -406.713854)
			(xy 63.199871 -406.741447) (xy 63.237598 -406.775182) (xy 63.269745 -406.814271) (xy 63.295562 -406.857801)
			(xy 63.314445 -406.904756) (xy 63.325954 -406.95404) (xy 63.32982 -407.004502) (xy 63.754523 -407.004502)
			(xy 63.758389 -406.954044) (xy 63.769898 -406.904764) (xy 63.788781 -406.857812) (xy 63.814597 -406.814286)
			(xy 63.846743 -406.775201) (xy 63.884469 -406.741471) (xy 63.926894 -406.713882) (xy 63.973027 -406.693079)
			(xy 64.021791 -406.679548) (xy 64.046862 -406.676098) (xy 64.059308 -406.674574) (xy 64.079628 -406.660604)
			(xy 64.130936 -406.565608) (xy 64.131444 -406.54097) (xy 64.125856 -406.529794) (xy 64.114016 -406.504931)
			(xy 64.097262 -406.452477) (xy 64.08878 -406.398069) (xy 64.088264 -406.370536) (xy 64.088762 -406.343887)
			(xy 64.096705 -406.291183) (xy 64.112415 -406.240253) (xy 64.135541 -406.192232) (xy 64.165565 -406.148195)
			(xy 64.201817 -406.109124) (xy 64.243488 -406.075893) (xy 64.289646 -406.049244) (xy 64.33926 -406.029772)
			(xy 64.391222 -406.017912) (xy 64.444372 -406.013929) (xy 64.497522 -406.017912) (xy 64.549484 -406.029772)
			(xy 64.599098 -406.049244) (xy 64.645256 -406.075893) (xy 64.686927 -406.109124) (xy 64.723179 -406.148195)
			(xy 64.753203 -406.192232) (xy 64.776329 -406.240253) (xy 64.792039 -406.291183) (xy 64.799982 -406.343887)
			(xy 64.80048 -406.370536) (xy 64.800009 -406.395712) (xy 64.792875 -406.445556) (xy 64.786256 -406.46985)
			(xy 64.784085 -406.478805) (xy 64.785502 -406.497161) (xy 64.78905 -406.505664) (xy 64.802258 -406.533604)
			(xy 64.806554 -406.541991) (xy 64.820123 -406.555046) (xy 64.828674 -406.559004) (xy 64.85418 -406.570037)
			(xy 64.902686 -406.597162) (xy 64.925448 -406.613106) (xy 64.93207 -406.61756) (xy 64.947196 -406.622614)
			(xy 64.955166 -406.623012) (xy 65.192402 -406.623012) (xy 65.200388 -406.622703) (xy 65.215538 -406.61764)
			(xy 65.22212 -406.613106) (xy 65.244885 -406.597169) (xy 65.293396 -406.570054) (xy 65.318894 -406.559004)
			(xy 65.327366 -406.554924) (xy 65.340917 -406.541916) (xy 65.34531 -406.533604) (xy 65.358518 -406.505664)
			(xy 65.362097 -406.497169) (xy 65.363518 -406.478802) (xy 65.361312 -406.46985) (xy 65.354669 -406.445561)
			(xy 65.347537 -406.395713) (xy 65.347088 -406.370536) (xy 65.347586 -406.343887) (xy 65.355529 -406.291183)
			(xy 65.371239 -406.240253) (xy 65.394365 -406.192232) (xy 65.424389 -406.148195) (xy 65.460641 -406.109124)
			(xy 65.502312 -406.075893) (xy 65.54847 -406.049244) (xy 65.598084 -406.029772) (xy 65.650046 -406.017912)
			(xy 65.703196 -406.013929) (xy 65.756346 -406.017912) (xy 65.808308 -406.029772) (xy 65.857922 -406.049244)
			(xy 65.90408 -406.075893) (xy 65.945751 -406.109124) (xy 65.982003 -406.148195) (xy 66.012027 -406.192232)
			(xy 66.035153 -406.240253) (xy 66.050863 -406.291183) (xy 66.058806 -406.343887) (xy 66.059304 -406.370536)
			(xy 66.058781 -406.398069) (xy 66.050311 -406.45248) (xy 66.033564 -406.504937) (xy 66.021712 -406.529794)
			(xy 66.016124 -406.54097) (xy 66.016632 -406.565608) (xy 66.06794 -406.660604) (xy 66.08826 -406.674574)
			(xy 66.100706 -406.676098) (xy 66.125782 -406.679513) (xy 66.174543 -406.693054) (xy 66.220673 -406.713864)
			(xy 66.263094 -406.741459) (xy 66.300816 -406.775194) (xy 66.332959 -406.814282) (xy 66.358771 -406.85781)
			(xy 66.377652 -406.904763) (xy 66.389159 -406.954044) (xy 66.393025 -407.004502) (xy 66.393024 -407.00452)
			(xy 66.818256 -407.00452) (xy 66.818709 -406.980006) (xy 66.825931 -406.931515) (xy 66.840235 -406.884621)
			(xy 66.861306 -406.840353) (xy 66.888684 -406.799683) (xy 66.921768 -406.763501) (xy 66.959831 -406.732602)
			(xy 67.00204 -406.707662) (xy 67.04747 -406.689228) (xy 67.095123 -406.677705) (xy 67.1195 -406.675082)
			(xy 67.132454 -406.674066) (xy 67.15379 -406.659588) (xy 67.205606 -406.560782) (xy 67.205098 -406.534874)
			(xy 67.198494 -406.523444) (xy 67.183733 -406.496343) (xy 67.162787 -406.438299) (xy 67.152158 -406.377514)
			(xy 67.151504 -406.34666) (xy 67.152002 -406.320011) (xy 67.159945 -406.267307) (xy 67.175655 -406.216377)
			(xy 67.198781 -406.168356) (xy 67.228805 -406.124319) (xy 67.265057 -406.085248) (xy 67.306728 -406.052017)
			(xy 67.352886 -406.025368) (xy 67.4025 -406.005896) (xy 67.454462 -405.994036) (xy 67.507612 -405.990053)
			(xy 67.560762 -405.994036) (xy 67.612724 -406.005896) (xy 67.662338 -406.025368) (xy 67.708496 -406.052017)
			(xy 67.750167 -406.085248) (xy 67.786419 -406.124319) (xy 67.816443 -406.168356) (xy 67.839569 -406.216377)
			(xy 67.855279 -406.267307) (xy 67.863222 -406.320011) (xy 67.86372 -406.34666) (xy 67.863279 -406.371436)
			(xy 67.856396 -406.420509) (xy 67.850004 -406.44445) (xy 67.847464 -406.45334) (xy 67.848988 -406.471374)
			(xy 67.884294 -406.548336) (xy 67.897248 -406.561036) (xy 67.90563 -406.564846) (xy 67.927411 -406.575071)
			(xy 67.969021 -406.599243) (xy 67.988688 -406.613106) (xy 67.995301 -406.617576) (xy 68.010434 -406.62262)
			(xy 68.018406 -406.623012) (xy 68.255642 -406.623012) (xy 68.263625 -406.622677) (xy 68.278776 -406.617632)
			(xy 68.28536 -406.613106) (xy 68.305035 -406.599255) (xy 68.346642 -406.575081) (xy 68.368418 -406.564846)
			(xy 68.3768 -406.561036) (xy 68.389754 -406.548336) (xy 68.42506 -406.471374) (xy 68.426584 -406.45334)
			(xy 68.424044 -406.44445) (xy 68.417645 -406.420509) (xy 68.410757 -406.371437) (xy 68.410328 -406.34666)
			(xy 68.410826 -406.320011) (xy 68.418769 -406.267307) (xy 68.434479 -406.216377) (xy 68.457605 -406.168356)
			(xy 68.487629 -406.124319) (xy 68.523881 -406.085248) (xy 68.565552 -406.052017) (xy 68.61171 -406.025368)
			(xy 68.661324 -406.005896) (xy 68.713286 -405.994036) (xy 68.766436 -405.990053) (xy 68.819586 -405.994036)
			(xy 68.871548 -406.005896) (xy 68.921162 -406.025368) (xy 68.96732 -406.052017) (xy 69.008991 -406.085248)
			(xy 69.045243 -406.124319) (xy 69.075267 -406.168356) (xy 69.098393 -406.216377) (xy 69.114103 -406.267307)
			(xy 69.122046 -406.320011) (xy 69.122544 -406.34666) (xy 69.121886 -406.377513) (xy 69.111248 -406.438294)
			(xy 69.090301 -406.496336) (xy 69.075554 -406.523444) (xy 69.06895 -406.534874) (xy 69.068442 -406.560782)
			(xy 69.120258 -406.659588) (xy 69.141594 -406.674066) (xy 69.154548 -406.675082) (xy 69.178915 -406.677761)
			(xy 69.226557 -406.689296) (xy 69.271975 -406.707735) (xy 69.314175 -406.732674) (xy 69.352232 -406.763568)
			(xy 69.385313 -406.79974) (xy 69.412695 -406.840398) (xy 69.433776 -406.884651) (xy 69.448097 -406.931531)
			(xy 69.455342 -406.980011) (xy 69.455792 -407.004502) (xy 69.881021 -407.004502) (xy 69.884886 -406.954046)
			(xy 69.896394 -406.904767) (xy 69.915276 -406.857817) (xy 69.94109 -406.814292) (xy 69.973234 -406.775207)
			(xy 70.010958 -406.741476) (xy 70.05338 -406.713887) (xy 70.09951 -406.693083) (xy 70.148272 -406.679549)
			(xy 70.173342 -406.676098) (xy 70.185788 -406.674574) (xy 70.206108 -406.660604) (xy 70.257416 -406.565608)
			(xy 70.257924 -406.54097) (xy 70.252336 -406.529794) (xy 70.240495 -406.504932) (xy 70.223741 -406.452477)
			(xy 70.21526 -406.398069) (xy 70.214744 -406.370536) (xy 70.215242 -406.343887) (xy 70.223185 -406.291183)
			(xy 70.238895 -406.240253) (xy 70.262021 -406.192232) (xy 70.292045 -406.148195) (xy 70.328297 -406.109124)
			(xy 70.369968 -406.075893) (xy 70.416126 -406.049244) (xy 70.46574 -406.029772) (xy 70.517702 -406.017912)
			(xy 70.570852 -406.013929) (xy 70.624002 -406.017912) (xy 70.675964 -406.029772) (xy 70.725578 -406.049244)
			(xy 70.771736 -406.075893) (xy 70.813407 -406.109124) (xy 70.849659 -406.148195) (xy 70.879683 -406.192232)
			(xy 70.902809 -406.240253) (xy 70.918519 -406.291183) (xy 70.926462 -406.343887) (xy 70.92696 -406.370536)
			(xy 70.92649 -406.395712) (xy 70.919355 -406.445556) (xy 70.912736 -406.46985) (xy 70.910566 -406.478806)
			(xy 70.911983 -406.497161) (xy 70.91553 -406.505664) (xy 70.928738 -406.533604) (xy 70.933041 -406.541987)
			(xy 70.946605 -406.555044) (xy 70.955154 -406.559004) (xy 70.980659 -406.57004) (xy 71.029166 -406.597163)
			(xy 71.051928 -406.613106) (xy 71.058532 -406.617591) (xy 71.073672 -406.622626) (xy 71.081646 -406.623012)
			(xy 71.318882 -406.623012) (xy 71.326867 -406.622695) (xy 71.342018 -406.617638) (xy 71.3486 -406.613106)
			(xy 71.371367 -406.597171) (xy 71.419876 -406.570055) (xy 71.445374 -406.559004) (xy 71.453859 -406.55495)
			(xy 71.467402 -406.541922) (xy 71.47179 -406.533604) (xy 71.484998 -406.505664) (xy 71.488577 -406.497169)
			(xy 71.489999 -406.478802) (xy 71.487792 -406.46985) (xy 71.481149 -406.445561) (xy 71.474017 -406.395713)
			(xy 71.473568 -406.370536) (xy 71.474066 -406.343887) (xy 71.482009 -406.291183) (xy 71.497719 -406.240253)
			(xy 71.520845 -406.192232) (xy 71.550869 -406.148195) (xy 71.587121 -406.109124) (xy 71.628792 -406.075893)
			(xy 71.67495 -406.049244) (xy 71.724564 -406.029772) (xy 71.776526 -406.017912) (xy 71.829676 -406.013929)
			(xy 71.882826 -406.017912) (xy 71.934788 -406.029772) (xy 71.984402 -406.049244) (xy 72.03056 -406.075893)
			(xy 72.072231 -406.109124) (xy 72.108483 -406.148195) (xy 72.138507 -406.192232) (xy 72.161633 -406.240253)
			(xy 72.177343 -406.291183) (xy 72.185286 -406.343887) (xy 72.185784 -406.370536) (xy 72.185253 -406.398069)
			(xy 72.176785 -406.452479) (xy 72.160042 -406.504937) (xy 72.148192 -406.529794) (xy 72.142604 -406.54097)
			(xy 72.143112 -406.565608) (xy 72.19442 -406.660604) (xy 72.21474 -406.674574) (xy 72.227186 -406.676098)
			(xy 72.252263 -406.679512) (xy 72.301027 -406.69305) (xy 72.347159 -406.713859) (xy 72.389582 -406.741453)
			(xy 72.427307 -406.775188) (xy 72.459452 -406.814276) (xy 72.485266 -406.857806) (xy 72.504148 -406.90476)
			(xy 72.515657 -406.954042) (xy 72.519522 -407.004502) (xy 72.944225 -407.004502) (xy 72.948092 -406.954042)
			(xy 72.959601 -406.90476) (xy 72.978486 -406.857808) (xy 73.004304 -406.814281) (xy 73.036452 -406.775195)
			(xy 73.074181 -406.741465) (xy 73.116608 -406.713877) (xy 73.162743 -406.693076) (xy 73.211509 -406.679547)
			(xy 73.236582 -406.676098) (xy 73.249028 -406.674574) (xy 73.269348 -406.660604) (xy 73.320656 -406.565608)
			(xy 73.321164 -406.54097) (xy 73.315576 -406.529794) (xy 73.303731 -406.504934) (xy 73.28698 -406.452478)
			(xy 73.2785 -406.398069) (xy 73.277984 -406.370536) (xy 73.278482 -406.343887) (xy 73.286425 -406.291183)
			(xy 73.302135 -406.240253) (xy 73.325261 -406.192232) (xy 73.355285 -406.148195) (xy 73.391537 -406.109124)
			(xy 73.433208 -406.075893) (xy 73.479366 -406.049244) (xy 73.52898 -406.029772) (xy 73.580942 -406.017912)
			(xy 73.634092 -406.013929) (xy 73.687242 -406.017912) (xy 73.739204 -406.029772) (xy 73.788818 -406.049244)
			(xy 73.834976 -406.075893) (xy 73.876647 -406.109124) (xy 73.912899 -406.148195) (xy 73.942923 -406.192232)
			(xy 73.966049 -406.240253) (xy 73.981759 -406.291183) (xy 73.989702 -406.343887) (xy 73.9902 -406.370536)
			(xy 73.989729 -406.395711) (xy 73.982594 -406.445556) (xy 73.975976 -406.46985) (xy 73.973803 -406.478805)
			(xy 73.975221 -406.497161) (xy 73.97877 -406.505664) (xy 73.991978 -406.533604) (xy 73.996266 -406.541996)
			(xy 74.00984 -406.555049) (xy 74.018394 -406.559004) (xy 74.043895 -406.570048) (xy 74.092404 -406.597166)
			(xy 74.115168 -406.613106) (xy 74.121785 -406.617568) (xy 74.136915 -406.622617) (xy 74.144886 -406.623012)
			(xy 74.382122 -406.623012) (xy 74.390108 -406.622712) (xy 74.405259 -406.617643) (xy 74.41184 -406.613106)
			(xy 74.434604 -406.597166) (xy 74.483115 -406.570053) (xy 74.508614 -406.559004) (xy 74.517089 -406.554931)
			(xy 74.530638 -406.541917) (xy 74.53503 -406.533604) (xy 74.548238 -406.505664) (xy 74.551817 -406.497169)
			(xy 74.553237 -406.478802) (xy 74.551032 -406.46985) (xy 74.54439 -406.445561) (xy 74.537257 -406.395713)
			(xy 74.536808 -406.370536) (xy 74.537306 -406.343887) (xy 74.545249 -406.291183) (xy 74.560959 -406.240253)
			(xy 74.584085 -406.192232) (xy 74.614109 -406.148195) (xy 74.650361 -406.109124) (xy 74.692032 -406.075893)
			(xy 74.73819 -406.049244) (xy 74.787804 -406.029772) (xy 74.839766 -406.017912) (xy 74.892916 -406.013929)
			(xy 74.946066 -406.017912) (xy 74.998028 -406.029772) (xy 75.047642 -406.049244) (xy 75.0938 -406.075893)
			(xy 75.135471 -406.109124) (xy 75.171723 -406.148195) (xy 75.201747 -406.192232) (xy 75.224873 -406.240253)
			(xy 75.240583 -406.291183) (xy 75.248526 -406.343887) (xy 75.249024 -406.370536) (xy 75.248499 -406.398069)
			(xy 75.24003 -406.45248) (xy 75.223284 -406.504937) (xy 75.211432 -406.529794) (xy 75.205844 -406.54097)
			(xy 75.206352 -406.565608) (xy 75.25766 -406.660604) (xy 75.27798 -406.674574) (xy 75.290426 -406.676098)
			(xy 75.315506 -406.679508) (xy 75.364277 -406.69304) (xy 75.410417 -406.713844) (xy 75.452848 -406.741436)
			(xy 75.49058 -406.77517) (xy 75.522732 -406.81426) (xy 75.548552 -406.857792) (xy 75.567438 -406.90475)
			(xy 75.578949 -406.954037) (xy 75.582815 -407.004502) (xy 76.007518 -407.004502) (xy 76.011384 -406.954047)
			(xy 76.022891 -406.90477) (xy 76.041771 -406.857821) (xy 76.067583 -406.814297) (xy 76.099725 -406.775213)
			(xy 76.137446 -406.741482) (xy 76.179866 -406.713892) (xy 76.225994 -406.693086) (xy 76.274753 -406.679551)
			(xy 76.299822 -406.676098) (xy 76.312268 -406.674574) (xy 76.332588 -406.660604) (xy 76.383896 -406.565608)
			(xy 76.384404 -406.54097) (xy 76.378816 -406.529794) (xy 76.366974 -406.504933) (xy 76.350221 -406.452477)
			(xy 76.34174 -406.398069) (xy 76.341224 -406.370536) (xy 76.341722 -406.343887) (xy 76.349665 -406.291183)
			(xy 76.365375 -406.240253) (xy 76.388501 -406.192232) (xy 76.418525 -406.148195) (xy 76.454777 -406.109124)
			(xy 76.496448 -406.075893) (xy 76.542606 -406.049244) (xy 76.59222 -406.029772) (xy 76.644182 -406.017912)
			(xy 76.697332 -406.013929) (xy 76.750482 -406.017912) (xy 76.802444 -406.029772) (xy 76.852058 -406.049244)
			(xy 76.898216 -406.075893) (xy 76.939887 -406.109124) (xy 76.976139 -406.148195) (xy 77.006163 -406.192232)
			(xy 77.029289 -406.240253) (xy 77.044999 -406.291183) (xy 77.052942 -406.343887) (xy 77.05344 -406.370536)
			(xy 77.052967 -406.395711) (xy 77.045834 -406.445556) (xy 77.039216 -406.46985) (xy 77.037048 -406.478806)
			(xy 77.038464 -406.497161) (xy 77.04201 -406.505664) (xy 77.055218 -406.533604) (xy 77.059528 -406.541983)
			(xy 77.073087 -406.555042) (xy 77.081634 -406.559004) (xy 77.107138 -406.570043) (xy 77.155645 -406.597164)
			(xy 77.178408 -406.613106) (xy 77.185016 -406.617583) (xy 77.200153 -406.622623) (xy 77.208126 -406.623012)
			(xy 77.445362 -406.623012) (xy 77.453346 -406.622686) (xy 77.468497 -406.617635) (xy 77.47508 -406.613106)
			(xy 77.497849 -406.597174) (xy 77.546357 -406.570056) (xy 77.571854 -406.559004) (xy 77.580336 -406.554943)
			(xy 77.593881 -406.54192) (xy 77.59827 -406.533604) (xy 77.611478 -406.505664) (xy 77.615057 -406.497168)
			(xy 77.616479 -406.478801) (xy 77.614272 -406.46985) (xy 77.60763 -406.44556) (xy 77.600497 -406.395713)
			(xy 77.600048 -406.370536) (xy 77.600546 -406.343887) (xy 77.608489 -406.291183) (xy 77.624199 -406.240253)
			(xy 77.647325 -406.192232) (xy 77.677349 -406.148195) (xy 77.713601 -406.109124) (xy 77.755272 -406.075893)
			(xy 77.80143 -406.049244) (xy 77.851044 -406.029772) (xy 77.903006 -406.017912) (xy 77.956156 -406.013929)
			(xy 78.009306 -406.017912) (xy 78.061268 -406.029772) (xy 78.110882 -406.049244) (xy 78.15704 -406.075893)
			(xy 78.198711 -406.109124) (xy 78.234963 -406.148195) (xy 78.264987 -406.192232) (xy 78.288113 -406.240253)
			(xy 78.303823 -406.291183) (xy 78.311766 -406.343887) (xy 78.312264 -406.370536) (xy 78.311735 -406.398069)
			(xy 78.303267 -406.452479) (xy 78.286523 -406.504937) (xy 78.274672 -406.529794) (xy 78.269084 -406.54097)
			(xy 78.269592 -406.565608) (xy 78.3209 -406.660604) (xy 78.34122 -406.674574) (xy 78.353666 -406.676098)
			(xy 78.378744 -406.679511) (xy 78.42751 -406.693047) (xy 78.473645 -406.713854) (xy 78.516071 -406.741447)
			(xy 78.553798 -406.775182) (xy 78.585945 -406.814271) (xy 78.611762 -406.857801) (xy 78.630645 -406.904756)
			(xy 78.642154 -406.95404) (xy 78.64602 -407.004502) (xy 79.070723 -407.004502) (xy 79.074589 -406.954044)
			(xy 79.086098 -406.904764) (xy 79.104981 -406.857812) (xy 79.130797 -406.814286) (xy 79.162943 -406.775201)
			(xy 79.200669 -406.741471) (xy 79.243094 -406.713882) (xy 79.289227 -406.693079) (xy 79.337991 -406.679548)
			(xy 79.363062 -406.676098) (xy 79.375508 -406.674574) (xy 79.395828 -406.660604) (xy 79.447136 -406.565608)
			(xy 79.447644 -406.54097) (xy 79.442056 -406.529794) (xy 79.430216 -406.504931) (xy 79.413462 -406.452477)
			(xy 79.40498 -406.398069) (xy 79.404464 -406.370536) (xy 79.404962 -406.343887) (xy 79.412905 -406.291183)
			(xy 79.428615 -406.240253) (xy 79.451741 -406.192232) (xy 79.481765 -406.148195) (xy 79.518017 -406.109124)
			(xy 79.559688 -406.075893) (xy 79.605846 -406.049244) (xy 79.65546 -406.029772) (xy 79.707422 -406.017912)
			(xy 79.760572 -406.013929) (xy 79.813722 -406.017912) (xy 79.865684 -406.029772) (xy 79.915298 -406.049244)
			(xy 79.961456 -406.075893) (xy 80.003127 -406.109124) (xy 80.039379 -406.148195) (xy 80.069403 -406.192232)
			(xy 80.092529 -406.240253) (xy 80.108239 -406.291183) (xy 80.116182 -406.343887) (xy 80.11668 -406.370536)
			(xy 80.116209 -406.395712) (xy 80.109075 -406.445556) (xy 80.102456 -406.46985) (xy 80.100285 -406.478805)
			(xy 80.101702 -406.497161) (xy 80.10525 -406.505664) (xy 80.118458 -406.533604) (xy 80.122754 -406.541991)
			(xy 80.136323 -406.555046) (xy 80.144874 -406.559004) (xy 80.17038 -406.570037) (xy 80.218886 -406.597162)
			(xy 80.241648 -406.613106) (xy 80.24827 -406.61756) (xy 80.263396 -406.622614) (xy 80.271366 -406.623012)
			(xy 80.508602 -406.623012) (xy 80.516588 -406.622703) (xy 80.531738 -406.61764) (xy 80.53832 -406.613106)
			(xy 80.561085 -406.597169) (xy 80.609596 -406.570054) (xy 80.635094 -406.559004) (xy 80.643566 -406.554924)
			(xy 80.657117 -406.541916) (xy 80.66151 -406.533604) (xy 80.674718 -406.505664) (xy 80.678297 -406.497169)
			(xy 80.679718 -406.478802) (xy 80.677512 -406.46985) (xy 80.670869 -406.445561) (xy 80.663737 -406.395713)
			(xy 80.663288 -406.370536) (xy 80.663786 -406.343887) (xy 80.671729 -406.291183) (xy 80.687439 -406.240253)
			(xy 80.710565 -406.192232) (xy 80.740589 -406.148195) (xy 80.776841 -406.109124) (xy 80.818512 -406.075893)
			(xy 80.86467 -406.049244) (xy 80.914284 -406.029772) (xy 80.966246 -406.017912) (xy 81.019396 -406.013929)
			(xy 81.072546 -406.017912) (xy 81.124508 -406.029772) (xy 81.174122 -406.049244) (xy 81.22028 -406.075893)
			(xy 81.261951 -406.109124) (xy 81.298203 -406.148195) (xy 81.328227 -406.192232) (xy 81.351353 -406.240253)
			(xy 81.367063 -406.291183) (xy 81.375006 -406.343887) (xy 81.375504 -406.370536) (xy 81.374981 -406.398069)
			(xy 81.366511 -406.45248) (xy 81.349764 -406.504937) (xy 81.337912 -406.529794) (xy 81.332324 -406.54097)
			(xy 81.332832 -406.565608) (xy 81.38414 -406.660604) (xy 81.40446 -406.674574) (xy 81.416906 -406.676098)
			(xy 81.441982 -406.679513) (xy 81.490743 -406.693054) (xy 81.536873 -406.713864) (xy 81.579294 -406.741459)
			(xy 81.617016 -406.775194) (xy 81.649159 -406.814282) (xy 81.674971 -406.85781) (xy 81.693852 -406.904763)
			(xy 81.705359 -406.954044) (xy 81.709225 -407.004502) (xy 82.134016 -407.004502) (xy 82.137881 -406.954049)
			(xy 82.149387 -406.904774) (xy 82.168266 -406.857826) (xy 82.194077 -406.814303) (xy 82.226216 -406.775219)
			(xy 82.263935 -406.741488) (xy 82.306352 -406.713897) (xy 82.352477 -406.69309) (xy 82.401234 -406.679552)
			(xy 82.426302 -406.676098) (xy 82.438748 -406.674574) (xy 82.459068 -406.660604) (xy 82.510376 -406.565608)
			(xy 82.510884 -406.54097) (xy 82.505296 -406.529794) (xy 82.493452 -406.504933) (xy 82.4767 -406.452478)
			(xy 82.46822 -406.398069) (xy 82.467704 -406.370536) (xy 82.468202 -406.343887) (xy 82.476145 -406.291183)
			(xy 82.491855 -406.240253) (xy 82.514981 -406.192232) (xy 82.545005 -406.148195) (xy 82.581257 -406.109124)
			(xy 82.622928 -406.075893) (xy 82.669086 -406.049244) (xy 82.7187 -406.029772) (xy 82.770662 -406.017912)
			(xy 82.823812 -406.013929) (xy 82.876962 -406.017912) (xy 82.928924 -406.029772) (xy 82.978538 -406.049244)
			(xy 83.024696 -406.075893) (xy 83.066367 -406.109124) (xy 83.102619 -406.148195) (xy 83.132643 -406.192232)
			(xy 83.155769 -406.240253) (xy 83.171479 -406.291183) (xy 83.179422 -406.343887) (xy 83.17992 -406.370536)
			(xy 83.179448 -406.395711) (xy 83.172314 -406.445556) (xy 83.165696 -406.46985) (xy 83.163522 -406.478805)
			(xy 83.16494 -406.497162) (xy 83.16849 -406.505664) (xy 83.181698 -406.533604) (xy 83.185979 -406.542)
			(xy 83.199558 -406.555051) (xy 83.208114 -406.559004) (xy 83.233616 -406.570046) (xy 83.282125 -406.597165)
			(xy 83.304888 -406.613106) (xy 83.311501 -406.617576) (xy 83.326634 -406.62262) (xy 83.334606 -406.623012)
			(xy 83.571842 -406.623012) (xy 83.579825 -406.622677) (xy 83.594976 -406.617632) (xy 83.60156 -406.613106)
			(xy 83.62433 -406.597176) (xy 83.672837 -406.570057) (xy 83.698334 -406.559004) (xy 83.706812 -406.554937)
			(xy 83.720359 -406.541919) (xy 83.72475 -406.533604) (xy 83.737958 -406.505664) (xy 83.741537 -406.497168)
			(xy 83.74296 -406.478801) (xy 83.740752 -406.46985) (xy 83.73411 -406.445561) (xy 83.726977 -406.395713)
			(xy 83.726528 -406.370536) (xy 83.727026 -406.343887) (xy 83.734969 -406.291183) (xy 83.750679 -406.240253)
			(xy 83.773805 -406.192232) (xy 83.803829 -406.148195) (xy 83.840081 -406.109124) (xy 83.881752 -406.075893)
			(xy 83.92791 -406.049244) (xy 83.977524 -406.029772) (xy 84.029486 -406.017912) (xy 84.082636 -406.013929)
			(xy 84.135786 -406.017912) (xy 84.187748 -406.029772) (xy 84.237362 -406.049244) (xy 84.28352 -406.075893)
			(xy 84.325191 -406.109124) (xy 84.361443 -406.148195) (xy 84.391467 -406.192232) (xy 84.414593 -406.240253)
			(xy 84.430303 -406.291183) (xy 84.438246 -406.343887) (xy 84.438744 -406.370536) (xy 84.438217 -406.398069)
			(xy 84.429748 -406.452479) (xy 84.413003 -406.504937) (xy 84.401152 -406.529794) (xy 84.395564 -406.54097)
			(xy 84.396072 -406.565608) (xy 84.44738 -406.660604) (xy 84.4677 -406.674574) (xy 84.480146 -406.676098)
			(xy 84.505225 -406.679509) (xy 84.553993 -406.693043) (xy 84.600131 -406.713849) (xy 84.64256 -406.741441)
			(xy 84.680289 -406.775176) (xy 84.712438 -406.814265) (xy 84.738257 -406.857796) (xy 84.757141 -406.904753)
			(xy 84.768651 -406.954039) (xy 84.772518 -407.004502) (xy 85.197221 -407.004502) (xy 85.201086 -406.954046)
			(xy 85.212594 -406.904767) (xy 85.231476 -406.857817) (xy 85.25729 -406.814292) (xy 85.289434 -406.775207)
			(xy 85.327158 -406.741476) (xy 85.36958 -406.713887) (xy 85.41571 -406.693083) (xy 85.464472 -406.679549)
			(xy 85.489542 -406.676098) (xy 85.501988 -406.674574) (xy 85.522308 -406.660604) (xy 85.573616 -406.565608)
			(xy 85.574124 -406.54097) (xy 85.568536 -406.529794) (xy 85.556695 -406.504932) (xy 85.539941 -406.452477)
			(xy 85.53146 -406.398069) (xy 85.530944 -406.370536) (xy 85.531442 -406.343887) (xy 85.539385 -406.291183)
			(xy 85.555095 -406.240253) (xy 85.578221 -406.192232) (xy 85.608245 -406.148195) (xy 85.644497 -406.109124)
			(xy 85.686168 -406.075893) (xy 85.732326 -406.049244) (xy 85.78194 -406.029772) (xy 85.833902 -406.017912)
			(xy 85.887052 -406.013929) (xy 85.940202 -406.017912) (xy 85.992164 -406.029772) (xy 86.041778 -406.049244)
			(xy 86.087936 -406.075893) (xy 86.129607 -406.109124) (xy 86.165859 -406.148195) (xy 86.195883 -406.192232)
			(xy 86.219009 -406.240253) (xy 86.234719 -406.291183) (xy 86.242662 -406.343887) (xy 86.24316 -406.370536)
			(xy 86.24269 -406.395712) (xy 86.235555 -406.445556) (xy 86.228936 -406.46985) (xy 86.226766 -406.478806)
			(xy 86.228183 -406.497161) (xy 86.23173 -406.505664) (xy 86.244938 -406.533604) (xy 86.249241 -406.541987)
			(xy 86.262805 -406.555044) (xy 86.271354 -406.559004) (xy 86.296859 -406.57004) (xy 86.345366 -406.597163)
			(xy 86.368128 -406.613106) (xy 86.374732 -406.617591) (xy 86.389872 -406.622626) (xy 86.397846 -406.623012)
			(xy 86.635082 -406.623012) (xy 86.643067 -406.622695) (xy 86.658218 -406.617638) (xy 86.6648 -406.613106)
			(xy 86.687567 -406.597171) (xy 86.736076 -406.570055) (xy 86.761574 -406.559004) (xy 86.770059 -406.55495)
			(xy 86.783602 -406.541922) (xy 86.78799 -406.533604) (xy 86.801198 -406.505664) (xy 86.804777 -406.497169)
			(xy 86.806199 -406.478802) (xy 86.803992 -406.46985) (xy 86.797349 -406.445561) (xy 86.790217 -406.395713)
			(xy 86.789768 -406.370536) (xy 86.790266 -406.343887) (xy 86.798209 -406.291183) (xy 86.813919 -406.240253)
			(xy 86.837045 -406.192232) (xy 86.867069 -406.148195) (xy 86.903321 -406.109124) (xy 86.944992 -406.075893)
			(xy 86.99115 -406.049244) (xy 87.040764 -406.029772) (xy 87.092726 -406.017912) (xy 87.145876 -406.013929)
			(xy 87.199026 -406.017912) (xy 87.250988 -406.029772) (xy 87.300602 -406.049244) (xy 87.34676 -406.075893)
			(xy 87.388431 -406.109124) (xy 87.424683 -406.148195) (xy 87.454707 -406.192232) (xy 87.477833 -406.240253)
			(xy 87.493543 -406.291183) (xy 87.501486 -406.343887) (xy 87.501984 -406.370536) (xy 87.501453 -406.398069)
			(xy 87.492985 -406.452479) (xy 87.476242 -406.504937) (xy 87.464392 -406.529794) (xy 87.458804 -406.54097)
			(xy 87.459312 -406.565608) (xy 87.51062 -406.660604) (xy 87.53094 -406.674574) (xy 87.543386 -406.676098)
			(xy 87.568463 -406.679512) (xy 87.617227 -406.69305) (xy 87.663359 -406.713859) (xy 87.705782 -406.741453)
			(xy 87.743507 -406.775188) (xy 87.775652 -406.814276) (xy 87.801466 -406.857806) (xy 87.820348 -406.90476)
			(xy 87.831857 -406.954042) (xy 87.835722 -407.004502) (xy 88.260425 -407.004502) (xy 88.264292 -406.954042)
			(xy 88.275801 -406.90476) (xy 88.294686 -406.857808) (xy 88.320504 -406.814281) (xy 88.352652 -406.775195)
			(xy 88.390381 -406.741465) (xy 88.432808 -406.713877) (xy 88.478943 -406.693076) (xy 88.527709 -406.679547)
			(xy 88.552782 -406.676098) (xy 88.565228 -406.674574) (xy 88.585548 -406.660604) (xy 88.636856 -406.565608)
			(xy 88.637364 -406.54097) (xy 88.631776 -406.529794) (xy 88.619931 -406.504934) (xy 88.60318 -406.452478)
			(xy 88.5947 -406.398069) (xy 88.594184 -406.370536) (xy 88.594682 -406.343887) (xy 88.602625 -406.291183)
			(xy 88.618335 -406.240253) (xy 88.641461 -406.192232) (xy 88.671485 -406.148195) (xy 88.707737 -406.109124)
			(xy 88.749408 -406.075893) (xy 88.795566 -406.049244) (xy 88.84518 -406.029772) (xy 88.897142 -406.017912)
			(xy 88.950292 -406.013929) (xy 89.003442 -406.017912) (xy 89.055404 -406.029772) (xy 89.105018 -406.049244)
			(xy 89.151176 -406.075893) (xy 89.192847 -406.109124) (xy 89.229099 -406.148195) (xy 89.259123 -406.192232)
			(xy 89.282249 -406.240253) (xy 89.297959 -406.291183) (xy 89.305902 -406.343887) (xy 89.3064 -406.370536)
			(xy 89.305929 -406.395711) (xy 89.298794 -406.445556) (xy 89.292176 -406.46985) (xy 89.290003 -406.478805)
			(xy 89.291421 -406.497161) (xy 89.29497 -406.505664) (xy 89.308178 -406.533604) (xy 89.312466 -406.541996)
			(xy 89.32604 -406.555049) (xy 89.334594 -406.559004) (xy 89.360095 -406.570048) (xy 89.408604 -406.597166)
			(xy 89.431368 -406.613106) (xy 89.437985 -406.617568) (xy 89.453115 -406.622617) (xy 89.461086 -406.623012)
			(xy 89.698322 -406.623012) (xy 89.706308 -406.622712) (xy 89.721459 -406.617643) (xy 89.72804 -406.613106)
			(xy 89.750804 -406.597166) (xy 89.799315 -406.570053) (xy 89.824814 -406.559004) (xy 89.833289 -406.554931)
			(xy 89.846838 -406.541917) (xy 89.85123 -406.533604) (xy 89.864438 -406.505664) (xy 89.868017 -406.497169)
			(xy 89.869437 -406.478802) (xy 89.867232 -406.46985) (xy 89.86059 -406.445561) (xy 89.853457 -406.395713)
			(xy 89.853008 -406.370536) (xy 89.853506 -406.343887) (xy 89.861449 -406.291183) (xy 89.877159 -406.240253)
			(xy 89.900285 -406.192232) (xy 89.930309 -406.148195) (xy 89.966561 -406.109124) (xy 90.008232 -406.075893)
			(xy 90.05439 -406.049244) (xy 90.104004 -406.029772) (xy 90.155966 -406.017912) (xy 90.209116 -406.013929)
			(xy 90.262266 -406.017912) (xy 90.314228 -406.029772) (xy 90.363842 -406.049244) (xy 90.41 -406.075893)
			(xy 90.451671 -406.109124) (xy 90.487923 -406.148195) (xy 90.517947 -406.192232) (xy 90.541073 -406.240253)
			(xy 90.556783 -406.291183) (xy 90.564726 -406.343887) (xy 90.565224 -406.370536) (xy 90.564699 -406.398069)
			(xy 90.55623 -406.45248) (xy 90.539484 -406.504937) (xy 90.527632 -406.529794) (xy 90.522044 -406.54097)
			(xy 90.522552 -406.565608) (xy 90.57386 -406.660604) (xy 90.59418 -406.674574) (xy 90.606626 -406.676098)
			(xy 90.631706 -406.679508) (xy 90.680477 -406.69304) (xy 90.726617 -406.713844) (xy 90.769048 -406.741436)
			(xy 90.80678 -406.77517) (xy 90.838932 -406.81426) (xy 90.864752 -406.857792) (xy 90.883638 -406.90475)
			(xy 90.895149 -406.954037) (xy 90.899015 -407.004502) (xy 90.899014 -407.00452) (xy 91.324176 -407.00452)
			(xy 91.32461 -406.980006) (xy 91.331833 -406.931512) (xy 91.346138 -406.884617) (xy 91.367211 -406.840348)
			(xy 91.394591 -406.799677) (xy 91.427677 -406.763495) (xy 91.465743 -406.732596) (xy 91.507955 -406.707657)
			(xy 91.553387 -406.689225) (xy 91.601042 -406.677704) (xy 91.62542 -406.675082) (xy 91.638374 -406.674066)
			(xy 91.65971 -406.659588) (xy 91.711526 -406.560782) (xy 91.711018 -406.534874) (xy 91.704414 -406.523444)
			(xy 91.689655 -406.496342) (xy 91.668707 -406.438299) (xy 91.658078 -406.377514) (xy 91.657424 -406.34666)
			(xy 91.657922 -406.320011) (xy 91.665865 -406.267307) (xy 91.681575 -406.216377) (xy 91.704701 -406.168356)
			(xy 91.734725 -406.124319) (xy 91.770977 -406.085248) (xy 91.812648 -406.052017) (xy 91.858806 -406.025368)
			(xy 91.90842 -406.005896) (xy 91.960382 -405.994036) (xy 92.013532 -405.990053) (xy 92.066682 -405.994036)
			(xy 92.118644 -406.005896) (xy 92.168258 -406.025368) (xy 92.214416 -406.052017) (xy 92.256087 -406.085248)
			(xy 92.292339 -406.124319) (xy 92.322363 -406.168356) (xy 92.345489 -406.216377) (xy 92.361199 -406.267307)
			(xy 92.369142 -406.320011) (xy 92.36964 -406.34666) (xy 92.369199 -406.371436) (xy 92.362316 -406.420509)
			(xy 92.355924 -406.44445) (xy 92.353384 -406.45334) (xy 92.354908 -406.471374) (xy 92.390214 -406.548336)
			(xy 92.403168 -406.561036) (xy 92.41155 -406.564846) (xy 92.433333 -406.575069) (xy 92.474941 -406.599242)
			(xy 92.494608 -406.613106) (xy 92.501216 -406.617583) (xy 92.516353 -406.622623) (xy 92.524326 -406.623012)
			(xy 92.761562 -406.623012) (xy 92.769546 -406.622686) (xy 92.784697 -406.617635) (xy 92.79128 -406.613106)
			(xy 92.810954 -406.599253) (xy 92.852561 -406.575081) (xy 92.874338 -406.564846) (xy 92.88272 -406.561036)
			(xy 92.895674 -406.548336) (xy 92.93098 -406.471374) (xy 92.932504 -406.45334) (xy 92.929964 -406.44445)
			(xy 92.923566 -406.420509) (xy 92.916677 -406.371437) (xy 92.916248 -406.34666) (xy 92.916746 -406.320011)
			(xy 92.924689 -406.267307) (xy 92.940399 -406.216377) (xy 92.963525 -406.168356) (xy 92.993549 -406.124319)
			(xy 93.029801 -406.085248) (xy 93.071472 -406.052017) (xy 93.11763 -406.025368) (xy 93.167244 -406.005896)
			(xy 93.219206 -405.994036) (xy 93.272356 -405.990053) (xy 93.325506 -405.994036) (xy 93.377468 -406.005896)
			(xy 93.427082 -406.025368) (xy 93.47324 -406.052017) (xy 93.514911 -406.085248) (xy 93.551163 -406.124319)
			(xy 93.581187 -406.168356) (xy 93.604313 -406.216377) (xy 93.620023 -406.267307) (xy 93.627966 -406.320011)
			(xy 93.628464 -406.34666) (xy 93.627944 -406.374193) (xy 93.619472 -406.428604) (xy 93.602724 -406.481061)
			(xy 93.590872 -406.505918) (xy 93.585284 -406.517094) (xy 93.585792 -406.541732) (xy 93.6371 -406.636728)
			(xy 93.65742 -406.650698) (xy 93.669866 -406.652222) (xy 93.69634 -406.655829) (xy 93.7477 -406.670557)
			(xy 93.796024 -406.69335) (xy 93.840055 -406.723614) (xy 93.878648 -406.760564) (xy 93.9108 -406.803237)
			(xy 93.935673 -406.850523) (xy 93.952621 -406.901194) (xy 93.961203 -406.953929) (xy 93.961712 -406.980644)
			(xy 93.961269 -407.004502) (xy 94.386923 -407.004502) (xy 94.390789 -406.954044) (xy 94.402298 -406.904764)
			(xy 94.421181 -406.857812) (xy 94.446997 -406.814286) (xy 94.479143 -406.775201) (xy 94.516869 -406.741471)
			(xy 94.559294 -406.713882) (xy 94.605427 -406.693079) (xy 94.654191 -406.679548) (xy 94.679262 -406.676098)
			(xy 94.691708 -406.674574) (xy 94.712028 -406.660604) (xy 94.763336 -406.565608) (xy 94.763844 -406.54097)
			(xy 94.758256 -406.529794) (xy 94.746416 -406.504931) (xy 94.729662 -406.452477) (xy 94.72118 -406.398069)
			(xy 94.720664 -406.370536) (xy 94.721162 -406.343887) (xy 94.729105 -406.291183) (xy 94.744815 -406.240253)
			(xy 94.767941 -406.192232) (xy 94.797965 -406.148195) (xy 94.834217 -406.109124) (xy 94.875888 -406.075893)
			(xy 94.922046 -406.049244) (xy 94.97166 -406.029772) (xy 95.023622 -406.017912) (xy 95.076772 -406.013929)
			(xy 95.129922 -406.017912) (xy 95.181884 -406.029772) (xy 95.231498 -406.049244) (xy 95.277656 -406.075893)
			(xy 95.319327 -406.109124) (xy 95.355579 -406.148195) (xy 95.385603 -406.192232) (xy 95.408729 -406.240253)
			(xy 95.424439 -406.291183) (xy 95.432382 -406.343887) (xy 95.43288 -406.370536) (xy 95.432409 -406.395712)
			(xy 95.425275 -406.445556) (xy 95.418656 -406.46985) (xy 95.416485 -406.478805) (xy 95.417902 -406.497161)
			(xy 95.42145 -406.505664) (xy 95.434658 -406.533604) (xy 95.438954 -406.541991) (xy 95.452523 -406.555046)
			(xy 95.461074 -406.559004) (xy 95.48658 -406.570037) (xy 95.535086 -406.597162) (xy 95.557848 -406.613106)
			(xy 95.56447 -406.61756) (xy 95.579596 -406.622614) (xy 95.587566 -406.623012) (xy 95.824802 -406.623012)
			(xy 95.832788 -406.622703) (xy 95.847938 -406.61764) (xy 95.85452 -406.613106) (xy 95.877285 -406.597169)
			(xy 95.925796 -406.570054) (xy 95.951294 -406.559004) (xy 95.959766 -406.554924) (xy 95.973317 -406.541916)
			(xy 95.97771 -406.533604) (xy 95.990918 -406.505664) (xy 95.994497 -406.497169) (xy 95.995918 -406.478802)
			(xy 95.993712 -406.46985) (xy 95.987069 -406.445561) (xy 95.979937 -406.395713) (xy 95.979488 -406.370536)
			(xy 95.979986 -406.343887) (xy 95.987929 -406.291183) (xy 96.003639 -406.240253) (xy 96.026765 -406.192232)
			(xy 96.056789 -406.148195) (xy 96.093041 -406.109124) (xy 96.134712 -406.075893) (xy 96.18087 -406.049244)
			(xy 96.230484 -406.029772) (xy 96.282446 -406.017912) (xy 96.335596 -406.013929) (xy 96.388746 -406.017912)
			(xy 96.440708 -406.029772) (xy 96.490322 -406.049244) (xy 96.53648 -406.075893) (xy 96.578151 -406.109124)
			(xy 96.614403 -406.148195) (xy 96.644427 -406.192232) (xy 96.667553 -406.240253) (xy 96.683263 -406.291183)
			(xy 96.691206 -406.343887) (xy 96.691704 -406.370536) (xy 96.691181 -406.398027) (xy 96.682692 -406.452351)
			(xy 96.665952 -406.504723) (xy 96.654112 -406.52954) (xy 96.648524 -406.540716) (xy 96.649032 -406.565608)
			(xy 96.700848 -406.660604) (xy 96.721422 -406.674574) (xy 96.733868 -406.675844) (xy 96.759066 -406.679113)
			(xy 96.808093 -406.692462) (xy 96.854502 -406.713152) (xy 96.897201 -406.740695) (xy 96.935186 -406.774443)
			(xy 96.967563 -406.813604) (xy 96.99357 -406.857255) (xy 97.012597 -406.90437) (xy 97.024195 -406.95384)
			(xy 97.028091 -407.004502) (xy 97.024194 -407.055164) (xy 97.012596 -407.104634) (xy 96.993568 -407.151749)
			(xy 96.96756 -407.1954) (xy 96.935182 -407.23456) (xy 96.897197 -407.268308) (xy 96.854498 -407.295851)
			(xy 96.808089 -407.316539) (xy 96.759062 -407.329888) (xy 96.733868 -407.333196) (xy 96.721422 -407.334466)
			(xy 96.700848 -407.348436) (xy 96.649032 -407.443432) (xy 96.648524 -407.468324) (xy 96.654112 -407.4795)
			(xy 96.665938 -407.504322) (xy 96.682678 -407.556693) (xy 96.691171 -407.611014) (xy 96.691704 -407.638504)
			(xy 96.691206 -407.665153) (xy 96.683263 -407.717857) (xy 96.667553 -407.768787) (xy 96.644427 -407.816808)
			(xy 96.614403 -407.860845) (xy 96.578151 -407.899916) (xy 96.53648 -407.933147) (xy 96.490322 -407.959796)
			(xy 96.440708 -407.979268) (xy 96.388746 -407.991128) (xy 96.335596 -407.995112) (xy 96.282446 -407.991128)
			(xy 96.230484 -407.979268) (xy 96.18087 -407.959796) (xy 96.134712 -407.933147) (xy 96.093041 -407.899916)
			(xy 96.056789 -407.860845) (xy 96.026765 -407.816808) (xy 96.003639 -407.768787) (xy 95.987929 -407.717857)
			(xy 95.979986 -407.665153) (xy 95.979488 -407.638504) (xy 95.979947 -407.613328) (xy 95.98709 -407.563484)
			(xy 95.993712 -407.53919) (xy 95.995917 -407.530241) (xy 95.994479 -407.511878) (xy 95.990918 -407.503376)
			(xy 95.97771 -407.475436) (xy 95.973445 -407.467031) (xy 95.959854 -407.453986) (xy 95.951294 -407.450036)
			(xy 95.925794 -407.43899) (xy 95.877284 -407.411874) (xy 95.85452 -407.395934) (xy 95.847903 -407.391472)
			(xy 95.832773 -407.386422) (xy 95.824802 -407.386028) (xy 95.587566 -407.386028) (xy 95.579585 -407.386377)
			(xy 95.564434 -407.391413) (xy 95.557848 -407.395934) (xy 95.535074 -407.411859) (xy 95.48657 -407.438982)
			(xy 95.461074 -407.450036) (xy 95.452589 -407.454091) (xy 95.439045 -407.467117) (xy 95.434658 -407.475436)
			(xy 95.42145 -407.503376) (xy 95.417902 -407.511882) (xy 95.416462 -407.53024) (xy 95.418656 -407.53919)
			(xy 95.425286 -407.563482) (xy 95.432427 -407.613327) (xy 95.43288 -407.638504) (xy 95.432382 -407.665153)
			(xy 95.424439 -407.717857) (xy 95.408729 -407.768787) (xy 95.385603 -407.816808) (xy 95.355579 -407.860845)
			(xy 95.319327 -407.899916) (xy 95.277656 -407.933147) (xy 95.231498 -407.959796) (xy 95.181884 -407.979268)
			(xy 95.129922 -407.991128) (xy 95.076772 -407.995112) (xy 95.023622 -407.991128) (xy 94.97166 -407.979268)
			(xy 94.922046 -407.959796) (xy 94.875888 -407.933147) (xy 94.834217 -407.899916) (xy 94.797965 -407.860845)
			(xy 94.767941 -407.816808) (xy 94.744815 -407.768787) (xy 94.729105 -407.717857) (xy 94.721162 -407.665153)
			(xy 94.720664 -407.638504) (xy 94.721168 -407.61097) (xy 94.729646 -407.556559) (xy 94.7464 -407.504102)
			(xy 94.758256 -407.479246) (xy 94.763844 -407.46807) (xy 94.763336 -407.443432) (xy 94.712028 -407.348436)
			(xy 94.691708 -407.334466) (xy 94.679262 -407.332942) (xy 94.654195 -407.329453) (xy 94.605431 -407.315923)
			(xy 94.559298 -407.29512) (xy 94.516873 -407.267532) (xy 94.479146 -407.233802) (xy 94.447 -407.194718)
			(xy 94.421183 -407.151192) (xy 94.402299 -407.104241) (xy 94.39079 -407.054961) (xy 94.386923 -407.004502)
			(xy 93.961269 -407.004502) (xy 93.961257 -407.005156) (xy 93.954027 -407.053645) (xy 93.939719 -407.100535)
			(xy 93.918644 -407.144799) (xy 93.891266 -407.185466) (xy 93.858184 -407.221646) (xy 93.820123 -407.252545)
			(xy 93.777918 -407.277487) (xy 93.732493 -407.295925) (xy 93.684843 -407.307455) (xy 93.660468 -407.310082)
			(xy 93.647514 -407.311098) (xy 93.626178 -407.325576) (xy 93.574362 -407.424382) (xy 93.57487 -407.45029)
			(xy 93.581474 -407.46172) (xy 93.596219 -407.48883) (xy 93.617172 -407.546869) (xy 93.627807 -407.607651)
			(xy 93.628464 -407.638504) (xy 93.627966 -407.665153) (xy 93.620023 -407.717857) (xy 93.604313 -407.768787)
			(xy 93.581187 -407.816808) (xy 93.551163 -407.860845) (xy 93.514911 -407.899916) (xy 93.47324 -407.933147)
			(xy 93.427082 -407.959796) (xy 93.377468 -407.979268) (xy 93.325506 -407.991128) (xy 93.272356 -407.995112)
			(xy 93.219206 -407.991128) (xy 93.167244 -407.979268) (xy 93.11763 -407.959796) (xy 93.071472 -407.933147)
			(xy 93.029801 -407.899916) (xy 92.993549 -407.860845) (xy 92.963525 -407.816808) (xy 92.940399 -407.768787)
			(xy 92.924689 -407.717857) (xy 92.916746 -407.665153) (xy 92.916248 -407.638504) (xy 92.916709 -407.613328)
			(xy 92.92385 -407.563484) (xy 92.930472 -407.53919) (xy 92.932673 -407.53024) (xy 92.931236 -407.511879)
			(xy 92.927678 -407.503376) (xy 92.91447 -407.475436) (xy 92.910183 -407.467044) (xy 92.896607 -407.453993)
			(xy 92.888054 -407.450036) (xy 92.862551 -407.438996) (xy 92.814043 -407.411875) (xy 92.79128 -407.395934)
			(xy 92.784672 -407.391456) (xy 92.769535 -407.386416) (xy 92.761562 -407.386028) (xy 92.524326 -407.386028)
			(xy 92.516343 -407.38636) (xy 92.501192 -407.391408) (xy 92.494608 -407.395934) (xy 92.471838 -407.411864)
			(xy 92.423331 -407.438983) (xy 92.397834 -407.450036) (xy 92.389342 -407.454079) (xy 92.375802 -407.467114)
			(xy 92.371418 -407.475436) (xy 92.35821 -407.503376) (xy 92.354662 -407.511882) (xy 92.35322 -407.53024)
			(xy 92.355416 -407.53919) (xy 92.362047 -407.563482) (xy 92.369187 -407.613327) (xy 92.36964 -407.638504)
			(xy 92.369142 -407.665153) (xy 92.361199 -407.717857) (xy 92.345489 -407.768787) (xy 92.322363 -407.816808)
			(xy 92.292339 -407.860845) (xy 92.256087 -407.899916) (xy 92.214416 -407.933147) (xy 92.168258 -407.959796)
			(xy 92.118644 -407.979268) (xy 92.066682 -407.991128) (xy 92.013532 -407.995112) (xy 91.960382 -407.991128)
			(xy 91.90842 -407.979268) (xy 91.858806 -407.959796) (xy 91.812648 -407.933147) (xy 91.770977 -407.899916)
			(xy 91.734725 -407.860845) (xy 91.704701 -407.816808) (xy 91.681575 -407.768787) (xy 91.665865 -407.717857)
			(xy 91.657922 -407.665153) (xy 91.657424 -407.638504) (xy 91.657932 -407.61097) (xy 91.666409 -407.55656)
			(xy 91.683162 -407.504102) (xy 91.695016 -407.479246) (xy 91.700604 -407.46807) (xy 91.700096 -407.443432)
			(xy 91.648788 -407.348436) (xy 91.628468 -407.334466) (xy 91.616022 -407.332942) (xy 91.589557 -407.329282)
			(xy 91.538203 -407.314557) (xy 91.489883 -407.291768) (xy 91.445855 -407.261509) (xy 91.407263 -407.224566)
			(xy 91.37511 -407.181901) (xy 91.350234 -407.134623) (xy 91.33328 -407.08396) (xy 91.32469 -407.031232)
			(xy 91.324176 -407.00452) (xy 90.899014 -407.00452) (xy 90.895148 -407.054968) (xy 90.883636 -407.104255)
			(xy 90.86475 -407.151212) (xy 90.838929 -407.194744) (xy 90.806777 -407.233833) (xy 90.769044 -407.267567)
			(xy 90.726613 -407.295158) (xy 90.680472 -407.315962) (xy 90.631701 -407.329493) (xy 90.606626 -407.332942)
			(xy 90.59418 -407.334466) (xy 90.57386 -407.348436) (xy 90.522552 -407.443432) (xy 90.522044 -407.46807)
			(xy 90.527632 -407.479246) (xy 90.539485 -407.504103) (xy 90.556235 -407.55656) (xy 90.564711 -407.610971)
			(xy 90.565224 -407.638504) (xy 90.564726 -407.665153) (xy 90.556783 -407.717857) (xy 90.541073 -407.768787)
			(xy 90.517947 -407.816808) (xy 90.487923 -407.860845) (xy 90.451671 -407.899916) (xy 90.41 -407.933147)
			(xy 90.363842 -407.959796) (xy 90.314228 -407.979268) (xy 90.262266 -407.991128) (xy 90.209116 -407.995112)
			(xy 90.155966 -407.991128) (xy 90.104004 -407.979268) (xy 90.05439 -407.959796) (xy 90.008232 -407.933147)
			(xy 89.966561 -407.899916) (xy 89.930309 -407.860845) (xy 89.900285 -407.816808) (xy 89.877159 -407.768787)
			(xy 89.861449 -407.717857) (xy 89.853506 -407.665153) (xy 89.853008 -407.638504) (xy 89.853467 -407.613328)
			(xy 89.860609 -407.563484) (xy 89.867232 -407.53919) (xy 89.869436 -407.53024) (xy 89.867998 -407.511878)
			(xy 89.864438 -407.503376) (xy 89.85123 -407.475436) (xy 89.846957 -407.467035) (xy 89.833371 -407.453988)
			(xy 89.824814 -407.450036) (xy 89.799315 -407.438987) (xy 89.750804 -407.411873) (xy 89.72804 -407.395934)
			(xy 89.721418 -407.391479) (xy 89.706292 -407.386425) (xy 89.698322 -407.386028) (xy 89.461086 -407.386028)
			(xy 89.453101 -407.386342) (xy 89.437951 -407.391402) (xy 89.431368 -407.395934) (xy 89.408601 -407.411869)
			(xy 89.360092 -407.438985) (xy 89.334594 -407.450036) (xy 89.326113 -407.454098) (xy 89.312566 -407.467119)
			(xy 89.308178 -407.475436) (xy 89.29497 -407.503376) (xy 89.291422 -407.511882) (xy 89.289981 -407.53024)
			(xy 89.292176 -407.53919) (xy 89.298806 -407.563482) (xy 89.305947 -407.613327) (xy 89.3064 -407.638504)
			(xy 89.305902 -407.665153) (xy 89.297959 -407.717857) (xy 89.282249 -407.768787) (xy 89.259123 -407.816808)
			(xy 89.229099 -407.860845) (xy 89.192847 -407.899916) (xy 89.151176 -407.933147) (xy 89.105018 -407.959796)
			(xy 89.055404 -407.979268) (xy 89.003442 -407.991128) (xy 88.950292 -407.995112) (xy 88.897142 -407.991128)
			(xy 88.84518 -407.979268) (xy 88.795566 -407.959796) (xy 88.749408 -407.933147) (xy 88.707737 -407.899916)
			(xy 88.671485 -407.860845) (xy 88.641461 -407.816808) (xy 88.618335 -407.768787) (xy 88.602625 -407.717857)
			(xy 88.594682 -407.665153) (xy 88.594184 -407.638504) (xy 88.594686 -407.61097) (xy 88.603165 -407.556559)
			(xy 88.61992 -407.504102) (xy 88.631776 -407.479246) (xy 88.637364 -407.46807) (xy 88.636856 -407.443432)
			(xy 88.585548 -407.348436) (xy 88.565228 -407.334466) (xy 88.552782 -407.332942) (xy 88.527714 -407.329454)
			(xy 88.478948 -407.315926) (xy 88.432812 -407.295125) (xy 88.390384 -407.267538) (xy 88.352655 -407.233808)
			(xy 88.320506 -407.194723) (xy 88.294688 -407.151197) (xy 88.275803 -407.104244) (xy 88.264292 -407.054962)
			(xy 88.260425 -407.004502) (xy 87.835722 -407.004502) (xy 87.831856 -407.054963) (xy 87.820347 -407.104245)
			(xy 87.801464 -407.151199) (xy 87.775649 -407.194727) (xy 87.743504 -407.233815) (xy 87.705779 -407.26755)
			(xy 87.663355 -407.295143) (xy 87.617222 -407.315952) (xy 87.568458 -407.329489) (xy 87.543386 -407.332942)
			(xy 87.53094 -407.334466) (xy 87.51062 -407.348436) (xy 87.459312 -407.443432) (xy 87.458804 -407.46807)
			(xy 87.464392 -407.479246) (xy 87.476249 -407.504101) (xy 87.492996 -407.556559) (xy 87.501471 -407.61097)
			(xy 87.501984 -407.638504) (xy 87.501486 -407.665153) (xy 87.493543 -407.717857) (xy 87.477833 -407.768787)
			(xy 87.454707 -407.816808) (xy 87.424683 -407.860845) (xy 87.388431 -407.899916) (xy 87.34676 -407.933147)
			(xy 87.300602 -407.959796) (xy 87.250988 -407.979268) (xy 87.199026 -407.991128) (xy 87.145876 -407.995112)
			(xy 87.092726 -407.991128) (xy 87.040764 -407.979268) (xy 86.99115 -407.959796) (xy 86.944992 -407.933147)
			(xy 86.903321 -407.899916) (xy 86.867069 -407.860845) (xy 86.837045 -407.816808) (xy 86.813919 -407.768787)
			(xy 86.798209 -407.717857) (xy 86.790266 -407.665153) (xy 86.789768 -407.638504) (xy 86.790228 -407.613328)
			(xy 86.79737 -407.563484) (xy 86.803992 -407.53919) (xy 86.806199 -407.530241) (xy 86.80476 -407.511878)
			(xy 86.801198 -407.503376) (xy 86.78799 -407.475436) (xy 86.783695 -407.467048) (xy 86.770125 -407.453995)
			(xy 86.761574 -407.450036) (xy 86.736072 -407.438993) (xy 86.687564 -407.411875) (xy 86.6648 -407.395934)
			(xy 86.658187 -407.391464) (xy 86.643054 -407.386419) (xy 86.635082 -407.386028) (xy 86.397846 -407.386028)
			(xy 86.389864 -407.386368) (xy 86.374713 -407.391411) (xy 86.368128 -407.395934) (xy 86.345356 -407.411861)
			(xy 86.29685 -407.438982) (xy 86.271354 -407.450036) (xy 86.262866 -407.454085) (xy 86.249324 -407.467116)
			(xy 86.244938 -407.475436) (xy 86.23173 -407.503376) (xy 86.228182 -407.511882) (xy 86.22674 -407.53024)
			(xy 86.228936 -407.53919) (xy 86.235565 -407.563483) (xy 86.242707 -407.613327) (xy 86.24316 -407.638504)
			(xy 86.242662 -407.665153) (xy 86.234719 -407.717857) (xy 86.219009 -407.768787) (xy 86.195883 -407.816808)
			(xy 86.165859 -407.860845) (xy 86.129607 -407.899916) (xy 86.087936 -407.933147) (xy 86.041778 -407.959796)
			(xy 85.992164 -407.979268) (xy 85.940202 -407.991128) (xy 85.887052 -407.995112) (xy 85.833902 -407.991128)
			(xy 85.78194 -407.979268) (xy 85.732326 -407.959796) (xy 85.686168 -407.933147) (xy 85.644497 -407.899916)
			(xy 85.608245 -407.860845) (xy 85.578221 -407.816808) (xy 85.555095 -407.768787) (xy 85.539385 -407.717857)
			(xy 85.531442 -407.665153) (xy 85.530944 -407.638504) (xy 85.53145 -407.61097) (xy 85.539928 -407.556559)
			(xy 85.556681 -407.504102) (xy 85.568536 -407.479246) (xy 85.574124 -407.46807) (xy 85.573616 -407.443432)
			(xy 85.522308 -407.348436) (xy 85.501988 -407.334466) (xy 85.489542 -407.332942) (xy 85.464476 -407.329452)
			(xy 85.415715 -407.315919) (xy 85.369584 -407.295115) (xy 85.327161 -407.267526) (xy 85.289437 -407.233796)
			(xy 85.257293 -407.194712) (xy 85.231478 -407.151187) (xy 85.212596 -407.104238) (xy 85.201087 -407.054959)
			(xy 85.197221 -407.004502) (xy 84.772518 -407.004502) (xy 84.768651 -407.054966) (xy 84.75714 -407.104251)
			(xy 84.738255 -407.151208) (xy 84.712436 -407.194738) (xy 84.680286 -407.233827) (xy 84.642556 -407.267561)
			(xy 84.600127 -407.295153) (xy 84.553989 -407.315958) (xy 84.50522 -407.329491) (xy 84.480146 -407.332942)
			(xy 84.4677 -407.334466) (xy 84.44738 -407.348436) (xy 84.396072 -407.443432) (xy 84.395564 -407.46807)
			(xy 84.401152 -407.479246) (xy 84.413006 -407.504102) (xy 84.429755 -407.55656) (xy 84.438231 -407.610971)
			(xy 84.438744 -407.638504) (xy 84.438246 -407.665153) (xy 84.430303 -407.717857) (xy 84.414593 -407.768787)
			(xy 84.391467 -407.816808) (xy 84.361443 -407.860845) (xy 84.325191 -407.899916) (xy 84.28352 -407.933147)
			(xy 84.237362 -407.959796) (xy 84.187748 -407.979268) (xy 84.135786 -407.991128) (xy 84.082636 -407.995112)
			(xy 84.029486 -407.991128) (xy 83.977524 -407.979268) (xy 83.92791 -407.959796) (xy 83.881752 -407.933147)
			(xy 83.840081 -407.899916) (xy 83.803829 -407.860845) (xy 83.773805 -407.816808) (xy 83.750679 -407.768787)
			(xy 83.734969 -407.717857) (xy 83.727026 -407.665153) (xy 83.726528 -407.638504) (xy 83.726986 -407.613328)
			(xy 83.734129 -407.563484) (xy 83.740752 -407.53919) (xy 83.742954 -407.53024) (xy 83.741516 -407.511879)
			(xy 83.737958 -407.503376) (xy 83.72475 -407.475436) (xy 83.72047 -407.467039) (xy 83.706889 -407.45399)
			(xy 83.698334 -407.450036) (xy 83.67283 -407.438998) (xy 83.624323 -407.411876) (xy 83.60156 -407.395934)
			(xy 83.594934 -407.391487) (xy 83.579811 -407.386428) (xy 83.571842 -407.386028) (xy 83.334606 -407.386028)
			(xy 83.326622 -407.386351) (xy 83.311471 -407.391405) (xy 83.304888 -407.395934) (xy 83.282119 -407.411866)
			(xy 83.233611 -407.438984) (xy 83.208114 -407.450036) (xy 83.199636 -407.454104) (xy 83.186087 -407.467121)
			(xy 83.181698 -407.475436) (xy 83.16849 -407.503376) (xy 83.164942 -407.511882) (xy 83.1635 -407.53024)
			(xy 83.165696 -407.53919) (xy 83.172327 -407.563482) (xy 83.179467 -407.613327) (xy 83.17992 -407.638504)
			(xy 83.179422 -407.665153) (xy 83.171479 -407.717857) (xy 83.155769 -407.768787) (xy 83.132643 -407.816808)
			(xy 83.102619 -407.860845) (xy 83.066367 -407.899916) (xy 83.024696 -407.933147) (xy 82.978538 -407.959796)
			(xy 82.928924 -407.979268) (xy 82.876962 -407.991128) (xy 82.823812 -407.995112) (xy 82.770662 -407.991128)
			(xy 82.7187 -407.979268) (xy 82.669086 -407.959796) (xy 82.622928 -407.933147) (xy 82.581257 -407.899916)
			(xy 82.545005 -407.860845) (xy 82.514981 -407.816808) (xy 82.491855 -407.768787) (xy 82.476145 -407.717857)
			(xy 82.468202 -407.665153) (xy 82.467704 -407.638504) (xy 82.468214 -407.61097) (xy 82.476691 -407.55656)
			(xy 82.493442 -407.504102) (xy 82.505296 -407.479246) (xy 82.510884 -407.46807) (xy 82.510376 -407.443432)
			(xy 82.459068 -407.348436) (xy 82.438748 -407.334466) (xy 82.426302 -407.332942) (xy 82.401238 -407.329449)
			(xy 82.352481 -407.315912) (xy 82.306356 -407.295105) (xy 82.263939 -407.267515) (xy 82.22622 -407.233784)
			(xy 82.194079 -407.194701) (xy 82.168268 -407.151178) (xy 82.149389 -407.104231) (xy 82.137882 -407.054956)
			(xy 82.134016 -407.004502) (xy 81.709225 -407.004502) (xy 81.705358 -407.054961) (xy 81.69385 -407.104242)
			(xy 81.674969 -407.151194) (xy 81.649156 -407.194722) (xy 81.617013 -407.233809) (xy 81.57929 -407.267544)
			(xy 81.536869 -407.295138) (xy 81.490739 -407.315948) (xy 81.441977 -407.329487) (xy 81.416906 -407.332942)
			(xy 81.40446 -407.334466) (xy 81.38414 -407.348436) (xy 81.332832 -407.443432) (xy 81.332324 -407.46807)
			(xy 81.337912 -407.479246) (xy 81.34977 -407.5041) (xy 81.366517 -407.556559) (xy 81.374991 -407.61097)
			(xy 81.375504 -407.638504) (xy 81.375006 -407.665153) (xy 81.367063 -407.717857) (xy 81.351353 -407.768787)
			(xy 81.328227 -407.816808) (xy 81.298203 -407.860845) (xy 81.261951 -407.899916) (xy 81.22028 -407.933147)
			(xy 81.174122 -407.959796) (xy 81.124508 -407.979268) (xy 81.072546 -407.991128) (xy 81.019396 -407.995112)
			(xy 80.966246 -407.991128) (xy 80.914284 -407.979268) (xy 80.86467 -407.959796) (xy 80.818512 -407.933147)
			(xy 80.776841 -407.899916) (xy 80.740589 -407.860845) (xy 80.710565 -407.816808) (xy 80.687439 -407.768787)
			(xy 80.671729 -407.717857) (xy 80.663786 -407.665153) (xy 80.663288 -407.638504) (xy 80.663747 -407.613328)
			(xy 80.67089 -407.563484) (xy 80.677512 -407.53919) (xy 80.679717 -407.530241) (xy 80.678279 -407.511878)
			(xy 80.674718 -407.503376) (xy 80.66151 -407.475436) (xy 80.657245 -407.467031) (xy 80.643654 -407.453986)
			(xy 80.635094 -407.450036) (xy 80.609594 -407.43899) (xy 80.561084 -407.411874) (xy 80.53832 -407.395934)
			(xy 80.531703 -407.391472) (xy 80.516573 -407.386422) (xy 80.508602 -407.386028) (xy 80.271366 -407.386028)
			(xy 80.263385 -407.386377) (xy 80.248234 -407.391413) (xy 80.241648 -407.395934) (xy 80.218874 -407.411859)
			(xy 80.17037 -407.438982) (xy 80.144874 -407.450036) (xy 80.136389 -407.454091) (xy 80.122845 -407.467117)
			(xy 80.118458 -407.475436) (xy 80.10525 -407.503376) (xy 80.101702 -407.511882) (xy 80.100262 -407.53024)
			(xy 80.102456 -407.53919) (xy 80.109086 -407.563482) (xy 80.116227 -407.613327) (xy 80.11668 -407.638504)
			(xy 80.116182 -407.665153) (xy 80.108239 -407.717857) (xy 80.092529 -407.768787) (xy 80.069403 -407.816808)
			(xy 80.039379 -407.860845) (xy 80.003127 -407.899916) (xy 79.961456 -407.933147) (xy 79.915298 -407.959796)
			(xy 79.865684 -407.979268) (xy 79.813722 -407.991128) (xy 79.760572 -407.995112) (xy 79.707422 -407.991128)
			(xy 79.65546 -407.979268) (xy 79.605846 -407.959796) (xy 79.559688 -407.933147) (xy 79.518017 -407.899916)
			(xy 79.481765 -407.860845) (xy 79.451741 -407.816808) (xy 79.428615 -407.768787) (xy 79.412905 -407.717857)
			(xy 79.404962 -407.665153) (xy 79.404464 -407.638504) (xy 79.404968 -407.61097) (xy 79.413446 -407.556559)
			(xy 79.4302 -407.504102) (xy 79.442056 -407.479246) (xy 79.447644 -407.46807) (xy 79.447136 -407.443432)
			(xy 79.395828 -407.348436) (xy 79.375508 -407.334466) (xy 79.363062 -407.332942) (xy 79.337995 -407.329453)
			(xy 79.289231 -407.315923) (xy 79.243098 -407.29512) (xy 79.200673 -407.267532) (xy 79.162946 -407.233802)
			(xy 79.1308 -407.194718) (xy 79.104983 -407.151192) (xy 79.086099 -407.104241) (xy 79.07459 -407.054961)
			(xy 79.070723 -407.004502) (xy 78.64602 -407.004502) (xy 78.642153 -407.054964) (xy 78.630643 -407.104248)
			(xy 78.611759 -407.151203) (xy 78.585942 -407.194733) (xy 78.553795 -407.233821) (xy 78.516067 -407.267556)
			(xy 78.473641 -407.295148) (xy 78.427506 -407.315955) (xy 78.378739 -407.32949) (xy 78.353666 -407.332942)
			(xy 78.34122 -407.334466) (xy 78.3209 -407.348436) (xy 78.269592 -407.443432) (xy 78.269084 -407.46807)
			(xy 78.274672 -407.479246) (xy 78.286527 -407.504102) (xy 78.303276 -407.55656) (xy 78.311751 -407.610971)
			(xy 78.312264 -407.638504) (xy 78.311766 -407.665153) (xy 78.303823 -407.717857) (xy 78.288113 -407.768787)
			(xy 78.264987 -407.816808) (xy 78.234963 -407.860845) (xy 78.198711 -407.899916) (xy 78.15704 -407.933147)
			(xy 78.110882 -407.959796) (xy 78.061268 -407.979268) (xy 78.009306 -407.991128) (xy 77.956156 -407.995112)
			(xy 77.903006 -407.991128) (xy 77.851044 -407.979268) (xy 77.80143 -407.959796) (xy 77.755272 -407.933147)
			(xy 77.713601 -407.899916) (xy 77.677349 -407.860845) (xy 77.647325 -407.816808) (xy 77.624199 -407.768787)
			(xy 77.608489 -407.717857) (xy 77.600546 -407.665153) (xy 77.600048 -407.638504) (xy 77.600509 -407.613328)
			(xy 77.60765 -407.563484) (xy 77.614272 -407.53919) (xy 77.616473 -407.53024) (xy 77.615036 -407.511879)
			(xy 77.611478 -407.503376) (xy 77.59827 -407.475436) (xy 77.593983 -407.467044) (xy 77.580407 -407.453993)
			(xy 77.571854 -407.450036) (xy 77.546351 -407.438996) (xy 77.497843 -407.411875) (xy 77.47508 -407.395934)
			(xy 77.468472 -407.391456) (xy 77.453335 -407.386416) (xy 77.445362 -407.386028) (xy 77.208126 -407.386028)
			(xy 77.200143 -407.38636) (xy 77.184992 -407.391408) (xy 77.178408 -407.395934) (xy 77.155638 -407.411864)
			(xy 77.107131 -407.438983) (xy 77.081634 -407.450036) (xy 77.073142 -407.454079) (xy 77.059602 -407.467114)
			(xy 77.055218 -407.475436) (xy 77.04201 -407.503376) (xy 77.038462 -407.511882) (xy 77.03702 -407.53024)
			(xy 77.039216 -407.53919) (xy 77.045847 -407.563482) (xy 77.052987 -407.613327) (xy 77.05344 -407.638504)
			(xy 77.052942 -407.665153) (xy 77.044999 -407.717857) (xy 77.029289 -407.768787) (xy 77.006163 -407.816808)
			(xy 76.976139 -407.860845) (xy 76.939887 -407.899916) (xy 76.898216 -407.933147) (xy 76.852058 -407.959796)
			(xy 76.802444 -407.979268) (xy 76.750482 -407.991128) (xy 76.697332 -407.995112) (xy 76.644182 -407.991128)
			(xy 76.59222 -407.979268) (xy 76.542606 -407.959796) (xy 76.496448 -407.933147) (xy 76.454777 -407.899916)
			(xy 76.418525 -407.860845) (xy 76.388501 -407.816808) (xy 76.365375 -407.768787) (xy 76.349665 -407.717857)
			(xy 76.341722 -407.665153) (xy 76.341224 -407.638504) (xy 76.341732 -407.61097) (xy 76.350209 -407.55656)
			(xy 76.366962 -407.504102) (xy 76.378816 -407.479246) (xy 76.384404 -407.46807) (xy 76.383896 -407.443432)
			(xy 76.332588 -407.348436) (xy 76.312268 -407.334466) (xy 76.299822 -407.332942) (xy 76.274757 -407.32945)
			(xy 76.225998 -407.315916) (xy 76.17987 -407.29511) (xy 76.13745 -407.267521) (xy 76.099729 -407.23379)
			(xy 76.067586 -407.194707) (xy 76.041773 -407.151183) (xy 76.022892 -407.104234) (xy 76.011384 -407.054957)
			(xy 76.007518 -407.004502) (xy 75.582815 -407.004502) (xy 75.578948 -407.054968) (xy 75.567436 -407.104255)
			(xy 75.54855 -407.151212) (xy 75.522729 -407.194744) (xy 75.490577 -407.233833) (xy 75.452844 -407.267567)
			(xy 75.410413 -407.295158) (xy 75.364272 -407.315962) (xy 75.315501 -407.329493) (xy 75.290426 -407.332942)
			(xy 75.27798 -407.334466) (xy 75.25766 -407.348436) (xy 75.206352 -407.443432) (xy 75.205844 -407.46807)
			(xy 75.211432 -407.479246) (xy 75.223285 -407.504103) (xy 75.240035 -407.55656) (xy 75.248511 -407.610971)
			(xy 75.249024 -407.638504) (xy 75.248526 -407.665153) (xy 75.240583 -407.717857) (xy 75.224873 -407.768787)
			(xy 75.201747 -407.816808) (xy 75.171723 -407.860845) (xy 75.135471 -407.899916) (xy 75.0938 -407.933147)
			(xy 75.047642 -407.959796) (xy 74.998028 -407.979268) (xy 74.946066 -407.991128) (xy 74.892916 -407.995112)
			(xy 74.839766 -407.991128) (xy 74.787804 -407.979268) (xy 74.73819 -407.959796) (xy 74.692032 -407.933147)
			(xy 74.650361 -407.899916) (xy 74.614109 -407.860845) (xy 74.584085 -407.816808) (xy 74.560959 -407.768787)
			(xy 74.545249 -407.717857) (xy 74.537306 -407.665153) (xy 74.536808 -407.638504) (xy 74.537267 -407.613328)
			(xy 74.544409 -407.563484) (xy 74.551032 -407.53919) (xy 74.553236 -407.53024) (xy 74.551798 -407.511878)
			(xy 74.548238 -407.503376) (xy 74.53503 -407.475436) (xy 74.530757 -407.467035) (xy 74.517171 -407.453988)
			(xy 74.508614 -407.450036) (xy 74.483115 -407.438987) (xy 74.434604 -407.411873) (xy 74.41184 -407.395934)
			(xy 74.405218 -407.391479) (xy 74.390092 -407.386425) (xy 74.382122 -407.386028) (xy 74.144886 -407.386028)
			(xy 74.136901 -407.386342) (xy 74.121751 -407.391402) (xy 74.115168 -407.395934) (xy 74.092401 -407.411869)
			(xy 74.043892 -407.438985) (xy 74.018394 -407.450036) (xy 74.009913 -407.454098) (xy 73.996366 -407.467119)
			(xy 73.991978 -407.475436) (xy 73.97877 -407.503376) (xy 73.975222 -407.511882) (xy 73.973781 -407.53024)
			(xy 73.975976 -407.53919) (xy 73.982606 -407.563482) (xy 73.989747 -407.613327) (xy 73.9902 -407.638504)
			(xy 73.989702 -407.665153) (xy 73.981759 -407.717857) (xy 73.966049 -407.768787) (xy 73.942923 -407.816808)
			(xy 73.912899 -407.860845) (xy 73.876647 -407.899916) (xy 73.834976 -407.933147) (xy 73.788818 -407.959796)
			(xy 73.739204 -407.979268) (xy 73.687242 -407.991128) (xy 73.634092 -407.995112) (xy 73.580942 -407.991128)
			(xy 73.52898 -407.979268) (xy 73.479366 -407.959796) (xy 73.433208 -407.933147) (xy 73.391537 -407.899916)
			(xy 73.355285 -407.860845) (xy 73.325261 -407.816808) (xy 73.302135 -407.768787) (xy 73.286425 -407.717857)
			(xy 73.278482 -407.665153) (xy 73.277984 -407.638504) (xy 73.278486 -407.61097) (xy 73.286965 -407.556559)
			(xy 73.30372 -407.504102) (xy 73.315576 -407.479246) (xy 73.321164 -407.46807) (xy 73.320656 -407.443432)
			(xy 73.269348 -407.348436) (xy 73.249028 -407.334466) (xy 73.236582 -407.332942) (xy 73.211514 -407.329454)
			(xy 73.162748 -407.315926) (xy 73.116612 -407.295125) (xy 73.074184 -407.267538) (xy 73.036455 -407.233808)
			(xy 73.004306 -407.194723) (xy 72.978488 -407.151197) (xy 72.959603 -407.104244) (xy 72.948092 -407.054962)
			(xy 72.944225 -407.004502) (xy 72.519522 -407.004502) (xy 72.515656 -407.054963) (xy 72.504147 -407.104245)
			(xy 72.485264 -407.151199) (xy 72.459449 -407.194727) (xy 72.427304 -407.233815) (xy 72.389579 -407.26755)
			(xy 72.347155 -407.295143) (xy 72.301022 -407.315952) (xy 72.252258 -407.329489) (xy 72.227186 -407.332942)
			(xy 72.21474 -407.334466) (xy 72.19442 -407.348436) (xy 72.143112 -407.443432) (xy 72.142604 -407.46807)
			(xy 72.148192 -407.479246) (xy 72.160049 -407.504101) (xy 72.176796 -407.556559) (xy 72.185271 -407.61097)
			(xy 72.185784 -407.638504) (xy 72.185286 -407.665153) (xy 72.177343 -407.717857) (xy 72.161633 -407.768787)
			(xy 72.138507 -407.816808) (xy 72.108483 -407.860845) (xy 72.072231 -407.899916) (xy 72.03056 -407.933147)
			(xy 71.984402 -407.959796) (xy 71.934788 -407.979268) (xy 71.882826 -407.991128) (xy 71.829676 -407.995112)
			(xy 71.776526 -407.991128) (xy 71.724564 -407.979268) (xy 71.67495 -407.959796) (xy 71.628792 -407.933147)
			(xy 71.587121 -407.899916) (xy 71.550869 -407.860845) (xy 71.520845 -407.816808) (xy 71.497719 -407.768787)
			(xy 71.482009 -407.717857) (xy 71.474066 -407.665153) (xy 71.473568 -407.638504) (xy 71.474028 -407.613328)
			(xy 71.48117 -407.563484) (xy 71.487792 -407.53919) (xy 71.489999 -407.530241) (xy 71.48856 -407.511878)
			(xy 71.484998 -407.503376) (xy 71.47179 -407.475436) (xy 71.467495 -407.467048) (xy 71.453925 -407.453995)
			(xy 71.445374 -407.450036) (xy 71.419872 -407.438993) (xy 71.371364 -407.411875) (xy 71.3486 -407.395934)
			(xy 71.341987 -407.391464) (xy 71.326854 -407.386419) (xy 71.318882 -407.386028) (xy 71.081646 -407.386028)
			(xy 71.073664 -407.386368) (xy 71.058513 -407.391411) (xy 71.051928 -407.395934) (xy 71.029156 -407.411861)
			(xy 70.98065 -407.438982) (xy 70.955154 -407.450036) (xy 70.946666 -407.454085) (xy 70.933124 -407.467116)
			(xy 70.928738 -407.475436) (xy 70.91553 -407.503376) (xy 70.911982 -407.511882) (xy 70.91054 -407.53024)
			(xy 70.912736 -407.53919) (xy 70.919365 -407.563483) (xy 70.926507 -407.613327) (xy 70.92696 -407.638504)
			(xy 70.926462 -407.665153) (xy 70.918519 -407.717857) (xy 70.902809 -407.768787) (xy 70.879683 -407.816808)
			(xy 70.849659 -407.860845) (xy 70.813407 -407.899916) (xy 70.771736 -407.933147) (xy 70.725578 -407.959796)
			(xy 70.675964 -407.979268) (xy 70.624002 -407.991128) (xy 70.570852 -407.995112) (xy 70.517702 -407.991128)
			(xy 70.46574 -407.979268) (xy 70.416126 -407.959796) (xy 70.369968 -407.933147) (xy 70.328297 -407.899916)
			(xy 70.292045 -407.860845) (xy 70.262021 -407.816808) (xy 70.238895 -407.768787) (xy 70.223185 -407.717857)
			(xy 70.215242 -407.665153) (xy 70.214744 -407.638504) (xy 70.21525 -407.61097) (xy 70.223728 -407.556559)
			(xy 70.240481 -407.504102) (xy 70.252336 -407.479246) (xy 70.257924 -407.46807) (xy 70.257416 -407.443432)
			(xy 70.206108 -407.348436) (xy 70.185788 -407.334466) (xy 70.173342 -407.332942) (xy 70.148276 -407.329452)
			(xy 70.099515 -407.315919) (xy 70.053384 -407.295115) (xy 70.010961 -407.267526) (xy 69.973237 -407.233796)
			(xy 69.941093 -407.194712) (xy 69.915278 -407.151187) (xy 69.896396 -407.104238) (xy 69.884887 -407.054959)
			(xy 69.881021 -407.004502) (xy 69.455792 -407.004502) (xy 69.455792 -407.00452) (xy 69.455317 -407.031234)
			(xy 69.446726 -407.083967) (xy 69.429769 -407.134634) (xy 69.404889 -407.181916) (xy 69.372732 -407.224583)
			(xy 69.334135 -407.261527) (xy 69.2901 -407.291786) (xy 69.241775 -407.314573) (xy 69.190415 -407.329296)
			(xy 69.163946 -407.332942) (xy 69.1515 -407.334466) (xy 69.13118 -407.348436) (xy 69.079872 -407.443432)
			(xy 69.079364 -407.46807) (xy 69.084952 -407.479246) (xy 69.096806 -407.504102) (xy 69.113555 -407.55656)
			(xy 69.122031 -407.610971) (xy 69.122544 -407.638504) (xy 69.122046 -407.665153) (xy 69.114103 -407.717857)
			(xy 69.098393 -407.768787) (xy 69.075267 -407.816808) (xy 69.045243 -407.860845) (xy 69.008991 -407.899916)
			(xy 68.96732 -407.933147) (xy 68.921162 -407.959796) (xy 68.871548 -407.979268) (xy 68.819586 -407.991128)
			(xy 68.766436 -407.995112) (xy 68.713286 -407.991128) (xy 68.661324 -407.979268) (xy 68.61171 -407.959796)
			(xy 68.565552 -407.933147) (xy 68.523881 -407.899916) (xy 68.487629 -407.860845) (xy 68.457605 -407.816808)
			(xy 68.434479 -407.768787) (xy 68.418769 -407.717857) (xy 68.410826 -407.665153) (xy 68.410328 -407.638504)
			(xy 68.410786 -407.613328) (xy 68.417929 -407.563484) (xy 68.424552 -407.53919) (xy 68.426754 -407.53024)
			(xy 68.425316 -407.511879) (xy 68.421758 -407.503376) (xy 68.40855 -407.475436) (xy 68.40427 -407.467039)
			(xy 68.390689 -407.45399) (xy 68.382134 -407.450036) (xy 68.35663 -407.438998) (xy 68.308123 -407.411876)
			(xy 68.28536 -407.395934) (xy 68.278734 -407.391487) (xy 68.263611 -407.386428) (xy 68.255642 -407.386028)
			(xy 68.018406 -407.386028) (xy 68.010422 -407.386351) (xy 67.995271 -407.391405) (xy 67.988688 -407.395934)
			(xy 67.965919 -407.411866) (xy 67.917411 -407.438984) (xy 67.891914 -407.450036) (xy 67.883436 -407.454104)
			(xy 67.869887 -407.467121) (xy 67.865498 -407.475436) (xy 67.85229 -407.503376) (xy 67.848742 -407.511882)
			(xy 67.8473 -407.53024) (xy 67.849496 -407.53919) (xy 67.856127 -407.563482) (xy 67.863267 -407.613327)
			(xy 67.86372 -407.638504) (xy 67.863222 -407.665153) (xy 67.855279 -407.717857) (xy 67.839569 -407.768787)
			(xy 67.816443 -407.816808) (xy 67.786419 -407.860845) (xy 67.750167 -407.899916) (xy 67.708496 -407.933147)
			(xy 67.662338 -407.959796) (xy 67.612724 -407.979268) (xy 67.560762 -407.991128) (xy 67.507612 -407.995112)
			(xy 67.454462 -407.991128) (xy 67.4025 -407.979268) (xy 67.352886 -407.959796) (xy 67.306728 -407.933147)
			(xy 67.265057 -407.899916) (xy 67.228805 -407.860845) (xy 67.198781 -407.816808) (xy 67.175655 -407.768787)
			(xy 67.159945 -407.717857) (xy 67.152002 -407.665153) (xy 67.151504 -407.638504) (xy 67.152014 -407.61097)
			(xy 67.160491 -407.55656) (xy 67.177242 -407.504102) (xy 67.189096 -407.479246) (xy 67.194684 -407.46807)
			(xy 67.194176 -407.443432) (xy 67.142868 -407.348436) (xy 67.122548 -407.334466) (xy 67.110102 -407.332942)
			(xy 67.083634 -407.329299) (xy 67.03228 -407.31457) (xy 66.983961 -407.291779) (xy 66.939933 -407.261517)
			(xy 66.901341 -407.224573) (xy 66.869189 -407.181906) (xy 66.844313 -407.134626) (xy 66.827359 -407.083962)
			(xy 66.818769 -407.031232) (xy 66.818256 -407.00452) (xy 66.393024 -407.00452) (xy 66.389158 -407.054961)
			(xy 66.37765 -407.104242) (xy 66.358769 -407.151194) (xy 66.332956 -407.194722) (xy 66.300813 -407.233809)
			(xy 66.26309 -407.267544) (xy 66.220669 -407.295138) (xy 66.174539 -407.315948) (xy 66.125777 -407.329487)
			(xy 66.100706 -407.332942) (xy 66.08826 -407.334466) (xy 66.06794 -407.348436) (xy 66.016632 -407.443432)
			(xy 66.016124 -407.46807) (xy 66.021712 -407.479246) (xy 66.03357 -407.5041) (xy 66.050317 -407.556559)
			(xy 66.058791 -407.61097) (xy 66.059304 -407.638504) (xy 66.058806 -407.665153) (xy 66.050863 -407.717857)
			(xy 66.035153 -407.768787) (xy 66.012027 -407.816808) (xy 65.982003 -407.860845) (xy 65.945751 -407.899916)
			(xy 65.90408 -407.933147) (xy 65.857922 -407.959796) (xy 65.808308 -407.979268) (xy 65.756346 -407.991128)
			(xy 65.703196 -407.995112) (xy 65.650046 -407.991128) (xy 65.598084 -407.979268) (xy 65.54847 -407.959796)
			(xy 65.502312 -407.933147) (xy 65.460641 -407.899916) (xy 65.424389 -407.860845) (xy 65.394365 -407.816808)
			(xy 65.371239 -407.768787) (xy 65.355529 -407.717857) (xy 65.347586 -407.665153) (xy 65.347088 -407.638504)
			(xy 65.347547 -407.613328) (xy 65.35469 -407.563484) (xy 65.361312 -407.53919) (xy 65.363517 -407.530241)
			(xy 65.362079 -407.511878) (xy 65.358518 -407.503376) (xy 65.34531 -407.475436) (xy 65.341045 -407.467031)
			(xy 65.327454 -407.453986) (xy 65.318894 -407.450036) (xy 65.293394 -407.43899) (xy 65.244884 -407.411874)
			(xy 65.22212 -407.395934) (xy 65.215503 -407.391472) (xy 65.200373 -407.386422) (xy 65.192402 -407.386028)
			(xy 64.955166 -407.386028) (xy 64.947185 -407.386377) (xy 64.932034 -407.391413) (xy 64.925448 -407.395934)
			(xy 64.902674 -407.411859) (xy 64.85417 -407.438982) (xy 64.828674 -407.450036) (xy 64.820189 -407.454091)
			(xy 64.806645 -407.467117) (xy 64.802258 -407.475436) (xy 64.78905 -407.503376) (xy 64.785502 -407.511882)
			(xy 64.784062 -407.53024) (xy 64.786256 -407.53919) (xy 64.792886 -407.563482) (xy 64.800027 -407.613327)
			(xy 64.80048 -407.638504) (xy 64.799982 -407.665153) (xy 64.792039 -407.717857) (xy 64.776329 -407.768787)
			(xy 64.753203 -407.816808) (xy 64.723179 -407.860845) (xy 64.686927 -407.899916) (xy 64.645256 -407.933147)
			(xy 64.599098 -407.959796) (xy 64.549484 -407.979268) (xy 64.497522 -407.991128) (xy 64.444372 -407.995112)
			(xy 64.391222 -407.991128) (xy 64.33926 -407.979268) (xy 64.289646 -407.959796) (xy 64.243488 -407.933147)
			(xy 64.201817 -407.899916) (xy 64.165565 -407.860845) (xy 64.135541 -407.816808) (xy 64.112415 -407.768787)
			(xy 64.096705 -407.717857) (xy 64.088762 -407.665153) (xy 64.088264 -407.638504) (xy 64.088768 -407.61097)
			(xy 64.097246 -407.556559) (xy 64.114 -407.504102) (xy 64.125856 -407.479246) (xy 64.131444 -407.46807)
			(xy 64.130936 -407.443432) (xy 64.079628 -407.348436) (xy 64.059308 -407.334466) (xy 64.046862 -407.332942)
			(xy 64.021795 -407.329453) (xy 63.973031 -407.315923) (xy 63.926898 -407.29512) (xy 63.884473 -407.267532)
			(xy 63.846746 -407.233802) (xy 63.8146 -407.194718) (xy 63.788783 -407.151192) (xy 63.769899 -407.104241)
			(xy 63.75839 -407.054961) (xy 63.754523 -407.004502) (xy 63.32982 -407.004502) (xy 63.325953 -407.054964)
			(xy 63.314443 -407.104248) (xy 63.295559 -407.151203) (xy 63.269742 -407.194733) (xy 63.237595 -407.233821)
			(xy 63.199867 -407.267556) (xy 63.157441 -407.295148) (xy 63.111306 -407.315955) (xy 63.062539 -407.32949)
			(xy 63.037466 -407.332942) (xy 63.02502 -407.334466) (xy 63.0047 -407.348436) (xy 62.953392 -407.443432)
			(xy 62.952884 -407.46807) (xy 62.958472 -407.479246) (xy 62.970327 -407.504102) (xy 62.987076 -407.55656)
			(xy 62.995551 -407.610971) (xy 62.996064 -407.638504) (xy 62.995566 -407.665153) (xy 62.987623 -407.717857)
			(xy 62.971913 -407.768787) (xy 62.948787 -407.816808) (xy 62.918763 -407.860845) (xy 62.882511 -407.899916)
			(xy 62.84084 -407.933147) (xy 62.794682 -407.959796) (xy 62.745068 -407.979268) (xy 62.693106 -407.991128)
			(xy 62.639956 -407.995112) (xy 62.586806 -407.991128) (xy 62.534844 -407.979268) (xy 62.48523 -407.959796)
			(xy 62.439072 -407.933147) (xy 62.397401 -407.899916) (xy 62.361149 -407.860845) (xy 62.331125 -407.816808)
			(xy 62.307999 -407.768787) (xy 62.292289 -407.717857) (xy 62.284346 -407.665153) (xy 62.283848 -407.638504)
			(xy 62.284309 -407.613328) (xy 62.29145 -407.563484) (xy 62.298072 -407.53919) (xy 62.300273 -407.53024)
			(xy 62.298836 -407.511879) (xy 62.295278 -407.503376) (xy 62.28207 -407.475436) (xy 62.277783 -407.467044)
			(xy 62.264207 -407.453993) (xy 62.255654 -407.450036) (xy 62.230151 -407.438996) (xy 62.181643 -407.411875)
			(xy 62.15888 -407.395934) (xy 62.152272 -407.391456) (xy 62.137135 -407.386416) (xy 62.129162 -407.386028)
			(xy 61.891926 -407.386028) (xy 61.883943 -407.38636) (xy 61.868792 -407.391408) (xy 61.862208 -407.395934)
			(xy 61.839438 -407.411864) (xy 61.790931 -407.438983) (xy 61.765434 -407.450036) (xy 61.756942 -407.454079)
			(xy 61.743402 -407.467114) (xy 61.739018 -407.475436) (xy 61.72581 -407.503376) (xy 61.722262 -407.511882)
			(xy 61.72082 -407.53024) (xy 61.723016 -407.53919) (xy 61.729647 -407.563482) (xy 61.736787 -407.613327)
			(xy 61.73724 -407.638504) (xy 61.736742 -407.665153) (xy 61.728799 -407.717857) (xy 61.713089 -407.768787)
			(xy 61.689963 -407.816808) (xy 61.659939 -407.860845) (xy 61.623687 -407.899916) (xy 61.582016 -407.933147)
			(xy 61.535858 -407.959796) (xy 61.486244 -407.979268) (xy 61.434282 -407.991128) (xy 61.381132 -407.995112)
			(xy 61.327982 -407.991128) (xy 61.27602 -407.979268) (xy 61.226406 -407.959796) (xy 61.180248 -407.933147)
			(xy 61.138577 -407.899916) (xy 61.102325 -407.860845) (xy 61.072301 -407.816808) (xy 61.049175 -407.768787)
			(xy 61.033465 -407.717857) (xy 61.025522 -407.665153) (xy 61.025024 -407.638504) (xy 61.025532 -407.61097)
			(xy 61.034009 -407.55656) (xy 61.050762 -407.504102) (xy 61.062616 -407.479246) (xy 61.068204 -407.46807)
			(xy 61.067696 -407.443432) (xy 61.016388 -407.348436) (xy 60.996068 -407.334466) (xy 60.983622 -407.332942)
			(xy 60.958557 -407.32945) (xy 60.909798 -407.315916) (xy 60.86367 -407.29511) (xy 60.82125 -407.267521)
			(xy 60.783529 -407.23379) (xy 60.751386 -407.194707) (xy 60.725573 -407.151183) (xy 60.706692 -407.104234)
			(xy 60.695184 -407.054957) (xy 60.691318 -407.004502) (xy 60.266615 -407.004502) (xy 60.262748 -407.054968)
			(xy 60.251236 -407.104255) (xy 60.23235 -407.151212) (xy 60.206529 -407.194744) (xy 60.174377 -407.233833)
			(xy 60.136644 -407.267567) (xy 60.094213 -407.295158) (xy 60.048072 -407.315962) (xy 59.999301 -407.329493)
			(xy 59.974226 -407.332942) (xy 59.96178 -407.334466) (xy 59.94146 -407.348436) (xy 59.890152 -407.443432)
			(xy 59.889644 -407.46807) (xy 59.895232 -407.479246) (xy 59.907085 -407.504103) (xy 59.923835 -407.55656)
			(xy 59.932311 -407.610971) (xy 59.932824 -407.638504) (xy 59.932326 -407.665153) (xy 59.924383 -407.717857)
			(xy 59.908673 -407.768787) (xy 59.885547 -407.816808) (xy 59.855523 -407.860845) (xy 59.819271 -407.899916)
			(xy 59.7776 -407.933147) (xy 59.731442 -407.959796) (xy 59.681828 -407.979268) (xy 59.629866 -407.991128)
			(xy 59.576716 -407.995112) (xy 59.523566 -407.991128) (xy 59.471604 -407.979268) (xy 59.42199 -407.959796)
			(xy 59.375832 -407.933147) (xy 59.334161 -407.899916) (xy 59.297909 -407.860845) (xy 59.267885 -407.816808)
			(xy 59.244759 -407.768787) (xy 59.229049 -407.717857) (xy 59.221106 -407.665153) (xy 59.220608 -407.638504)
			(xy 59.221067 -407.613328) (xy 59.228209 -407.563484) (xy 59.234832 -407.53919) (xy 59.237036 -407.53024)
			(xy 59.235598 -407.511878) (xy 59.232038 -407.503376) (xy 59.21883 -407.475436) (xy 59.214557 -407.467035)
			(xy 59.200971 -407.453988) (xy 59.192414 -407.450036) (xy 59.166915 -407.438987) (xy 59.118404 -407.411873)
			(xy 59.09564 -407.395934) (xy 59.089018 -407.391479) (xy 59.073892 -407.386425) (xy 59.065922 -407.386028)
			(xy 58.828686 -407.386028) (xy 58.820701 -407.386342) (xy 58.805551 -407.391402) (xy 58.798968 -407.395934)
			(xy 58.776201 -407.411869) (xy 58.727692 -407.438985) (xy 58.702194 -407.450036) (xy 58.693713 -407.454098)
			(xy 58.680166 -407.467119) (xy 58.675778 -407.475436) (xy 58.66257 -407.503376) (xy 58.659022 -407.511882)
			(xy 58.657581 -407.53024) (xy 58.659776 -407.53919) (xy 58.666406 -407.563482) (xy 58.673547 -407.613327)
			(xy 58.674 -407.638504) (xy 58.673502 -407.665153) (xy 58.665559 -407.717857) (xy 58.649849 -407.768787)
			(xy 58.626723 -407.816808) (xy 58.596699 -407.860845) (xy 58.560447 -407.899916) (xy 58.518776 -407.933147)
			(xy 58.472618 -407.959796) (xy 58.423004 -407.979268) (xy 58.371042 -407.991128) (xy 58.317892 -407.995112)
			(xy 58.264742 -407.991128) (xy 58.21278 -407.979268) (xy 58.163166 -407.959796) (xy 58.117008 -407.933147)
			(xy 58.075337 -407.899916) (xy 58.039085 -407.860845) (xy 58.009061 -407.816808) (xy 57.985935 -407.768787)
			(xy 57.970225 -407.717857) (xy 57.962282 -407.665153) (xy 57.961784 -407.638504) (xy 57.962286 -407.61097)
			(xy 57.970765 -407.556559) (xy 57.98752 -407.504102) (xy 57.999376 -407.479246) (xy 58.004964 -407.46807)
			(xy 58.004456 -407.443432) (xy 57.953148 -407.348436) (xy 57.932828 -407.334466) (xy 57.920382 -407.332942)
			(xy 57.895314 -407.329454) (xy 57.846548 -407.315926) (xy 57.800412 -407.295125) (xy 57.757984 -407.267538)
			(xy 57.720255 -407.233808) (xy 57.688106 -407.194723) (xy 57.662288 -407.151197) (xy 57.643403 -407.104244)
			(xy 57.631892 -407.054962) (xy 57.628025 -407.004502) (xy 57.203322 -407.004502) (xy 57.199456 -407.054963)
			(xy 57.187947 -407.104245) (xy 57.169064 -407.151199) (xy 57.143249 -407.194727) (xy 57.111104 -407.233815)
			(xy 57.073379 -407.26755) (xy 57.030955 -407.295143) (xy 56.984822 -407.315952) (xy 56.936058 -407.329489)
			(xy 56.910986 -407.332942) (xy 56.89854 -407.334466) (xy 56.87822 -407.348436) (xy 56.826912 -407.443432)
			(xy 56.826404 -407.46807) (xy 56.831992 -407.479246) (xy 56.843849 -407.504101) (xy 56.860596 -407.556559)
			(xy 56.869071 -407.61097) (xy 56.869584 -407.638504) (xy 56.869086 -407.665153) (xy 56.861143 -407.717857)
			(xy 56.845433 -407.768787) (xy 56.822307 -407.816808) (xy 56.792283 -407.860845) (xy 56.756031 -407.899916)
			(xy 56.71436 -407.933147) (xy 56.668202 -407.959796) (xy 56.618588 -407.979268) (xy 56.566626 -407.991128)
			(xy 56.513476 -407.995112) (xy 56.460326 -407.991128) (xy 56.408364 -407.979268) (xy 56.35875 -407.959796)
			(xy 56.312592 -407.933147) (xy 56.270921 -407.899916) (xy 56.234669 -407.860845) (xy 56.204645 -407.816808)
			(xy 56.181519 -407.768787) (xy 56.165809 -407.717857) (xy 56.157866 -407.665153) (xy 56.157368 -407.638504)
			(xy 56.157828 -407.613328) (xy 56.16497 -407.563484) (xy 56.171592 -407.53919) (xy 56.173799 -407.530241)
			(xy 56.17236 -407.511878) (xy 56.168798 -407.503376) (xy 56.15559 -407.475436) (xy 56.151295 -407.467048)
			(xy 56.137725 -407.453995) (xy 56.129174 -407.450036) (xy 56.103672 -407.438993) (xy 56.055164 -407.411875)
			(xy 56.0324 -407.395934) (xy 56.025787 -407.391464) (xy 56.010654 -407.386419) (xy 56.002682 -407.386028)
			(xy 55.765446 -407.386028) (xy 55.757464 -407.386368) (xy 55.742313 -407.391411) (xy 55.735728 -407.395934)
			(xy 55.712956 -407.411861) (xy 55.66445 -407.438982) (xy 55.638954 -407.450036) (xy 55.630466 -407.454085)
			(xy 55.616924 -407.467116) (xy 55.612538 -407.475436) (xy 55.59933 -407.503376) (xy 55.595782 -407.511882)
			(xy 55.59434 -407.53024) (xy 55.596536 -407.53919) (xy 55.603165 -407.563483) (xy 55.610307 -407.613327)
			(xy 55.61076 -407.638504) (xy 55.610262 -407.665153) (xy 55.602319 -407.717857) (xy 55.586609 -407.768787)
			(xy 55.563483 -407.816808) (xy 55.533459 -407.860845) (xy 55.497207 -407.899916) (xy 55.455536 -407.933147)
			(xy 55.409378 -407.959796) (xy 55.359764 -407.979268) (xy 55.307802 -407.991128) (xy 55.254652 -407.995112)
			(xy 55.201502 -407.991128) (xy 55.14954 -407.979268) (xy 55.099926 -407.959796) (xy 55.053768 -407.933147)
			(xy 55.012097 -407.899916) (xy 54.975845 -407.860845) (xy 54.945821 -407.816808) (xy 54.922695 -407.768787)
			(xy 54.906985 -407.717857) (xy 54.899042 -407.665153) (xy 54.898544 -407.638504) (xy 54.89905 -407.61097)
			(xy 54.907528 -407.556559) (xy 54.924281 -407.504102) (xy 54.936136 -407.479246) (xy 54.941724 -407.46807)
			(xy 54.941216 -407.443432) (xy 54.889908 -407.348436) (xy 54.869588 -407.334466) (xy 54.857142 -407.332942)
			(xy 54.832076 -407.329452) (xy 54.783315 -407.315919) (xy 54.737184 -407.295115) (xy 54.694761 -407.267526)
			(xy 54.657037 -407.233796) (xy 54.624893 -407.194712) (xy 54.599078 -407.151187) (xy 54.580196 -407.104238)
			(xy 54.568687 -407.054959) (xy 54.564821 -407.004502) (xy 54.140118 -407.004502) (xy 54.136251 -407.054966)
			(xy 54.12474 -407.104251) (xy 54.105855 -407.151208) (xy 54.080036 -407.194738) (xy 54.047886 -407.233827)
			(xy 54.010156 -407.267561) (xy 53.967727 -407.295153) (xy 53.921589 -407.315958) (xy 53.87282 -407.329491)
			(xy 53.847746 -407.332942) (xy 53.8353 -407.334466) (xy 53.81498 -407.348436) (xy 53.763672 -407.443432)
			(xy 53.763164 -407.46807) (xy 53.768752 -407.479246) (xy 53.780606 -407.504102) (xy 53.797355 -407.55656)
			(xy 53.805831 -407.610971) (xy 53.806344 -407.638504) (xy 53.805846 -407.665153) (xy 53.797903 -407.717857)
			(xy 53.782193 -407.768787) (xy 53.759067 -407.816808) (xy 53.729043 -407.860845) (xy 53.692791 -407.899916)
			(xy 53.65112 -407.933147) (xy 53.604962 -407.959796) (xy 53.555348 -407.979268) (xy 53.503386 -407.991128)
			(xy 53.450236 -407.995112) (xy 53.397086 -407.991128) (xy 53.345124 -407.979268) (xy 53.29551 -407.959796)
			(xy 53.249352 -407.933147) (xy 53.207681 -407.899916) (xy 53.171429 -407.860845) (xy 53.141405 -407.816808)
			(xy 53.118279 -407.768787) (xy 53.102569 -407.717857) (xy 53.094626 -407.665153) (xy 53.094128 -407.638504)
			(xy 53.094586 -407.613328) (xy 53.101729 -407.563484) (xy 53.108352 -407.53919) (xy 53.110554 -407.53024)
			(xy 53.109116 -407.511879) (xy 53.105558 -407.503376) (xy 53.09235 -407.475436) (xy 53.08807 -407.467039)
			(xy 53.074489 -407.45399) (xy 53.065934 -407.450036) (xy 53.04043 -407.438998) (xy 52.991923 -407.411876)
			(xy 52.96916 -407.395934) (xy 52.962534 -407.391487) (xy 52.947411 -407.386428) (xy 52.939442 -407.386028)
			(xy 52.702206 -407.386028) (xy 52.694222 -407.386351) (xy 52.679071 -407.391405) (xy 52.672488 -407.395934)
			(xy 52.649719 -407.411866) (xy 52.601211 -407.438984) (xy 52.575714 -407.450036) (xy 52.567236 -407.454104)
			(xy 52.553687 -407.467121) (xy 52.549298 -407.475436) (xy 52.53609 -407.503376) (xy 52.532542 -407.511882)
			(xy 52.5311 -407.53024) (xy 52.533296 -407.53919) (xy 52.539927 -407.563482) (xy 52.547067 -407.613327)
			(xy 52.54752 -407.638504) (xy 52.547022 -407.665153) (xy 52.539079 -407.717857) (xy 52.523369 -407.768787)
			(xy 52.500243 -407.816808) (xy 52.470219 -407.860845) (xy 52.433967 -407.899916) (xy 52.392296 -407.933147)
			(xy 52.346138 -407.959796) (xy 52.296524 -407.979268) (xy 52.244562 -407.991128) (xy 52.191412 -407.995112)
			(xy 52.138262 -407.991128) (xy 52.0863 -407.979268) (xy 52.036686 -407.959796) (xy 51.990528 -407.933147)
			(xy 51.948857 -407.899916) (xy 51.912605 -407.860845) (xy 51.882581 -407.816808) (xy 51.859455 -407.768787)
			(xy 51.843745 -407.717857) (xy 51.835802 -407.665153) (xy 51.835304 -407.638504) (xy 51.835814 -407.61097)
			(xy 51.844291 -407.55656) (xy 51.861042 -407.504102) (xy 51.872896 -407.479246) (xy 51.878484 -407.46807)
			(xy 51.877976 -407.443432) (xy 51.826668 -407.348436) (xy 51.806348 -407.334466) (xy 51.793902 -407.332942)
			(xy 51.768838 -407.329449) (xy 51.720081 -407.315912) (xy 51.673956 -407.295105) (xy 51.631539 -407.267515)
			(xy 51.59382 -407.233784) (xy 51.561679 -407.194701) (xy 51.535868 -407.151178) (xy 51.516989 -407.104231)
			(xy 51.505482 -407.054956) (xy 51.501616 -407.004502) (xy 51.076825 -407.004502) (xy 51.072958 -407.054961)
			(xy 51.06145 -407.104242) (xy 51.042569 -407.151194) (xy 51.016756 -407.194722) (xy 50.984613 -407.233809)
			(xy 50.94689 -407.267544) (xy 50.904469 -407.295138) (xy 50.858339 -407.315948) (xy 50.809577 -407.329487)
			(xy 50.784506 -407.332942) (xy 50.77206 -407.334466) (xy 50.75174 -407.348436) (xy 50.700432 -407.443432)
			(xy 50.699924 -407.46807) (xy 50.705512 -407.479246) (xy 50.71737 -407.5041) (xy 50.734117 -407.556559)
			(xy 50.742591 -407.61097) (xy 50.743104 -407.638504) (xy 50.742606 -407.665153) (xy 50.734663 -407.717857)
			(xy 50.718953 -407.768787) (xy 50.695827 -407.816808) (xy 50.665803 -407.860845) (xy 50.629551 -407.899916)
			(xy 50.58788 -407.933147) (xy 50.541722 -407.959796) (xy 50.492108 -407.979268) (xy 50.440146 -407.991128)
			(xy 50.386996 -407.995112) (xy 50.333846 -407.991128) (xy 50.281884 -407.979268) (xy 50.23227 -407.959796)
			(xy 50.186112 -407.933147) (xy 50.144441 -407.899916) (xy 50.108189 -407.860845) (xy 50.078165 -407.816808)
			(xy 50.055039 -407.768787) (xy 50.039329 -407.717857) (xy 50.031386 -407.665153) (xy 50.030888 -407.638504)
			(xy 50.031347 -407.613328) (xy 50.03849 -407.563484) (xy 50.045112 -407.53919) (xy 50.047317 -407.530241)
			(xy 50.045879 -407.511878) (xy 50.042318 -407.503376) (xy 50.02911 -407.475436) (xy 50.024845 -407.467031)
			(xy 50.011254 -407.453986) (xy 50.002694 -407.450036) (xy 49.977194 -407.43899) (xy 49.928684 -407.411874)
			(xy 49.90592 -407.395934) (xy 49.899303 -407.391472) (xy 49.884173 -407.386422) (xy 49.876202 -407.386028)
			(xy 49.638966 -407.386028) (xy 49.630985 -407.386377) (xy 49.615834 -407.391413) (xy 49.609248 -407.395934)
			(xy 49.586474 -407.411859) (xy 49.53797 -407.438982) (xy 49.512474 -407.450036) (xy 49.503989 -407.454091)
			(xy 49.490445 -407.467117) (xy 49.486058 -407.475436) (xy 49.47285 -407.503376) (xy 49.469302 -407.511882)
			(xy 49.467862 -407.53024) (xy 49.470056 -407.53919) (xy 49.476686 -407.563482) (xy 49.483827 -407.613327)
			(xy 49.48428 -407.638504) (xy 49.483782 -407.665153) (xy 49.475839 -407.717857) (xy 49.460129 -407.768787)
			(xy 49.437003 -407.816808) (xy 49.406979 -407.860845) (xy 49.370727 -407.899916) (xy 49.329056 -407.933147)
			(xy 49.282898 -407.959796) (xy 49.233284 -407.979268) (xy 49.181322 -407.991128) (xy 49.128172 -407.995112)
			(xy 49.075022 -407.991128) (xy 49.02306 -407.979268) (xy 48.973446 -407.959796) (xy 48.927288 -407.933147)
			(xy 48.885617 -407.899916) (xy 48.849365 -407.860845) (xy 48.819341 -407.816808) (xy 48.796215 -407.768787)
			(xy 48.780505 -407.717857) (xy 48.772562 -407.665153) (xy 48.772064 -407.638504) (xy 48.772568 -407.61097)
			(xy 48.781046 -407.556559) (xy 48.7978 -407.504102) (xy 48.809656 -407.479246) (xy 48.815244 -407.46807)
			(xy 48.814736 -407.443432) (xy 48.763428 -407.348436) (xy 48.743108 -407.334466) (xy 48.730662 -407.332942)
			(xy 48.705595 -407.329453) (xy 48.656831 -407.315923) (xy 48.610698 -407.29512) (xy 48.568273 -407.267532)
			(xy 48.530546 -407.233802) (xy 48.4984 -407.194718) (xy 48.472583 -407.151192) (xy 48.453699 -407.104241)
			(xy 48.44219 -407.054961) (xy 48.438323 -407.004502) (xy 45.217365 -407.004502) (xy 45.178668 -407.069028)
			(xy 45.073631 -407.227688) (xy 44.961627 -407.381509) (xy 44.84288 -407.530185) (xy 44.717624 -407.673422)
			(xy 44.586109 -407.810934) (xy 44.448596 -407.942448) (xy 44.305358 -408.067702) (xy 44.156681 -408.186449)
			(xy 44.002859 -408.298451) (xy 43.877101 -408.381705) (xy 98.12048 -408.381705) (xy 98.124208 -408.328455)
			(xy 98.135323 -408.276245) (xy 98.153607 -408.226094) (xy 98.178703 -408.178981) (xy 98.210121 -408.135827)
			(xy 98.247247 -408.097472) (xy 98.268028 -408.080718) (xy 98.276782 -408.073149) (xy 98.286969 -408.052395)
			(xy 98.287586 -408.04084) (xy 98.287586 -407.960576) (xy 98.286977 -407.949013) (xy 98.27681 -407.928241)
			(xy 98.268028 -407.920698) (xy 98.245549 -407.902501) (xy 98.205813 -407.860483) (xy 98.172872 -407.81295)
			(xy 98.147483 -407.76099) (xy 98.130226 -407.705793) (xy 98.121497 -407.648624) (xy 98.120962 -407.619708)
			(xy 98.121448 -407.592457) (xy 98.129204 -407.538509) (xy 98.144559 -407.486214) (xy 98.167201 -407.436637)
			(xy 98.196667 -407.390787) (xy 98.232358 -407.349596) (xy 98.273549 -407.313905) (xy 98.319399 -407.284439)
			(xy 98.368976 -407.261797) (xy 98.421271 -407.246442) (xy 98.475219 -407.238686) (xy 98.529721 -407.238686)
			(xy 98.583669 -407.246442) (xy 98.635964 -407.261797) (xy 98.685541 -407.284439) (xy 98.731391 -407.313905)
			(xy 98.772582 -407.349596) (xy 98.808273 -407.390787) (xy 98.837739 -407.436637) (xy 98.860381 -407.486214)
			(xy 98.875736 -407.538509) (xy 98.883492 -407.592457) (xy 98.883978 -407.619708) (xy 98.883402 -407.648623)
			(xy 98.874686 -407.705792) (xy 98.85744 -407.76099) (xy 98.832059 -407.812952) (xy 98.799125 -407.860487)
			(xy 98.759393 -407.902506) (xy 98.736912 -407.920698) (xy 98.728157 -407.928267) (xy 98.717969 -407.94902)
			(xy 98.717354 -407.960576) (xy 98.717354 -408.04084) (xy 98.71794 -408.052406) (xy 98.728122 -408.073179)
			(xy 98.736912 -408.080718) (xy 98.757704 -408.097461) (xy 98.794837 -408.135814) (xy 98.826261 -408.17897)
			(xy 98.851362 -408.226084) (xy 98.869649 -408.276238) (xy 98.880767 -408.328451) (xy 98.884496 -408.381705)
			(xy 98.880765 -408.434958) (xy 98.869647 -408.487171) (xy 98.851358 -408.537325) (xy 98.826256 -408.584439)
			(xy 98.794831 -408.627593) (xy 98.757697 -408.665946) (xy 98.736912 -408.682698) (xy 98.728157 -408.690267)
			(xy 98.717969 -408.71102) (xy 98.717354 -408.722576) (xy 98.717354 -408.80284) (xy 98.71794 -408.814406)
			(xy 98.728122 -408.835179) (xy 98.736912 -408.842718) (xy 98.759407 -408.860896) (xy 98.799141 -408.902919)
			(xy 98.832078 -408.950456) (xy 98.857464 -409.00242) (xy 98.874718 -409.05762) (xy 98.883444 -409.114791)
			(xy 98.883978 -409.143708) (xy 98.883492 -409.170959) (xy 98.875736 -409.224907) (xy 98.860381 -409.277202)
			(xy 98.837739 -409.326779) (xy 98.808273 -409.372629) (xy 98.772582 -409.41382) (xy 98.731391 -409.449511)
			(xy 98.685541 -409.478977) (xy 98.635964 -409.501619) (xy 98.583669 -409.516974) (xy 98.529721 -409.52473)
			(xy 98.475219 -409.52473) (xy 98.421271 -409.516974) (xy 98.368976 -409.501619) (xy 98.319399 -409.478977)
			(xy 98.273549 -409.449511) (xy 98.232358 -409.41382) (xy 98.196667 -409.372629) (xy 98.167201 -409.326779)
			(xy 98.144559 -409.277202) (xy 98.129204 -409.224907) (xy 98.121448 -409.170959) (xy 98.120962 -409.143708)
			(xy 98.121463 -409.11479) (xy 98.130192 -409.057617) (xy 98.147452 -409.002417) (xy 98.172847 -408.950455)
			(xy 98.205795 -408.902921) (xy 98.24554 -408.860907) (xy 98.268028 -408.842718) (xy 98.276782 -408.835149)
			(xy 98.286969 -408.814395) (xy 98.287586 -408.80284) (xy 98.287586 -408.722576) (xy 98.286977 -408.711013)
			(xy 98.27681 -408.690241) (xy 98.268028 -408.682698) (xy 98.247254 -408.665934) (xy 98.210127 -408.627581)
			(xy 98.178708 -408.584427) (xy 98.153611 -408.537315) (xy 98.135326 -408.487164) (xy 98.12421 -408.434954)
			(xy 98.12048 -408.381705) (xy 43.877101 -408.381705) (xy 43.844198 -408.403487) (xy 43.681014 -408.501348)
			(xy 43.597576 -408.547062) (xy 43.591226 -408.550364) (xy 42.121328 -410.020262) (xy 42.114488 -410.027663)
			(xy 42.106772 -410.046261) (xy 42.106342 -410.05633) (xy 42.106342 -414.247838) (xy 42.111422 -414.269682)
			(xy 42.124977 -414.299084) (xy 42.146209 -414.36025) (xy 42.160488 -414.423402) (xy 42.167637 -414.487752)
			(xy 42.168064 -414.520126) (xy 42.167644 -414.552499) (xy 42.160484 -414.616848) (xy 42.146201 -414.679999)
			(xy 42.124971 -414.741166) (xy 42.111422 -414.77057) (xy 42.106342 -414.792414) (xy 42.106342 -415.111438)
			(xy 42.111422 -415.133282) (xy 42.124977 -415.162684) (xy 42.146209 -415.22385) (xy 42.160488 -415.287002)
			(xy 42.167637 -415.351352) (xy 42.168064 -415.383726) (xy 42.167644 -415.416099) (xy 42.160484 -415.480448)
			(xy 42.146201 -415.543599) (xy 42.124971 -415.604766) (xy 42.111422 -415.63417) (xy 42.106342 -415.656014)
			(xy 42.106342 -417.436808) (xy 48.685958 -417.436808) (xy 48.686553 -417.401853) (xy 48.696113 -417.332601)
			(xy 48.715068 -417.26531) (xy 48.743059 -417.20125) (xy 48.779561 -417.141627) (xy 48.801274 -417.114228)
			(xy 48.806541 -417.107227) (xy 48.812388 -417.090726) (xy 48.812704 -417.08197) (xy 48.812704 -416.928046)
			(xy 48.812364 -416.919297) (xy 48.806511 -416.902806) (xy 48.801274 -416.895788) (xy 48.779552 -416.868396)
			(xy 48.743056 -416.808768) (xy 48.715066 -416.744706) (xy 48.696107 -416.677415) (xy 48.686537 -416.608163)
			(xy 48.685958 -416.573208) (xy 48.686464 -416.542478) (xy 48.69387 -416.481467) (xy 48.708577 -416.421794)
			(xy 48.730369 -416.364328) (xy 48.758929 -416.309908) (xy 48.79384 -416.259327) (xy 48.834593 -416.213323)
			(xy 48.880594 -416.172566) (xy 48.931172 -416.137651) (xy 48.98559 -416.109086) (xy 49.043054 -416.08729)
			(xy 49.102726 -416.072578) (xy 49.163737 -416.065166) (xy 49.194466 -416.0647) (xy 49.229838 -416.065311)
			(xy 49.299896 -416.075128) (xy 49.367918 -416.094564) (xy 49.432587 -416.123242) (xy 49.462944 -416.141408)
			(xy 49.473192 -416.147144) (xy 49.496541 -416.149443) (xy 49.518501 -416.141183) (xy 49.526952 -416.133026)
			(xy 49.545031 -416.114442) (xy 49.585362 -416.081863) (xy 49.629737 -416.05505) (xy 49.677336 -416.034497)
			(xy 49.727281 -416.020585) (xy 49.778651 -416.013569) (xy 49.804574 -416.013138) (xy 49.831831 -416.013507)
			(xy 49.885792 -416.021262) (xy 49.938099 -416.036618) (xy 49.987688 -416.059262) (xy 50.03355 -416.088732)
			(xy 50.074751 -416.12443) (xy 50.110452 -416.165629) (xy 50.139926 -416.211489) (xy 50.162573 -416.261077)
			(xy 50.177932 -416.313383) (xy 50.185691 -416.367343) (xy 50.185691 -416.421857) (xy 50.177932 -416.475817)
			(xy 50.162573 -416.528123) (xy 50.139926 -416.577711) (xy 50.110452 -416.623571) (xy 50.074751 -416.66477)
			(xy 50.03355 -416.700468) (xy 49.987688 -416.729938) (xy 49.938099 -416.752582) (xy 49.885792 -416.767938)
			(xy 49.831831 -416.775693) (xy 49.804574 -416.776154) (xy 49.78109 -416.77582) (xy 49.734474 -416.770094)
			(xy 49.71161 -416.764724) (xy 49.700139 -416.762529) (xy 49.67734 -416.767458) (xy 49.659018 -416.781895)
			(xy 49.653444 -416.792156) (xy 49.639806 -416.819745) (xy 49.606821 -416.871706) (xy 49.587658 -416.895788)
			(xy 49.582388 -416.902787) (xy 49.576542 -416.91929) (xy 49.576228 -416.928046) (xy 49.576228 -417.08197)
			(xy 49.576601 -417.090716) (xy 49.58243 -417.107208) (xy 49.587658 -417.114228) (xy 49.609378 -417.141622)
			(xy 49.645876 -417.201249) (xy 49.673868 -417.26531) (xy 49.692827 -417.332601) (xy 49.702396 -417.401853)
			(xy 49.702974 -417.436808) (xy 49.70145 -417.475162) (xy 49.701087 -417.484079) (xy 49.705915 -417.501251)
			(xy 49.710848 -417.50869) (xy 49.728628 -417.533074) (xy 49.733986 -417.539962) (xy 49.748258 -417.549974)
			(xy 49.756568 -417.552632) (xy 49.783264 -417.560286) (xy 49.834266 -417.58226) (xy 49.881544 -417.611396)
			(xy 49.924097 -417.647079) (xy 49.961028 -417.688554) (xy 49.991556 -417.734945) (xy 50.015035 -417.785272)
			(xy 50.03097 -417.838471) (xy 50.039023 -417.893419) (xy 50.039524 -417.921186) (xy 50.039009 -417.948436)
			(xy 50.031255 -418.002382) (xy 50.015902 -418.054675) (xy 49.993264 -418.104251) (xy 49.9638 -418.150101)
			(xy 49.928112 -418.191291) (xy 49.886925 -418.226982) (xy 49.841078 -418.256449) (xy 49.791503 -418.279092)
			(xy 49.739211 -418.294448) (xy 49.685266 -418.302207) (xy 49.658016 -418.302694) (xy 49.62931 -418.302159)
			(xy 49.572543 -418.293586) (xy 49.517702 -418.2766) (xy 49.466027 -418.251586) (xy 49.418686 -418.219108)
			(xy 49.376747 -418.179901) (xy 49.341159 -418.134851) (xy 49.312726 -418.084975) (xy 49.292091 -418.031401)
			(xy 49.285398 -418.003482) (xy 49.283245 -417.995016) (xy 49.274002 -417.980206) (xy 49.267364 -417.974526)
			(xy 49.243488 -417.955984) (xy 49.23629 -417.950728) (xy 49.21938 -417.945134) (xy 49.210468 -417.945062)
			(xy 49.194466 -417.945316) (xy 49.163735 -417.944876) (xy 49.10272 -417.937464) (xy 49.043044 -417.922752)
			(xy 48.985576 -417.900954) (xy 48.931155 -417.872389) (xy 48.880573 -417.837472) (xy 48.834568 -417.796713)
			(xy 48.793812 -417.750707) (xy 48.758898 -417.700123) (xy 48.730335 -417.6457) (xy 48.70854 -417.588231)
			(xy 48.693831 -417.528554) (xy 48.686422 -417.467539) (xy 48.685958 -417.436808) (xy 42.106342 -417.436808)
			(xy 42.106342 -417.45916) (xy 42.105861 -417.469176) (xy 42.098211 -417.487689) (xy 42.084058 -417.501864)
			(xy 42.065557 -417.509545) (xy 42.055542 -417.50996) (xy 36.746688 -417.50996) (xy 36.718494 -417.533836)
			(xy 36.715192 -417.552124) (xy 36.70991 -417.5803) (xy 36.693836 -417.635328) (xy 36.671686 -417.688203)
			(xy 36.658042 -417.713414) (xy 36.651692 -417.72459) (xy 36.65093 -417.748974) (xy 36.697666 -417.84651)
			(xy 36.717224 -417.861242) (xy 36.72967 -417.863274) (xy 36.755978 -417.868208) (xy 36.806973 -417.884474)
			(xy 36.855193 -417.90771) (xy 36.899691 -417.93746) (xy 36.939593 -417.973138) (xy 36.974114 -418.014045)
			(xy 37.002578 -418.059376) (xy 37.024424 -418.108241) (xy 37.039224 -418.159681) (xy 37.046687 -418.212685)
			(xy 37.04717 -418.239448) (xy 37.299644 -418.239448) (xy 37.303715 -418.183826) (xy 37.315841 -418.129389)
			(xy 37.335764 -418.077298) (xy 37.36306 -418.028663) (xy 37.397146 -417.98452) (xy 37.437295 -417.945811)
			(xy 37.482653 -417.91336) (xy 37.532253 -417.887859) (xy 37.585037 -417.869852) (xy 37.63988 -417.859722)
			(xy 37.695614 -417.857685) (xy 37.751051 -417.863785) (xy 37.805008 -417.877891) (xy 37.856337 -417.899703)
			(xy 37.903943 -417.928757) (xy 37.946811 -417.964432) (xy 37.984028 -418.005969) (xy 38.014801 -418.052482)
			(xy 38.038473 -418.102979) (xy 38.054541 -418.156386) (xy 38.062661 -418.211562) (xy 38.06317 -418.239448)
			(xy 38.062661 -418.267334) (xy 38.054541 -418.32251) (xy 38.038473 -418.375917) (xy 38.014801 -418.426414)
			(xy 37.984028 -418.472927) (xy 37.946811 -418.514464) (xy 37.903943 -418.550139) (xy 37.856337 -418.579193)
			(xy 37.805008 -418.601005) (xy 37.751051 -418.615111) (xy 37.695614 -418.621211) (xy 37.63988 -418.619174)
			(xy 37.585037 -418.609044) (xy 37.532253 -418.591037) (xy 37.482653 -418.565536) (xy 37.437295 -418.533085)
			(xy 37.397146 -418.494376) (xy 37.36306 -418.450233) (xy 37.335764 -418.401598) (xy 37.315841 -418.349507)
			(xy 37.303715 -418.29507) (xy 37.299644 -418.239448) (xy 37.04717 -418.239448) (xy 37.046684 -418.266699)
			(xy 37.038928 -418.320647) (xy 37.023573 -418.372942) (xy 37.000931 -418.422519) (xy 36.971465 -418.468369)
			(xy 36.935774 -418.50956) (xy 36.894583 -418.545251) (xy 36.848733 -418.574717) (xy 36.799156 -418.597359)
			(xy 36.746861 -418.612714) (xy 36.692913 -418.62047) (xy 36.638411 -418.62047) (xy 36.584463 -418.612714)
			(xy 36.532168 -418.597359) (xy 36.482591 -418.574717) (xy 36.436741 -418.545251) (xy 36.39555 -418.50956)
			(xy 36.359859 -418.468369) (xy 36.330393 -418.422519) (xy 36.307751 -418.372942) (xy 36.292396 -418.320647)
			(xy 36.28464 -418.266699) (xy 36.284154 -418.239448) (xy 36.284888 -418.206313) (xy 36.296389 -418.141048)
			(xy 36.307014 -418.109654) (xy 36.311078 -418.097716) (xy 36.30803 -418.073586) (xy 36.246054 -417.98494)
			(xy 36.224464 -417.97351) (xy 36.211764 -417.97351) (xy 36.188439 -417.973096) (xy 36.14201 -417.968517)
			(xy 36.119054 -417.964366) (xy 36.105338 -417.961826) (xy 36.079176 -417.971224) (xy 36.0045 -418.060886)
			(xy 36.000182 -418.088064) (xy 36.005262 -418.101018) (xy 36.013457 -418.123078) (xy 36.024973 -418.168709)
			(xy 36.030791 -418.215409) (xy 36.03117 -418.23894) (xy 36.03117 -418.239448) (xy 36.03068 -418.266695)
			(xy 36.022919 -418.320634) (xy 36.00756 -418.372919) (xy 35.984917 -418.422487) (xy 35.955451 -418.468327)
			(xy 35.919761 -418.509508) (xy 35.878573 -418.545191) (xy 35.832728 -418.574649) (xy 35.783156 -418.597284)
			(xy 35.730868 -418.612633) (xy 35.676928 -418.620385) (xy 35.622433 -418.620383) (xy 35.568494 -418.612625)
			(xy 35.516208 -418.59727) (xy 35.466639 -418.574631) (xy 35.420796 -418.545168) (xy 35.379612 -418.509481)
			(xy 35.343926 -418.468296) (xy 35.314464 -418.422453) (xy 35.291826 -418.372883) (xy 35.276473 -418.320596)
			(xy 35.268717 -418.266657) (xy 35.268715 -418.212162) (xy 35.276469 -418.158222) (xy 35.29182 -418.105935)
			(xy 35.314456 -418.056364) (xy 35.343915 -418.010519) (xy 35.379599 -417.969332) (xy 35.420781 -417.933643)
			(xy 35.466622 -417.904178) (xy 35.51619 -417.881537) (xy 35.568476 -417.866179) (xy 35.622415 -417.858419)
			(xy 35.649662 -417.85794) (xy 35.672522 -417.858702) (xy 35.686492 -417.859464) (xy 35.71113 -417.847018)
			(xy 35.773614 -417.748466) (xy 35.77463 -417.72078) (xy 35.768026 -417.708588) (xy 35.755056 -417.684051)
			(xy 35.733934 -417.632725) (xy 35.718536 -417.579401) (xy 35.713416 -417.552124) (xy 35.710114 -417.533836)
			(xy 35.68192 -417.50996) (xy 28.381706 -417.50996) (xy 28.371636 -417.509537) (xy 28.353034 -417.501819)
			(xy 28.345638 -417.494974) (xy 23.476712 -412.626048) (xy 23.469872 -412.618647) (xy 23.462155 -412.600049)
			(xy 23.461726 -412.58998) (xy 23.461726 -408.513534) (xy 23.461292 -408.503469) (xy 23.453563 -408.484879)
			(xy 23.44674 -408.477466) (xy 23.050754 -408.08148) (xy 23.043346 -408.074789) (xy 23.024911 -408.067191)
			(xy 23.01494 -408.066748) (xy 20.25015 -408.066748) (xy 20.240119 -408.067187) (xy 20.221547 -408.074765)
			(xy 20.214082 -408.08148) (xy 19.33575 -408.959812) (xy 19.3289 -408.967209) (xy 19.321162 -408.985807)
			(xy 19.320764 -408.99588) (xy 19.320764 -409.035504) (xy 19.322542 -409.041854) (xy 19.329905 -409.072764)
			(xy 19.337801 -409.135813) (xy 19.33829 -409.167584) (xy 19.337815 -409.199356) (xy 19.329914 -409.262406)
			(xy 19.322542 -409.293314) (xy 19.320764 -409.299664) (xy 19.320764 -410.564584) (xy 21.241764 -410.564584)
			(xy 21.245835 -410.508962) (xy 21.257961 -410.454525) (xy 21.277884 -410.402434) (xy 21.30518 -410.353799)
			(xy 21.339266 -410.309656) (xy 21.379415 -410.270947) (xy 21.424773 -410.238496) (xy 21.474373 -410.212995)
			(xy 21.527157 -410.194988) (xy 21.582 -410.184858) (xy 21.637734 -410.182821) (xy 21.693171 -410.188921)
			(xy 21.747128 -410.203027) (xy 21.798457 -410.224839) (xy 21.846063 -410.253893) (xy 21.888931 -410.289568)
			(xy 21.926148 -410.331105) (xy 21.956921 -410.377618) (xy 21.980593 -410.428115) (xy 21.996661 -410.481522)
			(xy 22.004781 -410.536698) (xy 22.00529 -410.564584) (xy 22.004781 -410.59247) (xy 21.996661 -410.647646)
			(xy 21.980593 -410.701053) (xy 21.956921 -410.75155) (xy 21.926148 -410.798063) (xy 21.888931 -410.8396)
			(xy 21.846063 -410.875275) (xy 21.798457 -410.904329) (xy 21.747128 -410.926141) (xy 21.693171 -410.940247)
			(xy 21.637734 -410.946347) (xy 21.582 -410.94431) (xy 21.527157 -410.93418) (xy 21.474373 -410.916173)
			(xy 21.424773 -410.890672) (xy 21.379415 -410.858221) (xy 21.339266 -410.819512) (xy 21.30518 -410.775369)
			(xy 21.277884 -410.726734) (xy 21.257961 -410.674643) (xy 21.245835 -410.620206) (xy 21.241764 -410.564584)
			(xy 19.320764 -410.564584) (xy 19.320764 -411.701488) (xy 19.322471 -411.707584) (xy 21.241764 -411.707584)
			(xy 21.245835 -411.651962) (xy 21.257961 -411.597525) (xy 21.277884 -411.545434) (xy 21.30518 -411.496799)
			(xy 21.339266 -411.452656) (xy 21.379415 -411.413947) (xy 21.424773 -411.381496) (xy 21.474373 -411.355995)
			(xy 21.527157 -411.337988) (xy 21.582 -411.327858) (xy 21.637734 -411.325821) (xy 21.693171 -411.331921)
			(xy 21.747128 -411.346027) (xy 21.798457 -411.367839) (xy 21.846063 -411.396893) (xy 21.888931 -411.432568)
			(xy 21.926148 -411.474105) (xy 21.956921 -411.520618) (xy 21.980593 -411.571115) (xy 21.996661 -411.624522)
			(xy 22.004781 -411.679698) (xy 22.00529 -411.707584) (xy 22.004781 -411.73547) (xy 21.996661 -411.790646)
			(xy 21.980593 -411.844053) (xy 21.956921 -411.89455) (xy 21.926148 -411.941063) (xy 21.888931 -411.9826)
			(xy 21.846063 -412.018275) (xy 21.798457 -412.047329) (xy 21.747128 -412.069141) (xy 21.693171 -412.083247)
			(xy 21.637734 -412.089347) (xy 21.582 -412.08731) (xy 21.527157 -412.07718) (xy 21.474373 -412.059173)
			(xy 21.424773 -412.033672) (xy 21.379415 -412.001221) (xy 21.339266 -411.962512) (xy 21.30518 -411.918369)
			(xy 21.277884 -411.869734) (xy 21.257961 -411.817643) (xy 21.245835 -411.763206) (xy 21.241764 -411.707584)
			(xy 19.322471 -411.707584) (xy 19.322542 -411.707838) (xy 19.330036 -411.738986) (xy 19.338056 -411.80255)
			(xy 19.338544 -411.834584) (xy 19.338075 -411.866619) (xy 19.330048 -411.930183) (xy 19.322542 -411.96133)
			(xy 19.320764 -411.96768) (xy 19.320764 -412.666434) (xy 19.320237 -412.676329) (xy 19.312644 -412.694612)
			(xy 19.306032 -412.701994) (xy 19.248628 -412.759398) (xy 19.242706 -412.765896) (xy 19.235271 -412.781813)
			(xy 19.233627 -412.799304) (xy 19.23542 -412.807912) (xy 19.246171 -412.850584) (xy 21.241764 -412.850584)
			(xy 21.245835 -412.794962) (xy 21.257961 -412.740525) (xy 21.277884 -412.688434) (xy 21.30518 -412.639799)
			(xy 21.339266 -412.595656) (xy 21.379415 -412.556947) (xy 21.424773 -412.524496) (xy 21.474373 -412.498995)
			(xy 21.527157 -412.480988) (xy 21.582 -412.470858) (xy 21.637734 -412.468821) (xy 21.693171 -412.474921)
			(xy 21.747128 -412.489027) (xy 21.798457 -412.510839) (xy 21.846063 -412.539893) (xy 21.888931 -412.575568)
			(xy 21.926148 -412.617105) (xy 21.956921 -412.663618) (xy 21.980593 -412.714115) (xy 21.996661 -412.767522)
			(xy 22.004781 -412.822698) (xy 22.00529 -412.850584) (xy 22.004781 -412.87847) (xy 21.996661 -412.933646)
			(xy 21.980593 -412.987053) (xy 21.956921 -413.03755) (xy 21.926148 -413.084063) (xy 21.888931 -413.1256)
			(xy 21.846063 -413.161275) (xy 21.798457 -413.190329) (xy 21.747128 -413.212141) (xy 21.693171 -413.226247)
			(xy 21.637734 -413.232347) (xy 21.582 -413.23031) (xy 21.527157 -413.22018) (xy 21.474373 -413.202173)
			(xy 21.424773 -413.176672) (xy 21.379415 -413.144221) (xy 21.339266 -413.105512) (xy 21.30518 -413.061369)
			(xy 21.277884 -413.012734) (xy 21.257961 -412.960643) (xy 21.245835 -412.906206) (xy 21.241764 -412.850584)
			(xy 19.246171 -412.850584) (xy 19.260058 -412.905702) (xy 19.2786 -412.924752) (xy 19.291554 -412.928562)
			(xy 19.322651 -412.938356) (xy 19.382254 -412.964779) (xy 19.43799 -412.998605) (xy 19.488944 -413.039279)
			(xy 19.534281 -413.086133) (xy 19.573256 -413.138398) (xy 19.60523 -413.195216) (xy 19.629678 -413.255656)
			(xy 19.6462 -413.318725) (xy 19.654523 -413.383389) (xy 19.655028 -413.415988) (xy 19.654565 -413.44672)
			(xy 19.647157 -413.507736) (xy 19.63245 -413.567414) (xy 19.610656 -413.624884) (xy 19.582094 -413.679308)
			(xy 19.54718 -413.729893) (xy 19.506423 -413.775901) (xy 19.460418 -413.81666) (xy 19.409836 -413.851577)
			(xy 19.355413 -413.880143) (xy 19.297944 -413.90194) (xy 19.238267 -413.916652) (xy 19.177252 -413.924063)
			(xy 19.14652 -413.924496) (xy 19.113188 -413.923974) (xy 19.047096 -413.915264) (xy 18.982709 -413.89799)
			(xy 18.921132 -413.872449) (xy 18.863422 -413.83908) (xy 18.810567 -413.798454) (xy 18.763476 -413.751269)
			(xy 18.722956 -413.698333) (xy 18.689702 -413.640556) (xy 18.664284 -413.578928) (xy 18.647139 -413.514507)
			(xy 18.64233 -413.48152) (xy 18.64106 -413.472884) (xy 18.633948 -413.458152) (xy 18.627852 -413.452056)
			(xy 18.620405 -413.445368) (xy 18.601909 -413.437772) (xy 18.581913 -413.437772) (xy 18.563417 -413.445368)
			(xy 18.55597 -413.452056) (xy 18.550128 -413.457898) (xy 18.531586 -413.465772) (xy 16.827754 -413.465772)
			(xy 16.798544 -413.493204) (xy 16.797528 -413.513524) (xy 16.795272 -413.545578) (xy 16.783686 -413.608783)
			(xy 16.76423 -413.670025) (xy 16.737213 -413.728328) (xy 16.703067 -413.782762) (xy 16.662335 -413.832461)
			(xy 16.615666 -413.876633) (xy 16.563804 -413.914573) (xy 16.507575 -413.945677) (xy 16.447876 -413.969449)
			(xy 16.385657 -413.985511) (xy 16.321911 -413.993607) (xy 16.257653 -413.993607) (xy 16.193907 -413.985511)
			(xy 16.131688 -413.969449) (xy 16.071989 -413.945677) (xy 16.01576 -413.914573) (xy 15.963898 -413.876633)
			(xy 15.917229 -413.832461) (xy 15.876497 -413.782762) (xy 15.842351 -413.728328) (xy 15.815334 -413.670025)
			(xy 15.795878 -413.608783) (xy 15.784292 -413.545578) (xy 15.782036 -413.513524) (xy 15.78102 -413.493204)
			(xy 15.75181 -413.465772) (xy 15.329154 -413.465772) (xy 15.319213 -413.466238) (xy 15.300821 -413.473788)
			(xy 15.286688 -413.487773) (xy 15.282418 -413.49676) (xy 15.24 -413.597344) (xy 15.245842 -413.627062)
			(xy 15.25651 -413.638238) (xy 15.279062 -413.662059) (xy 15.318484 -413.714489) (xy 15.350838 -413.771553)
			(xy 15.375586 -413.832304) (xy 15.392317 -413.895732) (xy 15.400753 -413.960785) (xy 15.40129 -413.993584)
			(xy 15.401254 -413.99587) (xy 21.2504 -413.99587) (xy 21.254471 -413.940248) (xy 21.266597 -413.885811)
			(xy 21.28652 -413.83372) (xy 21.313816 -413.785085) (xy 21.347902 -413.740942) (xy 21.388051 -413.702233)
			(xy 21.433409 -413.669782) (xy 21.483009 -413.644281) (xy 21.535793 -413.626274) (xy 21.590636 -413.616144)
			(xy 21.64637 -413.614107) (xy 21.701807 -413.620207) (xy 21.755764 -413.634313) (xy 21.807093 -413.656125)
			(xy 21.854699 -413.685179) (xy 21.897567 -413.720854) (xy 21.934784 -413.762391) (xy 21.965557 -413.808904)
			(xy 21.989229 -413.859401) (xy 22.005297 -413.912808) (xy 22.013417 -413.967984) (xy 22.013926 -413.99587)
			(xy 22.013417 -414.023756) (xy 22.005297 -414.078932) (xy 21.989229 -414.132339) (xy 21.965557 -414.182836)
			(xy 21.934784 -414.229349) (xy 21.897567 -414.270886) (xy 21.854699 -414.306561) (xy 21.807093 -414.335615)
			(xy 21.755764 -414.357427) (xy 21.701807 -414.371533) (xy 21.64637 -414.377633) (xy 21.590636 -414.375596)
			(xy 21.535793 -414.365466) (xy 21.483009 -414.347459) (xy 21.433409 -414.321958) (xy 21.388051 -414.289507)
			(xy 21.347902 -414.250798) (xy 21.313816 -414.206655) (xy 21.28652 -414.15802) (xy 21.266597 -414.105929)
			(xy 21.254471 -414.051492) (xy 21.2504 -413.99587) (xy 15.401254 -413.99587) (xy 15.400788 -414.025545)
			(xy 15.392777 -414.088963) (xy 15.37688 -414.150877) (xy 15.353348 -414.21031) (xy 15.322554 -414.266325)
			(xy 15.284981 -414.31804) (xy 15.241224 -414.364637) (xy 15.191971 -414.405382) (xy 15.138 -414.439633)
			(xy 15.080161 -414.46685) (xy 15.019368 -414.486603) (xy 14.956578 -414.498581) (xy 14.892782 -414.502595)
			(xy 14.828986 -414.498581) (xy 14.766196 -414.486603) (xy 14.705403 -414.46685) (xy 14.647564 -414.439633)
			(xy 14.593593 -414.405382) (xy 14.54434 -414.364637) (xy 14.500583 -414.31804) (xy 14.46301 -414.266325)
			(xy 14.432216 -414.21031) (xy 14.408684 -414.150877) (xy 14.392787 -414.088963) (xy 14.384776 -414.025545)
			(xy 14.384274 -413.993584) (xy 14.384787 -413.960785) (xy 14.393227 -413.895731) (xy 14.409963 -413.832303)
			(xy 14.434718 -413.771555) (xy 14.46708 -413.714494) (xy 14.506513 -413.662071) (xy 14.529054 -413.638238)
			(xy 14.539722 -413.627062) (xy 14.545564 -413.597344) (xy 14.503146 -413.49676) (xy 14.498836 -413.487793)
			(xy 14.484718 -413.473803) (xy 14.466347 -413.466219) (xy 14.45641 -413.465772) (xy 14.059154 -413.465772)
			(xy 14.049213 -413.466238) (xy 14.030821 -413.473788) (xy 14.016688 -413.487773) (xy 14.012418 -413.49676)
			(xy 13.97 -413.597344) (xy 13.975842 -413.627062) (xy 13.98651 -413.638238) (xy 14.009062 -413.662059)
			(xy 14.048484 -413.714489) (xy 14.080838 -413.771553) (xy 14.105586 -413.832304) (xy 14.122317 -413.895732)
			(xy 14.130753 -413.960785) (xy 14.13129 -413.993584) (xy 14.130788 -414.025545) (xy 14.122777 -414.088963)
			(xy 14.10688 -414.150877) (xy 14.083348 -414.21031) (xy 14.052554 -414.266325) (xy 14.014981 -414.31804)
			(xy 13.971224 -414.364637) (xy 13.921971 -414.405382) (xy 13.868 -414.439633) (xy 13.810161 -414.46685)
			(xy 13.749368 -414.486603) (xy 13.686578 -414.498581) (xy 13.622782 -414.502595) (xy 13.558986 -414.498581)
			(xy 13.496196 -414.486603) (xy 13.435403 -414.46685) (xy 13.377564 -414.439633) (xy 13.323593 -414.405382)
			(xy 13.27434 -414.364637) (xy 13.230583 -414.31804) (xy 13.19301 -414.266325) (xy 13.162216 -414.21031)
			(xy 13.138684 -414.150877) (xy 13.122787 -414.088963) (xy 13.114776 -414.025545) (xy 13.114274 -413.993584)
			(xy 13.114787 -413.960785) (xy 13.123227 -413.895731) (xy 13.139963 -413.832303) (xy 13.164718 -413.771555)
			(xy 13.19708 -413.714494) (xy 13.236513 -413.662071) (xy 13.259054 -413.638238) (xy 13.269722 -413.627062)
			(xy 13.275564 -413.597344) (xy 13.233146 -413.49676) (xy 13.228836 -413.487793) (xy 13.214718 -413.473803)
			(xy 13.196347 -413.466219) (xy 13.18641 -413.465772) (xy 13.029438 -413.465772) (xy 13.019448 -413.465241)
			(xy 13.001009 -413.457534) (xy 12.993624 -413.450786) (xy 12.370816 -412.827978) (xy 12.364169 -412.820621)
			(xy 12.356594 -412.80232) (xy 12.356084 -412.792418) (xy 12.356084 -412.547816) (xy 12.355364 -412.535564)
			(xy 12.344095 -412.513803) (xy 12.334494 -412.50616) (xy 12.256262 -412.451296) (xy 12.231624 -412.447994)
			(xy 12.21994 -412.452058) (xy 12.18872 -412.462566) (xy 12.123841 -412.473932) (xy 12.090908 -412.474664)
			(xy 12.063657 -412.474178) (xy 12.00971 -412.466421) (xy 11.957416 -412.451066) (xy 11.90784 -412.428425)
			(xy 11.86199 -412.398959) (xy 11.820801 -412.363268) (xy 11.78511 -412.322078) (xy 11.755644 -412.276228)
			(xy 11.733003 -412.226652) (xy 11.717648 -412.174358) (xy 11.709892 -412.120411) (xy 11.709892 -412.065909)
			(xy 11.717648 -412.011962) (xy 11.733003 -411.959668) (xy 11.755644 -411.910092) (xy 11.78511 -411.864242)
			(xy 11.820801 -411.823052) (xy 11.86199 -411.787361) (xy 11.90784 -411.757895) (xy 11.957416 -411.735254)
			(xy 12.00971 -411.719899) (xy 12.063657 -411.712142) (xy 12.090908 -411.711648) (xy 12.123842 -411.712364)
			(xy 12.188722 -411.723736) (xy 12.21994 -411.734254) (xy 12.231624 -411.738318) (xy 12.256262 -411.735016)
			(xy 12.334494 -411.680152) (xy 12.344123 -411.672528) (xy 12.355407 -411.650759) (xy 12.356084 -411.638496)
			(xy 12.356084 -410.385514) (xy 12.35578 -410.377025) (xy 12.350231 -410.360982) (xy 12.339712 -410.347658)
			(xy 12.332716 -410.342842) (xy 12.249912 -410.289502) (xy 12.224004 -410.287724) (xy 12.212066 -410.293058)
			(xy 12.17472 -410.309511) (xy 12.097278 -410.335268) (xy 12.017531 -410.352618) (xy 11.936388 -410.361364)
			(xy 11.895582 -410.361892) (xy 11.873688 -410.361721) (xy 11.829973 -410.35918) (xy 11.808206 -410.356812)
			(xy 11.802618 -410.356558) (xy 11.762232 -410.37637) (xy 11.738196 -410.40666) (xy 11.684926 -410.462717)
			(xy 11.626257 -410.513095) (xy 11.562791 -410.557276) (xy 11.495179 -410.594807) (xy 11.424115 -410.625303)
			(xy 11.350331 -410.64845) (xy 11.274582 -410.664011) (xy 11.197647 -410.671825) (xy 11.158982 -410.67228)
			(xy 11.120336 -410.671807) (xy 11.04344 -410.663987) (xy 10.96773 -410.648429) (xy 10.893982 -410.62529)
			(xy 10.822953 -410.59481) (xy 10.755373 -410.5573) (xy 10.691934 -410.513145) (xy 10.633288 -410.462799)
			(xy 10.580036 -410.406778) (xy 10.532725 -410.345657) (xy 10.49184 -410.280064) (xy 10.457801 -410.21067)
			(xy 10.430957 -410.138189) (xy 10.411583 -410.063364) (xy 10.399879 -409.986963) (xy 10.395964 -409.90977)
			(xy 10.399879 -409.832577) (xy 10.411583 -409.756176) (xy 10.430957 -409.681351) (xy 10.457801 -409.60887)
			(xy 10.49184 -409.539476) (xy 10.532725 -409.473883) (xy 10.580036 -409.412762) (xy 10.633288 -409.356741)
			(xy 10.691934 -409.306395) (xy 10.755373 -409.26224) (xy 10.822953 -409.22473) (xy 10.893982 -409.19425)
			(xy 10.96773 -409.171111) (xy 11.04344 -409.155553) (xy 11.120336 -409.147733) (xy 11.158982 -409.147264)
			(xy 11.180876 -409.147433) (xy 11.224592 -409.149973) (xy 11.246358 -409.152344) (xy 11.251946 -409.152598)
			(xy 11.292332 -409.132786) (xy 11.316368 -409.102496) (xy 11.369638 -409.046439) (xy 11.428308 -408.996062)
			(xy 11.491774 -408.95188) (xy 11.559386 -408.914348) (xy 11.630449 -408.88385) (xy 11.704234 -408.860701)
			(xy 11.779982 -408.845138) (xy 11.856917 -408.83732) (xy 11.895582 -408.836876) (xy 11.936389 -408.837404)
			(xy 12.017537 -408.846121) (xy 12.097288 -408.863466) (xy 12.174725 -408.889242) (xy 12.212066 -408.90571)
			(xy 12.224004 -408.911044) (xy 12.249912 -408.909266) (xy 12.332716 -408.855926) (xy 12.339682 -408.851075)
			(xy 12.350188 -408.837752) (xy 12.355788 -408.821736) (xy 12.356084 -408.813254) (xy 12.356084 -408.262836)
			(xy 12.355649 -408.252771) (xy 12.347916 -408.234185) (xy 12.341098 -408.226768) (xy 11.862562 -407.748486)
			(xy 11.855219 -407.741672) (xy 11.836755 -407.73394) (xy 11.826748 -407.7335) (xy 11.80846 -407.7335)
			(xy 11.798458 -407.733995) (xy 11.77998 -407.741662) (xy 11.765839 -407.755813) (xy 11.758187 -407.774297)
			(xy 11.75766 -407.7843) (xy 11.75766 -407.796492) (xy 11.762994 -407.80716) (xy 11.778791 -407.839228)
			(xy 11.804994 -407.905745) (xy 11.824848 -407.974424) (xy 11.838179 -408.044661) (xy 11.84487 -408.115838)
			(xy 11.84529 -408.151584) (xy 11.844801 -408.190229) (xy 11.836981 -408.267123) (xy 11.821423 -408.342831)
			(xy 11.798285 -408.416577) (xy 11.767805 -408.487604) (xy 11.730296 -408.555182) (xy 11.686142 -408.61862)
			(xy 11.635797 -408.677264) (xy 11.579778 -408.730515) (xy 11.518659 -408.777825) (xy 11.453066 -408.818709)
			(xy 11.383675 -408.852747) (xy 11.311195 -408.87959) (xy 11.236372 -408.898963) (xy 11.159973 -408.910667)
			(xy 11.082782 -408.914582) (xy 11.005591 -408.910667) (xy 10.929192 -408.898963) (xy 10.854369 -408.87959)
			(xy 10.781889 -408.852747) (xy 10.712498 -408.818709) (xy 10.646905 -408.777825) (xy 10.585786 -408.730515)
			(xy 10.529767 -408.677264) (xy 10.479422 -408.61862) (xy 10.435268 -408.555182) (xy 10.397759 -408.487604)
			(xy 10.367279 -408.416577) (xy 10.344141 -408.342831) (xy 10.328583 -408.267123) (xy 10.320763 -408.190229)
			(xy 10.320274 -408.151584) (xy 10.320711 -408.11582) (xy 10.327438 -408.044607) (xy 10.340794 -407.974336)
			(xy 10.360663 -407.905622) (xy 10.37336 -407.872184) (xy 10.377932 -407.8605) (xy 10.375138 -407.835608)
			(xy 10.320782 -407.755598) (xy 10.313206 -407.745664) (xy 10.291098 -407.734092) (xy 10.278618 -407.7335)
			(xy 8.771128 -407.7335) (xy 8.761103 -407.733915) (xy 8.742576 -407.74158) (xy 8.728395 -407.755753)
			(xy 8.72072 -407.774275) (xy 8.720328 -407.7843) (xy 8.720328 -408.60218) (xy 8.720958 -408.613598)
			(xy 8.730856 -408.634178) (xy 8.739378 -408.641804) (xy 8.81126 -408.6987) (xy 8.833612 -408.70378)
			(xy 8.845042 -408.700986) (xy 8.866574 -408.696242) (xy 8.910372 -408.691146) (xy 8.932418 -408.690826)
			(xy 8.959671 -408.691289) (xy 9.013621 -408.699046) (xy 9.065919 -408.714402) (xy 9.115499 -408.737044)
			(xy 9.161352 -408.766511) (xy 9.202544 -408.802205) (xy 9.238237 -408.843397) (xy 9.267705 -408.88925)
			(xy 9.290348 -408.938829) (xy 9.305704 -408.991127) (xy 9.313461 -409.045077) (xy 9.313461 -409.099583)
			(xy 9.305704 -409.153533) (xy 9.290348 -409.205831) (xy 9.267705 -409.25541) (xy 9.238237 -409.301263)
			(xy 9.202544 -409.342455) (xy 9.161352 -409.378149) (xy 9.115499 -409.407616) (xy 9.065919 -409.430258)
			(xy 9.013621 -409.445614) (xy 8.959671 -409.453371) (xy 8.932418 -409.453842) (xy 8.910371 -409.453532)
			(xy 8.866571 -409.448443) (xy 8.845042 -409.443682) (xy 8.833612 -409.440888) (xy 8.81126 -409.445968)
			(xy 8.739378 -409.502864) (xy 8.730855 -409.510491) (xy 8.720944 -409.531069) (xy 8.720328 -409.542488)
			(xy 8.720328 -411.453584) (xy 9.703818 -411.453584) (xy 9.707862 -411.37513) (xy 9.719951 -411.297508)
			(xy 9.739958 -411.22154) (xy 9.767669 -411.148032) (xy 9.802792 -411.077763) (xy 9.844954 -411.011478)
			(xy 9.893708 -410.949879) (xy 9.948537 -410.893619) (xy 10.00886 -410.843295) (xy 10.074038 -410.799441)
			(xy 10.143379 -410.76252) (xy 10.21615 -410.732925) (xy 10.291577 -410.71097) (xy 10.368862 -410.696886)
			(xy 10.447186 -410.690823) (xy 10.525718 -410.692846) (xy 10.603626 -410.702932) (xy 10.680083 -410.720976)
			(xy 10.754281 -410.746786) (xy 10.825431 -410.780088) (xy 10.89278 -410.820529) (xy 10.955614 -410.86768)
			(xy 11.013266 -410.921043) (xy 11.065126 -410.98005) (xy 11.110645 -411.044077) (xy 11.149338 -411.112445)
			(xy 11.180797 -411.184429) (xy 11.204688 -411.259266) (xy 11.220757 -411.336163) (xy 11.228834 -411.414305)
			(xy 11.22934 -411.453584) (xy 11.228834 -411.492863) (xy 11.220757 -411.571005) (xy 11.204688 -411.647902)
			(xy 11.180797 -411.722739) (xy 11.149338 -411.794723) (xy 11.110645 -411.863091) (xy 11.065126 -411.927118)
			(xy 11.013266 -411.986125) (xy 10.955614 -412.039488) (xy 10.89278 -412.086639) (xy 10.825431 -412.12708)
			(xy 10.754281 -412.160382) (xy 10.680083 -412.186192) (xy 10.603626 -412.204236) (xy 10.525718 -412.214322)
			(xy 10.447186 -412.216345) (xy 10.368862 -412.210282) (xy 10.291577 -412.196198) (xy 10.21615 -412.174243)
			(xy 10.143379 -412.144648) (xy 10.074038 -412.107727) (xy 10.00886 -412.063873) (xy 9.948537 -412.013549)
			(xy 9.893708 -411.957289) (xy 9.844954 -411.89569) (xy 9.802792 -411.829405) (xy 9.767669 -411.759136)
			(xy 9.739958 -411.685628) (xy 9.719951 -411.60966) (xy 9.707862 -411.532038) (xy 9.703818 -411.453584)
			(xy 8.720328 -411.453584) (xy 8.720328 -411.825694) (xy 8.720844 -411.837432) (xy 8.731158 -411.85851)
			(xy 8.74014 -411.86608) (xy 8.8138 -411.922468) (xy 8.837168 -411.92704) (xy 8.848598 -411.923738)
			(xy 8.873205 -411.917464) (xy 8.923537 -411.910708) (xy 8.948928 -411.910276) (xy 8.949182 -411.910276)
			(xy 8.976433 -411.910762) (xy 9.03038 -411.918519) (xy 9.082674 -411.933874) (xy 9.13225 -411.956515)
			(xy 9.1781 -411.985981) (xy 9.219289 -412.021672) (xy 9.25498 -412.062862) (xy 9.284446 -412.108712)
			(xy 9.307087 -412.158288) (xy 9.322442 -412.210582) (xy 9.330198 -412.264529) (xy 9.330198 -412.319031)
			(xy 9.322442 -412.372978) (xy 9.307087 -412.425272) (xy 9.284446 -412.474848) (xy 9.25498 -412.520698)
			(xy 9.219289 -412.561888) (xy 9.1781 -412.597579) (xy 9.13225 -412.627045) (xy 9.082674 -412.649686)
			(xy 9.03038 -412.665041) (xy 8.976433 -412.672798) (xy 8.949182 -412.673292) (xy 8.948928 -412.673292)
			(xy 8.923534 -412.672895) (xy 8.873198 -412.666142) (xy 8.848598 -412.65983) (xy 8.837168 -412.656528)
			(xy 8.8138 -412.6611) (xy 8.74014 -412.717488) (xy 8.731237 -412.725122) (xy 8.720927 -412.74616)
			(xy 8.720328 -412.757874) (xy 8.720328 -414.127442) (xy 8.720856 -414.137337) (xy 8.72845 -414.155618)
			(xy 8.73506 -414.163002) (xy 8.807958 -414.2359) (xy 8.815312 -414.242555) (xy 8.833613 -414.25015)
			(xy 8.843518 -414.250632) (xy 9.663176 -414.250632) (xy 9.673077 -414.250118) (xy 9.691381 -414.242547)
			(xy 9.698736 -414.2359) (xy 9.753092 -414.181544) (xy 9.778635 -414.156719) (xy 9.834336 -414.112317)
			(xy 9.894654 -414.074426) (xy 9.958833 -414.043521) (xy 10.026067 -414.019991) (xy 10.095511 -414.004131)
			(xy 10.166294 -413.99614) (xy 10.20191 -413.995616) (xy 10.202418 -413.995616) (xy 10.238065 -413.996117)
			(xy 10.308911 -414.004101) (xy 10.378417 -414.019966) (xy 10.44571 -414.043514) (xy 10.509943 -414.074448)
			(xy 10.57031 -414.112379) (xy 10.62605 -414.156829) (xy 10.676463 -414.207241) (xy 10.720915 -414.262981)
			(xy 10.758846 -414.323346) (xy 10.789781 -414.387579) (xy 10.81333 -414.454872) (xy 10.829197 -414.524378)
			(xy 10.837183 -414.595223) (xy 10.837672 -414.63087) (xy 10.837672 -414.631378) (xy 10.837159 -414.666993)
			(xy 10.829159 -414.737774) (xy 10.817787 -414.787545) (xy 15.908776 -414.787545) (xy 15.908776 -414.723623)
			(xy 15.916787 -414.660205) (xy 15.932684 -414.598291) (xy 15.956216 -414.538858) (xy 15.98701 -414.482843)
			(xy 16.024583 -414.431128) (xy 16.06834 -414.384531) (xy 16.117593 -414.343786) (xy 16.171564 -414.309535)
			(xy 16.229403 -414.282318) (xy 16.290196 -414.262565) (xy 16.352986 -414.250587) (xy 16.416782 -414.246574)
			(xy 16.480578 -414.250587) (xy 16.543368 -414.262565) (xy 16.604161 -414.282318) (xy 16.662 -414.309535)
			(xy 16.715971 -414.343786) (xy 16.765224 -414.384531) (xy 16.808981 -414.431128) (xy 16.846554 -414.482843)
			(xy 16.877348 -414.538858) (xy 16.90088 -414.598291) (xy 16.916777 -414.660205) (xy 16.924788 -414.723623)
			(xy 16.92529 -414.755584) (xy 16.924788 -414.787545) (xy 16.916777 -414.850963) (xy 16.90088 -414.912877)
			(xy 16.877348 -414.97231) (xy 16.846554 -415.028325) (xy 16.808981 -415.08004) (xy 16.765224 -415.126637)
			(xy 16.715971 -415.167382) (xy 16.662 -415.201633) (xy 16.604161 -415.22885) (xy 16.543368 -415.248603)
			(xy 16.480578 -415.260581) (xy 16.416782 -415.264595) (xy 16.352986 -415.260581) (xy 16.290196 -415.248603)
			(xy 16.229403 -415.22885) (xy 16.171564 -415.201633) (xy 16.117593 -415.167382) (xy 16.06834 -415.126637)
			(xy 16.024583 -415.08004) (xy 15.98701 -415.028325) (xy 15.956216 -414.97231) (xy 15.932684 -414.912877)
			(xy 15.916787 -414.850963) (xy 15.908776 -414.787545) (xy 10.817787 -414.787545) (xy 10.813293 -414.807216)
			(xy 10.789758 -414.874447) (xy 10.75885 -414.938623) (xy 10.720957 -414.998939) (xy 10.676554 -415.054638)
			(xy 10.651744 -415.080196) (xy 10.563606 -415.168334) (xy 10.556465 -415.176275) (xy 10.548819 -415.196189)
			(xy 10.549894 -415.217492) (xy 10.554208 -415.227262) (xy 10.60577 -415.3281) (xy 10.635234 -415.343086)
			(xy 10.65149 -415.340292) (xy 10.686244 -415.335083) (xy 10.756303 -415.329492) (xy 10.791444 -415.329116)
			(xy 10.792714 -415.329116) (xy 10.834639 -415.3296) (xy 10.918117 -415.337491) (xy 11.000482 -415.353203)
			(xy 11.081003 -415.376597) (xy 11.158964 -415.407465) (xy 11.233675 -415.445532) (xy 11.304472 -415.490462)
			(xy 11.370726 -415.541854) (xy 11.43185 -415.599254) (xy 11.487301 -415.662151) (xy 11.536587 -415.729987)
			(xy 11.575757 -415.79622) (xy 18.735051 -415.79622) (xy 18.739065 -415.732425) (xy 18.751043 -415.669635)
			(xy 18.770796 -415.608842) (xy 18.798012 -415.551004) (xy 18.832263 -415.497034) (xy 18.873007 -415.447781)
			(xy 18.919604 -415.404024) (xy 18.971317 -415.366451) (xy 19.027332 -415.335657) (xy 19.086765 -415.312125)
			(xy 19.148678 -415.296228) (xy 19.212095 -415.288216) (xy 19.244056 -415.287714) (xy 19.277385 -415.288212)
			(xy 19.343474 -415.296911) (xy 19.407861 -415.314165) (xy 19.469444 -415.33968) (xy 19.527167 -415.373018)
			(xy 19.580043 -415.413608) (xy 19.603974 -415.436812) (xy 19.611086 -415.444178) (xy 19.629628 -415.451798)
			(xy 19.72183 -415.451798) (xy 19.740372 -415.443924) (xy 19.747738 -415.436812) (xy 19.771658 -415.413583)
			(xy 19.824515 -415.372939) (xy 19.882231 -415.339552) (xy 19.943816 -415.313995) (xy 20.008213 -415.296708)
			(xy 20.074317 -415.287987) (xy 20.107656 -415.28746) (xy 20.139618 -415.287945) (xy 20.203039 -415.295956)
			(xy 20.264956 -415.311853) (xy 20.324392 -415.335385) (xy 20.380409 -415.366181) (xy 20.432126 -415.403755)
			(xy 20.478725 -415.447514) (xy 20.519473 -415.496769) (xy 20.553725 -415.550742) (xy 20.580943 -415.608583)
			(xy 20.600697 -415.669379) (xy 20.612676 -415.732171) (xy 20.61669 -415.79597) (xy 20.612676 -415.859769)
			(xy 20.600697 -415.922561) (xy 20.580943 -415.983357) (xy 20.553725 -416.041198) (xy 20.519473 -416.095171)
			(xy 20.478725 -416.144426) (xy 20.432126 -416.188185) (xy 20.380409 -416.225759) (xy 20.324392 -416.256555)
			(xy 20.264956 -416.280087) (xy 20.203039 -416.295984) (xy 20.139618 -416.303995) (xy 20.107656 -416.304476)
			(xy 20.074327 -416.303973) (xy 20.008238 -416.295276) (xy 19.943851 -416.278022) (xy 19.882268 -416.252509)
			(xy 19.824545 -416.219172) (xy 19.771669 -416.178582) (xy 19.747738 -416.155378) (xy 19.740626 -416.148012)
			(xy 19.722084 -416.140392) (xy 19.629882 -416.140392) (xy 19.61134 -416.148266) (xy 19.603974 -416.155378)
			(xy 19.580047 -416.178599) (xy 19.527192 -416.219245) (xy 19.469477 -416.252633) (xy 19.407894 -416.278191)
			(xy 19.343498 -416.29548) (xy 19.277394 -416.304202) (xy 19.244056 -416.30473) (xy 19.212095 -416.304224)
			(xy 19.148678 -416.296212) (xy 19.086765 -416.280315) (xy 19.027332 -416.256783) (xy 18.971317 -416.225989)
			(xy 18.919604 -416.188416) (xy 18.873007 -416.144659) (xy 18.832263 -416.095406) (xy 18.798012 -416.041436)
			(xy 18.770796 -415.983598) (xy 18.751043 -415.922805) (xy 18.739065 -415.860015) (xy 18.735051 -415.79622)
			(xy 11.575757 -415.79622) (xy 11.57927 -415.80216) (xy 11.614971 -415.87803) (xy 11.643374 -415.956923)
			(xy 11.664227 -416.038139) (xy 11.677344 -416.120957) (xy 11.682609 -416.204642) (xy 11.679975 -416.28845)
			(xy 11.669465 -416.371639) (xy 11.651174 -416.45347) (xy 11.625263 -416.533216) (xy 11.591962 -416.61017)
			(xy 11.551567 -416.683649) (xy 11.504436 -416.752999) (xy 11.450988 -416.817607) (xy 11.428343 -416.840252)
			(xy 12.657562 -416.840252) (xy 12.657562 -416.785748) (xy 12.665318 -416.7318) (xy 12.680673 -416.679505)
			(xy 12.703314 -416.629926) (xy 12.73278 -416.584075) (xy 12.768471 -416.542883) (xy 12.809661 -416.50719)
			(xy 12.855511 -416.477722) (xy 12.905088 -416.455079) (xy 12.957382 -416.439722) (xy 13.01133 -416.431963)
			(xy 13.038582 -416.431476) (xy 13.067882 -416.431956) (xy 13.125791 -416.440936) (xy 13.181648 -416.458656)
			(xy 13.234143 -416.484702) (xy 13.282043 -416.518461) (xy 13.324224 -416.559141) (xy 13.359695 -416.605787)
			(xy 13.387624 -416.657304) (xy 13.397992 -416.684714) (xy 13.403351 -416.698216) (xy 13.420423 -416.721705)
			(xy 13.443412 -416.739443) (xy 13.470463 -416.749998) (xy 13.49939 -416.752516) (xy 13.527858 -416.746796)
			(xy 13.553567 -416.733299) (xy 13.564362 -416.723576) (xy 13.585861 -416.703507) (xy 13.633853 -416.669519)
			(xy 13.686492 -416.643295) (xy 13.74253 -416.625457) (xy 13.800642 -416.616427) (xy 13.830046 -416.61588)
			(xy 13.857299 -416.616347) (xy 13.91125 -416.624104) (xy 13.963548 -416.639459) (xy 14.013128 -416.662101)
			(xy 14.058982 -416.691569) (xy 14.100175 -416.727262) (xy 14.135869 -416.768455) (xy 14.165337 -416.814308)
			(xy 14.187979 -416.863888) (xy 14.202269 -416.912552) (xy 14.511274 -416.912552) (xy 14.51176 -416.885301)
			(xy 14.519516 -416.831353) (xy 14.534871 -416.779058) (xy 14.557513 -416.729481) (xy 14.586979 -416.683631)
			(xy 14.62267 -416.64244) (xy 14.663861 -416.606749) (xy 14.709711 -416.577283) (xy 14.759288 -416.554641)
			(xy 14.811583 -416.539286) (xy 14.865531 -416.53153) (xy 14.920033 -416.53153) (xy 14.973981 -416.539286)
			(xy 15.026276 -416.554641) (xy 15.075853 -416.577283) (xy 15.121703 -416.606749) (xy 15.162894 -416.64244)
			(xy 15.198585 -416.683631) (xy 15.228051 -416.729481) (xy 15.250693 -416.779058) (xy 15.266048 -416.831353)
			(xy 15.273804 -416.885301) (xy 15.27429 -416.912552) (xy 15.27379 -416.939544) (xy 15.266192 -416.99299)
			(xy 15.25114 -417.044832) (xy 15.228935 -417.094038) (xy 15.20002 -417.139624) (xy 15.18285 -417.160456)
			(xy 15.174058 -417.171377) (xy 15.16232 -417.196828) (xy 15.157955 -417.224514) (xy 15.161293 -417.252342)
			(xy 15.172082 -417.278209) (xy 15.189506 -417.300163) (xy 15.212249 -417.316542) (xy 15.225268 -417.321746)
			(xy 15.252426 -417.332279) (xy 15.303468 -417.360337) (xy 15.349652 -417.395828) (xy 15.389907 -417.437925)
			(xy 15.423295 -417.485651) (xy 15.449042 -417.537897) (xy 15.46655 -417.593449) (xy 15.475412 -417.651017)
			(xy 15.475966 -417.68014) (xy 16.99844 -417.68014) (xy 17.002511 -417.624518) (xy 17.014637 -417.570081)
			(xy 17.03456 -417.51799) (xy 17.061856 -417.469355) (xy 17.095942 -417.425212) (xy 17.136091 -417.386503)
			(xy 17.181449 -417.354052) (xy 17.231049 -417.328551) (xy 17.283833 -417.310544) (xy 17.338676 -417.300414)
			(xy 17.39441 -417.298377) (xy 17.449847 -417.304477) (xy 17.503804 -417.318583) (xy 17.555133 -417.340395)
			(xy 17.602739 -417.369449) (xy 17.645607 -417.405124) (xy 17.682824 -417.446661) (xy 17.713597 -417.493174)
			(xy 17.737269 -417.543671) (xy 17.753337 -417.597078) (xy 17.761457 -417.652254) (xy 17.761966 -417.68014)
			(xy 18.26844 -417.68014) (xy 18.272511 -417.624518) (xy 18.284637 -417.570081) (xy 18.30456 -417.51799)
			(xy 18.331856 -417.469355) (xy 18.365942 -417.425212) (xy 18.406091 -417.386503) (xy 18.451449 -417.354052)
			(xy 18.501049 -417.328551) (xy 18.553833 -417.310544) (xy 18.608676 -417.300414) (xy 18.66441 -417.298377)
			(xy 18.719847 -417.304477) (xy 18.773804 -417.318583) (xy 18.825133 -417.340395) (xy 18.872739 -417.369449)
			(xy 18.915607 -417.405124) (xy 18.952824 -417.446661) (xy 18.983597 -417.493174) (xy 19.007269 -417.543671)
			(xy 19.023337 -417.597078) (xy 19.031457 -417.652254) (xy 19.031966 -417.68014) (xy 19.031457 -417.708026)
			(xy 19.023337 -417.763202) (xy 19.007269 -417.816609) (xy 18.983597 -417.867106) (xy 18.952824 -417.913619)
			(xy 18.915607 -417.955156) (xy 18.872739 -417.990831) (xy 18.825133 -418.019885) (xy 18.773804 -418.041697)
			(xy 18.719847 -418.055803) (xy 18.66441 -418.061903) (xy 18.608676 -418.059866) (xy 18.553833 -418.049736)
			(xy 18.501049 -418.031729) (xy 18.451449 -418.006228) (xy 18.406091 -417.973777) (xy 18.365942 -417.935068)
			(xy 18.331856 -417.890925) (xy 18.30456 -417.84229) (xy 18.284637 -417.790199) (xy 18.272511 -417.735762)
			(xy 18.26844 -417.68014) (xy 17.761966 -417.68014) (xy 17.761457 -417.708026) (xy 17.753337 -417.763202)
			(xy 17.737269 -417.816609) (xy 17.713597 -417.867106) (xy 17.682824 -417.913619) (xy 17.645607 -417.955156)
			(xy 17.602739 -417.990831) (xy 17.555133 -418.019885) (xy 17.503804 -418.041697) (xy 17.449847 -418.055803)
			(xy 17.39441 -418.061903) (xy 17.338676 -418.059866) (xy 17.283833 -418.049736) (xy 17.231049 -418.031729)
			(xy 17.181449 -418.006228) (xy 17.136091 -417.973777) (xy 17.095942 -417.935068) (xy 17.061856 -417.890925)
			(xy 17.03456 -417.84229) (xy 17.014637 -417.790199) (xy 17.002511 -417.735762) (xy 16.99844 -417.68014)
			(xy 15.475966 -417.68014) (xy 15.47548 -417.707391) (xy 15.467724 -417.761339) (xy 15.452369 -417.813634)
			(xy 15.429727 -417.863211) (xy 15.400261 -417.909061) (xy 15.36457 -417.950252) (xy 15.323379 -417.985943)
			(xy 15.277529 -418.015409) (xy 15.227952 -418.038051) (xy 15.175657 -418.053406) (xy 15.121709 -418.061162)
			(xy 15.067207 -418.061162) (xy 15.013259 -418.053406) (xy 14.960964 -418.038051) (xy 14.911387 -418.015409)
			(xy 14.865537 -417.985943) (xy 14.824346 -417.950252) (xy 14.788655 -417.909061) (xy 14.759189 -417.863211)
			(xy 14.736547 -417.813634) (xy 14.721192 -417.761339) (xy 14.713436 -417.707391) (xy 14.71295 -417.68014)
			(xy 14.713436 -417.653148) (xy 14.721036 -417.599701) (xy 14.73609 -417.547857) (xy 14.758299 -417.498652)
			(xy 14.787218 -417.453067) (xy 14.80439 -417.432236) (xy 14.813216 -417.421338) (xy 14.824964 -417.395881)
			(xy 14.829332 -417.368186) (xy 14.825991 -417.340349) (xy 14.815194 -417.314474) (xy 14.797757 -417.292519)
			(xy 14.774999 -417.276144) (xy 14.761972 -417.270946) (xy 14.73482 -417.260398) (xy 14.683777 -417.232344)
			(xy 14.63759 -417.196857) (xy 14.597335 -417.154762) (xy 14.563945 -417.107038) (xy 14.538197 -417.054793)
			(xy 14.520689 -416.999242) (xy 14.511828 -416.941674) (xy 14.511274 -416.912552) (xy 14.202269 -416.912552)
			(xy 14.203336 -416.916186) (xy 14.211093 -416.970137) (xy 14.211093 -417.024643) (xy 14.203336 -417.078594)
			(xy 14.187979 -417.130892) (xy 14.165337 -417.180472) (xy 14.135869 -417.226325) (xy 14.100175 -417.267518)
			(xy 14.058982 -417.303211) (xy 14.013128 -417.332679) (xy 13.963548 -417.355321) (xy 13.91125 -417.370676)
			(xy 13.857299 -417.378433) (xy 13.830046 -417.378896) (xy 13.800749 -417.378344) (xy 13.742846 -417.36937)
			(xy 13.686993 -417.351658) (xy 13.634501 -417.325622) (xy 13.586601 -417.291873) (xy 13.544419 -417.251204)
			(xy 13.508944 -417.204569) (xy 13.481008 -417.153063) (xy 13.470636 -417.125658) (xy 13.465243 -417.112172)
			(xy 13.448174 -417.088691) (xy 13.425191 -417.070958) (xy 13.398148 -417.060404) (xy 13.369229 -417.057882)
			(xy 13.340768 -417.063594) (xy 13.315061 -417.07708) (xy 13.304266 -417.086796) (xy 13.282794 -417.106894)
			(xy 13.234795 -417.14088) (xy 13.182149 -417.167099) (xy 13.126105 -417.18493) (xy 13.067988 -417.19395)
			(xy 13.038582 -417.194492) (xy 13.01133 -417.194037) (xy 12.957382 -417.186278) (xy 12.905088 -417.170921)
			(xy 12.855511 -417.148278) (xy 12.809661 -417.11881) (xy 12.768471 -417.083117) (xy 12.73278 -417.041925)
			(xy 12.703314 -416.996074) (xy 12.680673 -416.946495) (xy 12.665318 -416.8942) (xy 12.657562 -416.840252)
			(xy 11.428343 -416.840252) (xy 11.391697 -416.876898) (xy 11.327089 -416.930346) (xy 11.257739 -416.977477)
			(xy 11.18426 -417.017872) (xy 11.107306 -417.051173) (xy 11.02756 -417.077084) (xy 10.945729 -417.095375)
			(xy 10.86254 -417.105885) (xy 10.778732 -417.108519) (xy 10.695047 -417.103254) (xy 10.612229 -417.090137)
			(xy 10.531013 -417.069284) (xy 10.45212 -417.040881) (xy 10.37625 -417.00518) (xy 10.304077 -416.962497)
			(xy 10.236241 -416.913211) (xy 10.173344 -416.85776) (xy 10.115944 -416.796636) (xy 10.064552 -416.730382)
			(xy 10.019622 -416.659585) (xy 9.981555 -416.584874) (xy 9.950687 -416.506913) (xy 9.927293 -416.426392)
			(xy 9.911581 -416.344027) (xy 9.90369 -416.260549) (xy 9.903206 -416.218624) (xy 9.903666 -416.177506)
			(xy 9.911256 -416.09562) (xy 9.926374 -416.014785) (xy 9.94889 -415.935691) (xy 9.978613 -415.859013)
			(xy 10.015288 -415.785408) (xy 10.058601 -415.715502) (xy 10.083038 -415.68243) (xy 10.092182 -415.670238)
			(xy 10.094214 -415.64052) (xy 10.03554 -415.532824) (xy 10.009378 -415.5186) (xy 9.994392 -415.51987)
			(xy 9.947148 -415.521648) (xy 8.559546 -415.521648) (xy 8.523886 -415.521163) (xy 8.453014 -415.51317)
			(xy 8.383484 -415.497291) (xy 8.316169 -415.473725) (xy 8.251917 -415.442769) (xy 8.191536 -415.404813)
			(xy 8.135784 -415.360333) (xy 8.11022 -415.335466) (xy 7.856474 -415.081466) (xy 7.849031 -415.074773)
			(xy 7.830535 -415.067179) (xy 7.81054 -415.067204) (xy 7.801102 -415.070544) (xy 7.786624 -415.07664)
			(xy 7.76986 -415.101786) (xy 7.76986 -419.155118) (xy 12.663424 -419.155118) (xy 12.663895 -419.127748)
			(xy 12.671711 -419.073569) (xy 12.687198 -419.021065) (xy 12.710039 -418.971319) (xy 12.739763 -418.925352)
			(xy 12.757404 -418.90442) (xy 12.7635 -418.897308) (xy 12.76985 -418.88029) (xy 12.76985 -418.794946)
			(xy 12.7635 -418.777928) (xy 12.757404 -418.770816) (xy 12.73976 -418.749888) (xy 12.710048 -418.703914)
			(xy 12.687213 -418.654166) (xy 12.671724 -418.601664) (xy 12.663897 -418.547487) (xy 12.663424 -418.520118)
			(xy 12.66391 -418.492867) (xy 12.671666 -418.438919) (xy 12.687021 -418.386624) (xy 12.709663 -418.337047)
			(xy 12.739129 -418.291197) (xy 12.77482 -418.250006) (xy 12.816011 -418.214315) (xy 12.861861 -418.184849)
			(xy 12.911438 -418.162207) (xy 12.963733 -418.146852) (xy 13.017681 -418.139096) (xy 13.072183 -418.139096)
			(xy 13.126131 -418.146852) (xy 13.178426 -418.162207) (xy 13.228003 -418.184849) (xy 13.273853 -418.214315)
			(xy 13.302859 -418.239448) (xy 29.171644 -418.239448) (xy 29.175715 -418.183826) (xy 29.187841 -418.129389)
			(xy 29.207764 -418.077298) (xy 29.23506 -418.028663) (xy 29.269146 -417.98452) (xy 29.309295 -417.945811)
			(xy 29.354653 -417.91336) (xy 29.404253 -417.887859) (xy 29.457037 -417.869852) (xy 29.51188 -417.859722)
			(xy 29.567614 -417.857685) (xy 29.623051 -417.863785) (xy 29.677008 -417.877891) (xy 29.728337 -417.899703)
			(xy 29.775943 -417.928757) (xy 29.818811 -417.964432) (xy 29.856028 -418.005969) (xy 29.886801 -418.052482)
			(xy 29.910473 -418.102979) (xy 29.926541 -418.156386) (xy 29.934661 -418.211562) (xy 29.93517 -418.239448)
			(xy 30.187644 -418.239448) (xy 30.191715 -418.183826) (xy 30.203841 -418.129389) (xy 30.223764 -418.077298)
			(xy 30.25106 -418.028663) (xy 30.285146 -417.98452) (xy 30.325295 -417.945811) (xy 30.370653 -417.91336)
			(xy 30.420253 -417.887859) (xy 30.473037 -417.869852) (xy 30.52788 -417.859722) (xy 30.583614 -417.857685)
			(xy 30.639051 -417.863785) (xy 30.693008 -417.877891) (xy 30.744337 -417.899703) (xy 30.791943 -417.928757)
			(xy 30.834811 -417.964432) (xy 30.872028 -418.005969) (xy 30.902801 -418.052482) (xy 30.926473 -418.102979)
			(xy 30.942541 -418.156386) (xy 30.950661 -418.211562) (xy 30.95117 -418.239448) (xy 31.203644 -418.239448)
			(xy 31.207715 -418.183826) (xy 31.219841 -418.129389) (xy 31.239764 -418.077298) (xy 31.26706 -418.028663)
			(xy 31.301146 -417.98452) (xy 31.341295 -417.945811) (xy 31.386653 -417.91336) (xy 31.436253 -417.887859)
			(xy 31.489037 -417.869852) (xy 31.54388 -417.859722) (xy 31.599614 -417.857685) (xy 31.655051 -417.863785)
			(xy 31.709008 -417.877891) (xy 31.760337 -417.899703) (xy 31.807943 -417.928757) (xy 31.850811 -417.964432)
			(xy 31.888028 -418.005969) (xy 31.918801 -418.052482) (xy 31.942473 -418.102979) (xy 31.958541 -418.156386)
			(xy 31.966661 -418.211562) (xy 31.96717 -418.239448) (xy 32.219644 -418.239448) (xy 32.223715 -418.183826)
			(xy 32.235841 -418.129389) (xy 32.255764 -418.077298) (xy 32.28306 -418.028663) (xy 32.317146 -417.98452)
			(xy 32.357295 -417.945811) (xy 32.402653 -417.91336) (xy 32.452253 -417.887859) (xy 32.505037 -417.869852)
			(xy 32.55988 -417.859722) (xy 32.615614 -417.857685) (xy 32.671051 -417.863785) (xy 32.725008 -417.877891)
			(xy 32.776337 -417.899703) (xy 32.823943 -417.928757) (xy 32.866811 -417.964432) (xy 32.904028 -418.005969)
			(xy 32.934801 -418.052482) (xy 32.958473 -418.102979) (xy 32.974541 -418.156386) (xy 32.982661 -418.211562)
			(xy 32.98317 -418.239448) (xy 32.982661 -418.267334) (xy 32.974541 -418.32251) (xy 32.958473 -418.375917)
			(xy 32.934801 -418.426414) (xy 32.904028 -418.472927) (xy 32.866811 -418.514464) (xy 32.823943 -418.550139)
			(xy 32.776337 -418.579193) (xy 32.725008 -418.601005) (xy 32.671051 -418.615111) (xy 32.615614 -418.621211)
			(xy 32.55988 -418.619174) (xy 32.505037 -418.609044) (xy 32.452253 -418.591037) (xy 32.402653 -418.565536)
			(xy 32.357295 -418.533085) (xy 32.317146 -418.494376) (xy 32.28306 -418.450233) (xy 32.255764 -418.401598)
			(xy 32.235841 -418.349507) (xy 32.223715 -418.29507) (xy 32.219644 -418.239448) (xy 31.96717 -418.239448)
			(xy 31.966661 -418.267334) (xy 31.958541 -418.32251) (xy 31.942473 -418.375917) (xy 31.918801 -418.426414)
			(xy 31.888028 -418.472927) (xy 31.850811 -418.514464) (xy 31.807943 -418.550139) (xy 31.760337 -418.579193)
			(xy 31.709008 -418.601005) (xy 31.655051 -418.615111) (xy 31.599614 -418.621211) (xy 31.54388 -418.619174)
			(xy 31.489037 -418.609044) (xy 31.436253 -418.591037) (xy 31.386653 -418.565536) (xy 31.341295 -418.533085)
			(xy 31.301146 -418.494376) (xy 31.26706 -418.450233) (xy 31.239764 -418.401598) (xy 31.219841 -418.349507)
			(xy 31.207715 -418.29507) (xy 31.203644 -418.239448) (xy 30.95117 -418.239448) (xy 30.950661 -418.267334)
			(xy 30.942541 -418.32251) (xy 30.926473 -418.375917) (xy 30.902801 -418.426414) (xy 30.872028 -418.472927)
			(xy 30.834811 -418.514464) (xy 30.791943 -418.550139) (xy 30.744337 -418.579193) (xy 30.693008 -418.601005)
			(xy 30.639051 -418.615111) (xy 30.583614 -418.621211) (xy 30.52788 -418.619174) (xy 30.473037 -418.609044)
			(xy 30.420253 -418.591037) (xy 30.370653 -418.565536) (xy 30.325295 -418.533085) (xy 30.285146 -418.494376)
			(xy 30.25106 -418.450233) (xy 30.223764 -418.401598) (xy 30.203841 -418.349507) (xy 30.191715 -418.29507)
			(xy 30.187644 -418.239448) (xy 29.93517 -418.239448) (xy 29.934661 -418.267334) (xy 29.926541 -418.32251)
			(xy 29.910473 -418.375917) (xy 29.886801 -418.426414) (xy 29.856028 -418.472927) (xy 29.818811 -418.514464)
			(xy 29.775943 -418.550139) (xy 29.728337 -418.579193) (xy 29.677008 -418.601005) (xy 29.623051 -418.615111)
			(xy 29.567614 -418.621211) (xy 29.51188 -418.619174) (xy 29.457037 -418.609044) (xy 29.404253 -418.591037)
			(xy 29.354653 -418.565536) (xy 29.309295 -418.533085) (xy 29.269146 -418.494376) (xy 29.23506 -418.450233)
			(xy 29.207764 -418.401598) (xy 29.187841 -418.349507) (xy 29.175715 -418.29507) (xy 29.171644 -418.239448)
			(xy 13.302859 -418.239448) (xy 13.315044 -418.250006) (xy 13.350735 -418.291197) (xy 13.380201 -418.337047)
			(xy 13.402843 -418.386624) (xy 13.418198 -418.438919) (xy 13.425954 -418.492867) (xy 13.42644 -418.520118)
			(xy 13.425999 -418.547489) (xy 13.418177 -418.60167) (xy 13.402683 -418.654174) (xy 13.379836 -418.703921)
			(xy 13.350105 -418.749886) (xy 13.33246 -418.770816) (xy 13.326364 -418.777928) (xy 13.320014 -418.794946)
			(xy 13.320014 -418.88029) (xy 13.326364 -418.897308) (xy 13.33246 -418.90442) (xy 13.350069 -418.925377)
			(xy 13.356034 -418.934603) (xy 44.619158 -418.934603) (xy 44.619158 -418.870681) (xy 44.627169 -418.807263)
			(xy 44.643066 -418.745349) (xy 44.666598 -418.685916) (xy 44.697392 -418.629901) (xy 44.734965 -418.578186)
			(xy 44.778722 -418.531589) (xy 44.827975 -418.490844) (xy 44.881946 -418.456593) (xy 44.939785 -418.429376)
			(xy 45.000578 -418.409623) (xy 45.063368 -418.397645) (xy 45.127164 -418.393632) (xy 45.19096 -418.397645)
			(xy 45.25375 -418.409623) (xy 45.314543 -418.429376) (xy 45.372382 -418.456593) (xy 45.426353 -418.490844)
			(xy 45.475606 -418.531589) (xy 45.519363 -418.578186) (xy 45.556936 -418.629901) (xy 45.58773 -418.685916)
			(xy 45.611262 -418.745349) (xy 45.627159 -418.807263) (xy 45.63517 -418.870681) (xy 45.635672 -418.902642)
			(xy 45.63517 -418.934603) (xy 45.627159 -418.998021) (xy 45.611262 -419.059935) (xy 45.58773 -419.119368)
			(xy 45.556936 -419.175383) (xy 45.519363 -419.227098) (xy 45.475606 -419.273695) (xy 45.426353 -419.31444)
			(xy 45.372382 -419.348691) (xy 45.314543 -419.375908) (xy 45.25375 -419.395661) (xy 45.19096 -419.407639)
			(xy 45.127164 -419.411653) (xy 45.063368 -419.407639) (xy 45.000578 -419.395661) (xy 44.939785 -419.375908)
			(xy 44.881946 -419.348691) (xy 44.827975 -419.31444) (xy 44.778722 -419.273695) (xy 44.734965 -419.227098)
			(xy 44.697392 -419.175383) (xy 44.666598 -419.119368) (xy 44.643066 -419.059935) (xy 44.627169 -418.998021)
			(xy 44.619158 -418.934603) (xy 13.356034 -418.934603) (xy 13.379787 -418.971342) (xy 13.402629 -419.021083)
			(xy 13.418127 -419.073579) (xy 13.425962 -419.12775) (xy 13.42644 -419.155118) (xy 13.425954 -419.182369)
			(xy 13.418198 -419.236317) (xy 13.402843 -419.288612) (xy 13.380201 -419.338189) (xy 13.350735 -419.384039)
			(xy 13.315044 -419.42523) (xy 13.273853 -419.460921) (xy 13.228003 -419.490387) (xy 13.178426 -419.513029)
			(xy 13.126131 -419.528384) (xy 13.072183 -419.53614) (xy 13.017681 -419.53614) (xy 12.963733 -419.528384)
			(xy 12.911438 -419.513029) (xy 12.861861 -419.490387) (xy 12.816011 -419.460921) (xy 12.77482 -419.42523)
			(xy 12.739129 -419.384039) (xy 12.709663 -419.338189) (xy 12.687021 -419.288612) (xy 12.671666 -419.236317)
			(xy 12.66391 -419.182369) (xy 12.663424 -419.155118) (xy 7.76986 -419.155118) (xy 7.76986 -421.428254)
			(xy 9.379141 -421.428254) (xy 9.379141 -421.373746) (xy 9.386898 -421.319793) (xy 9.402255 -421.267492)
			(xy 9.424899 -421.21791) (xy 9.454368 -421.172055) (xy 9.490064 -421.130861) (xy 9.531258 -421.095166)
			(xy 9.577114 -421.065697) (xy 9.626696 -421.043054) (xy 9.678997 -421.027697) (xy 9.73295 -421.019941)
			(xy 9.760204 -421.019478) (xy 9.782186 -421.019813) (xy 9.825856 -421.024906) (xy 9.847326 -421.029638)
			(xy 9.855807 -421.031235) (xy 9.872943 -421.029277) (xy 9.880854 -421.025828) (xy 9.908032 -421.012874)
			(xy 9.915827 -421.008725) (xy 9.928167 -420.996111) (xy 9.932162 -420.988236) (xy 9.946226 -420.958772)
			(xy 9.980745 -420.903355) (xy 10.000996 -420.877746) (xy 10.006283 -420.870741) (xy 10.012262 -420.854254)
			(xy 10.01268 -420.845488) (xy 10.01268 -420.691564) (xy 10.01232 -420.682787) (xy 10.006332 -420.666285)
			(xy 10.000996 -420.659306) (xy 9.98071 -420.633721) (xy 9.946184 -420.578303) (xy 9.932162 -420.548816)
			(xy 9.928153 -420.540952) (xy 9.915809 -420.528353) (xy 9.908032 -420.524178) (xy 9.880854 -420.511224)
			(xy 9.872945 -420.507764) (xy 9.855807 -420.505807) (xy 9.847326 -420.507414) (xy 9.825857 -420.51215)
			(xy 9.782187 -420.517248) (xy 9.760204 -420.517574) (xy 9.732951 -420.517119) (xy 9.678999 -420.509362)
			(xy 9.6267 -420.494006) (xy 9.577119 -420.471364) (xy 9.531265 -420.441896) (xy 9.490071 -420.406202)
			(xy 9.454377 -420.365009) (xy 9.424908 -420.319155) (xy 9.402265 -420.269574) (xy 9.386909 -420.217275)
			(xy 9.379151 -420.163323) (xy 9.379151 -420.108817) (xy 9.386909 -420.054865) (xy 9.402265 -420.002566)
			(xy 9.424908 -419.952985) (xy 9.454377 -419.907131) (xy 9.490071 -419.865938) (xy 9.531265 -419.830244)
			(xy 9.577119 -419.800776) (xy 9.6267 -419.778134) (xy 9.678999 -419.762778) (xy 9.732951 -419.755021)
			(xy 9.760204 -419.754558) (xy 9.787028 -419.755047) (xy 9.840146 -419.762558) (xy 9.891691 -419.77743)
			(xy 9.940646 -419.799371) (xy 9.986048 -419.827949) (xy 10.027002 -419.862601) (xy 10.045192 -419.88232)
			(xy 10.051164 -419.888519) (xy 10.066228 -419.896825) (xy 10.074656 -419.898576) (xy 10.104374 -419.903656)
			(xy 10.11311 -419.904675) (xy 10.130383 -419.901422) (xy 10.138156 -419.897306) (xy 10.167422 -419.880897)
			(xy 10.229346 -419.855064) (xy 10.294126 -419.837584) (xy 10.36064 -419.82876) (xy 10.394188 -419.828218)
			(xy 10.424919 -419.828688) (xy 10.485932 -419.836096) (xy 10.545608 -419.850805) (xy 10.603076 -419.872599)
			(xy 10.62547 -419.884352) (xy 13.244574 -419.884352) (xy 13.248645 -419.82873) (xy 13.260771 -419.774293)
			(xy 13.280694 -419.722202) (xy 13.30799 -419.673567) (xy 13.342076 -419.629424) (xy 13.382225 -419.590715)
			(xy 13.427583 -419.558264) (xy 13.477183 -419.532763) (xy 13.529967 -419.514756) (xy 13.58481 -419.504626)
			(xy 13.640544 -419.502589) (xy 13.695981 -419.508689) (xy 13.749938 -419.522795) (xy 13.801267 -419.544607)
			(xy 13.848873 -419.573661) (xy 13.891741 -419.609336) (xy 13.928958 -419.650873) (xy 13.959731 -419.697386)
			(xy 13.983403 -419.747883) (xy 13.999471 -419.80129) (xy 14.007591 -419.856466) (xy 14.0081 -419.884352)
			(xy 14.007591 -419.912238) (xy 13.999471 -419.967414) (xy 13.983403 -420.020821) (xy 13.959731 -420.071318)
			(xy 13.928958 -420.117831) (xy 13.891741 -420.159368) (xy 13.848873 -420.195043) (xy 13.801267 -420.224097)
			(xy 13.749938 -420.245909) (xy 13.695981 -420.260015) (xy 13.640544 -420.266115) (xy 13.58481 -420.264078)
			(xy 13.529967 -420.253948) (xy 13.477183 -420.235941) (xy 13.427583 -420.21044) (xy 13.382225 -420.177989)
			(xy 13.342076 -420.13928) (xy 13.30799 -420.095137) (xy 13.280694 -420.046502) (xy 13.260771 -419.994411)
			(xy 13.248645 -419.939974) (xy 13.244574 -419.884352) (xy 10.62547 -419.884352) (xy 10.657497 -419.901161)
			(xy 10.708079 -419.936075) (xy 10.754084 -419.976831) (xy 10.794841 -420.022836) (xy 10.829756 -420.073417)
			(xy 10.858319 -420.127839) (xy 10.880114 -420.185306) (xy 10.894823 -420.244982) (xy 10.902232 -420.305995)
			(xy 10.902696 -420.336726) (xy 10.90213 -420.371682) (xy 10.892565 -420.440936) (xy 10.873604 -420.508227)
			(xy 10.845605 -420.572287) (xy 10.809097 -420.631909) (xy 10.78738 -420.659306) (xy 10.782081 -420.666303)
			(xy 10.776107 -420.682796) (xy 10.775696 -420.691564) (xy 10.775696 -420.845488) (xy 10.776063 -420.854265)
			(xy 10.782045 -420.870767) (xy 10.78738 -420.877746) (xy 10.809065 -420.905166) (xy 10.845568 -420.964786)
			(xy 10.873566 -421.028841) (xy 10.892533 -421.096125) (xy 10.902112 -421.165373) (xy 10.902696 -421.200326)
			(xy 10.902268 -421.231058) (xy 10.894857 -421.292074) (xy 10.880145 -421.351751) (xy 10.858347 -421.40922)
			(xy 10.82978 -421.463642) (xy 10.80618 -421.497831) (xy 20.78734 -421.497831) (xy 20.78734 -421.443329)
			(xy 20.795096 -421.389381) (xy 20.810451 -421.337087) (xy 20.833092 -421.28751) (xy 20.862558 -421.24166)
			(xy 20.89825 -421.20047) (xy 20.93944 -421.164778) (xy 20.98529 -421.135312) (xy 21.034867 -421.112671)
			(xy 21.087161 -421.097316) (xy 21.141109 -421.08956) (xy 21.16836 -421.089074) (xy 21.190342 -421.089417)
			(xy 21.234012 -421.094504) (xy 21.255482 -421.099234) (xy 21.263965 -421.10081) (xy 21.281099 -421.098867)
			(xy 21.28901 -421.095424) (xy 21.316188 -421.08247) (xy 21.323976 -421.078309) (xy 21.33632 -421.065705)
			(xy 21.340318 -421.057832) (xy 21.354376 -421.028365) (xy 21.388899 -420.97295) (xy 21.409152 -420.947342)
			(xy 21.414436 -420.940334) (xy 21.420418 -420.92385) (xy 21.420836 -420.915084) (xy 21.420836 -420.76116)
			(xy 21.420439 -420.752386) (xy 21.414478 -420.735884) (xy 21.409152 -420.728902) (xy 21.388862 -420.70332)
			(xy 21.354339 -420.647899) (xy 21.340318 -420.618412) (xy 21.336292 -420.610559) (xy 21.32396 -420.597954)
			(xy 21.316188 -420.593774) (xy 21.28901 -420.58082) (xy 21.281109 -420.577339) (xy 21.263964 -420.575396)
			(xy 21.255482 -420.57701) (xy 21.234014 -420.581754) (xy 21.190343 -420.586847) (xy 21.16836 -420.58717)
			(xy 21.141109 -420.58668) (xy 21.087161 -420.578924) (xy 21.034867 -420.563569) (xy 20.98529 -420.540928)
			(xy 20.93944 -420.511462) (xy 20.89825 -420.47577) (xy 20.862558 -420.43458) (xy 20.833092 -420.38873)
			(xy 20.810451 -420.339153) (xy 20.795096 -420.286859) (xy 20.78734 -420.232911) (xy 20.78734 -420.178409)
			(xy 20.795096 -420.124461) (xy 20.810451 -420.072167) (xy 20.833092 -420.02259) (xy 20.862558 -419.97674)
			(xy 20.89825 -419.93555) (xy 20.93944 -419.899858) (xy 20.98529 -419.870392) (xy 21.034867 -419.847751)
			(xy 21.087161 -419.832396) (xy 21.141109 -419.82464) (xy 21.16836 -419.824154) (xy 21.195185 -419.824607)
			(xy 21.248305 -419.832125) (xy 21.29985 -419.847004) (xy 21.348806 -419.868952) (xy 21.394206 -419.897536)
			(xy 21.435159 -419.932194) (xy 21.453348 -419.951916) (xy 21.459335 -419.958099) (xy 21.474388 -419.966415)
			(xy 21.482812 -419.968172) (xy 21.51253 -419.973252) (xy 21.521267 -419.97425) (xy 21.538538 -419.971011)
			(xy 21.546312 -419.966902) (xy 21.575587 -419.95051) (xy 21.637508 -419.924672) (xy 21.702285 -419.907188)
			(xy 21.768797 -419.898359) (xy 21.802344 -419.897814) (xy 21.833077 -419.898214) (xy 21.894094 -419.905628)
			(xy 21.953772 -419.920343) (xy 22.011242 -419.942143) (xy 22.065665 -419.970712) (xy 22.116248 -420.005632)
			(xy 22.162253 -420.046394) (xy 22.203009 -420.092404) (xy 22.237923 -420.142992) (xy 22.266484 -420.197418)
			(xy 22.288277 -420.254891) (xy 22.302984 -420.314571) (xy 22.305853 -420.338207) (xy 22.578562 -420.338207)
			(xy 22.578562 -420.274285) (xy 22.586573 -420.210867) (xy 22.60247 -420.148953) (xy 22.626002 -420.08952)
			(xy 22.656796 -420.033505) (xy 22.694369 -419.98179) (xy 22.738126 -419.935193) (xy 22.787379 -419.894448)
			(xy 22.84135 -419.860197) (xy 22.899189 -419.83298) (xy 22.959982 -419.813227) (xy 23.022772 -419.801249)
			(xy 23.086568 -419.797236) (xy 23.150364 -419.801249) (xy 23.213154 -419.813227) (xy 23.273947 -419.83298)
			(xy 23.331786 -419.860197) (xy 23.385757 -419.894448) (xy 23.43501 -419.935193) (xy 23.478767 -419.98179)
			(xy 23.51634 -420.033505) (xy 23.537255 -420.07155) (xy 44.578778 -420.07155) (xy 44.57928 -420.039589)
			(xy 44.587291 -419.976171) (xy 44.603188 -419.914257) (xy 44.62672 -419.854824) (xy 44.657514 -419.798809)
			(xy 44.695087 -419.747094) (xy 44.738844 -419.700497) (xy 44.788097 -419.659752) (xy 44.842068 -419.625501)
			(xy 44.899907 -419.598284) (xy 44.9607 -419.578531) (xy 45.02349 -419.566553) (xy 45.087286 -419.56254)
			(xy 45.151082 -419.566553) (xy 45.213872 -419.578531) (xy 45.274665 -419.598284) (xy 45.332504 -419.625501)
			(xy 45.386475 -419.659752) (xy 45.435728 -419.700497) (xy 45.479485 -419.747094) (xy 45.517058 -419.798809)
			(xy 45.547852 -419.854824) (xy 45.571384 -419.914257) (xy 45.587281 -419.976171) (xy 45.595292 -420.039589)
			(xy 45.595794 -420.07155) (xy 45.595362 -420.102103) (xy 45.594513 -420.109142) (xy 46.207172 -420.109142)
			(xy 46.207657 -420.077018) (xy 46.215766 -420.013282) (xy 46.231836 -419.951075) (xy 46.25561 -419.891387)
			(xy 46.28671 -419.835167) (xy 46.324641 -419.78331) (xy 46.346364 -419.759638) (xy 46.352076 -419.753114)
			(xy 46.359085 -419.737265) (xy 46.36008 -419.72865) (xy 46.362366 -419.698932) (xy 46.362715 -419.690249)
			(xy 46.358154 -419.673491) (xy 46.353476 -419.666166) (xy 46.336253 -419.640569) (xy 46.307481 -419.585992)
			(xy 46.285525 -419.528335) (xy 46.270708 -419.468444) (xy 46.263248 -419.4072) (xy 46.262798 -419.376352)
			(xy 46.2633 -419.344391) (xy 46.271311 -419.280973) (xy 46.287208 -419.219059) (xy 46.31074 -419.159626)
			(xy 46.341534 -419.103611) (xy 46.379107 -419.051896) (xy 46.422864 -419.005299) (xy 46.472117 -418.964554)
			(xy 46.526088 -418.930303) (xy 46.583927 -418.903086) (xy 46.64472 -418.883333) (xy 46.70751 -418.871355)
			(xy 46.771306 -418.867342) (xy 46.835102 -418.871355) (xy 46.897892 -418.883333) (xy 46.958685 -418.903086)
			(xy 47.016524 -418.930303) (xy 47.070495 -418.964554) (xy 47.119748 -419.005299) (xy 47.163505 -419.051896)
			(xy 47.201078 -419.103611) (xy 47.231872 -419.159626) (xy 47.255404 -419.219059) (xy 47.271301 -419.280973)
			(xy 47.279312 -419.344391) (xy 47.279814 -419.376352) (xy 47.279329 -419.408476) (xy 47.27122 -419.472212)
			(xy 47.255151 -419.534419) (xy 47.231377 -419.594108) (xy 47.200277 -419.650328) (xy 47.162345 -419.702185)
			(xy 47.140622 -419.725856) (xy 47.13491 -419.732381) (xy 47.127902 -419.748229) (xy 47.126906 -419.756844)
			(xy 47.12462 -419.786562) (xy 47.124276 -419.795245) (xy 47.128834 -419.812002) (xy 47.13351 -419.819328)
			(xy 47.150728 -419.844927) (xy 47.179501 -419.899503) (xy 47.201458 -419.95716) (xy 47.216276 -420.017051)
			(xy 47.223738 -420.078294) (xy 47.224188 -420.109142) (xy 47.223636 -420.143701) (xy 47.214287 -420.212185)
			(xy 47.195754 -420.278772) (xy 47.168377 -420.342237) (xy 47.13266 -420.401413) (xy 47.111412 -420.428674)
			(xy 47.106192 -420.435869) (xy 47.100449 -420.45267) (xy 47.100782 -420.470423) (xy 47.10715 -420.486997)
			(xy 47.112682 -420.493952) (xy 47.132323 -420.517162) (xy 47.166526 -420.567435) (xy 47.194493 -420.621426)
			(xy 47.215824 -420.678366) (xy 47.230215 -420.737443) (xy 47.235958 -420.78529) (xy 47.93945 -420.78529)
			(xy 47.943521 -420.729668) (xy 47.955647 -420.675231) (xy 47.97557 -420.62314) (xy 48.002866 -420.574505)
			(xy 48.036952 -420.530362) (xy 48.077101 -420.491653) (xy 48.122459 -420.459202) (xy 48.172059 -420.433701)
			(xy 48.224843 -420.415694) (xy 48.279686 -420.405564) (xy 48.33542 -420.403527) (xy 48.390857 -420.409627)
			(xy 48.444814 -420.423733) (xy 48.496143 -420.445545) (xy 48.543749 -420.474599) (xy 48.586617 -420.510274)
			(xy 48.610227 -420.536624) (xy 50.633374 -420.536624) (xy 50.637445 -420.481002) (xy 50.649571 -420.426565)
			(xy 50.669494 -420.374474) (xy 50.69679 -420.325839) (xy 50.730876 -420.281696) (xy 50.771025 -420.242987)
			(xy 50.816383 -420.210536) (xy 50.865983 -420.185035) (xy 50.918767 -420.167028) (xy 50.97361 -420.156898)
			(xy 51.029344 -420.154861) (xy 51.084781 -420.160961) (xy 51.138738 -420.175067) (xy 51.190067 -420.196879)
			(xy 51.237673 -420.225933) (xy 51.280541 -420.261608) (xy 51.317758 -420.303145) (xy 51.348531 -420.349658)
			(xy 51.372203 -420.400155) (xy 51.388271 -420.453562) (xy 51.396391 -420.508738) (xy 51.3969 -420.536624)
			(xy 51.396391 -420.56451) (xy 51.388271 -420.619686) (xy 51.372203 -420.673093) (xy 51.348531 -420.72359)
			(xy 51.317758 -420.770103) (xy 51.280541 -420.81164) (xy 51.237673 -420.847315) (xy 51.190067 -420.876369)
			(xy 51.138738 -420.898181) (xy 51.084781 -420.912287) (xy 51.029344 -420.918387) (xy 50.97361 -420.91635)
			(xy 50.918767 -420.90622) (xy 50.865983 -420.888213) (xy 50.816383 -420.862712) (xy 50.771025 -420.830261)
			(xy 50.730876 -420.791552) (xy 50.69679 -420.747409) (xy 50.669494 -420.698774) (xy 50.649571 -420.646683)
			(xy 50.637445 -420.592246) (xy 50.633374 -420.536624) (xy 48.610227 -420.536624) (xy 48.623834 -420.551811)
			(xy 48.654607 -420.598324) (xy 48.678279 -420.648821) (xy 48.694347 -420.702228) (xy 48.702467 -420.757404)
			(xy 48.702976 -420.78529) (xy 48.702467 -420.813176) (xy 48.694347 -420.868352) (xy 48.678279 -420.921759)
			(xy 48.654607 -420.972256) (xy 48.623834 -421.018769) (xy 48.586617 -421.060306) (xy 48.543749 -421.095981)
			(xy 48.496143 -421.125035) (xy 48.444814 -421.146847) (xy 48.390857 -421.160953) (xy 48.33542 -421.167053)
			(xy 48.279686 -421.165016) (xy 48.224843 -421.154886) (xy 48.172059 -421.136879) (xy 48.122459 -421.111378)
			(xy 48.077101 -421.078927) (xy 48.036952 -421.040218) (xy 48.002866 -420.996075) (xy 47.97557 -420.94744)
			(xy 47.955647 -420.895349) (xy 47.943521 -420.840912) (xy 47.93945 -420.78529) (xy 47.235958 -420.78529)
			(xy 47.237461 -420.797814) (xy 47.237904 -420.828216) (xy 47.237399 -420.86223) (xy 47.228326 -420.92965)
			(xy 47.210344 -420.995258) (xy 47.183775 -421.057883) (xy 47.149092 -421.116405) (xy 47.12843 -421.14343)
			(xy 47.121863 -421.152801) (xy 47.116883 -421.175101) (xy 47.122037 -421.197362) (xy 47.128684 -421.206676)
			(xy 47.149819 -421.233873) (xy 47.18534 -421.292885) (xy 47.212575 -421.35615) (xy 47.231028 -421.42251)
			(xy 47.24036 -421.490753) (xy 47.240952 -421.525192) (xy 47.24045 -421.557153) (xy 47.232439 -421.620571)
			(xy 47.216542 -421.682485) (xy 47.19301 -421.741918) (xy 47.162216 -421.797933) (xy 47.124643 -421.849648)
			(xy 47.080886 -421.896245) (xy 47.031633 -421.93699) (xy 46.977662 -421.971241) (xy 46.919823 -421.998458)
			(xy 46.85903 -422.018211) (xy 46.79624 -422.030189) (xy 46.732444 -422.034203) (xy 46.668648 -422.030189)
			(xy 46.605858 -422.018211) (xy 46.545065 -421.998458) (xy 46.487226 -421.971241) (xy 46.433255 -421.93699)
			(xy 46.384002 -421.896245) (xy 46.340245 -421.849648) (xy 46.302672 -421.797933) (xy 46.271878 -421.741918)
			(xy 46.248346 -421.682485) (xy 46.232449 -421.620571) (xy 46.224438 -421.557153) (xy 46.223936 -421.525192)
			(xy 46.224458 -421.491179) (xy 46.233529 -421.42376) (xy 46.251508 -421.358152) (xy 46.278073 -421.295528)
			(xy 46.312751 -421.237004) (xy 46.33341 -421.209978) (xy 46.339965 -421.200601) (xy 46.344944 -421.178305)
			(xy 46.339797 -421.156047) (xy 46.333156 -421.146732) (xy 46.31203 -421.119528) (xy 46.276507 -421.060518)
			(xy 46.249269 -420.997255) (xy 46.230814 -420.930896) (xy 46.22148 -420.862654) (xy 46.220888 -420.828216)
			(xy 46.221477 -420.793658) (xy 46.230818 -420.725176) (xy 46.249343 -420.65859) (xy 46.276712 -420.595124)
			(xy 46.31242 -420.535947) (xy 46.333664 -420.508684) (xy 46.338927 -420.501517) (xy 46.344665 -420.484703)
			(xy 46.34432 -420.466939) (xy 46.337935 -420.45036) (xy 46.332394 -420.443406) (xy 46.312776 -420.420177)
			(xy 46.278571 -420.369908) (xy 46.250602 -420.315921) (xy 46.229267 -420.258985) (xy 46.21487 -420.199911)
			(xy 46.207618 -420.139543) (xy 46.207172 -420.109142) (xy 45.594513 -420.109142) (xy 45.588044 -420.16277)
			(xy 45.573506 -420.222123) (xy 45.551959 -420.279305) (xy 45.523713 -420.333491) (xy 45.489176 -420.383902)
			(xy 45.448845 -420.429809) (xy 45.426376 -420.450518) (xy 45.41774 -420.458138) (xy 45.409104 -420.478966)
			(xy 45.413422 -420.580566) (xy 45.42409 -420.600632) (xy 45.433234 -420.60749) (xy 45.459933 -420.628128)
			(xy 45.50816 -420.675328) (xy 45.549718 -420.728496) (xy 45.583875 -420.786694) (xy 45.610031 -420.848901)
			(xy 45.627726 -420.914022) (xy 45.636649 -420.980911) (xy 45.637196 -421.014652) (xy 45.636694 -421.046613)
			(xy 45.628683 -421.110031) (xy 45.612786 -421.171945) (xy 45.589254 -421.231378) (xy 45.55846 -421.287393)
			(xy 45.520887 -421.339108) (xy 45.47713 -421.385705) (xy 45.427877 -421.42645) (xy 45.373906 -421.460701)
			(xy 45.316067 -421.487918) (xy 45.255274 -421.507671) (xy 45.192484 -421.519649) (xy 45.128688 -421.523663)
			(xy 45.064892 -421.519649) (xy 45.002102 -421.507671) (xy 44.941309 -421.487918) (xy 44.88347 -421.460701)
			(xy 44.829499 -421.42645) (xy 44.780246 -421.385705) (xy 44.736489 -421.339108) (xy 44.698916 -421.287393)
			(xy 44.668122 -421.231378) (xy 44.64459 -421.171945) (xy 44.628693 -421.110031) (xy 44.620682 -421.046613)
			(xy 44.62018 -421.014652) (xy 44.620622 -420.984099) (xy 44.62794 -420.923433) (xy 44.642476 -420.864081)
			(xy 44.664022 -420.806899) (xy 44.692266 -420.752713) (xy 44.726802 -420.702302) (xy 44.76713 -420.656394)
			(xy 44.789598 -420.635684) (xy 44.798234 -420.628064) (xy 44.80687 -420.607236) (xy 44.802552 -420.505636)
			(xy 44.791884 -420.48557) (xy 44.78274 -420.478712) (xy 44.756058 -420.458052) (xy 44.707827 -420.410858)
			(xy 44.666266 -420.357695) (xy 44.632105 -420.2995) (xy 44.605946 -420.237296) (xy 44.58825 -420.172178)
			(xy 44.579326 -420.10529) (xy 44.578778 -420.07155) (xy 23.537255 -420.07155) (xy 23.547134 -420.08952)
			(xy 23.570666 -420.148953) (xy 23.586563 -420.210867) (xy 23.594574 -420.274285) (xy 23.595076 -420.306246)
			(xy 23.594574 -420.338207) (xy 23.586563 -420.401625) (xy 23.570666 -420.463539) (xy 23.547134 -420.522972)
			(xy 23.51634 -420.578987) (xy 23.478767 -420.630702) (xy 23.43501 -420.677299) (xy 23.385757 -420.718044)
			(xy 23.331786 -420.752295) (xy 23.273947 -420.779512) (xy 23.213154 -420.799265) (xy 23.150364 -420.811243)
			(xy 23.086568 -420.815257) (xy 23.022772 -420.811243) (xy 22.959982 -420.799265) (xy 22.899189 -420.779512)
			(xy 22.84135 -420.752295) (xy 22.787379 -420.718044) (xy 22.738126 -420.677299) (xy 22.694369 -420.630702)
			(xy 22.656796 -420.578987) (xy 22.626002 -420.522972) (xy 22.60247 -420.463539) (xy 22.586573 -420.401625)
			(xy 22.578562 -420.338207) (xy 22.305853 -420.338207) (xy 22.31039 -420.375589) (xy 22.310852 -420.406322)
			(xy 22.310271 -420.441277) (xy 22.300708 -420.51053) (xy 22.28175 -420.577821) (xy 22.253755 -420.641881)
			(xy 22.21725 -420.701503) (xy 22.195536 -420.728902) (xy 22.190233 -420.735897) (xy 22.184263 -420.752392)
			(xy 22.183852 -420.76116) (xy 22.183852 -420.915084) (xy 22.18423 -420.923859) (xy 22.190205 -420.940362)
			(xy 22.195536 -420.947342) (xy 22.217274 -420.974722) (xy 22.253766 -421.034354) (xy 22.281754 -421.098419)
			(xy 22.300709 -421.165712) (xy 22.310275 -421.234966) (xy 22.310852 -421.269922) (xy 22.310365 -421.300652)
			(xy 22.302955 -421.361663) (xy 22.288245 -421.421336) (xy 22.26645 -421.478802) (xy 22.237888 -421.533221)
			(xy 22.202976 -421.583802) (xy 22.162221 -421.629806) (xy 22.116219 -421.670562) (xy 22.06564 -421.705477)
			(xy 22.011222 -421.734041) (xy 21.953757 -421.755838) (xy 21.894085 -421.770551) (xy 21.833074 -421.777963)
			(xy 21.802344 -421.77843) (xy 21.768793 -421.777906) (xy 21.702271 -421.769112) (xy 21.637487 -421.751632)
			(xy 21.57557 -421.725771) (xy 21.546312 -421.709342) (xy 21.538556 -421.705181) (xy 21.521269 -421.70194)
			(xy 21.51253 -421.702992) (xy 21.482812 -421.708072) (xy 21.474386 -421.709825) (xy 21.459325 -421.718135)
			(xy 21.453348 -421.724328) (xy 21.435173 -421.744064) (xy 21.394221 -421.778726) (xy 21.348818 -421.807311)
			(xy 21.299859 -421.829257) (xy 21.24831 -421.84413) (xy 21.195186 -421.851638) (xy 21.16836 -421.85209)
			(xy 21.141109 -421.8516) (xy 21.087161 -421.843844) (xy 21.034867 -421.828489) (xy 20.98529 -421.805848)
			(xy 20.93944 -421.776382) (xy 20.89825 -421.74069) (xy 20.862558 -421.6995) (xy 20.833092 -421.65365)
			(xy 20.810451 -421.604073) (xy 20.795096 -421.551779) (xy 20.78734 -421.497831) (xy 10.80618 -421.497831)
			(xy 10.794863 -421.514225) (xy 10.754103 -421.56023) (xy 10.708095 -421.600986) (xy 10.65751 -421.6359)
			(xy 10.603085 -421.664462) (xy 10.545615 -421.686256) (xy 10.485936 -421.700964) (xy 10.42492 -421.708371)
			(xy 10.394188 -421.708834) (xy 10.360638 -421.70829) (xy 10.294116 -421.699502) (xy 10.229332 -421.682028)
			(xy 10.167414 -421.656172) (xy 10.138156 -421.639746) (xy 10.130393 -421.635601) (xy 10.113112 -421.632352)
			(xy 10.104374 -421.633396) (xy 10.074656 -421.638476) (xy 10.066223 -421.640205) (xy 10.051166 -421.648532)
			(xy 10.045192 -421.654732) (xy 10.026996 -421.674447) (xy 9.986048 -421.709111) (xy 9.94065 -421.737699)
			(xy 9.891695 -421.759648) (xy 9.84015 -421.774525) (xy 9.787029 -421.782039) (xy 9.760204 -421.782494)
			(xy 9.73295 -421.782059) (xy 9.678997 -421.774303) (xy 9.626696 -421.758946) (xy 9.577114 -421.736303)
			(xy 9.531258 -421.706834) (xy 9.490064 -421.671139) (xy 9.454368 -421.629945) (xy 9.424899 -421.58409)
			(xy 9.402255 -421.534508) (xy 9.386898 -421.482207) (xy 9.379141 -421.428254) (xy 7.76986 -421.428254)
			(xy 7.76986 -422.07053) (xy 15.217392 -422.07053) (xy 15.221463 -422.014908) (xy 15.233589 -421.960471)
			(xy 15.253512 -421.90838) (xy 15.280808 -421.859745) (xy 15.314894 -421.815602) (xy 15.355043 -421.776893)
			(xy 15.400401 -421.744442) (xy 15.450001 -421.718941) (xy 15.502785 -421.700934) (xy 15.557628 -421.690804)
			(xy 15.613362 -421.688767) (xy 15.668799 -421.694867) (xy 15.722756 -421.708973) (xy 15.774085 -421.730785)
			(xy 15.821691 -421.759839) (xy 15.864559 -421.795514) (xy 15.901776 -421.837051) (xy 15.932549 -421.883564)
			(xy 15.956221 -421.934061) (xy 15.972289 -421.987468) (xy 15.980409 -422.042644) (xy 15.980918 -422.07053)
			(xy 15.980409 -422.098416) (xy 15.979541 -422.104312) (xy 17.267426 -422.104312) (xy 17.271497 -422.04869)
			(xy 17.283623 -421.994253) (xy 17.303546 -421.942162) (xy 17.330842 -421.893527) (xy 17.364928 -421.849384)
			(xy 17.405077 -421.810675) (xy 17.450435 -421.778224) (xy 17.500035 -421.752723) (xy 17.552819 -421.734716)
			(xy 17.607662 -421.724586) (xy 17.663396 -421.722549) (xy 17.718833 -421.728649) (xy 17.77279 -421.742755)
			(xy 17.824119 -421.764567) (xy 17.871725 -421.793621) (xy 17.914593 -421.829296) (xy 17.95181 -421.870833)
			(xy 17.982583 -421.917346) (xy 18.006255 -421.967843) (xy 18.022323 -422.02125) (xy 18.030443 -422.076426)
			(xy 18.030952 -422.104312) (xy 18.030443 -422.132198) (xy 18.022323 -422.187374) (xy 18.006255 -422.240781)
			(xy 17.982583 -422.291278) (xy 17.95181 -422.337791) (xy 17.914593 -422.379328) (xy 17.871725 -422.415003)
			(xy 17.835597 -422.437052) (xy 22.342346 -422.437052) (xy 22.346417 -422.38143) (xy 22.358543 -422.326993)
			(xy 22.378466 -422.274902) (xy 22.405762 -422.226267) (xy 22.439848 -422.182124) (xy 22.479997 -422.143415)
			(xy 22.525355 -422.110964) (xy 22.574955 -422.085463) (xy 22.627739 -422.067456) (xy 22.682582 -422.057326)
			(xy 22.738316 -422.055289) (xy 22.793753 -422.061389) (xy 22.84771 -422.075495) (xy 22.899039 -422.097307)
			(xy 22.946645 -422.126361) (xy 22.951587 -422.130474) (xy 24.750014 -422.130474) (xy 24.750578 -422.095518)
			(xy 24.760143 -422.026264) (xy 24.779104 -421.958973) (xy 24.807103 -421.894913) (xy 24.843613 -421.835291)
			(xy 24.86533 -421.807894) (xy 24.870606 -421.800899) (xy 24.876449 -421.784393) (xy 24.87676 -421.775636)
			(xy 24.87676 -421.621712) (xy 24.876398 -421.612965) (xy 24.870561 -421.596473) (xy 24.86533 -421.589454)
			(xy 24.843646 -421.562033) (xy 24.807143 -421.502413) (xy 24.779144 -421.438359) (xy 24.760177 -421.371074)
			(xy 24.750598 -421.301827) (xy 24.750014 -421.266874) (xy 24.750432 -421.236142) (xy 24.757844 -421.175125)
			(xy 24.772556 -421.115447) (xy 24.794355 -421.057978) (xy 24.822921 -421.003555) (xy 24.85784 -420.952972)
			(xy 24.898601 -420.906967) (xy 24.94461 -420.86621) (xy 24.995196 -420.831297) (xy 25.049622 -420.802735)
			(xy 25.107093 -420.780942) (xy 25.166773 -420.766235) (xy 25.22779 -420.758829) (xy 25.258522 -420.758366)
			(xy 25.292072 -420.758906) (xy 25.358594 -420.767695) (xy 25.423378 -420.78517) (xy 25.485296 -420.811027)
			(xy 25.514554 -420.827454) (xy 25.522314 -420.831604) (xy 25.539598 -420.83485) (xy 25.548336 -420.833804)
			(xy 25.578054 -420.828978) (xy 25.58657 -420.827201) (xy 25.601767 -420.818761) (xy 25.607772 -420.812468)
			(xy 25.625977 -420.792802) (xy 25.666897 -420.758201) (xy 25.712256 -420.729666) (xy 25.761161 -420.707759)
			(xy 25.812651 -420.69291) (xy 25.865712 -420.685413) (xy 25.892506 -420.68496) (xy 25.919755 -420.685511)
			(xy 25.973697 -420.693267) (xy 26.025987 -420.708621) (xy 26.075559 -420.731261) (xy 26.121405 -420.760725)
			(xy 26.162591 -420.796413) (xy 26.198279 -420.8376) (xy 26.227742 -420.883446) (xy 26.250381 -420.933019)
			(xy 26.265734 -420.985309) (xy 26.27349 -421.039251) (xy 26.27349 -421.093749) (xy 26.265734 -421.147691)
			(xy 26.250381 -421.199981) (xy 26.227742 -421.249554) (xy 26.198279 -421.2954) (xy 26.162591 -421.336587)
			(xy 26.121405 -421.372275) (xy 26.075559 -421.401739) (xy 26.025987 -421.424379) (xy 25.973697 -421.439733)
			(xy 25.919755 -421.447489) (xy 25.892506 -421.447976) (xy 25.870524 -421.44764) (xy 25.826854 -421.442548)
			(xy 25.805384 -421.437816) (xy 25.796903 -421.436228) (xy 25.779767 -421.43818) (xy 25.771856 -421.441626)
			(xy 25.744678 -421.45458) (xy 25.736895 -421.458748) (xy 25.724549 -421.471348) (xy 25.720548 -421.479218)
			(xy 25.706514 -421.508638) (xy 25.671985 -421.563927) (xy 25.651714 -421.589454) (xy 25.646464 -421.596467)
			(xy 25.640605 -421.612959) (xy 25.640284 -421.621712) (xy 25.640284 -421.726956) (xy 26.688445 -421.726956)
			(xy 26.688445 -421.672444) (xy 26.696203 -421.618488) (xy 26.711562 -421.566186) (xy 26.734208 -421.516601)
			(xy 26.763681 -421.470745) (xy 26.79938 -421.42955) (xy 26.840579 -421.393856) (xy 26.886438 -421.364388)
			(xy 26.936025 -421.341747) (xy 26.988329 -421.326394) (xy 27.042286 -421.318642) (xy 27.069542 -421.318182)
			(xy 27.094817 -421.318592) (xy 27.144924 -421.325266) (xy 27.193709 -421.338507) (xy 27.240315 -421.35808)
			(xy 27.262328 -421.370506) (xy 27.272721 -421.375833) (xy 27.295997 -421.377422) (xy 27.317615 -421.368649)
			(xy 27.325828 -421.360346) (xy 27.346511 -421.337889) (xy 27.392409 -421.297627) (xy 27.442798 -421.263151)
			(xy 27.496953 -421.234956) (xy 27.554093 -421.213448) (xy 27.613399 -421.198937) (xy 27.674015 -421.191631)
			(xy 27.704542 -421.191182) (xy 27.739498 -421.191744) (xy 27.808752 -421.201311) (xy 27.876043 -421.220273)
			(xy 27.940103 -421.248272) (xy 27.999724 -421.284781) (xy 28.027122 -421.306498) (xy 28.034115 -421.311778)
			(xy 28.050622 -421.317619) (xy 28.05938 -421.317928) (xy 28.213304 -421.317928) (xy 28.22205 -421.31756)
			(xy 28.238541 -421.311726) (xy 28.245562 -421.306498) (xy 28.272974 -421.284802) (xy 28.332596 -421.248302)
			(xy 28.396653 -421.220306) (xy 28.46394 -421.201341) (xy 28.533188 -421.191765) (xy 28.568142 -421.191182)
			(xy 28.598669 -421.19161) (xy 28.659283 -421.198925) (xy 28.718585 -421.213444) (xy 28.775722 -421.23496)
			(xy 28.829872 -421.263162) (xy 28.85608 -421.281098) (xy 30.930594 -421.281098) (xy 30.934665 -421.225476)
			(xy 30.946791 -421.171039) (xy 30.966714 -421.118948) (xy 30.99401 -421.070313) (xy 31.028096 -421.02617)
			(xy 31.068245 -420.987461) (xy 31.113603 -420.95501) (xy 31.163203 -420.929509) (xy 31.215987 -420.911502)
			(xy 31.27083 -420.901372) (xy 31.326564 -420.899335) (xy 31.382001 -420.905435) (xy 31.435958 -420.919541)
			(xy 31.487287 -420.941353) (xy 31.534893 -420.970407) (xy 31.577761 -421.006082) (xy 31.614978 -421.047619)
			(xy 31.645751 -421.094132) (xy 31.669423 -421.144629) (xy 31.685491 -421.198036) (xy 31.693611 -421.253212)
			(xy 31.69412 -421.281098) (xy 31.693611 -421.308984) (xy 31.685491 -421.36416) (xy 31.669423 -421.417567)
			(xy 31.645751 -421.468064) (xy 31.614978 -421.514577) (xy 31.577761 -421.556114) (xy 31.534893 -421.591789)
			(xy 31.487287 -421.620843) (xy 31.435958 -421.642655) (xy 31.382001 -421.656761) (xy 31.326564 -421.662861)
			(xy 31.27083 -421.660824) (xy 31.215987 -421.650694) (xy 31.163203 -421.632687) (xy 31.113603 -421.607186)
			(xy 31.068245 -421.574735) (xy 31.028096 -421.536026) (xy 30.99401 -421.491883) (xy 30.966714 -421.443248)
			(xy 30.946791 -421.391157) (xy 30.934665 -421.33672) (xy 30.930594 -421.281098) (xy 28.85608 -421.281098)
			(xy 28.880256 -421.297644) (xy 28.926149 -421.337911) (xy 28.946856 -421.360346) (xy 28.955052 -421.368694)
			(xy 28.976672 -421.377552) (xy 28.999978 -421.375903) (xy 29.010356 -421.370506) (xy 29.032377 -421.358096)
			(xy 29.078982 -421.338524) (xy 29.127764 -421.325281) (xy 29.177868 -421.318596) (xy 29.203142 -421.318182)
			(xy 29.230391 -421.318691) (xy 29.284332 -421.326452) (xy 29.336621 -421.341811) (xy 29.386191 -421.364454)
			(xy 29.432035 -421.39392) (xy 29.473219 -421.429611) (xy 29.508905 -421.470799) (xy 29.538367 -421.516646)
			(xy 29.561004 -421.566219) (xy 29.576357 -421.618509) (xy 29.584112 -421.672451) (xy 29.584112 -421.726949)
			(xy 29.576357 -421.780891) (xy 29.561004 -421.833181) (xy 29.538367 -421.882754) (xy 29.508905 -421.928601)
			(xy 29.473219 -421.969789) (xy 29.432035 -422.00548) (xy 29.414023 -422.017057) (xy 41.019613 -422.017057)
			(xy 41.019613 -421.962543) (xy 41.027372 -421.908583) (xy 41.042731 -421.856277) (xy 41.065378 -421.80669)
			(xy 41.094852 -421.76083) (xy 41.130553 -421.719632) (xy 41.171754 -421.683934) (xy 41.217616 -421.654464)
			(xy 41.267205 -421.63182) (xy 41.319513 -421.616465) (xy 41.373473 -421.608711) (xy 41.40073 -421.60825)
			(xy 41.42778 -421.608687) (xy 41.481337 -421.616341) (xy 41.533277 -421.631476) (xy 41.582561 -421.65379)
			(xy 41.628203 -421.682836) (xy 41.669289 -421.718033) (xy 41.687496 -421.738044) (xy 41.69347 -421.744413)
			(xy 41.708675 -421.752978) (xy 41.717214 -421.754808) (xy 41.746678 -421.759888) (xy 41.755456 -421.761034)
			(xy 41.772869 -421.757898) (xy 41.780714 -421.753792) (xy 41.809806 -421.737665) (xy 41.871264 -421.712221)
			(xy 41.935512 -421.694996) (xy 42.001456 -421.686285) (xy 42.034714 -421.68572) (xy 42.065447 -421.686125)
			(xy 42.126466 -421.693535) (xy 42.186146 -421.708247) (xy 42.243618 -421.730046) (xy 42.298044 -421.758613)
			(xy 42.348629 -421.793532) (xy 42.394636 -421.834294) (xy 42.435394 -421.880304) (xy 42.470309 -421.930892)
			(xy 42.498872 -421.98532) (xy 42.520665 -422.042794) (xy 42.535372 -422.102475) (xy 42.542778 -422.163494)
			(xy 42.543222 -422.194228) (xy 42.542651 -422.229184) (xy 42.533086 -422.298437) (xy 42.514126 -422.365728)
			(xy 42.486129 -422.429788) (xy 42.449622 -422.48941) (xy 42.427906 -422.516808) (xy 42.422633 -422.523806)
			(xy 42.416788 -422.540309) (xy 42.416476 -422.549066) (xy 42.416476 -422.70299) (xy 42.41685 -422.711736)
			(xy 42.42268 -422.728227) (xy 42.427906 -422.735248) (xy 42.449596 -422.762665) (xy 42.486097 -422.822286)
			(xy 42.514094 -422.886342) (xy 42.515618 -422.891747) (xy 49.496012 -422.891747) (xy 49.496012 -422.837253)
			(xy 49.503767 -422.783313) (xy 49.519119 -422.731026) (xy 49.541755 -422.681456) (xy 49.571216 -422.635611)
			(xy 49.6069 -422.594426) (xy 49.648082 -422.558737) (xy 49.693924 -422.529273) (xy 49.743492 -422.506631)
			(xy 49.795778 -422.491275) (xy 49.849717 -422.483515) (xy 49.876964 -422.483026) (xy 49.884076 -422.483026)
			(xy 49.896522 -422.48328) (xy 49.918112 -422.472866) (xy 49.982628 -422.387268) (xy 49.986692 -422.363646)
			(xy 49.983136 -422.351708) (xy 49.972708 -422.315318) (xy 49.961481 -422.240458) (xy 49.960784 -422.20261)
			(xy 49.961257 -422.171068) (xy 49.969059 -422.108469) (xy 49.984544 -422.047315) (xy 50.007474 -421.988546)
			(xy 50.037498 -421.933065) (xy 50.074154 -421.881724) (xy 50.116879 -421.835311) (xy 50.165016 -421.79454)
			(xy 50.217828 -421.760035) (xy 50.274501 -421.732328) (xy 50.334167 -421.711845) (xy 50.395908 -421.698898)
			(xy 50.458776 -421.693688) (xy 50.521806 -421.696295) (xy 50.584029 -421.706678) (xy 50.644491 -421.724677)
			(xy 50.702261 -421.750018) (xy 50.756454 -421.782309) (xy 50.806236 -421.821056) (xy 50.850843 -421.865663)
			(xy 50.88959 -421.915445) (xy 50.889802 -421.915801) (xy 52.016146 -421.915801) (xy 52.016146 -421.851879)
			(xy 52.024157 -421.788461) (xy 52.040054 -421.726547) (xy 52.063586 -421.667114) (xy 52.09438 -421.611099)
			(xy 52.131953 -421.559384) (xy 52.17571 -421.512787) (xy 52.224963 -421.472042) (xy 52.278934 -421.437791)
			(xy 52.336773 -421.410574) (xy 52.397566 -421.390821) (xy 52.460356 -421.378843) (xy 52.524152 -421.37483)
			(xy 52.587948 -421.378843) (xy 52.650738 -421.390821) (xy 52.711531 -421.410574) (xy 52.76937 -421.437791)
			(xy 52.823341 -421.472042) (xy 52.872594 -421.512787) (xy 52.916351 -421.559384) (xy 52.953924 -421.611099)
			(xy 52.984718 -421.667114) (xy 53.00825 -421.726547) (xy 53.024147 -421.788461) (xy 53.032158 -421.851879)
			(xy 53.03266 -421.88384) (xy 53.032158 -421.915801) (xy 53.024147 -421.979219) (xy 53.00825 -422.041133)
			(xy 52.984718 -422.100566) (xy 52.953924 -422.156581) (xy 52.916351 -422.208296) (xy 52.872594 -422.254893)
			(xy 52.823341 -422.295638) (xy 52.76937 -422.329889) (xy 52.711531 -422.357106) (xy 52.650738 -422.376859)
			(xy 52.587948 -422.388837) (xy 52.524152 -422.392851) (xy 52.460356 -422.388837) (xy 52.397566 -422.376859)
			(xy 52.336773 -422.357106) (xy 52.278934 -422.329889) (xy 52.224963 -422.295638) (xy 52.17571 -422.254893)
			(xy 52.131953 -422.208296) (xy 52.09438 -422.156581) (xy 52.063586 -422.100566) (xy 52.040054 -422.041133)
			(xy 52.024157 -421.979219) (xy 52.016146 -421.915801) (xy 50.889802 -421.915801) (xy 50.921882 -421.969637)
			(xy 50.947222 -422.027407) (xy 50.965222 -422.087869) (xy 50.975605 -422.150092) (xy 50.978212 -422.213122)
			(xy 50.973002 -422.27599) (xy 50.960056 -422.337731) (xy 50.939572 -422.397397) (xy 50.911866 -422.454071)
			(xy 50.877362 -422.506882) (xy 50.83659 -422.55502) (xy 50.790178 -422.597745) (xy 50.738836 -422.634401)
			(xy 50.683356 -422.664425) (xy 50.624587 -422.687355) (xy 50.563433 -422.702841) (xy 50.500834 -422.710643)
			(xy 50.469292 -422.711118) (xy 50.445527 -422.710835) (xy 50.398205 -422.706385) (xy 50.374804 -422.702228)
			(xy 50.362612 -422.699942) (xy 50.339498 -422.7068) (xy 50.261774 -422.780206) (xy 50.253646 -422.802812)
			(xy 50.25517 -422.815258) (xy 50.2567 -422.82752) (xy 50.258351 -422.852178) (xy 50.258472 -422.864534)
			(xy 50.258229 -422.883913) (xy 50.254286 -422.92247) (xy 50.250598 -422.941496) (xy 50.247804 -422.95572)
			(xy 50.257456 -422.982644) (xy 50.351944 -423.056812) (xy 50.380138 -423.060114) (xy 50.393346 -423.053764)
			(xy 50.418934 -423.04228) (xy 50.472631 -423.026092) (xy 50.528118 -423.017923) (xy 50.55616 -423.017442)
			(xy 50.583984 -423.017975) (xy 50.639045 -423.026033) (xy 50.692349 -423.042013) (xy 50.742762 -423.065575)
			(xy 50.789213 -423.096219) (xy 50.830713 -423.133291) (xy 50.86638 -423.176005) (xy 50.895457 -423.223452)
			(xy 50.917324 -423.274624) (xy 50.931517 -423.328431) (xy 50.935128 -423.356024) (xy 50.936398 -423.36593)
			(xy 50.945796 -423.383456) (xy 51.01717 -423.44086) (xy 51.03622 -423.446702) (xy 51.04638 -423.445686)
			(xy 51.08448 -423.443654) (xy 51.111731 -423.444192) (xy 51.165679 -423.451946) (xy 51.217974 -423.467299)
			(xy 51.267552 -423.489938) (xy 51.313403 -423.519402) (xy 51.354594 -423.555092) (xy 51.390286 -423.596281)
			(xy 51.419753 -423.642131) (xy 51.442394 -423.691707) (xy 51.45775 -423.744002) (xy 51.465507 -423.797949)
			(xy 51.465507 -423.852451) (xy 51.45775 -423.906398) (xy 51.442394 -423.958693) (xy 51.419753 -424.008269)
			(xy 51.390286 -424.054119) (xy 51.354594 -424.095308) (xy 51.313403 -424.130998) (xy 51.267552 -424.160462)
			(xy 51.217974 -424.183101) (xy 51.165679 -424.198454) (xy 51.111731 -424.206208) (xy 51.08448 -424.20667)
			(xy 51.056655 -424.206182) (xy 51.001592 -424.198116) (xy 50.948288 -424.182129) (xy 50.897875 -424.15856)
			(xy 50.851425 -424.127911) (xy 50.809926 -424.090834) (xy 50.774259 -424.048116) (xy 50.745183 -424.000666)
			(xy 50.723316 -423.949492) (xy 50.709123 -423.895682) (xy 50.705512 -423.868088) (xy 50.704242 -423.858182)
			(xy 50.694844 -423.840656) (xy 50.62347 -423.783252) (xy 50.60442 -423.77741) (xy 50.59426 -423.778426)
			(xy 50.55616 -423.780458) (xy 50.528904 -423.780082) (xy 50.474947 -423.772318) (xy 50.422645 -423.756955)
			(xy 50.373061 -423.734304) (xy 50.327206 -423.704827) (xy 50.286012 -423.669124) (xy 50.250319 -423.627922)
			(xy 50.220853 -423.58206) (xy 50.198214 -423.532471) (xy 50.182862 -423.480165) (xy 50.175111 -423.426206)
			(xy 50.174652 -423.39895) (xy 50.174892 -423.379571) (xy 50.178837 -423.341014) (xy 50.182526 -423.321988)
			(xy 50.18532 -423.307764) (xy 50.175668 -423.28084) (xy 50.08118 -423.206672) (xy 50.052986 -423.20337)
			(xy 50.039778 -423.20972) (xy 50.014187 -423.221195) (xy 49.960491 -423.237386) (xy 49.905006 -423.24556)
			(xy 49.876964 -423.246042) (xy 49.849717 -423.245485) (xy 49.795778 -423.237725) (xy 49.743492 -423.222369)
			(xy 49.693924 -423.199727) (xy 49.648082 -423.170263) (xy 49.6069 -423.134574) (xy 49.571216 -423.093389)
			(xy 49.541755 -423.047544) (xy 49.519119 -422.997974) (xy 49.503767 -422.945687) (xy 49.496012 -422.891747)
			(xy 42.515618 -422.891747) (xy 42.53306 -422.953627) (xy 42.542638 -423.022875) (xy 42.543222 -423.057828)
			(xy 42.54277 -423.088559) (xy 42.535359 -423.149573) (xy 42.520647 -423.209248) (xy 42.498851 -423.266716)
			(xy 42.470286 -423.321137) (xy 42.43537 -423.371718) (xy 42.394613 -423.417723) (xy 42.348607 -423.458479)
			(xy 42.298025 -423.493393) (xy 42.243603 -423.521956) (xy 42.186135 -423.543752) (xy 42.126459 -423.558461)
			(xy 42.065445 -423.565871) (xy 42.034714 -423.566336) (xy 42.002988 -423.565854) (xy 41.940029 -423.557956)
			(xy 41.878541 -423.542293) (xy 41.819476 -423.519107) (xy 41.791382 -423.50436) (xy 41.78341 -423.500455)
			(xy 41.765858 -423.497872) (xy 41.757092 -423.49928) (xy 41.727374 -423.505122) (xy 41.718888 -423.507247)
			(xy 41.703959 -423.516347) (xy 41.698164 -423.522902) (xy 41.679939 -423.54438) (xy 41.638247 -423.582256)
			(xy 41.591441 -423.613592) (xy 41.540538 -423.637708) (xy 41.486642 -423.654081) (xy 41.430926 -423.662355)
			(xy 41.402762 -423.662856) (xy 41.375516 -423.662271) (xy 41.321579 -423.654511) (xy 41.269296 -423.639155)
			(xy 41.21973 -423.616514) (xy 41.17389 -423.587051) (xy 41.132709 -423.551364) (xy 41.097026 -423.51018)
			(xy 41.067567 -423.464337) (xy 41.044932 -423.414769) (xy 41.029581 -423.362484) (xy 41.021826 -423.308546)
			(xy 41.021826 -423.254054) (xy 41.029581 -423.200116) (xy 41.044932 -423.147831) (xy 41.067567 -423.098263)
			(xy 41.097026 -423.05242) (xy 41.132709 -423.011236) (xy 41.17389 -422.975549) (xy 41.21973 -422.946086)
			(xy 41.269296 -422.923445) (xy 41.321579 -422.908089) (xy 41.375516 -422.900329) (xy 41.402762 -422.89984)
			(xy 41.422401 -422.900116) (xy 41.461467 -422.904189) (xy 41.48074 -422.907968) (xy 41.489359 -422.909369)
			(xy 41.506634 -422.906889) (xy 41.514522 -422.903142) (xy 41.541446 -422.889172) (xy 41.549169 -422.884762)
			(xy 41.561131 -422.871614) (xy 41.564814 -422.863518) (xy 41.579754 -422.829096) (xy 41.618265 -422.764696)
			(xy 41.641522 -422.735248) (xy 41.646775 -422.728237) (xy 41.652632 -422.711743) (xy 41.652952 -422.70299)
			(xy 41.652952 -422.549066) (xy 41.652613 -422.540317) (xy 41.64676 -422.523825) (xy 41.641522 -422.516808)
			(xy 41.620695 -422.49056) (xy 41.585402 -422.433602) (xy 41.571164 -422.40327) (xy 41.567221 -422.395421)
			(xy 41.555012 -422.382813) (xy 41.547288 -422.378632) (xy 41.52011 -422.365424) (xy 41.512141 -422.361946)
			(xy 41.494873 -422.360003) (xy 41.486328 -422.361614) (xy 41.465219 -422.366139) (xy 41.422317 -422.370979)
			(xy 41.40073 -422.371266) (xy 41.373473 -422.370889) (xy 41.319513 -422.363135) (xy 41.267205 -422.34778)
			(xy 41.217616 -422.325136) (xy 41.171754 -422.295666) (xy 41.130553 -422.259968) (xy 41.094852 -422.21877)
			(xy 41.065378 -422.172911) (xy 41.042731 -422.123323) (xy 41.027372 -422.071017) (xy 41.019613 -422.017057)
			(xy 29.414023 -422.017057) (xy 29.386191 -422.034946) (xy 29.336621 -422.057589) (xy 29.284332 -422.072948)
			(xy 29.230391 -422.080709) (xy 29.203142 -422.081198) (xy 29.177867 -422.080798) (xy 29.127759 -422.074121)
			(xy 29.078975 -422.060878) (xy 29.032369 -422.041302) (xy 29.010356 -422.028874) (xy 28.999977 -422.02351)
			(xy 28.976688 -422.021924) (xy 28.955064 -422.030717) (xy 28.946856 -422.039034) (xy 28.926126 -422.061446)
			(xy 28.880237 -422.101712) (xy 28.829857 -422.136193) (xy 28.77571 -422.164394) (xy 28.718576 -422.185909)
			(xy 28.659278 -422.200429) (xy 28.598667 -422.207744) (xy 28.568142 -422.208198) (xy 28.533186 -422.20765)
			(xy 28.463931 -422.19808) (xy 28.39664 -422.179115) (xy 28.33258 -422.151113) (xy 28.272959 -422.1146)
			(xy 28.245562 -422.092882) (xy 28.238547 -422.087635) (xy 28.222057 -422.081775) (xy 28.213304 -422.081452)
			(xy 28.05938 -422.081452) (xy 28.050631 -422.081797) (xy 28.034139 -422.087645) (xy 28.027122 -422.092882)
			(xy 27.999713 -422.114582) (xy 27.94009 -422.151082) (xy 27.876032 -422.179078) (xy 27.808745 -422.198041)
			(xy 27.739496 -422.207616) (xy 27.704542 -422.208198) (xy 27.674017 -422.207719) (xy 27.613404 -422.200414)
			(xy 27.554103 -422.185903) (xy 27.496966 -422.164396) (xy 27.442815 -422.136202) (xy 27.39243 -422.101726)
			(xy 27.346536 -422.061466) (xy 27.325828 -422.039034) (xy 27.317644 -422.030673) (xy 27.296017 -422.021821)
			(xy 27.272707 -422.023475) (xy 27.262328 -422.028874) (xy 27.240309 -422.041289) (xy 27.193703 -422.060859)
			(xy 27.144921 -422.074102) (xy 27.094816 -422.080785) (xy 27.069542 -422.081198) (xy 27.042286 -422.080758)
			(xy 26.988329 -422.073006) (xy 26.936025 -422.057653) (xy 26.886438 -422.035012) (xy 26.840579 -422.005544)
			(xy 26.79938 -421.96985) (xy 26.763681 -421.928655) (xy 26.734208 -421.882799) (xy 26.711562 -421.833214)
			(xy 26.696203 -421.780912) (xy 26.688445 -421.726956) (xy 25.640284 -421.726956) (xy 25.640284 -421.775636)
			(xy 25.640635 -421.784384) (xy 25.646481 -421.800875) (xy 25.651714 -421.807894) (xy 25.672254 -421.833753)
			(xy 25.707159 -421.889815) (xy 25.72131 -421.919654) (xy 25.725337 -421.927507) (xy 25.737668 -421.940113)
			(xy 25.74544 -421.944292) (xy 25.772364 -421.9575) (xy 25.780337 -421.960966) (xy 25.797602 -421.962916)
			(xy 25.806146 -421.96131) (xy 25.827435 -421.95668) (xy 25.870721 -421.951714) (xy 25.892506 -421.951404)
			(xy 25.919758 -421.951866) (xy 25.973707 -421.959624) (xy 26.026002 -421.97498) (xy 26.07558 -421.997622)
			(xy 26.121431 -422.027089) (xy 26.162622 -422.062782) (xy 26.198314 -422.103973) (xy 26.227781 -422.149825)
			(xy 26.250422 -422.199403) (xy 26.265778 -422.251699) (xy 26.273534 -422.305648) (xy 26.273534 -422.360152)
			(xy 26.265778 -422.414101) (xy 26.250422 -422.466397) (xy 26.227781 -422.515975) (xy 26.198314 -422.561827)
			(xy 26.162622 -422.603018) (xy 26.121431 -422.638711) (xy 26.078577 -422.666252) (xy 38.12816 -422.666252)
			(xy 38.12816 -422.611748) (xy 38.135917 -422.557798) (xy 38.151272 -422.505501) (xy 38.173914 -422.455922)
			(xy 38.203381 -422.41007) (xy 38.239074 -422.368878) (xy 38.280265 -422.333185) (xy 38.326117 -422.303717)
			(xy 38.375696 -422.281074) (xy 38.427992 -422.265718) (xy 38.481942 -422.25796) (xy 38.509194 -422.257474)
			(xy 38.53447 -422.257862) (xy 38.584577 -422.264543) (xy 38.633362 -422.27779) (xy 38.679968 -422.297369)
			(xy 38.70198 -422.309798) (xy 38.712392 -422.315081) (xy 38.735654 -422.316686) (xy 38.757266 -422.307932)
			(xy 38.76548 -422.299638) (xy 38.786186 -422.277203) (xy 38.83208 -422.23694) (xy 38.882465 -422.202461)
			(xy 38.936615 -422.174264) (xy 38.993753 -422.152752) (xy 39.053055 -422.138237) (xy 39.113668 -422.130926)
			(xy 39.144194 -422.130474) (xy 39.179149 -422.131065) (xy 39.248402 -422.140625) (xy 39.315692 -422.15958)
			(xy 39.379753 -422.187573) (xy 39.439375 -422.224076) (xy 39.466774 -422.24579) (xy 39.473781 -422.251049)
			(xy 39.490278 -422.256903) (xy 39.499032 -422.25722) (xy 39.652956 -422.25722) (xy 39.661705 -422.256877)
			(xy 39.678196 -422.251026) (xy 39.685214 -422.24579) (xy 39.712607 -422.224069) (xy 39.772235 -422.187573)
			(xy 39.836297 -422.159582) (xy 39.903587 -422.140623) (xy 39.972839 -422.131053) (xy 40.007794 -422.130474)
			(xy 40.03832 -422.130938) (xy 40.098932 -422.138247) (xy 40.158234 -422.152761) (xy 40.21537 -422.174271)
			(xy 40.269521 -422.202467) (xy 40.319906 -422.236944) (xy 40.3658 -422.277206) (xy 40.386508 -422.299638)
			(xy 40.394667 -422.308028) (xy 40.416308 -422.316877) (xy 40.439628 -422.315207) (xy 40.450008 -422.309798)
			(xy 40.472023 -422.297376) (xy 40.51863 -422.277806) (xy 40.567414 -422.264565) (xy 40.61752 -422.257885)
			(xy 40.642794 -422.257474) (xy 40.670046 -422.257973) (xy 40.723995 -422.265729) (xy 40.776291 -422.281084)
			(xy 40.82587 -422.303725) (xy 40.871721 -422.333191) (xy 40.912913 -422.368883) (xy 40.948605 -422.410074)
			(xy 40.978072 -422.455925) (xy 41.000714 -422.505503) (xy 41.01607 -422.557799) (xy 41.023827 -422.611748)
			(xy 41.023827 -422.666252) (xy 41.01607 -422.720201) (xy 41.000714 -422.772497) (xy 40.978072 -422.822075)
			(xy 40.948605 -422.867926) (xy 40.912913 -422.909117) (xy 40.871721 -422.944809) (xy 40.82587 -422.974275)
			(xy 40.776291 -422.996916) (xy 40.723995 -423.012271) (xy 40.670046 -423.020027) (xy 40.642794 -423.02049)
			(xy 40.61752 -423.020055) (xy 40.567414 -423.013386) (xy 40.51863 -423.000153) (xy 40.472022 -422.980588)
			(xy 40.450008 -422.968166) (xy 40.439607 -422.962855) (xy 40.416334 -422.961251) (xy 40.394718 -422.970021)
			(xy 40.386508 -422.978326) (xy 40.365801 -423.00076) (xy 40.319908 -423.041024) (xy 40.269523 -423.075504)
			(xy 40.215373 -423.103702) (xy 40.158236 -423.125214) (xy 40.098934 -423.139729) (xy 40.03832 -423.147039)
			(xy 40.007794 -423.14749) (xy 39.972839 -423.146914) (xy 39.903585 -423.137351) (xy 39.836294 -423.118393)
			(xy 39.772234 -423.090397) (xy 39.712612 -423.05389) (xy 39.685214 -423.032174) (xy 39.678213 -423.026907)
			(xy 39.661712 -423.021059) (xy 39.652956 -423.020744) (xy 39.499032 -423.020744) (xy 39.490281 -423.021068)
			(xy 39.47379 -423.026931) (xy 39.466774 -423.032174) (xy 39.439381 -423.053895) (xy 39.379754 -423.090392)
			(xy 39.315692 -423.118384) (xy 39.248401 -423.137342) (xy 39.179149 -423.146911) (xy 39.144194 -423.14749)
			(xy 39.113667 -423.147047) (xy 39.053054 -423.139735) (xy 38.993752 -423.125219) (xy 38.936614 -423.103706)
			(xy 38.882464 -423.075506) (xy 38.83208 -423.041026) (xy 38.786187 -423.00076) (xy 38.76548 -422.978326)
			(xy 38.757331 -422.969925) (xy 38.735684 -422.961084) (xy 38.712361 -422.962756) (xy 38.70198 -422.968166)
			(xy 38.679971 -422.980599) (xy 38.633361 -423.000165) (xy 38.584576 -423.013403) (xy 38.534469 -423.02008)
			(xy 38.509194 -423.02049) (xy 38.481942 -423.02004) (xy 38.427992 -423.012282) (xy 38.375696 -422.996926)
			(xy 38.326117 -422.974283) (xy 38.280265 -422.944815) (xy 38.239074 -422.909122) (xy 38.203381 -422.86793)
			(xy 38.173914 -422.822078) (xy 38.151272 -422.772499) (xy 38.135917 -422.720202) (xy 38.12816 -422.666252)
			(xy 26.078577 -422.666252) (xy 26.07558 -422.668178) (xy 26.026002 -422.69082) (xy 25.973707 -422.706176)
			(xy 25.919758 -422.713934) (xy 25.892506 -422.71442) (xy 25.865579 -422.713954) (xy 25.812261 -422.706369)
			(xy 25.760539 -422.691364) (xy 25.711441 -422.669236) (xy 25.665941 -422.640426) (xy 25.624943 -422.605505)
			(xy 25.606756 -422.585642) (xy 25.60074 -422.579361) (xy 25.585549 -422.570918) (xy 25.577038 -422.569132)
			(xy 25.54732 -422.564306) (xy 25.538602 -422.563199) (xy 25.521322 -422.566323) (xy 25.513538 -422.570402)
			(xy 25.484366 -422.586687) (xy 25.422678 -422.612343) (xy 25.358161 -422.629698) (xy 25.291927 -422.638452)
			(xy 25.258522 -422.638982) (xy 25.227789 -422.638542) (xy 25.166772 -422.631135) (xy 25.107092 -422.616427)
			(xy 25.049621 -422.594632) (xy 24.995196 -422.566069) (xy 24.944611 -422.531153) (xy 24.898603 -422.490394)
			(xy 24.857844 -422.444386) (xy 24.822929 -422.393801) (xy 24.794366 -422.339375) (xy 24.772572 -422.281904)
			(xy 24.757864 -422.222224) (xy 24.750458 -422.161207) (xy 24.750014 -422.130474) (xy 22.951587 -422.130474)
			(xy 22.989513 -422.162036) (xy 23.02673 -422.203573) (xy 23.057503 -422.250086) (xy 23.081175 -422.300583)
			(xy 23.097243 -422.35399) (xy 23.105363 -422.409166) (xy 23.105872 -422.437052) (xy 23.105363 -422.464938)
			(xy 23.097243 -422.520114) (xy 23.081175 -422.573521) (xy 23.057503 -422.624018) (xy 23.02673 -422.670531)
			(xy 22.989513 -422.712068) (xy 22.946645 -422.747743) (xy 22.899039 -422.776797) (xy 22.84771 -422.798609)
			(xy 22.793753 -422.812715) (xy 22.738316 -422.818815) (xy 22.682582 -422.816778) (xy 22.627739 -422.806648)
			(xy 22.574955 -422.788641) (xy 22.525355 -422.76314) (xy 22.479997 -422.730689) (xy 22.439848 -422.69198)
			(xy 22.405762 -422.647837) (xy 22.378466 -422.599202) (xy 22.358543 -422.547111) (xy 22.346417 -422.492674)
			(xy 22.342346 -422.437052) (xy 17.835597 -422.437052) (xy 17.824119 -422.444057) (xy 17.77279 -422.465869)
			(xy 17.718833 -422.479975) (xy 17.663396 -422.486075) (xy 17.607662 -422.484038) (xy 17.552819 -422.473908)
			(xy 17.500035 -422.455901) (xy 17.450435 -422.4304) (xy 17.405077 -422.397949) (xy 17.364928 -422.35924)
			(xy 17.330842 -422.315097) (xy 17.303546 -422.266462) (xy 17.283623 -422.214371) (xy 17.271497 -422.159934)
			(xy 17.267426 -422.104312) (xy 15.979541 -422.104312) (xy 15.972289 -422.153592) (xy 15.956221 -422.206999)
			(xy 15.932549 -422.257496) (xy 15.901776 -422.304009) (xy 15.864559 -422.345546) (xy 15.821691 -422.381221)
			(xy 15.774085 -422.410275) (xy 15.722756 -422.432087) (xy 15.668799 -422.446193) (xy 15.613362 -422.452293)
			(xy 15.557628 -422.450256) (xy 15.502785 -422.440126) (xy 15.450001 -422.422119) (xy 15.400401 -422.396618)
			(xy 15.355043 -422.364167) (xy 15.314894 -422.325458) (xy 15.280808 -422.281315) (xy 15.253512 -422.23268)
			(xy 15.233589 -422.180589) (xy 15.221463 -422.126152) (xy 15.217392 -422.07053) (xy 7.76986 -422.07053)
			(xy 7.76986 -423.821098) (xy 10.14044 -423.821098) (xy 10.144511 -423.765476) (xy 10.156637 -423.711039)
			(xy 10.17656 -423.658948) (xy 10.203856 -423.610313) (xy 10.237942 -423.56617) (xy 10.278091 -423.527461)
			(xy 10.323449 -423.49501) (xy 10.373049 -423.469509) (xy 10.425833 -423.451502) (xy 10.480676 -423.441372)
			(xy 10.53641 -423.439335) (xy 10.591847 -423.445435) (xy 10.610296 -423.450258) (xy 22.342346 -423.450258)
			(xy 22.346417 -423.394636) (xy 22.358543 -423.340199) (xy 22.378466 -423.288108) (xy 22.405762 -423.239473)
			(xy 22.439848 -423.19533) (xy 22.479997 -423.156621) (xy 22.525355 -423.12417) (xy 22.574955 -423.098669)
			(xy 22.627739 -423.080662) (xy 22.682582 -423.070532) (xy 22.738316 -423.068495) (xy 22.793753 -423.074595)
			(xy 22.84771 -423.088701) (xy 22.899039 -423.110513) (xy 22.946645 -423.139567) (xy 22.989513 -423.175242)
			(xy 23.02673 -423.216779) (xy 23.057503 -423.263292) (xy 23.081175 -423.313789) (xy 23.097243 -423.367196)
			(xy 23.105363 -423.422372) (xy 23.105872 -423.450258) (xy 23.105363 -423.478144) (xy 23.10072 -423.509694)
			(xy 25.129488 -423.509694) (xy 25.133559 -423.454072) (xy 25.145685 -423.399635) (xy 25.165608 -423.347544)
			(xy 25.192904 -423.298909) (xy 25.22699 -423.254766) (xy 25.267139 -423.216057) (xy 25.312497 -423.183606)
			(xy 25.362097 -423.158105) (xy 25.414881 -423.140098) (xy 25.469724 -423.129968) (xy 25.525458 -423.127931)
			(xy 25.580895 -423.134031) (xy 25.634852 -423.148137) (xy 25.686181 -423.169949) (xy 25.733787 -423.199003)
			(xy 25.776655 -423.234678) (xy 25.813872 -423.276215) (xy 25.844645 -423.322728) (xy 25.868317 -423.373225)
			(xy 25.870402 -423.380154) (xy 34.174174 -423.380154) (xy 34.178245 -423.324532) (xy 34.190371 -423.270095)
			(xy 34.210294 -423.218004) (xy 34.23759 -423.169369) (xy 34.271676 -423.125226) (xy 34.311825 -423.086517)
			(xy 34.357183 -423.054066) (xy 34.406783 -423.028565) (xy 34.459567 -423.010558) (xy 34.51441 -423.000428)
			(xy 34.570144 -422.998391) (xy 34.625581 -423.004491) (xy 34.679538 -423.018597) (xy 34.730867 -423.040409)
			(xy 34.778473 -423.069463) (xy 34.821341 -423.105138) (xy 34.858558 -423.146675) (xy 34.889331 -423.193188)
			(xy 34.913003 -423.243685) (xy 34.929071 -423.297092) (xy 34.937191 -423.352268) (xy 34.9377 -423.380154)
			(xy 34.937191 -423.40804) (xy 34.929071 -423.463216) (xy 34.913003 -423.516623) (xy 34.889331 -423.56712)
			(xy 34.858558 -423.613633) (xy 34.821341 -423.65517) (xy 34.778473 -423.690845) (xy 34.730867 -423.719899)
			(xy 34.679538 -423.741711) (xy 34.625581 -423.755817) (xy 34.570144 -423.761917) (xy 34.51441 -423.75988)
			(xy 34.459567 -423.74975) (xy 34.406783 -423.731743) (xy 34.357183 -423.706242) (xy 34.311825 -423.673791)
			(xy 34.271676 -423.635082) (xy 34.23759 -423.590939) (xy 34.210294 -423.542304) (xy 34.190371 -423.490213)
			(xy 34.178245 -423.435776) (xy 34.174174 -423.380154) (xy 25.870402 -423.380154) (xy 25.884385 -423.426632)
			(xy 25.892505 -423.481808) (xy 25.893014 -423.509694) (xy 25.892505 -423.53758) (xy 25.884385 -423.592756)
			(xy 25.868317 -423.646163) (xy 25.844645 -423.69666) (xy 25.813872 -423.743173) (xy 25.776655 -423.78471)
			(xy 25.733787 -423.820385) (xy 25.686181 -423.849439) (xy 25.634852 -423.871251) (xy 25.580895 -423.885357)
			(xy 25.525458 -423.891457) (xy 25.469724 -423.88942) (xy 25.414881 -423.87929) (xy 25.362097 -423.861283)
			(xy 25.312497 -423.835782) (xy 25.267139 -423.803331) (xy 25.22699 -423.764622) (xy 25.192904 -423.720479)
			(xy 25.165608 -423.671844) (xy 25.145685 -423.619753) (xy 25.133559 -423.565316) (xy 25.129488 -423.509694)
			(xy 23.10072 -423.509694) (xy 23.097243 -423.53332) (xy 23.081175 -423.586727) (xy 23.057503 -423.637224)
			(xy 23.02673 -423.683737) (xy 22.989513 -423.725274) (xy 22.946645 -423.760949) (xy 22.899039 -423.790003)
			(xy 22.84771 -423.811815) (xy 22.793753 -423.825921) (xy 22.738316 -423.832021) (xy 22.682582 -423.829984)
			(xy 22.627739 -423.819854) (xy 22.574955 -423.801847) (xy 22.525355 -423.776346) (xy 22.479997 -423.743895)
			(xy 22.439848 -423.705186) (xy 22.405762 -423.661043) (xy 22.378466 -423.612408) (xy 22.358543 -423.560317)
			(xy 22.346417 -423.50588) (xy 22.342346 -423.450258) (xy 10.610296 -423.450258) (xy 10.645804 -423.459541)
			(xy 10.697133 -423.481353) (xy 10.744739 -423.510407) (xy 10.787607 -423.546082) (xy 10.824824 -423.587619)
			(xy 10.855597 -423.634132) (xy 10.879269 -423.684629) (xy 10.895337 -423.738036) (xy 10.903457 -423.793212)
			(xy 10.903966 -423.821098) (xy 10.903457 -423.848984) (xy 10.895337 -423.90416) (xy 10.879269 -423.957567)
			(xy 10.855597 -424.008064) (xy 10.824824 -424.054577) (xy 10.787607 -424.096114) (xy 10.744739 -424.131789)
			(xy 10.697133 -424.160843) (xy 10.693295 -424.162474) (xy 15.206978 -424.162474) (xy 15.211049 -424.106852)
			(xy 15.223175 -424.052415) (xy 15.243098 -424.000324) (xy 15.270394 -423.951689) (xy 15.30448 -423.907546)
			(xy 15.344629 -423.868837) (xy 15.389987 -423.836386) (xy 15.439587 -423.810885) (xy 15.492371 -423.792878)
			(xy 15.547214 -423.782748) (xy 15.602948 -423.780711) (xy 15.658385 -423.786811) (xy 15.712342 -423.800917)
			(xy 15.763671 -423.822729) (xy 15.811277 -423.851783) (xy 15.854145 -423.887458) (xy 15.891362 -423.928995)
			(xy 15.922135 -423.975508) (xy 15.945807 -424.026005) (xy 15.961875 -424.079412) (xy 15.969995 -424.134588)
			(xy 15.970258 -424.149012) (xy 17.293588 -424.149012) (xy 17.297659 -424.09339) (xy 17.309785 -424.038953)
			(xy 17.329708 -423.986862) (xy 17.357004 -423.938227) (xy 17.39109 -423.894084) (xy 17.431239 -423.855375)
			(xy 17.476597 -423.822924) (xy 17.526197 -423.797423) (xy 17.578981 -423.779416) (xy 17.633824 -423.769286)
			(xy 17.689558 -423.767249) (xy 17.744995 -423.773349) (xy 17.798952 -423.787455) (xy 17.850281 -423.809267)
			(xy 17.897887 -423.838321) (xy 17.940755 -423.873996) (xy 17.977972 -423.915533) (xy 18.008745 -423.962046)
			(xy 18.032417 -424.012543) (xy 18.048485 -424.06595) (xy 18.056605 -424.121126) (xy 18.057114 -424.149012)
			(xy 18.056605 -424.176898) (xy 18.048485 -424.232074) (xy 18.032417 -424.285481) (xy 18.029663 -424.291356)
			(xy 21.309229 -424.291356) (xy 21.309229 -424.236844) (xy 21.316987 -424.182887) (xy 21.332346 -424.130583)
			(xy 21.354992 -424.080997) (xy 21.384465 -424.035139) (xy 21.420164 -423.993943) (xy 21.461363 -423.958247)
			(xy 21.507224 -423.928778) (xy 21.556811 -423.906135) (xy 21.609116 -423.890781) (xy 21.663074 -423.883027)
			(xy 21.69033 -423.882566) (xy 21.717154 -423.883035) (xy 21.770274 -423.890549) (xy 21.821819 -423.905425)
			(xy 21.870774 -423.92737) (xy 21.916176 -423.955951) (xy 21.957129 -423.990607) (xy 21.975318 -424.010328)
			(xy 21.981281 -424.016537) (xy 21.996352 -424.024838) (xy 22.004782 -424.026584) (xy 22.0345 -424.031664)
			(xy 22.043235 -424.032695) (xy 22.060509 -424.029433) (xy 22.068282 -424.025314) (xy 22.097543 -424.008896)
			(xy 22.159469 -423.983064) (xy 22.22425 -423.965587) (xy 22.290765 -423.956766) (xy 22.324314 -423.956226)
			(xy 22.355048 -423.956625) (xy 22.416067 -423.964035) (xy 22.475748 -423.978748) (xy 22.53322 -424.000546)
			(xy 22.587645 -424.029114) (xy 22.638231 -424.064034) (xy 22.684238 -424.104796) (xy 22.724996 -424.150807)
			(xy 22.759911 -424.201396) (xy 22.760279 -424.202098) (xy 39.071294 -424.202098) (xy 39.075365 -424.146476)
			(xy 39.087491 -424.092039) (xy 39.107414 -424.039948) (xy 39.13471 -423.991313) (xy 39.168796 -423.94717)
			(xy 39.208945 -423.908461) (xy 39.254303 -423.87601) (xy 39.303903 -423.850509) (xy 39.356687 -423.832502)
			(xy 39.41153 -423.822372) (xy 39.467264 -423.820335) (xy 39.522701 -423.826435) (xy 39.576658 -423.840541)
			(xy 39.627987 -423.862353) (xy 39.675593 -423.891407) (xy 39.718461 -423.927082) (xy 39.755678 -423.968619)
			(xy 39.786451 -424.015132) (xy 39.810123 -424.065629) (xy 39.826191 -424.119036) (xy 39.834311 -424.174212)
			(xy 39.83482 -424.202098) (xy 39.834311 -424.229984) (xy 39.826191 -424.28516) (xy 39.810123 -424.338567)
			(xy 39.786451 -424.389064) (xy 39.755678 -424.435577) (xy 39.718461 -424.477114) (xy 39.675593 -424.512789)
			(xy 39.627987 -424.541843) (xy 39.576658 -424.563655) (xy 39.522701 -424.577761) (xy 39.467264 -424.583861)
			(xy 39.41153 -424.581824) (xy 39.356687 -424.571694) (xy 39.303903 -424.553687) (xy 39.254303 -424.528186)
			(xy 39.208945 -424.495735) (xy 39.168796 -424.457026) (xy 39.13471 -424.412883) (xy 39.107414 -424.364248)
			(xy 39.087491 -424.312157) (xy 39.075365 -424.25772) (xy 39.071294 -424.202098) (xy 22.760279 -424.202098)
			(xy 22.788473 -424.255824) (xy 22.810267 -424.313298) (xy 22.824973 -424.37298) (xy 22.832378 -424.434)
			(xy 22.832822 -424.464734) (xy 22.832255 -424.49969) (xy 22.822689 -424.568943) (xy 22.80682 -424.625262)
			(xy 47.946816 -424.625262) (xy 47.950887 -424.56964) (xy 47.963013 -424.515203) (xy 47.982936 -424.463112)
			(xy 48.010232 -424.414477) (xy 48.044318 -424.370334) (xy 48.084467 -424.331625) (xy 48.129825 -424.299174)
			(xy 48.179425 -424.273673) (xy 48.232209 -424.255666) (xy 48.287052 -424.245536) (xy 48.342786 -424.243499)
			(xy 48.398223 -424.249599) (xy 48.45218 -424.263705) (xy 48.503509 -424.285517) (xy 48.551115 -424.314571)
			(xy 48.593983 -424.350246) (xy 48.6312 -424.391783) (xy 48.661973 -424.438296) (xy 48.685645 -424.488793)
			(xy 48.701713 -424.5422) (xy 48.709833 -424.597376) (xy 48.710342 -424.625262) (xy 48.709833 -424.653148)
			(xy 48.701713 -424.708324) (xy 48.685645 -424.761731) (xy 48.661973 -424.812228) (xy 48.6312 -424.858741)
			(xy 48.593983 -424.900278) (xy 48.551115 -424.935953) (xy 48.503509 -424.965007) (xy 48.45218 -424.986819)
			(xy 48.398223 -425.000925) (xy 48.342786 -425.007025) (xy 48.287052 -425.004988) (xy 48.232209 -424.994858)
			(xy 48.179425 -424.976851) (xy 48.129825 -424.95135) (xy 48.084467 -424.918899) (xy 48.044318 -424.88019)
			(xy 48.010232 -424.836047) (xy 47.982936 -424.787412) (xy 47.963013 -424.735321) (xy 47.950887 -424.680884)
			(xy 47.946816 -424.625262) (xy 22.80682 -424.625262) (xy 22.803728 -424.636234) (xy 22.77573 -424.700294)
			(xy 22.739222 -424.759916) (xy 22.717506 -424.787314) (xy 22.71223 -424.79431) (xy 22.706387 -424.810815)
			(xy 22.706076 -424.819572) (xy 22.706076 -424.973496) (xy 22.706447 -424.982242) (xy 22.712279 -424.998733)
			(xy 22.717506 -425.005754) (xy 22.739199 -425.033168) (xy 22.775699 -425.09279) (xy 22.803696 -425.156847)
			(xy 22.822661 -425.224132) (xy 22.832097 -425.29235) (xy 40.980366 -425.29235) (xy 40.980366 -425.23785)
			(xy 40.988121 -425.183904) (xy 41.003475 -425.131611) (xy 41.026114 -425.082034) (xy 41.055577 -425.036185)
			(xy 41.091266 -424.994994) (xy 41.132452 -424.959301) (xy 41.178299 -424.929833) (xy 41.227873 -424.907189)
			(xy 41.280165 -424.89183) (xy 41.33411 -424.884069) (xy 41.36136 -424.88358) (xy 41.388407 -424.884089)
			(xy 41.44196 -424.891731) (xy 41.493897 -424.906854) (xy 41.543182 -424.929154) (xy 41.588826 -424.958187)
			(xy 41.629916 -424.99337) (xy 41.648126 -425.013374) (xy 41.654118 -425.019724) (xy 41.66931 -425.028299)
			(xy 41.677844 -425.030138) (xy 41.707308 -425.035218) (xy 41.716089 -425.036325) (xy 41.733497 -425.033215)
			(xy 41.741344 -425.029122) (xy 41.770427 -425.012977) (xy 41.831889 -424.987539) (xy 41.896139 -424.97032)
			(xy 41.962085 -424.961613) (xy 41.995344 -424.96105) (xy 42.026074 -424.961514) (xy 42.087086 -424.968927)
			(xy 42.14676 -424.983639) (xy 42.204226 -425.005436) (xy 42.258646 -425.034) (xy 42.309226 -425.068915)
			(xy 42.35523 -425.109671) (xy 42.395986 -425.155675) (xy 42.430901 -425.206256) (xy 42.459465 -425.260676)
			(xy 42.481262 -425.318142) (xy 42.495973 -425.377816) (xy 42.503386 -425.438828) (xy 42.503852 -425.469558)
			(xy 42.503292 -425.504514) (xy 42.493723 -425.573768) (xy 42.47476 -425.641058) (xy 42.446761 -425.705118)
			(xy 42.410252 -425.76474) (xy 42.388536 -425.792138) (xy 42.383218 -425.799123) (xy 42.377257 -425.815625)
			(xy 42.376852 -425.824396) (xy 42.376852 -425.952877) (xy 45.855376 -425.952877) (xy 45.855376 -425.888955)
			(xy 45.863387 -425.825537) (xy 45.879284 -425.763623) (xy 45.902816 -425.70419) (xy 45.93361 -425.648175)
			(xy 45.971183 -425.59646) (xy 46.01494 -425.549863) (xy 46.064193 -425.509118) (xy 46.118164 -425.474867)
			(xy 46.176003 -425.44765) (xy 46.236796 -425.427897) (xy 46.299586 -425.415919) (xy 46.363382 -425.411906)
			(xy 46.427178 -425.415919) (xy 46.489968 -425.427897) (xy 46.550761 -425.44765) (xy 46.6086 -425.474867)
			(xy 46.662571 -425.509118) (xy 46.711824 -425.549863) (xy 46.755581 -425.59646) (xy 46.783671 -425.635123)
			(xy 50.227732 -425.635123) (xy 50.227732 -425.571201) (xy 50.235743 -425.507783) (xy 50.25164 -425.445869)
			(xy 50.275172 -425.386436) (xy 50.305966 -425.330421) (xy 50.343539 -425.278706) (xy 50.387296 -425.232109)
			(xy 50.436549 -425.191364) (xy 50.49052 -425.157113) (xy 50.548359 -425.129896) (xy 50.609152 -425.110143)
			(xy 50.671942 -425.098165) (xy 50.735738 -425.094152) (xy 50.799534 -425.098165) (xy 50.862324 -425.110143)
			(xy 50.923117 -425.129896) (xy 50.980956 -425.157113) (xy 51.034927 -425.191364) (xy 51.08418 -425.232109)
			(xy 51.127937 -425.278706) (xy 51.16551 -425.330421) (xy 51.196304 -425.386436) (xy 51.219836 -425.445869)
			(xy 51.235733 -425.507783) (xy 51.243744 -425.571201) (xy 51.244246 -425.603162) (xy 51.243744 -425.635123)
			(xy 51.235733 -425.698541) (xy 51.219836 -425.760455) (xy 51.196304 -425.819888) (xy 51.16551 -425.875903)
			(xy 51.127937 -425.927618) (xy 51.08418 -425.974215) (xy 51.034927 -426.01496) (xy 50.980956 -426.049211)
			(xy 50.923117 -426.076428) (xy 50.862324 -426.096181) (xy 50.799534 -426.108159) (xy 50.735738 -426.112173)
			(xy 50.671942 -426.108159) (xy 50.609152 -426.096181) (xy 50.548359 -426.076428) (xy 50.49052 -426.049211)
			(xy 50.436549 -426.01496) (xy 50.387296 -425.974215) (xy 50.343539 -425.927618) (xy 50.305966 -425.875903)
			(xy 50.275172 -425.819888) (xy 50.25164 -425.760455) (xy 50.235743 -425.698541) (xy 50.227732 -425.635123)
			(xy 46.783671 -425.635123) (xy 46.793154 -425.648175) (xy 46.823948 -425.70419) (xy 46.84748 -425.763623)
			(xy 46.863377 -425.825537) (xy 46.871388 -425.888955) (xy 46.87189 -425.920916) (xy 46.871388 -425.952877)
			(xy 46.863377 -426.016295) (xy 46.84748 -426.078209) (xy 46.823948 -426.137642) (xy 46.793154 -426.193657)
			(xy 46.755581 -426.245372) (xy 46.711824 -426.291969) (xy 46.662571 -426.332714) (xy 46.6086 -426.366965)
			(xy 46.550761 -426.394182) (xy 46.489968 -426.413935) (xy 46.427178 -426.425913) (xy 46.363382 -426.429927)
			(xy 46.299586 -426.425913) (xy 46.236796 -426.413935) (xy 46.176003 -426.394182) (xy 46.118164 -426.366965)
			(xy 46.064193 -426.332714) (xy 46.01494 -426.291969) (xy 45.971183 -426.245372) (xy 45.93361 -426.193657)
			(xy 45.902816 -426.137642) (xy 45.879284 -426.078209) (xy 45.863387 -426.016295) (xy 45.855376 -425.952877)
			(xy 42.376852 -425.952877) (xy 42.376852 -425.97832) (xy 42.377213 -425.987097) (xy 42.3832 -426.003599)
			(xy 42.388536 -426.010578) (xy 42.410244 -426.037981) (xy 42.446741 -426.097606) (xy 42.474734 -426.161666)
			(xy 42.493696 -426.228954) (xy 42.50327 -426.298204) (xy 42.503852 -426.333158) (xy 42.503305 -426.363886)
			(xy 42.495902 -426.424896) (xy 42.481199 -426.484568) (xy 42.459411 -426.542033) (xy 42.430855 -426.596452)
			(xy 42.395948 -426.647033) (xy 42.382163 -426.662596) (xy 49.186844 -426.662596) (xy 49.190915 -426.606974)
			(xy 49.203041 -426.552537) (xy 49.222964 -426.500446) (xy 49.25026 -426.451811) (xy 49.284346 -426.407668)
			(xy 49.324495 -426.368959) (xy 49.369853 -426.336508) (xy 49.419453 -426.311007) (xy 49.472237 -426.293)
			(xy 49.52708 -426.28287) (xy 49.582814 -426.280833) (xy 49.638251 -426.286933) (xy 49.692208 -426.301039)
			(xy 49.743537 -426.322851) (xy 49.791143 -426.351905) (xy 49.834011 -426.38758) (xy 49.871228 -426.429117)
			(xy 49.902001 -426.47563) (xy 49.925673 -426.526127) (xy 49.941741 -426.579534) (xy 49.949861 -426.63471)
			(xy 49.95037 -426.662596) (xy 49.949861 -426.690482) (xy 49.941741 -426.745658) (xy 49.925673 -426.799065)
			(xy 49.902001 -426.849562) (xy 49.871228 -426.896075) (xy 49.834011 -426.937612) (xy 49.791143 -426.973287)
			(xy 49.743537 -427.002341) (xy 49.706824 -427.017942) (xy 51.38496 -427.017942) (xy 51.389031 -426.96232)
			(xy 51.401157 -426.907883) (xy 51.42108 -426.855792) (xy 51.448376 -426.807157) (xy 51.482462 -426.763014)
			(xy 51.522611 -426.724305) (xy 51.567969 -426.691854) (xy 51.617569 -426.666353) (xy 51.670353 -426.648346)
			(xy 51.725196 -426.638216) (xy 51.78093 -426.636179) (xy 51.836367 -426.642279) (xy 51.890324 -426.656385)
			(xy 51.941653 -426.678197) (xy 51.989259 -426.707251) (xy 52.032127 -426.742926) (xy 52.069344 -426.784463)
			(xy 52.100117 -426.830976) (xy 52.123789 -426.881473) (xy 52.139857 -426.93488) (xy 52.147977 -426.990056)
			(xy 52.148486 -427.017942) (xy 52.147977 -427.045828) (xy 52.139857 -427.101004) (xy 52.123789 -427.154411)
			(xy 52.100117 -427.204908) (xy 52.069344 -427.251421) (xy 52.032127 -427.292958) (xy 51.989259 -427.328633)
			(xy 51.941653 -427.357687) (xy 51.890324 -427.379499) (xy 51.836367 -427.393605) (xy 51.78093 -427.399705)
			(xy 51.725196 -427.397668) (xy 51.670353 -427.387538) (xy 51.617569 -427.369531) (xy 51.567969 -427.34403)
			(xy 51.522611 -427.311579) (xy 51.482462 -427.27287) (xy 51.448376 -427.228727) (xy 51.42108 -427.180092)
			(xy 51.401157 -427.128001) (xy 51.389031 -427.073564) (xy 51.38496 -427.017942) (xy 49.706824 -427.017942)
			(xy 49.692208 -427.024153) (xy 49.638251 -427.038259) (xy 49.582814 -427.044359) (xy 49.52708 -427.042322)
			(xy 49.472237 -427.032192) (xy 49.419453 -427.014185) (xy 49.369853 -426.988684) (xy 49.324495 -426.956233)
			(xy 49.284346 -426.917524) (xy 49.25026 -426.873381) (xy 49.222964 -426.824746) (xy 49.203041 -426.772655)
			(xy 49.190915 -426.718218) (xy 49.186844 -426.662596) (xy 42.382163 -426.662596) (xy 42.355199 -426.693038)
			(xy 42.309201 -426.733795) (xy 42.258626 -426.768711) (xy 42.204211 -426.797276) (xy 42.14675 -426.819074)
			(xy 42.08708 -426.833786) (xy 42.026072 -426.841199) (xy 41.995344 -426.841666) (xy 41.963619 -426.841168)
			(xy 41.900661 -426.833274) (xy 41.839172 -426.817615) (xy 41.780107 -426.794435) (xy 41.752012 -426.77969)
			(xy 41.744033 -426.7758) (xy 41.726487 -426.773207) (xy 41.717722 -426.77461) (xy 41.688004 -426.780452)
			(xy 41.679519 -426.782581) (xy 41.664589 -426.791678) (xy 41.658794 -426.798232) (xy 41.64056 -426.819702)
			(xy 41.598869 -426.857577) (xy 41.552065 -426.888913) (xy 41.501163 -426.913031) (xy 41.44727 -426.929406)
			(xy 41.391555 -426.937683) (xy 41.363392 -426.938186) (xy 41.33614 -426.937744) (xy 41.28219 -426.929986)
			(xy 41.229893 -426.914629) (xy 41.180314 -426.891986) (xy 41.134462 -426.862518) (xy 41.09327 -426.826824)
			(xy 41.057577 -426.785632) (xy 41.02811 -426.739779) (xy 41.005468 -426.6902) (xy 40.990113 -426.637903)
			(xy 40.982356 -426.583952) (xy 40.982356 -426.529448) (xy 40.990113 -426.475497) (xy 41.005468 -426.4232)
			(xy 41.02811 -426.373621) (xy 41.057577 -426.327768) (xy 41.09327 -426.286576) (xy 41.134462 -426.250882)
			(xy 41.180314 -426.221414) (xy 41.229893 -426.198771) (xy 41.28219 -426.183414) (xy 41.33614 -426.175656)
			(xy 41.363392 -426.17517) (xy 41.383031 -426.175441) (xy 41.422097 -426.179517) (xy 41.44137 -426.183298)
			(xy 41.449993 -426.184661) (xy 41.467262 -426.182206) (xy 41.475152 -426.178472) (xy 41.502076 -426.164502)
			(xy 41.50978 -426.160063) (xy 41.521753 -426.146936) (xy 41.525444 -426.138848) (xy 41.540386 -426.104427)
			(xy 41.578896 -426.040026) (xy 41.602152 -426.010578) (xy 41.607462 -426.003588) (xy 41.613428 -425.98709)
			(xy 41.613836 -425.97832) (xy 41.613836 -425.824396) (xy 41.61347 -425.815619) (xy 41.607487 -425.799117)
			(xy 41.602152 -425.792138) (xy 41.581332 -425.765885) (xy 41.546034 -425.70893) (xy 41.531794 -425.6786)
			(xy 41.527865 -425.670743) (xy 41.515647 -425.658138) (xy 41.507918 -425.653962) (xy 41.48074 -425.640754)
			(xy 41.472765 -425.637291) (xy 41.455502 -425.635338) (xy 41.446958 -425.636944) (xy 41.425848 -425.641464)
			(xy 41.382947 -425.646308) (xy 41.36136 -425.646596) (xy 41.33411 -425.646131) (xy 41.280165 -425.63837)
			(xy 41.227873 -425.623011) (xy 41.178299 -425.600367) (xy 41.132452 -425.570899) (xy 41.091266 -425.535206)
			(xy 41.055577 -425.494015) (xy 41.026114 -425.448166) (xy 41.003475 -425.398589) (xy 40.988121 -425.346296)
			(xy 40.980366 -425.29235) (xy 22.832097 -425.29235) (xy 22.832239 -425.29338) (xy 22.832822 -425.328334)
			(xy 22.832376 -425.359065) (xy 22.824964 -425.420079) (xy 22.810252 -425.479755) (xy 22.788455 -425.537222)
			(xy 22.75989 -425.591643) (xy 22.724973 -425.642225) (xy 22.684215 -425.688229) (xy 22.638209 -425.728986)
			(xy 22.587626 -425.7639) (xy 22.533204 -425.792463) (xy 22.475736 -425.814258) (xy 22.416059 -425.828968)
			(xy 22.355045 -425.836378) (xy 22.324314 -425.836842) (xy 22.290763 -425.836329) (xy 22.22424 -425.827532)
			(xy 22.159456 -425.810049) (xy 22.097539 -425.784184) (xy 22.068282 -425.767754) (xy 22.060514 -425.763621)
			(xy 22.043237 -425.760365) (xy 22.0345 -425.761404) (xy 22.004782 -425.766484) (xy 21.996359 -425.768248)
			(xy 21.981298 -425.776552) (xy 21.975318 -425.78274) (xy 21.95711 -425.802444) (xy 21.916165 -425.837108)
			(xy 21.870769 -425.865697) (xy 21.821817 -425.887648) (xy 21.770273 -425.902529) (xy 21.717154 -425.910045)
			(xy 21.69033 -425.910502) (xy 21.663075 -425.910053) (xy 21.60912 -425.902299) (xy 21.556818 -425.886945)
			(xy 21.507233 -425.864304) (xy 21.461376 -425.834837) (xy 21.420179 -425.799142) (xy 21.384481 -425.757948)
			(xy 21.35501 -425.712093) (xy 21.332365 -425.66251) (xy 21.317007 -425.610209) (xy 21.309249 -425.556255)
			(xy 21.309249 -425.501745) (xy 21.317007 -425.447791) (xy 21.332365 -425.39549) (xy 21.35501 -425.345907)
			(xy 21.384481 -425.300052) (xy 21.420179 -425.258858) (xy 21.461376 -425.223163) (xy 21.507233 -425.193696)
			(xy 21.556818 -425.171055) (xy 21.60912 -425.155701) (xy 21.663075 -425.147947) (xy 21.69033 -425.147486)
			(xy 21.712313 -425.147816) (xy 21.755982 -425.152912) (xy 21.777452 -425.157646) (xy 21.785937 -425.159206)
			(xy 21.803068 -425.157273) (xy 21.81098 -425.153836) (xy 21.838158 -425.140882) (xy 21.845938 -425.136709)
			(xy 21.858287 -425.124113) (xy 21.862288 -425.116244) (xy 21.876351 -425.086779) (xy 21.91087 -425.031363)
			(xy 21.931122 -425.005754) (xy 21.936372 -424.998741) (xy 21.942231 -424.982249) (xy 21.942552 -424.973496)
			(xy 21.942552 -424.819572) (xy 21.94221 -424.810823) (xy 21.93636 -424.794331) (xy 21.931122 -424.787314)
			(xy 21.910839 -424.761727) (xy 21.876311 -424.70631) (xy 21.862288 -424.676824) (xy 21.858268 -424.668967)
			(xy 21.845932 -424.656364) (xy 21.838158 -424.652186) (xy 21.81098 -424.639232) (xy 21.803084 -424.635737)
			(xy 21.785935 -424.633803) (xy 21.777452 -424.635422) (xy 21.755985 -424.640171) (xy 21.712314 -424.645261)
			(xy 21.69033 -424.645582) (xy 21.663074 -424.645173) (xy 21.609116 -424.637419) (xy 21.556811 -424.622065)
			(xy 21.507224 -424.599422) (xy 21.461363 -424.569953) (xy 21.420164 -424.534257) (xy 21.384465 -424.493061)
			(xy 21.354992 -424.447203) (xy 21.332346 -424.397617) (xy 21.316987 -424.345313) (xy 21.309229 -424.291356)
			(xy 18.029663 -424.291356) (xy 18.008745 -424.335978) (xy 17.977972 -424.382491) (xy 17.940755 -424.424028)
			(xy 17.897887 -424.459703) (xy 17.850281 -424.488757) (xy 17.798952 -424.510569) (xy 17.744995 -424.524675)
			(xy 17.689558 -424.530775) (xy 17.633824 -424.528738) (xy 17.578981 -424.518608) (xy 17.526197 -424.500601)
			(xy 17.476597 -424.4751) (xy 17.431239 -424.442649) (xy 17.39109 -424.40394) (xy 17.357004 -424.359797)
			(xy 17.329708 -424.311162) (xy 17.309785 -424.259071) (xy 17.297659 -424.204634) (xy 17.293588 -424.149012)
			(xy 15.970258 -424.149012) (xy 15.970504 -424.162474) (xy 15.969995 -424.19036) (xy 15.961875 -424.245536)
			(xy 15.945807 -424.298943) (xy 15.922135 -424.34944) (xy 15.891362 -424.395953) (xy 15.854145 -424.43749)
			(xy 15.811277 -424.473165) (xy 15.763671 -424.502219) (xy 15.712342 -424.524031) (xy 15.658385 -424.538137)
			(xy 15.602948 -424.544237) (xy 15.547214 -424.5422) (xy 15.492371 -424.53207) (xy 15.439587 -424.514063)
			(xy 15.389987 -424.488562) (xy 15.344629 -424.456111) (xy 15.30448 -424.417402) (xy 15.270394 -424.373259)
			(xy 15.243098 -424.324624) (xy 15.223175 -424.272533) (xy 15.211049 -424.218096) (xy 15.206978 -424.162474)
			(xy 10.693295 -424.162474) (xy 10.645804 -424.182655) (xy 10.591847 -424.196761) (xy 10.53641 -424.202861)
			(xy 10.480676 -424.200824) (xy 10.425833 -424.190694) (xy 10.373049 -424.172687) (xy 10.323449 -424.147186)
			(xy 10.278091 -424.114735) (xy 10.237942 -424.076026) (xy 10.203856 -424.031883) (xy 10.17656 -423.983248)
			(xy 10.156637 -423.931157) (xy 10.144511 -423.87672) (xy 10.14044 -423.821098) (xy 7.76986 -423.821098)
			(xy 7.76986 -425.887642) (xy 10.077958 -425.887642) (xy 10.078516 -425.852686) (xy 10.088085 -425.783432)
			(xy 10.107048 -425.716141) (xy 10.135048 -425.652081) (xy 10.171557 -425.59246) (xy 10.193274 -425.565062)
			(xy 10.198527 -425.558051) (xy 10.204382 -425.541557) (xy 10.204704 -425.532804) (xy 10.204704 -425.37888)
			(xy 10.204348 -425.370132) (xy 10.198506 -425.353641) (xy 10.193274 -425.346622) (xy 10.171567 -425.319218)
			(xy 10.13507 -425.259593) (xy 10.107076 -425.195534) (xy 10.088114 -425.128246) (xy 10.07854 -425.058996)
			(xy 10.077958 -425.024042) (xy 10.078477 -424.993312) (xy 10.08588 -424.9323) (xy 10.100584 -424.872625)
			(xy 10.122373 -424.815157) (xy 10.150931 -424.760735) (xy 10.18584 -424.710152) (xy 10.226592 -424.664146)
			(xy 10.272592 -424.623387) (xy 10.32317 -424.58847) (xy 10.377588 -424.559904) (xy 10.435052 -424.538106)
			(xy 10.494725 -424.523394) (xy 10.555736 -424.515982) (xy 10.586466 -424.515534) (xy 10.616819 -424.516005)
			(xy 10.677093 -424.523228) (xy 10.736079 -424.537576) (xy 10.792937 -424.558844) (xy 10.846859 -424.58673)
			(xy 10.872216 -424.603418) (xy 10.880598 -424.60926) (xy 10.899902 -424.613324) (xy 10.989818 -424.596814)
			(xy 11.006582 -424.586146) (xy 11.012424 -424.578018) (xy 11.027771 -424.556941) (xy 11.063348 -424.518828)
			(xy 11.103787 -424.485917) (xy 11.148332 -424.458823) (xy 11.196154 -424.43805) (xy 11.246359 -424.423986)
			(xy 11.298013 -424.416894) (xy 11.324082 -424.416474) (xy 11.351334 -424.416972) (xy 11.405285 -424.424727)
			(xy 11.457582 -424.44008) (xy 11.507162 -424.462721) (xy 11.553016 -424.492187) (xy 11.594208 -424.527879)
			(xy 11.629902 -424.56907) (xy 11.659371 -424.614922) (xy 11.682013 -424.664501) (xy 11.69737 -424.716798)
			(xy 11.705127 -424.770748) (xy 11.705127 -424.825252) (xy 11.69737 -424.879202) (xy 11.682013 -424.931499)
			(xy 11.659371 -424.981078) (xy 11.629902 -425.02693) (xy 11.594208 -425.068121) (xy 11.553016 -425.103813)
			(xy 11.507162 -425.133279) (xy 11.457582 -425.15592) (xy 11.405285 -425.171273) (xy 11.351334 -425.179028)
			(xy 11.324082 -425.17949) (xy 11.289592 -425.178747) (xy 11.221734 -425.166351) (xy 11.189208 -425.154852)
			(xy 11.17981 -425.151296) (xy 11.159998 -425.151804) (xy 11.076432 -425.188634) (xy 11.062716 -425.202858)
			(xy 11.058906 -425.212256) (xy 11.043759 -425.248393) (xy 11.003951 -425.315879) (xy 10.979658 -425.346622)
			(xy 10.974373 -425.353612) (xy 10.968536 -425.370122) (xy 10.968228 -425.37888) (xy 10.968228 -425.532804)
			(xy 10.968585 -425.541552) (xy 10.974425 -425.558043) (xy 10.979658 -425.565062) (xy 11.003926 -425.595822)
			(xy 11.043732 -425.663305) (xy 11.058906 -425.699428) (xy 11.062716 -425.708826) (xy 11.076432 -425.72305)
			(xy 11.159998 -425.75988) (xy 11.17981 -425.760388) (xy 11.189208 -425.756832) (xy 11.221735 -425.745336)
			(xy 11.289592 -425.732938) (xy 11.324082 -425.732194) (xy 11.351336 -425.732652) (xy 11.405289 -425.740407)
			(xy 11.457589 -425.755762) (xy 11.507172 -425.778403) (xy 11.553028 -425.807871) (xy 11.594223 -425.843565)
			(xy 11.629918 -425.884758) (xy 11.659388 -425.930612) (xy 11.682032 -425.980194) (xy 11.697389 -426.032493)
			(xy 11.699497 -426.047154) (xy 33.539174 -426.047154) (xy 33.543245 -425.991532) (xy 33.555371 -425.937095)
			(xy 33.575294 -425.885004) (xy 33.60259 -425.836369) (xy 33.636676 -425.792226) (xy 33.676825 -425.753517)
			(xy 33.722183 -425.721066) (xy 33.771783 -425.695565) (xy 33.824567 -425.677558) (xy 33.87941 -425.667428)
			(xy 33.935144 -425.665391) (xy 33.990581 -425.671491) (xy 34.044538 -425.685597) (xy 34.095867 -425.707409)
			(xy 34.143473 -425.736463) (xy 34.186341 -425.772138) (xy 34.223558 -425.813675) (xy 34.254331 -425.860188)
			(xy 34.278003 -425.910685) (xy 34.285997 -425.937255) (xy 38.102449 -425.937255) (xy 38.102449 -425.882745)
			(xy 38.110208 -425.82879) (xy 38.125566 -425.776488) (xy 38.148212 -425.726904) (xy 38.177684 -425.681048)
			(xy 38.213382 -425.639854) (xy 38.25458 -425.60416) (xy 38.300439 -425.574692) (xy 38.350025 -425.552052)
			(xy 38.402329 -425.536699) (xy 38.456285 -425.528947) (xy 38.48354 -425.528486) (xy 38.508815 -425.528896)
			(xy 38.558922 -425.53557) (xy 38.607707 -425.548811) (xy 38.654313 -425.568384) (xy 38.676326 -425.58081)
			(xy 38.686711 -425.586161) (xy 38.709997 -425.587754) (xy 38.731618 -425.578965) (xy 38.739826 -425.57065)
			(xy 38.760511 -425.548195) (xy 38.806409 -425.507933) (xy 38.856797 -425.473456) (xy 38.910951 -425.445261)
			(xy 38.968092 -425.423753) (xy 39.027397 -425.409241) (xy 39.088013 -425.401935) (xy 39.11854 -425.401486)
			(xy 39.153496 -425.402048) (xy 39.22275 -425.411615) (xy 39.290041 -425.430577) (xy 39.354101 -425.458576)
			(xy 39.413722 -425.495085) (xy 39.44112 -425.516802) (xy 39.448114 -425.522081) (xy 39.46462 -425.527923)
			(xy 39.473378 -425.528232) (xy 39.627302 -425.528232) (xy 39.636048 -425.527862) (xy 39.652539 -425.522029)
			(xy 39.65956 -425.516802) (xy 39.686973 -425.495108) (xy 39.746595 -425.458607) (xy 39.810652 -425.430611)
			(xy 39.877938 -425.411646) (xy 39.947186 -425.402069) (xy 39.98214 -425.401486) (xy 40.012667 -425.401914)
			(xy 40.073281 -425.409229) (xy 40.132583 -425.423749) (xy 40.18972 -425.445264) (xy 40.24387 -425.473466)
			(xy 40.294254 -425.507948) (xy 40.340147 -425.548215) (xy 40.360854 -425.57065) (xy 40.369052 -425.578996)
			(xy 40.390671 -425.587854) (xy 40.413976 -425.586206) (xy 40.424354 -425.58081) (xy 40.446376 -425.568401)
			(xy 40.492981 -425.548829) (xy 40.541763 -425.535585) (xy 40.591866 -425.5289) (xy 40.61714 -425.528486)
			(xy 40.644389 -425.528986) (xy 40.698332 -425.536748) (xy 40.750621 -425.552106) (xy 40.800192 -425.574749)
			(xy 40.846037 -425.604216) (xy 40.887222 -425.639907) (xy 40.922908 -425.681095) (xy 40.95237 -425.726943)
			(xy 40.975008 -425.776517) (xy 40.990361 -425.828808) (xy 40.998116 -425.882751) (xy 40.998116 -425.937249)
			(xy 40.990361 -425.991192) (xy 40.975008 -426.043483) (xy 40.95237 -426.093057) (xy 40.922908 -426.138905)
			(xy 40.887222 -426.180093) (xy 40.846037 -426.215784) (xy 40.800192 -426.245251) (xy 40.750621 -426.267894)
			(xy 40.698332 -426.283252) (xy 40.644389 -426.291014) (xy 40.61714 -426.291502) (xy 40.591865 -426.291103)
			(xy 40.541757 -426.284425) (xy 40.492973 -426.271182) (xy 40.446367 -426.251606) (xy 40.424354 -426.239178)
			(xy 40.413976 -426.233811) (xy 40.390686 -426.232225) (xy 40.369062 -426.24102) (xy 40.360854 -426.249338)
			(xy 40.340126 -426.271752) (xy 40.294236 -426.312017) (xy 40.243856 -426.346498) (xy 40.189709 -426.374699)
			(xy 40.132575 -426.396214) (xy 40.073276 -426.410733) (xy 40.012665 -426.418048) (xy 39.98214 -426.418502)
			(xy 39.947184 -426.417954) (xy 39.877929 -426.408384) (xy 39.810638 -426.389419) (xy 39.746578 -426.361417)
			(xy 39.686957 -426.324904) (xy 39.65956 -426.303186) (xy 39.652545 -426.297939) (xy 39.636055 -426.292078)
			(xy 39.627302 -426.291756) (xy 39.473378 -426.291756) (xy 39.464629 -426.292099) (xy 39.448137 -426.297948)
			(xy 39.44112 -426.303186) (xy 39.413712 -426.324888) (xy 39.354089 -426.361388) (xy 39.290031 -426.389383)
			(xy 39.222744 -426.408346) (xy 39.153494 -426.41792) (xy 39.11854 -426.418502) (xy 39.088015 -426.418023)
			(xy 39.027402 -426.410718) (xy 38.968101 -426.396207) (xy 38.910964 -426.3747) (xy 38.856814 -426.346505)
			(xy 38.806428 -426.31203) (xy 38.760534 -426.27177) (xy 38.739826 -426.249338) (xy 38.731643 -426.240975)
			(xy 38.710016 -426.232123) (xy 38.686705 -426.233779) (xy 38.676326 -426.239178) (xy 38.654308 -426.251594)
			(xy 38.607702 -426.271164) (xy 38.558919 -426.284407) (xy 38.508814 -426.291089) (xy 38.48354 -426.291502)
			(xy 38.456285 -426.291053) (xy 38.402329 -426.283301) (xy 38.350025 -426.267948) (xy 38.300439 -426.245308)
			(xy 38.25458 -426.21584) (xy 38.213382 -426.180146) (xy 38.177684 -426.138952) (xy 38.148212 -426.093096)
			(xy 38.125566 -426.043512) (xy 38.110208 -425.99121) (xy 38.102449 -425.937255) (xy 34.285997 -425.937255)
			(xy 34.294071 -425.964092) (xy 34.302191 -426.019268) (xy 34.3027 -426.047154) (xy 34.302191 -426.07504)
			(xy 34.294071 -426.130216) (xy 34.278003 -426.183623) (xy 34.254331 -426.23412) (xy 34.223558 -426.280633)
			(xy 34.186341 -426.32217) (xy 34.143473 -426.357845) (xy 34.095867 -426.386899) (xy 34.044538 -426.408711)
			(xy 33.990581 -426.422817) (xy 33.935144 -426.428917) (xy 33.87941 -426.42688) (xy 33.824567 -426.41675)
			(xy 33.771783 -426.398743) (xy 33.722183 -426.373242) (xy 33.676825 -426.340791) (xy 33.636676 -426.302082)
			(xy 33.60259 -426.257939) (xy 33.575294 -426.209304) (xy 33.555371 -426.157213) (xy 33.543245 -426.102776)
			(xy 33.539174 -426.047154) (xy 11.699497 -426.047154) (xy 11.705147 -426.086446) (xy 11.705147 -426.140954)
			(xy 11.697389 -426.194907) (xy 11.682032 -426.247206) (xy 11.659388 -426.296788) (xy 11.629918 -426.342642)
			(xy 11.594223 -426.383835) (xy 11.553028 -426.419529) (xy 11.507172 -426.448997) (xy 11.457589 -426.471638)
			(xy 11.405289 -426.486993) (xy 11.351336 -426.494748) (xy 11.324082 -426.49521) (xy 11.298017 -426.494767)
			(xy 11.246374 -426.487655) (xy 11.19618 -426.473579) (xy 11.148369 -426.452801) (xy 11.103832 -426.425709)
			(xy 11.063397 -426.392806) (xy 11.027818 -426.354705) (xy 11.012424 -426.333666) (xy 11.006582 -426.325538)
			(xy 10.989818 -426.31487) (xy 10.899902 -426.29836) (xy 10.880598 -426.302424) (xy 10.872216 -426.308266)
			(xy 10.846866 -426.324968) (xy 10.792945 -426.352861) (xy 10.736085 -426.374134) (xy 10.677097 -426.388485)
			(xy 10.61682 -426.39571) (xy 10.586466 -426.39615) (xy 10.555735 -426.395688) (xy 10.494721 -426.388279)
			(xy 10.435045 -426.37357) (xy 10.377577 -426.351775) (xy 10.323156 -426.323212) (xy 10.272573 -426.288297)
			(xy 10.226569 -426.24754) (xy 10.185812 -426.201535) (xy 10.150897 -426.150953) (xy 10.122335 -426.096531)
			(xy 10.10054 -426.039063) (xy 10.085831 -425.979387) (xy 10.078422 -425.918373) (xy 10.077958 -425.887642)
			(xy 7.76986 -425.887642) (xy 7.76986 -427.839843) (xy 10.935202 -427.839843) (xy 10.935202 -427.775921)
			(xy 10.943213 -427.712503) (xy 10.95911 -427.650589) (xy 10.982642 -427.591156) (xy 11.013436 -427.535141)
			(xy 11.051009 -427.483426) (xy 11.094766 -427.436829) (xy 11.144019 -427.396084) (xy 11.19799 -427.361833)
			(xy 11.255829 -427.334616) (xy 11.316622 -427.314863) (xy 11.379412 -427.302885) (xy 11.443208 -427.298872)
			(xy 11.507004 -427.302885) (xy 11.569794 -427.314863) (xy 11.630587 -427.334616) (xy 11.688426 -427.361833)
			(xy 11.742397 -427.396084) (xy 11.79165 -427.436829) (xy 11.835407 -427.483426) (xy 11.87298 -427.535141)
			(xy 11.903774 -427.591156) (xy 11.927306 -427.650589) (xy 11.943203 -427.712503) (xy 11.947037 -427.742858)
			(xy 12.83919 -427.742858) (xy 12.843261 -427.687236) (xy 12.855387 -427.632799) (xy 12.87531 -427.580708)
			(xy 12.902606 -427.532073) (xy 12.936692 -427.48793) (xy 12.976841 -427.449221) (xy 13.022199 -427.41677)
			(xy 13.071799 -427.391269) (xy 13.124583 -427.373262) (xy 13.179426 -427.363132) (xy 13.23516 -427.361095)
			(xy 13.290597 -427.367195) (xy 13.344554 -427.381301) (xy 13.395883 -427.403113) (xy 13.443489 -427.432167)
			(xy 13.486357 -427.467842) (xy 13.523574 -427.509379) (xy 13.554347 -427.555892) (xy 13.578019 -427.606389)
			(xy 13.594087 -427.659796) (xy 13.602207 -427.714972) (xy 13.602716 -427.742858) (xy 13.602207 -427.770744)
			(xy 13.594087 -427.82592) (xy 13.578019 -427.879327) (xy 13.554347 -427.929824) (xy 13.523574 -427.976337)
			(xy 13.486357 -428.017874) (xy 13.443489 -428.053549) (xy 13.395883 -428.082603) (xy 13.344554 -428.104415)
			(xy 13.290597 -428.118521) (xy 13.23516 -428.124621) (xy 13.179426 -428.122584) (xy 13.124583 -428.112454)
			(xy 13.071799 -428.094447) (xy 13.022199 -428.068946) (xy 12.976841 -428.036495) (xy 12.936692 -427.997786)
			(xy 12.902606 -427.953643) (xy 12.87531 -427.905008) (xy 12.855387 -427.852917) (xy 12.843261 -427.79848)
			(xy 12.83919 -427.742858) (xy 11.947037 -427.742858) (xy 11.951214 -427.775921) (xy 11.951716 -427.807882)
			(xy 11.951214 -427.839843) (xy 11.943203 -427.903261) (xy 11.927306 -427.965175) (xy 11.903774 -428.024608)
			(xy 11.87298 -428.080623) (xy 11.835407 -428.132338) (xy 11.79165 -428.178935) (xy 11.742397 -428.21968)
			(xy 11.688426 -428.253931) (xy 11.630587 -428.281148) (xy 11.569794 -428.300901) (xy 11.507004 -428.312879)
			(xy 11.443208 -428.316893) (xy 11.379412 -428.312879) (xy 11.316622 -428.300901) (xy 11.255829 -428.281148)
			(xy 11.19799 -428.253931) (xy 11.144019 -428.21968) (xy 11.094766 -428.178935) (xy 11.051009 -428.132338)
			(xy 11.013436 -428.080623) (xy 10.982642 -428.024608) (xy 10.95911 -427.965175) (xy 10.943213 -427.903261)
			(xy 10.935202 -427.839843) (xy 7.76986 -427.839843) (xy 7.76986 -427.918118) (xy 7.770336 -427.928085)
			(xy 7.777907 -427.946525) (xy 7.784592 -427.953932) (xy 8.420608 -428.589948) (xy 17.43024 -428.589948)
			(xy 17.434311 -428.534326) (xy 17.446437 -428.479889) (xy 17.46636 -428.427798) (xy 17.493656 -428.379163)
			(xy 17.527742 -428.33502) (xy 17.567891 -428.296311) (xy 17.613249 -428.26386) (xy 17.662849 -428.238359)
			(xy 17.715633 -428.220352) (xy 17.770476 -428.210222) (xy 17.82621 -428.208185) (xy 17.881647 -428.214285)
			(xy 17.935604 -428.228391) (xy 17.986933 -428.250203) (xy 18.034539 -428.279257) (xy 18.077407 -428.314932)
			(xy 18.114624 -428.356469) (xy 18.145397 -428.402982) (xy 18.169069 -428.453479) (xy 18.185137 -428.506886)
			(xy 18.193257 -428.562062) (xy 18.193766 -428.589948) (xy 18.44624 -428.589948) (xy 18.450311 -428.534326)
			(xy 18.462437 -428.479889) (xy 18.48236 -428.427798) (xy 18.509656 -428.379163) (xy 18.543742 -428.33502)
			(xy 18.583891 -428.296311) (xy 18.629249 -428.26386) (xy 18.678849 -428.238359) (xy 18.731633 -428.220352)
			(xy 18.786476 -428.210222) (xy 18.84221 -428.208185) (xy 18.897647 -428.214285) (xy 18.951604 -428.228391)
			(xy 19.002933 -428.250203) (xy 19.050539 -428.279257) (xy 19.093407 -428.314932) (xy 19.130624 -428.356469)
			(xy 19.161397 -428.402982) (xy 19.185069 -428.453479) (xy 19.201137 -428.506886) (xy 19.209257 -428.562062)
			(xy 19.209766 -428.589948) (xy 19.46224 -428.589948) (xy 19.466311 -428.534326) (xy 19.478437 -428.479889)
			(xy 19.49836 -428.427798) (xy 19.525656 -428.379163) (xy 19.559742 -428.33502) (xy 19.599891 -428.296311)
			(xy 19.645249 -428.26386) (xy 19.694849 -428.238359) (xy 19.747633 -428.220352) (xy 19.802476 -428.210222)
			(xy 19.85821 -428.208185) (xy 19.913647 -428.214285) (xy 19.967604 -428.228391) (xy 20.018933 -428.250203)
			(xy 20.066539 -428.279257) (xy 20.109407 -428.314932) (xy 20.146624 -428.356469) (xy 20.177397 -428.402982)
			(xy 20.201069 -428.453479) (xy 20.217137 -428.506886) (xy 20.225257 -428.562062) (xy 20.225766 -428.589948)
			(xy 21.49424 -428.589948) (xy 21.498311 -428.534326) (xy 21.510437 -428.479889) (xy 21.53036 -428.427798)
			(xy 21.557656 -428.379163) (xy 21.591742 -428.33502) (xy 21.631891 -428.296311) (xy 21.677249 -428.26386)
			(xy 21.726849 -428.238359) (xy 21.779633 -428.220352) (xy 21.834476 -428.210222) (xy 21.89021 -428.208185)
			(xy 21.945647 -428.214285) (xy 21.999604 -428.228391) (xy 22.050933 -428.250203) (xy 22.098539 -428.279257)
			(xy 22.141407 -428.314932) (xy 22.178624 -428.356469) (xy 22.209397 -428.402982) (xy 22.233069 -428.453479)
			(xy 22.249137 -428.506886) (xy 22.257257 -428.562062) (xy 22.257766 -428.589948) (xy 22.257298 -428.615602)
			(xy 25.004014 -428.615602) (xy 25.004593 -428.580647) (xy 25.014155 -428.511393) (xy 25.033113 -428.444102)
			(xy 25.061108 -428.380042) (xy 25.097614 -428.32042) (xy 25.11933 -428.293022) (xy 25.124595 -428.286019)
			(xy 25.130444 -428.269519) (xy 25.13076 -428.260764) (xy 25.13076 -428.10684) (xy 25.130431 -428.09809)
			(xy 25.124571 -428.081598) (xy 25.11933 -428.074582) (xy 25.097613 -428.047186) (xy 25.061115 -427.98756)
			(xy 25.033123 -427.923499) (xy 25.014163 -427.856209) (xy 25.004593 -427.786957) (xy 25.004014 -427.752002)
			(xy 25.00444 -427.721269) (xy 25.011848 -427.660251) (xy 25.026558 -427.600572) (xy 25.048355 -427.5431)
			(xy 25.07692 -427.488675) (xy 25.111837 -427.43809) (xy 25.152598 -427.392083) (xy 25.198606 -427.351325)
			(xy 25.249192 -427.31641) (xy 25.303619 -427.287847) (xy 25.361091 -427.266052) (xy 25.420771 -427.251345)
			(xy 25.481789 -427.243938) (xy 25.512522 -427.243494) (xy 25.528778 -427.243748) (xy 25.537283 -427.243714)
			(xy 25.553508 -427.238644) (xy 25.560528 -427.233842) (xy 25.584404 -427.216316) (xy 25.590891 -427.211062)
			(xy 25.60036 -427.197329) (xy 25.602946 -427.189392) (xy 25.607785 -427.173397) (xy 25.619867 -427.142238)
			(xy 25.627076 -427.127162) (xy 25.632156 -427.116494) (xy 25.632156 -427.093126) (xy 25.586182 -426.999654)
			(xy 25.567894 -426.98543) (xy 25.555956 -426.983144) (xy 25.527619 -426.976786) (xy 25.473148 -426.956651)
			(xy 25.422358 -426.928496) (xy 25.376419 -426.89297) (xy 25.336394 -426.850893) (xy 25.303207 -426.803238)
			(xy 25.277623 -426.751104) (xy 25.260234 -426.695696) (xy 25.251442 -426.638292) (xy 25.250902 -426.609256)
			(xy 25.251388 -426.582005) (xy 25.259144 -426.528057) (xy 25.274499 -426.475762) (xy 25.297141 -426.426185)
			(xy 25.326607 -426.380335) (xy 25.362298 -426.339144) (xy 25.403489 -426.303453) (xy 25.449339 -426.273987)
			(xy 25.498916 -426.251345) (xy 25.551211 -426.23599) (xy 25.605159 -426.228234) (xy 25.659661 -426.228234)
			(xy 25.713609 -426.23599) (xy 25.765904 -426.251345) (xy 25.815481 -426.273987) (xy 25.861331 -426.303453)
			(xy 25.902522 -426.339144) (xy 25.938213 -426.380335) (xy 25.967679 -426.426185) (xy 25.990321 -426.475762)
			(xy 26.005676 -426.528057) (xy 26.013432 -426.582005) (xy 26.013918 -426.609256) (xy 26.013371 -426.638199)
			(xy 26.004593 -426.695418) (xy 25.987292 -426.75066) (xy 25.975056 -426.776896) (xy 25.969976 -426.787564)
			(xy 25.969976 -426.810932) (xy 26.01595 -426.904404) (xy 26.034238 -426.918628) (xy 26.046176 -426.920914)
			(xy 26.074515 -426.927266) (xy 26.12899 -426.947395) (xy 26.179785 -426.975548) (xy 26.225727 -427.011073)
			(xy 26.265754 -427.053151) (xy 26.298942 -427.100809) (xy 26.324524 -427.152946) (xy 26.341908 -427.208358)
			(xy 26.350694 -427.265764) (xy 26.35123 -427.294802) (xy 26.350732 -427.322177) (xy 26.342897 -427.376363)
			(xy 26.327403 -427.428875) (xy 26.304567 -427.478635) (xy 26.274858 -427.524623) (xy 26.238884 -427.565895)
			(xy 26.197385 -427.601607) (xy 26.151209 -427.631024) (xy 26.101306 -427.653545) (xy 26.075132 -427.661578)
			(xy 26.067196 -427.664169) (xy 26.053456 -427.673629) (xy 26.048208 -427.68012) (xy 26.030682 -427.703996)
			(xy 26.025922 -427.711038) (xy 26.020848 -427.727248) (xy 26.020776 -427.735746) (xy 26.02103 -427.752002)
			(xy 26.020443 -427.786957) (xy 26.010881 -427.85621) (xy 25.991925 -427.9235) (xy 25.963932 -427.987561)
			(xy 25.927428 -428.047184) (xy 25.905714 -428.074582) (xy 25.900452 -428.081587) (xy 25.8946 -428.098085)
			(xy 25.894284 -428.10684) (xy 25.894284 -428.211054) (xy 26.306457 -428.211054) (xy 26.306457 -428.156546)
			(xy 26.314215 -428.102593) (xy 26.329572 -428.050294) (xy 26.352217 -428.000712) (xy 26.381687 -427.954858)
			(xy 26.417383 -427.913665) (xy 26.458579 -427.877971) (xy 26.504435 -427.848504) (xy 26.554018 -427.825863)
			(xy 26.606319 -427.810509) (xy 26.660272 -427.802756) (xy 26.687526 -427.802294) (xy 26.712801 -427.802709)
			(xy 26.762908 -427.809382) (xy 26.811692 -427.82262) (xy 26.858299 -427.842192) (xy 26.880312 -427.854618)
			(xy 26.890704 -427.859953) (xy 26.913984 -427.861551) (xy 26.935603 -427.852769) (xy 26.943812 -427.844458)
			(xy 26.964506 -427.822011) (xy 27.010402 -427.781748) (xy 27.060788 -427.74727) (xy 27.114941 -427.719074)
			(xy 27.172081 -427.697565) (xy 27.231384 -427.683052) (xy 27.291999 -427.675744) (xy 27.322526 -427.675294)
			(xy 27.357482 -427.675862) (xy 27.426736 -427.685427) (xy 27.494027 -427.704388) (xy 27.558087 -427.732386)
			(xy 27.617708 -427.768894) (xy 27.645106 -427.79061) (xy 27.652103 -427.795884) (xy 27.668607 -427.801728)
			(xy 27.677364 -427.80204) (xy 27.831288 -427.80204) (xy 27.840036 -427.801682) (xy 27.856527 -427.795843)
			(xy 27.863546 -427.79061) (xy 27.890965 -427.768923) (xy 27.950585 -427.732421) (xy 28.014641 -427.704423)
			(xy 28.081925 -427.685457) (xy 28.151173 -427.675878) (xy 28.186126 -427.675294) (xy 28.216653 -427.675729)
			(xy 28.277267 -427.683042) (xy 28.336569 -427.697561) (xy 28.393706 -427.719075) (xy 28.447856 -427.747276)
			(xy 28.49824 -427.781757) (xy 28.544133 -427.822024) (xy 28.56484 -427.844458) (xy 28.573047 -427.852793)
			(xy 28.594661 -427.861652) (xy 28.617963 -427.86001) (xy 28.62834 -427.854618) (xy 28.650344 -427.842176)
			(xy 28.696955 -427.822612) (xy 28.745743 -427.809377) (xy 28.795851 -427.802703) (xy 28.821126 -427.802294)
			(xy 28.848376 -427.802778) (xy 28.902321 -427.810537) (xy 28.954613 -427.825895) (xy 29.004187 -427.848537)
			(xy 29.050035 -427.878004) (xy 29.091222 -427.913696) (xy 29.126911 -427.954886) (xy 29.156375 -428.000735)
			(xy 29.161564 -428.012098) (xy 36.937694 -428.012098) (xy 36.941765 -427.956476) (xy 36.953891 -427.902039)
			(xy 36.973814 -427.849948) (xy 37.00111 -427.801313) (xy 37.035196 -427.75717) (xy 37.075345 -427.718461)
			(xy 37.120703 -427.68601) (xy 37.170303 -427.660509) (xy 37.223087 -427.642502) (xy 37.27793 -427.632372)
			(xy 37.333664 -427.630335) (xy 37.389101 -427.636435) (xy 37.443058 -427.650541) (xy 37.494387 -427.672353)
			(xy 37.541993 -427.701407) (xy 37.584861 -427.737082) (xy 37.622078 -427.778619) (xy 37.652851 -427.825132)
			(xy 37.676523 -427.875629) (xy 37.692591 -427.929036) (xy 37.700711 -427.984212) (xy 37.70122 -428.012098)
			(xy 37.700711 -428.039984) (xy 37.692591 -428.09516) (xy 37.676523 -428.148567) (xy 37.652851 -428.199064)
			(xy 37.622078 -428.245577) (xy 37.584861 -428.287114) (xy 37.541993 -428.322789) (xy 37.494387 -428.351843)
			(xy 37.443058 -428.373655) (xy 37.389101 -428.387761) (xy 37.333664 -428.393861) (xy 37.27793 -428.391824)
			(xy 37.223087 -428.381694) (xy 37.170303 -428.363687) (xy 37.120703 -428.338186) (xy 37.075345 -428.305735)
			(xy 37.035196 -428.267026) (xy 37.00111 -428.222883) (xy 36.973814 -428.174248) (xy 36.953891 -428.122157)
			(xy 36.941765 -428.06772) (xy 36.937694 -428.012098) (xy 29.161564 -428.012098) (xy 29.179015 -428.050311)
			(xy 29.194368 -428.102604) (xy 29.202124 -428.15655) (xy 29.202124 -428.21105) (xy 29.194368 -428.264996)
			(xy 29.179015 -428.317289) (xy 29.156375 -428.366865) (xy 29.126911 -428.412714) (xy 29.091222 -428.453904)
			(xy 29.050035 -428.489596) (xy 29.004187 -428.519063) (xy 28.954613 -428.541705) (xy 28.902321 -428.557063)
			(xy 28.848376 -428.564822) (xy 28.821126 -428.56531) (xy 28.795851 -428.564916) (xy 28.745743 -428.558236)
			(xy 28.696958 -428.544992) (xy 28.650352 -428.525414) (xy 28.62834 -428.512986) (xy 28.617968 -428.507604)
			(xy 28.594673 -428.506022) (xy 28.573047 -428.514824) (xy 28.56484 -428.523146) (xy 28.544121 -428.545568)
			(xy 28.498229 -428.585833) (xy 28.447847 -428.620313) (xy 28.393699 -428.648513) (xy 28.336563 -428.670026)
			(xy 28.277263 -428.684544) (xy 28.216652 -428.691857) (xy 28.186126 -428.69231) (xy 28.151171 -428.691712)
			(xy 28.081919 -428.682154) (xy 28.014628 -428.6632) (xy 27.950568 -428.635209) (xy 27.890945 -428.598707)
			(xy 27.863546 -428.576994) (xy 27.856534 -428.571742) (xy 27.840041 -428.565884) (xy 27.831288 -428.565564)
			(xy 27.677364 -428.565564) (xy 27.668616 -428.565919) (xy 27.652126 -428.571762) (xy 27.645106 -428.576994)
			(xy 27.617704 -428.598703) (xy 27.558079 -428.635202) (xy 27.494019 -428.663195) (xy 27.426731 -428.682157)
			(xy 27.35748 -428.691729) (xy 27.322526 -428.69231) (xy 27.292 -428.691838) (xy 27.231388 -428.684531)
			(xy 27.172087 -428.670019) (xy 27.11495 -428.64851) (xy 27.060799 -428.620315) (xy 27.010414 -428.585839)
			(xy 26.96452 -428.545578) (xy 26.943812 -428.523146) (xy 26.935639 -428.514772) (xy 26.914006 -428.505922)
			(xy 26.890691 -428.507583) (xy 26.880312 -428.512986) (xy 26.858297 -428.525408) (xy 26.81169 -428.544977)
			(xy 26.762906 -428.558217) (xy 26.7128 -428.564898) (xy 26.687526 -428.56531) (xy 26.660272 -428.564844)
			(xy 26.606319 -428.557091) (xy 26.554018 -428.541737) (xy 26.504435 -428.519096) (xy 26.458579 -428.489629)
			(xy 26.417383 -428.453935) (xy 26.381687 -428.412742) (xy 26.352217 -428.366888) (xy 26.329572 -428.317306)
			(xy 26.314215 -428.265007) (xy 26.306457 -428.211054) (xy 25.894284 -428.211054) (xy 25.894284 -428.260764)
			(xy 25.894622 -428.269513) (xy 25.900477 -428.286004) (xy 25.905714 -428.293022) (xy 25.927439 -428.320412)
			(xy 25.963934 -428.38004) (xy 25.991925 -428.444103) (xy 26.010882 -428.511394) (xy 26.020451 -428.580647)
			(xy 26.02103 -428.615602) (xy 26.020776 -428.631858) (xy 26.020814 -428.640363) (xy 26.025881 -428.656588)
			(xy 26.030682 -428.663608) (xy 26.048208 -428.687484) (xy 26.053459 -428.693974) (xy 26.067194 -428.703442)
			(xy 26.075132 -428.706026) (xy 26.095203 -428.712122) (xy 40.11244 -428.712122) (xy 40.116511 -428.6565)
			(xy 40.128637 -428.602063) (xy 40.14856 -428.549972) (xy 40.175856 -428.501337) (xy 40.209942 -428.457194)
			(xy 40.250091 -428.418485) (xy 40.295449 -428.386034) (xy 40.345049 -428.360533) (xy 40.397833 -428.342526)
			(xy 40.452676 -428.332396) (xy 40.50841 -428.330359) (xy 40.563847 -428.336459) (xy 40.617804 -428.350565)
			(xy 40.669133 -428.372377) (xy 40.716739 -428.401431) (xy 40.759607 -428.437106) (xy 40.784582 -428.46498)
			(xy 46.672498 -428.46498) (xy 46.676569 -428.409358) (xy 46.688695 -428.354921) (xy 46.708618 -428.30283)
			(xy 46.735914 -428.254195) (xy 46.77 -428.210052) (xy 46.810149 -428.171343) (xy 46.855507 -428.138892)
			(xy 46.905107 -428.113391) (xy 46.957891 -428.095384) (xy 47.012734 -428.085254) (xy 47.068468 -428.083217)
			(xy 47.123905 -428.089317) (xy 47.177862 -428.103423) (xy 47.229191 -428.125235) (xy 47.276797 -428.154289)
			(xy 47.319665 -428.189964) (xy 47.356882 -428.231501) (xy 47.387655 -428.278014) (xy 47.411327 -428.328511)
			(xy 47.427395 -428.381918) (xy 47.435515 -428.437094) (xy 47.436024 -428.46498) (xy 50.399188 -428.46498)
			(xy 50.39969 -428.433019) (xy 50.407701 -428.369601) (xy 50.423598 -428.307687) (xy 50.44713 -428.248254)
			(xy 50.477924 -428.192239) (xy 50.515497 -428.140524) (xy 50.559254 -428.093927) (xy 50.608507 -428.053182)
			(xy 50.662478 -428.018931) (xy 50.720317 -427.991714) (xy 50.78111 -427.971961) (xy 50.8439 -427.959983)
			(xy 50.907696 -427.95597) (xy 50.971492 -427.959983) (xy 51.034282 -427.971961) (xy 51.095075 -427.991714)
			(xy 51.152914 -428.018931) (xy 51.206885 -428.053182) (xy 51.256138 -428.093927) (xy 51.299895 -428.140524)
			(xy 51.337468 -428.192239) (xy 51.368262 -428.248254) (xy 51.391794 -428.307687) (xy 51.407691 -428.369601)
			(xy 51.415702 -428.433019) (xy 51.416204 -428.46498) (xy 51.415796 -428.494921) (xy 51.408748 -428.554387)
			(xy 51.394769 -428.612615) (xy 51.374054 -428.668801) (xy 51.346888 -428.722167) (xy 51.313648 -428.771976)
			(xy 51.274791 -428.81754) (xy 51.230856 -428.85823) (xy 51.206908 -428.876206) (xy 51.197002 -428.883318)
			(xy 51.18608 -428.905162) (xy 51.186588 -429.01235) (xy 51.198018 -429.03394) (xy 51.207924 -429.041052)
			(xy 51.232414 -429.058948) (xy 51.277372 -429.099667) (xy 51.317166 -429.145446) (xy 51.35123 -429.195635)
			(xy 51.37908 -429.249521) (xy 51.40032 -429.306338) (xy 51.414648 -429.365279) (xy 51.421862 -429.425505)
			(xy 51.4223 -429.455834) (xy 51.421798 -429.487795) (xy 51.413787 -429.551213) (xy 51.39789 -429.613127)
			(xy 51.374358 -429.67256) (xy 51.343564 -429.728575) (xy 51.305991 -429.78029) (xy 51.262234 -429.826887)
			(xy 51.212981 -429.867632) (xy 51.15901 -429.901883) (xy 51.101171 -429.9291) (xy 51.040378 -429.948853)
			(xy 50.977588 -429.960831) (xy 50.913792 -429.964845) (xy 50.849996 -429.960831) (xy 50.787206 -429.948853)
			(xy 50.726413 -429.9291) (xy 50.668574 -429.901883) (xy 50.614603 -429.867632) (xy 50.56535 -429.826887)
			(xy 50.521593 -429.78029) (xy 50.48402 -429.728575) (xy 50.453226 -429.67256) (xy 50.429694 -429.613127)
			(xy 50.413797 -429.551213) (xy 50.405786 -429.487795) (xy 50.405284 -429.455834) (xy 50.405707 -429.425893)
			(xy 50.412754 -429.366428) (xy 50.426731 -429.3082) (xy 50.447444 -429.252015) (xy 50.474607 -429.198649)
			(xy 50.507846 -429.14884) (xy 50.5467 -429.103275) (xy 50.590633 -429.062585) (xy 50.61458 -429.044608)
			(xy 50.624486 -429.037496) (xy 50.635408 -429.015652) (xy 50.6349 -428.908464) (xy 50.62347 -428.886874)
			(xy 50.613564 -428.879762) (xy 50.589078 -428.861861) (xy 50.54412 -428.821143) (xy 50.504326 -428.775364)
			(xy 50.470262 -428.725175) (xy 50.442412 -428.67129) (xy 50.421171 -428.614474) (xy 50.406842 -428.555534)
			(xy 50.399627 -428.495308) (xy 50.399188 -428.46498) (xy 47.436024 -428.46498) (xy 47.435515 -428.492866)
			(xy 47.427395 -428.548042) (xy 47.411327 -428.601449) (xy 47.387655 -428.651946) (xy 47.356882 -428.698459)
			(xy 47.319665 -428.739996) (xy 47.276797 -428.775671) (xy 47.229191 -428.804725) (xy 47.177862 -428.826537)
			(xy 47.123905 -428.840643) (xy 47.068468 -428.846743) (xy 47.012734 -428.844706) (xy 46.957891 -428.834576)
			(xy 46.905107 -428.816569) (xy 46.855507 -428.791068) (xy 46.810149 -428.758617) (xy 46.77 -428.719908)
			(xy 46.735914 -428.675765) (xy 46.708618 -428.62713) (xy 46.688695 -428.575039) (xy 46.676569 -428.520602)
			(xy 46.672498 -428.46498) (xy 40.784582 -428.46498) (xy 40.796824 -428.478643) (xy 40.827597 -428.525156)
			(xy 40.851269 -428.575653) (xy 40.867337 -428.62906) (xy 40.875457 -428.684236) (xy 40.875966 -428.712122)
			(xy 40.875457 -428.740008) (xy 40.867337 -428.795184) (xy 40.851269 -428.848591) (xy 40.827597 -428.899088)
			(xy 40.796824 -428.945601) (xy 40.759607 -428.987138) (xy 40.716739 -429.022813) (xy 40.669133 -429.051867)
			(xy 40.617804 -429.073679) (xy 40.563847 -429.087785) (xy 40.50841 -429.093885) (xy 40.452676 -429.091848)
			(xy 40.397833 -429.081718) (xy 40.345049 -429.063711) (xy 40.295449 -429.03821) (xy 40.250091 -429.005759)
			(xy 40.209942 -428.96705) (xy 40.175856 -428.922907) (xy 40.14856 -428.874272) (xy 40.128637 -428.822181)
			(xy 40.116511 -428.767744) (xy 40.11244 -428.712122) (xy 26.095203 -428.712122) (xy 26.101334 -428.713984)
			(xy 26.151254 -428.736496) (xy 26.197444 -428.765913) (xy 26.238955 -428.801629) (xy 26.274935 -428.842913)
			(xy 26.304644 -428.888915) (xy 26.327473 -428.938691) (xy 26.342953 -428.99122) (xy 26.350766 -429.045421)
			(xy 26.35123 -429.072802) (xy 26.350724 -429.100052) (xy 26.342968 -429.153998) (xy 26.327614 -429.206291)
			(xy 26.304974 -429.255867) (xy 26.275509 -429.301716) (xy 26.23982 -429.342906) (xy 26.198632 -429.378597)
			(xy 26.152785 -429.408064) (xy 26.10321 -429.430707) (xy 26.050918 -429.446064) (xy 25.996972 -429.453823)
			(xy 25.969722 -429.45431) (xy 25.942348 -429.453822) (xy 25.888164 -429.445979) (xy 25.835655 -429.430479)
			(xy 25.785898 -429.407639) (xy 25.739912 -429.377928) (xy 25.69864 -429.341955) (xy 25.662928 -429.300457)
			(xy 25.633508 -429.254285) (xy 25.610982 -429.204385) (xy 25.602946 -429.178212) (xy 25.600356 -429.170276)
			(xy 25.590895 -429.156537) (xy 25.584404 -429.151288) (xy 25.560528 -429.133762) (xy 25.553506 -429.128969)
			(xy 25.537281 -429.123915) (xy 25.528778 -429.123856) (xy 25.512522 -429.12411) (xy 25.48179 -429.123642)
			(xy 25.420775 -429.116236) (xy 25.361098 -429.101529) (xy 25.303628 -429.079736) (xy 25.249204 -429.051174)
			(xy 25.19862 -429.01626) (xy 25.152613 -428.975504) (xy 25.111854 -428.929499) (xy 25.076938 -428.878917)
			(xy 25.048374 -428.824494) (xy 25.026578 -428.767025) (xy 25.011869 -428.707348) (xy 25.00446 -428.646334)
			(xy 25.004014 -428.615602) (xy 22.257298 -428.615602) (xy 22.257257 -428.617834) (xy 22.249137 -428.67301)
			(xy 22.233069 -428.726417) (xy 22.209397 -428.776914) (xy 22.178624 -428.823427) (xy 22.141407 -428.864964)
			(xy 22.098539 -428.900639) (xy 22.050933 -428.929693) (xy 21.999604 -428.951505) (xy 21.945647 -428.965611)
			(xy 21.89021 -428.971711) (xy 21.834476 -428.969674) (xy 21.779633 -428.959544) (xy 21.726849 -428.941537)
			(xy 21.677249 -428.916036) (xy 21.631891 -428.883585) (xy 21.591742 -428.844876) (xy 21.557656 -428.800733)
			(xy 21.53036 -428.752098) (xy 21.510437 -428.700007) (xy 21.498311 -428.64557) (xy 21.49424 -428.589948)
			(xy 20.225766 -428.589948) (xy 20.225257 -428.617834) (xy 20.217137 -428.67301) (xy 20.201069 -428.726417)
			(xy 20.177397 -428.776914) (xy 20.146624 -428.823427) (xy 20.109407 -428.864964) (xy 20.066539 -428.900639)
			(xy 20.018933 -428.929693) (xy 19.967604 -428.951505) (xy 19.913647 -428.965611) (xy 19.85821 -428.971711)
			(xy 19.802476 -428.969674) (xy 19.747633 -428.959544) (xy 19.694849 -428.941537) (xy 19.645249 -428.916036)
			(xy 19.599891 -428.883585) (xy 19.559742 -428.844876) (xy 19.525656 -428.800733) (xy 19.49836 -428.752098)
			(xy 19.478437 -428.700007) (xy 19.466311 -428.64557) (xy 19.46224 -428.589948) (xy 19.209766 -428.589948)
			(xy 19.209257 -428.617834) (xy 19.201137 -428.67301) (xy 19.185069 -428.726417) (xy 19.161397 -428.776914)
			(xy 19.130624 -428.823427) (xy 19.093407 -428.864964) (xy 19.050539 -428.900639) (xy 19.002933 -428.929693)
			(xy 18.951604 -428.951505) (xy 18.897647 -428.965611) (xy 18.84221 -428.971711) (xy 18.786476 -428.969674)
			(xy 18.731633 -428.959544) (xy 18.678849 -428.941537) (xy 18.629249 -428.916036) (xy 18.583891 -428.883585)
			(xy 18.543742 -428.844876) (xy 18.509656 -428.800733) (xy 18.48236 -428.752098) (xy 18.462437 -428.700007)
			(xy 18.450311 -428.64557) (xy 18.44624 -428.589948) (xy 18.193766 -428.589948) (xy 18.193257 -428.617834)
			(xy 18.185137 -428.67301) (xy 18.169069 -428.726417) (xy 18.145397 -428.776914) (xy 18.114624 -428.823427)
			(xy 18.077407 -428.864964) (xy 18.034539 -428.900639) (xy 17.986933 -428.929693) (xy 17.935604 -428.951505)
			(xy 17.881647 -428.965611) (xy 17.82621 -428.971711) (xy 17.770476 -428.969674) (xy 17.715633 -428.959544)
			(xy 17.662849 -428.941537) (xy 17.613249 -428.916036) (xy 17.567891 -428.883585) (xy 17.527742 -428.844876)
			(xy 17.493656 -428.800733) (xy 17.46636 -428.752098) (xy 17.446437 -428.700007) (xy 17.434311 -428.64557)
			(xy 17.43024 -428.589948) (xy 8.420608 -428.589948) (xy 9.204706 -429.374046) (xy 9.212102 -429.380897)
			(xy 9.230701 -429.388638) (xy 9.240774 -429.389032) (xy 17.652746 -429.389032) (xy 17.662812 -429.389464)
			(xy 17.681401 -429.397194) (xy 17.688814 -429.404018) (xy 18.081709 -429.796913) (xy 46.50333 -429.796913)
			(xy 46.50333 -429.732991) (xy 46.511341 -429.669573) (xy 46.527238 -429.607659) (xy 46.55077 -429.548226)
			(xy 46.581564 -429.492211) (xy 46.619137 -429.440496) (xy 46.662894 -429.393899) (xy 46.712147 -429.353154)
			(xy 46.766118 -429.318903) (xy 46.823957 -429.291686) (xy 46.88475 -429.271933) (xy 46.94754 -429.259955)
			(xy 47.011336 -429.255942) (xy 47.075132 -429.259955) (xy 47.137922 -429.271933) (xy 47.198715 -429.291686)
			(xy 47.256554 -429.318903) (xy 47.310525 -429.353154) (xy 47.359778 -429.393899) (xy 47.403535 -429.440496)
			(xy 47.441108 -429.492211) (xy 47.471902 -429.548226) (xy 47.495434 -429.607659) (xy 47.511331 -429.669573)
			(xy 47.519342 -429.732991) (xy 47.519844 -429.764952) (xy 47.519342 -429.796913) (xy 47.511331 -429.860331)
			(xy 47.495434 -429.922245) (xy 47.471902 -429.981678) (xy 47.441108 -430.037693) (xy 47.403535 -430.089408)
			(xy 47.359778 -430.136005) (xy 47.310525 -430.17675) (xy 47.256554 -430.211001) (xy 47.198715 -430.238218)
			(xy 47.137922 -430.257971) (xy 47.075132 -430.269949) (xy 47.011336 -430.273963) (xy 46.94754 -430.269949)
			(xy 46.88475 -430.257971) (xy 46.823957 -430.238218) (xy 46.766118 -430.211001) (xy 46.712147 -430.17675)
			(xy 46.662894 -430.136005) (xy 46.619137 -430.089408) (xy 46.581564 -430.037693) (xy 46.55077 -429.981678)
			(xy 46.527238 -429.922245) (xy 46.511341 -429.860331) (xy 46.50333 -429.796913) (xy 18.081709 -429.796913)
			(xy 19.738551 -431.453755) (xy 20.446994 -431.453755) (xy 20.446994 -431.389833) (xy 20.455005 -431.326415)
			(xy 20.470902 -431.264501) (xy 20.494434 -431.205068) (xy 20.525228 -431.149053) (xy 20.562801 -431.097338)
			(xy 20.606558 -431.050741) (xy 20.655811 -431.009996) (xy 20.709782 -430.975745) (xy 20.767621 -430.948528)
			(xy 20.828414 -430.928775) (xy 20.891204 -430.916797) (xy 20.955 -430.912784) (xy 21.018796 -430.916797)
			(xy 21.081586 -430.928775) (xy 21.101012 -430.935087) (xy 23.901648 -430.935087) (xy 23.901648 -430.871165)
			(xy 23.909659 -430.807747) (xy 23.925556 -430.745833) (xy 23.949088 -430.6864) (xy 23.979882 -430.630385)
			(xy 24.017455 -430.57867) (xy 24.061212 -430.532073) (xy 24.110465 -430.491328) (xy 24.164436 -430.457077)
			(xy 24.222275 -430.42986) (xy 24.283068 -430.410107) (xy 24.345858 -430.398129) (xy 24.409654 -430.394116)
			(xy 24.47345 -430.398129) (xy 24.53624 -430.410107) (xy 24.597033 -430.42986) (xy 24.654872 -430.457077)
			(xy 24.708843 -430.491328) (xy 24.758096 -430.532073) (xy 24.801853 -430.57867) (xy 24.839426 -430.630385)
			(xy 24.87022 -430.6864) (xy 24.893752 -430.745833) (xy 24.909649 -430.807747) (xy 24.91766 -430.871165)
			(xy 24.91803 -430.894744) (xy 26.655774 -430.894744) (xy 26.659845 -430.839122) (xy 26.671971 -430.784685)
			(xy 26.691894 -430.732594) (xy 26.71919 -430.683959) (xy 26.753276 -430.639816) (xy 26.793425 -430.601107)
			(xy 26.838783 -430.568656) (xy 26.888383 -430.543155) (xy 26.941167 -430.525148) (xy 26.99601 -430.515018)
			(xy 27.051744 -430.512981) (xy 27.107181 -430.519081) (xy 27.161138 -430.533187) (xy 27.212467 -430.554999)
			(xy 27.260073 -430.584053) (xy 27.302941 -430.619728) (xy 27.340158 -430.661265) (xy 27.370931 -430.707778)
			(xy 27.394603 -430.758275) (xy 27.397834 -430.769014) (xy 28.917644 -430.769014) (xy 28.921715 -430.713392)
			(xy 28.933841 -430.658955) (xy 28.953764 -430.606864) (xy 28.98106 -430.558229) (xy 29.015146 -430.514086)
			(xy 29.055295 -430.475377) (xy 29.100653 -430.442926) (xy 29.150253 -430.417425) (xy 29.203037 -430.399418)
			(xy 29.25788 -430.389288) (xy 29.313614 -430.387251) (xy 29.369051 -430.393351) (xy 29.423008 -430.407457)
			(xy 29.474337 -430.429269) (xy 29.521943 -430.458323) (xy 29.564811 -430.493998) (xy 29.602028 -430.535535)
			(xy 29.632801 -430.582048) (xy 29.656473 -430.632545) (xy 29.672541 -430.685952) (xy 29.680661 -430.741128)
			(xy 29.68117 -430.769014) (xy 29.933644 -430.769014) (xy 29.937715 -430.713392) (xy 29.949841 -430.658955)
			(xy 29.969764 -430.606864) (xy 29.99706 -430.558229) (xy 30.031146 -430.514086) (xy 30.071295 -430.475377)
			(xy 30.116653 -430.442926) (xy 30.166253 -430.417425) (xy 30.219037 -430.399418) (xy 30.27388 -430.389288)
			(xy 30.329614 -430.387251) (xy 30.385051 -430.393351) (xy 30.439008 -430.407457) (xy 30.490337 -430.429269)
			(xy 30.537943 -430.458323) (xy 30.580811 -430.493998) (xy 30.618028 -430.535535) (xy 30.648801 -430.582048)
			(xy 30.672473 -430.632545) (xy 30.688541 -430.685952) (xy 30.696661 -430.741128) (xy 30.69717 -430.769014)
			(xy 30.696661 -430.7969) (xy 30.696242 -430.799748) (xy 32.981644 -430.799748) (xy 32.985715 -430.744126)
			(xy 32.997841 -430.689689) (xy 33.017764 -430.637598) (xy 33.04506 -430.588963) (xy 33.079146 -430.54482)
			(xy 33.119295 -430.506111) (xy 33.164653 -430.47366) (xy 33.214253 -430.448159) (xy 33.267037 -430.430152)
			(xy 33.32188 -430.420022) (xy 33.377614 -430.417985) (xy 33.433051 -430.424085) (xy 33.487008 -430.438191)
			(xy 33.538337 -430.460003) (xy 33.585943 -430.489057) (xy 33.628811 -430.524732) (xy 33.666028 -430.566269)
			(xy 33.696801 -430.612782) (xy 33.720473 -430.663279) (xy 33.736541 -430.716686) (xy 33.744661 -430.771862)
			(xy 33.74517 -430.799748) (xy 33.997644 -430.799748) (xy 34.001715 -430.744126) (xy 34.013841 -430.689689)
			(xy 34.033764 -430.637598) (xy 34.06106 -430.588963) (xy 34.095146 -430.54482) (xy 34.135295 -430.506111)
			(xy 34.180653 -430.47366) (xy 34.230253 -430.448159) (xy 34.283037 -430.430152) (xy 34.33788 -430.420022)
			(xy 34.393614 -430.417985) (xy 34.449051 -430.424085) (xy 34.503008 -430.438191) (xy 34.554337 -430.460003)
			(xy 34.601943 -430.489057) (xy 34.644811 -430.524732) (xy 34.682028 -430.566269) (xy 34.712801 -430.612782)
			(xy 34.736473 -430.663279) (xy 34.752541 -430.716686) (xy 34.760661 -430.771862) (xy 34.76117 -430.799748)
			(xy 35.013644 -430.799748) (xy 35.017715 -430.744126) (xy 35.029841 -430.689689) (xy 35.049764 -430.637598)
			(xy 35.07706 -430.588963) (xy 35.111146 -430.54482) (xy 35.151295 -430.506111) (xy 35.196653 -430.47366)
			(xy 35.246253 -430.448159) (xy 35.299037 -430.430152) (xy 35.35388 -430.420022) (xy 35.409614 -430.417985)
			(xy 35.465051 -430.424085) (xy 35.519008 -430.438191) (xy 35.570337 -430.460003) (xy 35.617943 -430.489057)
			(xy 35.660811 -430.524732) (xy 35.698028 -430.566269) (xy 35.728801 -430.612782) (xy 35.752473 -430.663279)
			(xy 35.768541 -430.716686) (xy 35.776661 -430.771862) (xy 35.77717 -430.799748) (xy 36.029644 -430.799748)
			(xy 36.033715 -430.744126) (xy 36.045841 -430.689689) (xy 36.065764 -430.637598) (xy 36.09306 -430.588963)
			(xy 36.127146 -430.54482) (xy 36.167295 -430.506111) (xy 36.212653 -430.47366) (xy 36.262253 -430.448159)
			(xy 36.315037 -430.430152) (xy 36.36988 -430.420022) (xy 36.425614 -430.417985) (xy 36.481051 -430.424085)
			(xy 36.535008 -430.438191) (xy 36.586337 -430.460003) (xy 36.633943 -430.489057) (xy 36.676811 -430.524732)
			(xy 36.714028 -430.566269) (xy 36.744801 -430.612782) (xy 36.768473 -430.663279) (xy 36.784541 -430.716686)
			(xy 36.792661 -430.771862) (xy 36.79317 -430.799748) (xy 36.792661 -430.827634) (xy 36.784541 -430.88281)
			(xy 36.768473 -430.936217) (xy 36.747213 -430.981569) (xy 39.986452 -430.981569) (xy 39.986452 -430.917647)
			(xy 39.994463 -430.854229) (xy 40.01036 -430.792315) (xy 40.033892 -430.732882) (xy 40.064686 -430.676867)
			(xy 40.102259 -430.625152) (xy 40.146016 -430.578555) (xy 40.195269 -430.53781) (xy 40.24924 -430.503559)
			(xy 40.307079 -430.476342) (xy 40.367872 -430.456589) (xy 40.430662 -430.444611) (xy 40.494458 -430.440598)
			(xy 40.558254 -430.444611) (xy 40.621044 -430.456589) (xy 40.681837 -430.476342) (xy 40.739676 -430.503559)
			(xy 40.783471 -430.531352) (xy 49.22517 -430.531352) (xy 49.22517 -430.476848) (xy 49.232926 -430.422899)
			(xy 49.248282 -430.370603) (xy 49.270924 -430.321025) (xy 49.30039 -430.275174) (xy 49.336083 -430.233983)
			(xy 49.377274 -430.19829) (xy 49.423125 -430.168824) (xy 49.472703 -430.146182) (xy 49.524999 -430.130826)
			(xy 49.578948 -430.12307) (xy 49.6062 -430.122584) (xy 49.633648 -430.123013) (xy 49.687978 -430.130868)
			(xy 49.740621 -430.146429) (xy 49.79049 -430.169376) (xy 49.836554 -430.199234) (xy 49.877863 -430.235387)
			(xy 49.913563 -430.277089) (xy 49.942916 -430.323476) (xy 49.965317 -430.373593) (xy 49.980302 -430.426403)
			(xy 49.984406 -430.453546) (xy 49.98593 -430.464468) (xy 49.997106 -430.482756) (xy 50.078386 -430.53762)
			(xy 50.099468 -430.541176) (xy 50.110136 -430.538382) (xy 50.141105 -430.530989) (xy 50.204284 -430.523094)
			(xy 50.23612 -430.522634) (xy 50.267659 -430.523089) (xy 50.330252 -430.530893) (xy 50.3914 -430.54638)
			(xy 50.450162 -430.569311) (xy 50.505636 -430.599334) (xy 50.556971 -430.635989) (xy 50.603379 -430.678711)
			(xy 50.644145 -430.726846) (xy 50.678645 -430.779653) (xy 50.706348 -430.836322) (xy 50.7203 -430.876964)
			(xy 51.38496 -430.876964) (xy 51.389031 -430.821342) (xy 51.401157 -430.766905) (xy 51.42108 -430.714814)
			(xy 51.448376 -430.666179) (xy 51.482462 -430.622036) (xy 51.522611 -430.583327) (xy 51.567969 -430.550876)
			(xy 51.617569 -430.525375) (xy 51.670353 -430.507368) (xy 51.725196 -430.497238) (xy 51.78093 -430.495201)
			(xy 51.836367 -430.501301) (xy 51.890324 -430.515407) (xy 51.941653 -430.537219) (xy 51.989259 -430.566273)
			(xy 52.032127 -430.601948) (xy 52.069344 -430.643485) (xy 52.100117 -430.689998) (xy 52.123789 -430.740495)
			(xy 52.139857 -430.793902) (xy 52.147977 -430.849078) (xy 52.148486 -430.876964) (xy 52.147977 -430.90485)
			(xy 52.139857 -430.960026) (xy 52.123789 -431.013433) (xy 52.100117 -431.06393) (xy 52.069344 -431.110443)
			(xy 52.032127 -431.15198) (xy 51.989259 -431.187655) (xy 51.941653 -431.216709) (xy 51.890324 -431.238521)
			(xy 51.836367 -431.252627) (xy 51.78093 -431.258727) (xy 51.725196 -431.25669) (xy 51.670353 -431.24656)
			(xy 51.617569 -431.228553) (xy 51.567969 -431.203052) (xy 51.522611 -431.170601) (xy 51.482462 -431.131892)
			(xy 51.448376 -431.087749) (xy 51.42108 -431.039114) (xy 51.401157 -430.987023) (xy 51.389031 -430.932586)
			(xy 51.38496 -430.876964) (xy 50.7203 -430.876964) (xy 50.726829 -430.895982) (xy 50.739773 -430.957718)
			(xy 50.744982 -431.02058) (xy 50.742375 -431.083604) (xy 50.731993 -431.145822) (xy 50.713995 -431.206278)
			(xy 50.688658 -431.264043) (xy 50.65637 -431.318231) (xy 50.617628 -431.368009) (xy 50.573026 -431.412613)
			(xy 50.523249 -431.451358) (xy 50.469063 -431.483648) (xy 50.411299 -431.508988) (xy 50.350844 -431.526988)
			(xy 50.288626 -431.537373) (xy 50.225602 -431.539982) (xy 50.16274 -431.534776) (xy 50.101004 -431.521834)
			(xy 50.041342 -431.501356) (xy 49.984672 -431.473655) (xy 49.931863 -431.439158) (xy 49.883727 -431.398394)
			(xy 49.841003 -431.351988) (xy 49.804346 -431.300655) (xy 49.77432 -431.245182) (xy 49.751387 -431.186421)
			(xy 49.735897 -431.125274) (xy 49.72809 -431.062681) (xy 49.727612 -431.031142) (xy 49.728882 -430.994058)
			(xy 49.729898 -430.983136) (xy 49.722532 -430.96307) (xy 49.653952 -430.892712) (xy 49.63414 -430.884838)
			(xy 49.623218 -430.885346) (xy 49.6062 -430.8856) (xy 49.578948 -430.88513) (xy 49.524999 -430.877374)
			(xy 49.472703 -430.862018) (xy 49.423125 -430.839376) (xy 49.377274 -430.80991) (xy 49.336083 -430.774217)
			(xy 49.30039 -430.733026) (xy 49.270924 -430.687175) (xy 49.248282 -430.637597) (xy 49.232926 -430.585301)
			(xy 49.22517 -430.531352) (xy 40.783471 -430.531352) (xy 40.793647 -430.53781) (xy 40.8429 -430.578555)
			(xy 40.886657 -430.625152) (xy 40.92423 -430.676867) (xy 40.955024 -430.732882) (xy 40.978556 -430.792315)
			(xy 40.994453 -430.854229) (xy 41.002464 -430.917647) (xy 41.002966 -430.949608) (xy 41.002464 -430.981569)
			(xy 40.994453 -431.044987) (xy 40.978556 -431.106901) (xy 40.955024 -431.166334) (xy 40.92423 -431.222349)
			(xy 40.886657 -431.274064) (xy 40.8429 -431.320661) (xy 40.793647 -431.361406) (xy 40.739676 -431.395657)
			(xy 40.681837 -431.422874) (xy 40.621044 -431.442627) (xy 40.558254 -431.454605) (xy 40.494458 -431.458619)
			(xy 40.430662 -431.454605) (xy 40.367872 -431.442627) (xy 40.307079 -431.422874) (xy 40.24924 -431.395657)
			(xy 40.195269 -431.361406) (xy 40.146016 -431.320661) (xy 40.102259 -431.274064) (xy 40.064686 -431.222349)
			(xy 40.033892 -431.166334) (xy 40.01036 -431.106901) (xy 39.994463 -431.044987) (xy 39.986452 -430.981569)
			(xy 36.747213 -430.981569) (xy 36.744801 -430.986714) (xy 36.714028 -431.033227) (xy 36.676811 -431.074764)
			(xy 36.633943 -431.110439) (xy 36.586337 -431.139493) (xy 36.535008 -431.161305) (xy 36.481051 -431.175411)
			(xy 36.425614 -431.181511) (xy 36.36988 -431.179474) (xy 36.315037 -431.169344) (xy 36.262253 -431.151337)
			(xy 36.212653 -431.125836) (xy 36.167295 -431.093385) (xy 36.127146 -431.054676) (xy 36.09306 -431.010533)
			(xy 36.065764 -430.961898) (xy 36.045841 -430.909807) (xy 36.033715 -430.85537) (xy 36.029644 -430.799748)
			(xy 35.77717 -430.799748) (xy 35.776661 -430.827634) (xy 35.768541 -430.88281) (xy 35.752473 -430.936217)
			(xy 35.728801 -430.986714) (xy 35.698028 -431.033227) (xy 35.660811 -431.074764) (xy 35.617943 -431.110439)
			(xy 35.570337 -431.139493) (xy 35.519008 -431.161305) (xy 35.465051 -431.175411) (xy 35.409614 -431.181511)
			(xy 35.35388 -431.179474) (xy 35.299037 -431.169344) (xy 35.246253 -431.151337) (xy 35.196653 -431.125836)
			(xy 35.151295 -431.093385) (xy 35.111146 -431.054676) (xy 35.07706 -431.010533) (xy 35.049764 -430.961898)
			(xy 35.029841 -430.909807) (xy 35.017715 -430.85537) (xy 35.013644 -430.799748) (xy 34.76117 -430.799748)
			(xy 34.760661 -430.827634) (xy 34.752541 -430.88281) (xy 34.736473 -430.936217) (xy 34.712801 -430.986714)
			(xy 34.682028 -431.033227) (xy 34.644811 -431.074764) (xy 34.601943 -431.110439) (xy 34.554337 -431.139493)
			(xy 34.503008 -431.161305) (xy 34.449051 -431.175411) (xy 34.393614 -431.181511) (xy 34.33788 -431.179474)
			(xy 34.283037 -431.169344) (xy 34.230253 -431.151337) (xy 34.180653 -431.125836) (xy 34.135295 -431.093385)
			(xy 34.095146 -431.054676) (xy 34.06106 -431.010533) (xy 34.033764 -430.961898) (xy 34.013841 -430.909807)
			(xy 34.001715 -430.85537) (xy 33.997644 -430.799748) (xy 33.74517 -430.799748) (xy 33.744661 -430.827634)
			(xy 33.736541 -430.88281) (xy 33.720473 -430.936217) (xy 33.696801 -430.986714) (xy 33.666028 -431.033227)
			(xy 33.628811 -431.074764) (xy 33.585943 -431.110439) (xy 33.538337 -431.139493) (xy 33.487008 -431.161305)
			(xy 33.433051 -431.175411) (xy 33.377614 -431.181511) (xy 33.32188 -431.179474) (xy 33.267037 -431.169344)
			(xy 33.214253 -431.151337) (xy 33.164653 -431.125836) (xy 33.119295 -431.093385) (xy 33.079146 -431.054676)
			(xy 33.04506 -431.010533) (xy 33.017764 -430.961898) (xy 32.997841 -430.909807) (xy 32.985715 -430.85537)
			(xy 32.981644 -430.799748) (xy 30.696242 -430.799748) (xy 30.688541 -430.852076) (xy 30.672473 -430.905483)
			(xy 30.648801 -430.95598) (xy 30.618028 -431.002493) (xy 30.580811 -431.04403) (xy 30.537943 -431.079705)
			(xy 30.490337 -431.108759) (xy 30.439008 -431.130571) (xy 30.385051 -431.144677) (xy 30.329614 -431.150777)
			(xy 30.27388 -431.14874) (xy 30.219037 -431.13861) (xy 30.166253 -431.120603) (xy 30.116653 -431.095102)
			(xy 30.071295 -431.062651) (xy 30.031146 -431.023942) (xy 29.99706 -430.979799) (xy 29.969764 -430.931164)
			(xy 29.949841 -430.879073) (xy 29.937715 -430.824636) (xy 29.933644 -430.769014) (xy 29.68117 -430.769014)
			(xy 29.680661 -430.7969) (xy 29.672541 -430.852076) (xy 29.656473 -430.905483) (xy 29.632801 -430.95598)
			(xy 29.602028 -431.002493) (xy 29.564811 -431.04403) (xy 29.521943 -431.079705) (xy 29.474337 -431.108759)
			(xy 29.423008 -431.130571) (xy 29.369051 -431.144677) (xy 29.313614 -431.150777) (xy 29.25788 -431.14874)
			(xy 29.203037 -431.13861) (xy 29.150253 -431.120603) (xy 29.100653 -431.095102) (xy 29.055295 -431.062651)
			(xy 29.015146 -431.023942) (xy 28.98106 -430.979799) (xy 28.953764 -430.931164) (xy 28.933841 -430.879073)
			(xy 28.921715 -430.824636) (xy 28.917644 -430.769014) (xy 27.397834 -430.769014) (xy 27.410671 -430.811682)
			(xy 27.418791 -430.866858) (xy 27.4193 -430.894744) (xy 27.418791 -430.92263) (xy 27.410671 -430.977806)
			(xy 27.394603 -431.031213) (xy 27.370931 -431.08171) (xy 27.340158 -431.128223) (xy 27.302941 -431.16976)
			(xy 27.260073 -431.205435) (xy 27.212467 -431.234489) (xy 27.161138 -431.256301) (xy 27.107181 -431.270407)
			(xy 27.051744 -431.276507) (xy 26.99601 -431.27447) (xy 26.941167 -431.26434) (xy 26.888383 -431.246333)
			(xy 26.838783 -431.220832) (xy 26.793425 -431.188381) (xy 26.753276 -431.149672) (xy 26.71919 -431.105529)
			(xy 26.691894 -431.056894) (xy 26.671971 -431.004803) (xy 26.659845 -430.950366) (xy 26.655774 -430.894744)
			(xy 24.91803 -430.894744) (xy 24.918162 -430.903126) (xy 24.91766 -430.935087) (xy 24.909649 -430.998505)
			(xy 24.893752 -431.060419) (xy 24.87022 -431.119852) (xy 24.839426 -431.175867) (xy 24.801853 -431.227582)
			(xy 24.758096 -431.274179) (xy 24.708843 -431.314924) (xy 24.654872 -431.349175) (xy 24.597033 -431.376392)
			(xy 24.53624 -431.396145) (xy 24.47345 -431.408123) (xy 24.409654 -431.412137) (xy 24.345858 -431.408123)
			(xy 24.283068 -431.396145) (xy 24.222275 -431.376392) (xy 24.164436 -431.349175) (xy 24.110465 -431.314924)
			(xy 24.061212 -431.274179) (xy 24.017455 -431.227582) (xy 23.979882 -431.175867) (xy 23.949088 -431.119852)
			(xy 23.925556 -431.060419) (xy 23.909659 -430.998505) (xy 23.901648 -430.935087) (xy 21.101012 -430.935087)
			(xy 21.142379 -430.948528) (xy 21.200218 -430.975745) (xy 21.254189 -431.009996) (xy 21.303442 -431.050741)
			(xy 21.347199 -431.097338) (xy 21.384772 -431.149053) (xy 21.415566 -431.205068) (xy 21.439098 -431.264501)
			(xy 21.454995 -431.326415) (xy 21.463006 -431.389833) (xy 21.463508 -431.421794) (xy 21.463006 -431.453755)
			(xy 21.454995 -431.517173) (xy 21.439098 -431.579087) (xy 21.415566 -431.63852) (xy 21.384772 -431.694535)
			(xy 21.347199 -431.74625) (xy 21.303442 -431.792847) (xy 21.254189 -431.833592) (xy 21.200218 -431.867843)
			(xy 21.142379 -431.89506) (xy 21.081586 -431.914813) (xy 21.018796 -431.926791) (xy 20.955 -431.930805)
			(xy 20.891204 -431.926791) (xy 20.828414 -431.914813) (xy 20.767621 -431.89506) (xy 20.709782 -431.867843)
			(xy 20.655811 -431.833592) (xy 20.606558 -431.792847) (xy 20.562801 -431.74625) (xy 20.525228 -431.694535)
			(xy 20.494434 -431.63852) (xy 20.470902 -431.579087) (xy 20.455005 -431.517173) (xy 20.446994 -431.453755)
			(xy 19.738551 -431.453755) (xy 19.783298 -431.498502) (xy 19.790144 -431.5059) (xy 19.797879 -431.524498)
			(xy 19.798284 -431.53457) (xy 19.798284 -432.4223) (xy 19.937982 -432.4223) (xy 19.942053 -432.366678)
			(xy 19.954179 -432.312241) (xy 19.974102 -432.26015) (xy 20.001398 -432.211515) (xy 20.035484 -432.167372)
			(xy 20.075633 -432.128663) (xy 20.120991 -432.096212) (xy 20.170591 -432.070711) (xy 20.223375 -432.052704)
			(xy 20.278218 -432.042574) (xy 20.333952 -432.040537) (xy 20.389389 -432.046637) (xy 20.443346 -432.060743)
			(xy 20.494675 -432.082555) (xy 20.542281 -432.111609) (xy 20.585149 -432.147284) (xy 20.622366 -432.188821)
			(xy 20.653139 -432.235334) (xy 20.676811 -432.285831) (xy 20.692879 -432.339238) (xy 20.700999 -432.394414)
			(xy 20.701508 -432.4223) (xy 20.700999 -432.450186) (xy 20.693013 -432.504453) (xy 31.396142 -432.504453)
			(xy 31.396142 -432.449947) (xy 31.403898 -432.395996) (xy 31.419254 -432.343698) (xy 31.441896 -432.294118)
			(xy 31.471363 -432.248264) (xy 31.507055 -432.207071) (xy 31.548247 -432.171376) (xy 31.594099 -432.141906)
			(xy 31.643678 -432.119262) (xy 31.695975 -432.103903) (xy 31.749925 -432.096143) (xy 31.777178 -432.095656)
			(xy 31.791394 -432.095814) (xy 31.819744 -432.097975) (xy 31.83382 -432.099974) (xy 31.84652 -432.101752)
			(xy 31.87065 -432.093116) (xy 31.94431 -432.010566) (xy 31.950406 -431.985674) (xy 31.947104 -431.973228)
			(xy 31.939048 -431.941062) (xy 31.930383 -431.875319) (xy 31.929832 -431.842164) (xy 31.930303 -431.810623)
			(xy 31.938106 -431.748024) (xy 31.953591 -431.686872) (xy 31.976522 -431.628104) (xy 32.006546 -431.572625)
			(xy 32.043201 -431.521285) (xy 32.085925 -431.474873) (xy 32.134063 -431.434102) (xy 32.186873 -431.399599)
			(xy 32.243546 -431.371893) (xy 32.30321 -431.35141) (xy 32.36495 -431.338464) (xy 32.427818 -431.333254)
			(xy 32.490846 -431.335861) (xy 32.553069 -431.346244) (xy 32.613529 -431.364243) (xy 32.671299 -431.389583)
			(xy 32.72549 -431.421874) (xy 32.775271 -431.46062) (xy 32.819878 -431.505226) (xy 32.858624 -431.555007)
			(xy 32.890915 -431.609198) (xy 32.916256 -431.666967) (xy 32.934256 -431.727427) (xy 32.944639 -431.78965)
			(xy 32.947246 -431.852678) (xy 32.942037 -431.915546) (xy 32.929091 -431.977286) (xy 32.908608 -432.03695)
			(xy 32.883283 -432.088755) (xy 35.813994 -432.088755) (xy 35.813994 -432.024833) (xy 35.822005 -431.961415)
			(xy 35.837902 -431.899501) (xy 35.861434 -431.840068) (xy 35.892228 -431.784053) (xy 35.929801 -431.732338)
			(xy 35.973558 -431.685741) (xy 36.022811 -431.644996) (xy 36.076782 -431.610745) (xy 36.134621 -431.583528)
			(xy 36.195414 -431.563775) (xy 36.258204 -431.551797) (xy 36.322 -431.547784) (xy 36.385796 -431.551797)
			(xy 36.448586 -431.563775) (xy 36.509379 -431.583528) (xy 36.567218 -431.610745) (xy 36.621189 -431.644996)
			(xy 36.670442 -431.685741) (xy 36.714199 -431.732338) (xy 36.751772 -431.784053) (xy 36.782566 -431.840068)
			(xy 36.806098 -431.899501) (xy 36.821995 -431.961415) (xy 36.830006 -432.024833) (xy 36.830508 -432.056794)
			(xy 36.830006 -432.088755) (xy 36.821995 -432.152173) (xy 36.806098 -432.214087) (xy 36.782566 -432.27352)
			(xy 36.766846 -432.302115) (xy 46.51349 -432.302115) (xy 46.51349 -432.238193) (xy 46.521501 -432.174775)
			(xy 46.537398 -432.112861) (xy 46.56093 -432.053428) (xy 46.591724 -431.997413) (xy 46.629297 -431.945698)
			(xy 46.673054 -431.899101) (xy 46.722307 -431.858356) (xy 46.776278 -431.824105) (xy 46.834117 -431.796888)
			(xy 46.89491 -431.777135) (xy 46.9577 -431.765157) (xy 47.021496 -431.761144) (xy 47.085292 -431.765157)
			(xy 47.148082 -431.777135) (xy 47.208875 -431.796888) (xy 47.266714 -431.824105) (xy 47.320685 -431.858356)
			(xy 47.369938 -431.899101) (xy 47.413695 -431.945698) (xy 47.451268 -431.997413) (xy 47.482062 -432.053428)
			(xy 47.505594 -432.112861) (xy 47.521491 -432.174775) (xy 47.529502 -432.238193) (xy 47.530004 -432.270154)
			(xy 47.529502 -432.302115) (xy 47.529144 -432.304952) (xy 47.977296 -432.304952) (xy 47.981367 -432.24933)
			(xy 47.993493 -432.194893) (xy 48.013416 -432.142802) (xy 48.040712 -432.094167) (xy 48.074798 -432.050024)
			(xy 48.114947 -432.011315) (xy 48.160305 -431.978864) (xy 48.209905 -431.953363) (xy 48.262689 -431.935356)
			(xy 48.317532 -431.925226) (xy 48.373266 -431.923189) (xy 48.428703 -431.929289) (xy 48.48266 -431.943395)
			(xy 48.533989 -431.965207) (xy 48.581595 -431.994261) (xy 48.624463 -432.029936) (xy 48.66168 -432.071473)
			(xy 48.692453 -432.117986) (xy 48.716125 -432.168483) (xy 48.732193 -432.22189) (xy 48.740313 -432.277066)
			(xy 48.740822 -432.304952) (xy 48.740313 -432.332838) (xy 48.732193 -432.388014) (xy 48.716125 -432.441421)
			(xy 48.692453 -432.491918) (xy 48.66168 -432.538431) (xy 48.624463 -432.579968) (xy 48.581595 -432.615643)
			(xy 48.533989 -432.644697) (xy 48.48266 -432.666509) (xy 48.428703 -432.680615) (xy 48.373266 -432.686715)
			(xy 48.317532 -432.684678) (xy 48.262689 -432.674548) (xy 48.209905 -432.656541) (xy 48.160305 -432.63104)
			(xy 48.114947 -432.598589) (xy 48.074798 -432.55988) (xy 48.040712 -432.515737) (xy 48.013416 -432.467102)
			(xy 47.993493 -432.415011) (xy 47.981367 -432.360574) (xy 47.977296 -432.304952) (xy 47.529144 -432.304952)
			(xy 47.521491 -432.365533) (xy 47.505594 -432.427447) (xy 47.482062 -432.48688) (xy 47.451268 -432.542895)
			(xy 47.413695 -432.59461) (xy 47.369938 -432.641207) (xy 47.320685 -432.681952) (xy 47.266714 -432.716203)
			(xy 47.208875 -432.74342) (xy 47.148082 -432.763173) (xy 47.085292 -432.775151) (xy 47.021496 -432.779165)
			(xy 46.9577 -432.775151) (xy 46.89491 -432.763173) (xy 46.834117 -432.74342) (xy 46.776278 -432.716203)
			(xy 46.722307 -432.681952) (xy 46.673054 -432.641207) (xy 46.629297 -432.59461) (xy 46.591724 -432.542895)
			(xy 46.56093 -432.48688) (xy 46.537398 -432.427447) (xy 46.521501 -432.365533) (xy 46.51349 -432.302115)
			(xy 36.766846 -432.302115) (xy 36.751772 -432.329535) (xy 36.714199 -432.38125) (xy 36.670442 -432.427847)
			(xy 36.621189 -432.468592) (xy 36.567218 -432.502843) (xy 36.509379 -432.53006) (xy 36.448586 -432.549813)
			(xy 36.385796 -432.561791) (xy 36.322 -432.565805) (xy 36.258204 -432.561791) (xy 36.195414 -432.549813)
			(xy 36.134621 -432.53006) (xy 36.076782 -432.502843) (xy 36.022811 -432.468592) (xy 35.973558 -432.427847)
			(xy 35.929801 -432.38125) (xy 35.892228 -432.329535) (xy 35.861434 -432.27352) (xy 35.837902 -432.214087)
			(xy 35.822005 -432.152173) (xy 35.813994 -432.088755) (xy 32.883283 -432.088755) (xy 32.880903 -432.093623)
			(xy 32.8464 -432.146434) (xy 32.80563 -432.194572) (xy 32.759218 -432.237296) (xy 32.707879 -432.273952)
			(xy 32.652399 -432.303976) (xy 32.593632 -432.326908) (xy 32.53248 -432.342393) (xy 32.469881 -432.350196)
			(xy 32.43834 -432.350672) (xy 32.400024 -432.350005) (xy 32.324259 -432.338521) (xy 32.287464 -432.327812)
			(xy 32.275272 -432.324002) (xy 32.250126 -432.328828) (xy 32.164528 -432.39944) (xy 32.15513 -432.423062)
			(xy 32.1564 -432.435762) (xy 32.157465 -432.44608) (xy 32.158609 -432.466792) (xy 32.158686 -432.477164)
			(xy 32.157995 -432.509353) (xy 32.147139 -432.572811) (xy 32.137096 -432.603402) (xy 32.132524 -432.616356)
			(xy 32.13735 -432.642518) (xy 32.21101 -432.730402) (xy 32.235902 -432.739546) (xy 32.249364 -432.73726)
			(xy 32.269795 -432.734145) (xy 32.310994 -432.730842) (xy 32.33166 -432.730656) (xy 32.363205 -432.731125)
			(xy 32.42581 -432.738924) (xy 32.486969 -432.754407) (xy 32.545744 -432.777337) (xy 32.601231 -432.80736)
			(xy 32.652578 -432.844017) (xy 32.698997 -432.886743) (xy 32.739773 -432.934884) (xy 32.774282 -432.987698)
			(xy 32.801993 -433.044375) (xy 32.822481 -433.104045) (xy 32.83543 -433.165791) (xy 32.840188 -433.2232)
			(xy 36.59673 -433.2232) (xy 36.600745 -433.159393) (xy 36.612726 -433.096593) (xy 36.632483 -433.035789)
			(xy 36.659706 -432.977942) (xy 36.693964 -432.923962) (xy 36.734719 -432.874703) (xy 36.781326 -432.830939)
			(xy 36.833051 -432.793363) (xy 36.889077 -432.762567) (xy 36.948522 -432.739035) (xy 37.010448 -432.72314)
			(xy 37.073877 -432.715132) (xy 37.105844 -432.714654) (xy 37.137354 -432.715171) (xy 37.199892 -432.722958)
			(xy 37.260989 -432.738407) (xy 37.319711 -432.761282) (xy 37.37516 -432.791233) (xy 37.426486 -432.827801)
			(xy 37.450014 -432.848766) (xy 37.457126 -432.85537) (xy 37.474906 -432.862228) (xy 37.56279 -432.862228)
			(xy 37.58057 -432.85537) (xy 37.587682 -432.848766) (xy 37.611189 -432.827773) (xy 37.662513 -432.791192)
			(xy 37.717963 -432.761232) (xy 37.776691 -432.738353) (xy 37.837794 -432.722905) (xy 37.900339 -432.715124)
			(xy 37.931852 -432.714654) (xy 37.963391 -432.715184) (xy 38.025985 -432.72298) (xy 38.087135 -432.738459)
			(xy 38.1459 -432.761382) (xy 38.201379 -432.791398) (xy 38.252719 -432.828046) (xy 38.299132 -432.870762)
			(xy 38.339905 -432.918891) (xy 38.357556 -432.945032) (xy 38.36416 -432.955192) (xy 38.384988 -432.96713)
			(xy 38.49116 -432.973226) (xy 38.513004 -432.963574) (xy 38.520878 -432.954176) (xy 38.539085 -432.932885)
			(xy 38.580666 -432.895345) (xy 38.627293 -432.864294) (xy 38.677963 -432.840402) (xy 38.731583 -432.824183)
			(xy 38.787 -432.815986) (xy 38.81501 -432.815492) (xy 38.842261 -432.815978) (xy 38.896207 -432.823736)
			(xy 38.948501 -432.839092) (xy 38.998077 -432.861734) (xy 39.043926 -432.8912) (xy 39.085115 -432.926892)
			(xy 39.120806 -432.968082) (xy 39.150271 -433.013932) (xy 39.172911 -433.063508) (xy 39.175625 -433.072751)
			(xy 40.827954 -433.072751) (xy 40.827954 -433.008829) (xy 40.835965 -432.945411) (xy 40.851862 -432.883497)
			(xy 40.875394 -432.824064) (xy 40.906188 -432.768049) (xy 40.943761 -432.716334) (xy 40.987518 -432.669737)
			(xy 41.036771 -432.628992) (xy 41.090742 -432.594741) (xy 41.148581 -432.567524) (xy 41.209374 -432.547771)
			(xy 41.272164 -432.535793) (xy 41.33596 -432.53178) (xy 41.399756 -432.535793) (xy 41.462546 -432.547771)
			(xy 41.523339 -432.567524) (xy 41.581178 -432.594741) (xy 41.635149 -432.628992) (xy 41.684402 -432.669737)
			(xy 41.728159 -432.716334) (xy 41.765732 -432.768049) (xy 41.796526 -432.824064) (xy 41.820058 -432.883497)
			(xy 41.835955 -432.945411) (xy 41.839019 -432.96967) (xy 50.30343 -432.96967) (xy 50.303906 -432.943567)
			(xy 50.311032 -432.891849) (xy 50.325147 -432.841587) (xy 50.345986 -432.793721) (xy 50.373161 -432.749145)
			(xy 50.406163 -432.708693) (xy 50.444374 -432.673121) (xy 50.465482 -432.657758) (xy 50.47361 -432.651916)
			(xy 50.484024 -432.63566) (xy 50.50155 -432.547268) (xy 50.497994 -432.528218) (xy 50.49266 -432.519836)
			(xy 50.477454 -432.495298) (xy 50.452124 -432.44342) (xy 50.432836 -432.389007) (xy 50.419841 -432.332757)
			(xy 50.413305 -432.275398) (xy 50.412904 -432.246532) (xy 50.413406 -432.214571) (xy 50.421417 -432.151153)
			(xy 50.437314 -432.089239) (xy 50.460846 -432.029806) (xy 50.49164 -431.973791) (xy 50.529213 -431.922076)
			(xy 50.57297 -431.875479) (xy 50.622223 -431.834734) (xy 50.676194 -431.800483) (xy 50.734033 -431.773266)
			(xy 50.794826 -431.753513) (xy 50.857616 -431.741535) (xy 50.921412 -431.737522) (xy 50.985208 -431.741535)
			(xy 51.047998 -431.753513) (xy 51.108791 -431.773266) (xy 51.16663 -431.800483) (xy 51.220601 -431.834734)
			(xy 51.269854 -431.875479) (xy 51.313611 -431.922076) (xy 51.351184 -431.973791) (xy 51.381978 -432.029806)
			(xy 51.40551 -432.089239) (xy 51.421407 -432.151153) (xy 51.429418 -432.214571) (xy 51.42992 -432.246532)
			(xy 51.429443 -432.277048) (xy 51.422157 -432.337643) (xy 51.407667 -432.396929) (xy 51.386184 -432.454055)
			(xy 51.358016 -432.508197) (xy 51.323569 -432.558578) (xy 51.283338 -432.604472) (xy 51.237901 -432.64522)
			(xy 51.187913 -432.680234) (xy 51.134092 -432.709012) (xy 51.105816 -432.720496) (xy 51.096418 -432.724052)
			(xy 51.082448 -432.73726) (xy 51.044348 -432.818794) (xy 51.043332 -432.838098) (xy 51.04638 -432.847496)
			(xy 51.055758 -432.877164) (xy 51.065834 -432.938561) (xy 51.066446 -432.96967) (xy 51.06596 -432.996921)
			(xy 51.058204 -433.050869) (xy 51.042849 -433.103164) (xy 51.020207 -433.152741) (xy 50.990741 -433.198591)
			(xy 50.95505 -433.239782) (xy 50.913859 -433.275473) (xy 50.868009 -433.304939) (xy 50.818432 -433.327581)
			(xy 50.766137 -433.342936) (xy 50.712189 -433.350692) (xy 50.657687 -433.350692) (xy 50.603739 -433.342936)
			(xy 50.551444 -433.327581) (xy 50.501867 -433.304939) (xy 50.456017 -433.275473) (xy 50.414826 -433.239782)
			(xy 50.379135 -433.198591) (xy 50.349669 -433.152741) (xy 50.327027 -433.103164) (xy 50.311672 -433.050869)
			(xy 50.303916 -432.996921) (xy 50.30343 -432.96967) (xy 41.839019 -432.96967) (xy 41.843966 -433.008829)
			(xy 41.844468 -433.04079) (xy 41.843966 -433.072751) (xy 41.835955 -433.136169) (xy 41.820058 -433.198083)
			(xy 41.796526 -433.257516) (xy 41.765732 -433.313531) (xy 41.728159 -433.365246) (xy 41.684402 -433.411843)
			(xy 41.635149 -433.452588) (xy 41.581178 -433.486839) (xy 41.523339 -433.514056) (xy 41.462546 -433.533809)
			(xy 41.399756 -433.545787) (xy 41.33596 -433.549801) (xy 41.272164 -433.545787) (xy 41.209374 -433.533809)
			(xy 41.148581 -433.514056) (xy 41.090742 -433.486839) (xy 41.036771 -433.452588) (xy 40.987518 -433.411843)
			(xy 40.943761 -433.365246) (xy 40.906188 -433.313531) (xy 40.875394 -433.257516) (xy 40.851862 -433.198083)
			(xy 40.835965 -433.136169) (xy 40.827954 -433.072751) (xy 39.175625 -433.072751) (xy 39.188266 -433.115802)
			(xy 39.196022 -433.169749) (xy 39.196022 -433.224251) (xy 39.188266 -433.278198) (xy 39.172911 -433.330492)
			(xy 39.150271 -433.380068) (xy 39.120806 -433.425918) (xy 39.085115 -433.467108) (xy 39.043926 -433.5028)
			(xy 38.998077 -433.532266) (xy 38.948501 -433.554908) (xy 38.896207 -433.570264) (xy 38.842261 -433.578022)
			(xy 38.81501 -433.578508) (xy 38.788894 -433.578055) (xy 38.737151 -433.570932) (xy 38.686866 -433.556806)
			(xy 38.638983 -433.535942) (xy 38.594401 -433.50873) (xy 38.553955 -433.475682) (xy 38.535864 -433.456842)
			(xy 38.527482 -433.447952) (xy 38.504876 -433.43957) (xy 38.399466 -433.451762) (xy 38.3794 -433.465224)
			(xy 38.373304 -433.475638) (xy 38.356238 -433.504383) (xy 38.315722 -433.557556) (xy 38.26859 -433.604964)
			(xy 38.215654 -433.64579) (xy 38.157827 -433.679329) (xy 38.096104 -433.705005) (xy 38.03155 -433.722374)
			(xy 37.965277 -433.731137) (xy 37.931852 -433.73167) (xy 37.900341 -433.731176) (xy 37.837802 -433.723387)
			(xy 37.776703 -433.707935) (xy 37.717981 -433.685056) (xy 37.662533 -433.6551) (xy 37.611209 -433.618526)
			(xy 37.587682 -433.597558) (xy 37.58057 -433.590954) (xy 37.56279 -433.584096) (xy 37.474906 -433.584096)
			(xy 37.457126 -433.590954) (xy 37.450014 -433.597558) (xy 37.426497 -433.61854) (xy 37.375177 -433.655125)
			(xy 37.319729 -433.685088) (xy 37.261003 -433.707969) (xy 37.199901 -433.723419) (xy 37.137357 -433.7312)
			(xy 37.105844 -433.73167) (xy 37.073877 -433.731268) (xy 37.010448 -433.72326) (xy 36.948522 -433.707365)
			(xy 36.889077 -433.683833) (xy 36.833051 -433.653037) (xy 36.781326 -433.615461) (xy 36.734719 -433.571697)
			(xy 36.693964 -433.522438) (xy 36.659706 -433.468458) (xy 36.632483 -433.410611) (xy 36.612726 -433.349807)
			(xy 36.600745 -433.287007) (xy 36.59673 -433.2232) (xy 32.840188 -433.2232) (xy 32.840641 -433.228664)
			(xy 32.838036 -433.2917) (xy 32.827653 -433.353929) (xy 32.809653 -433.414395) (xy 32.784311 -433.472171)
			(xy 32.752018 -433.526368) (xy 32.713268 -433.576154) (xy 32.668657 -433.620765) (xy 32.618871 -433.659515)
			(xy 32.564674 -433.69181) (xy 32.506899 -433.717152) (xy 32.446432 -433.735153) (xy 32.384204 -433.745536)
			(xy 32.321168 -433.748142) (xy 32.258295 -433.74293) (xy 32.196549 -433.729982) (xy 32.136879 -433.709495)
			(xy 32.080201 -433.681784) (xy 32.027387 -433.647276) (xy 31.979246 -433.606499) (xy 31.936519 -433.560081)
			(xy 31.899863 -433.508734) (xy 31.869839 -433.453248) (xy 31.846909 -433.394473) (xy 31.831425 -433.333314)
			(xy 31.823626 -433.270709) (xy 31.823152 -433.239164) (xy 31.823588 -433.208946) (xy 31.830759 -433.148936)
			(xy 31.844994 -433.090199) (xy 31.866093 -433.033565) (xy 31.87954 -433.0065) (xy 31.885636 -432.994308)
			(xy 31.88462 -432.967892) (xy 31.82366 -432.870864) (xy 31.800292 -432.858164) (xy 31.786576 -432.858672)
			(xy 31.777178 -432.858672) (xy 31.749925 -432.858257) (xy 31.695975 -432.850497) (xy 31.643678 -432.835138)
			(xy 31.594099 -432.812494) (xy 31.548247 -432.783024) (xy 31.507055 -432.747329) (xy 31.471363 -432.706136)
			(xy 31.441896 -432.660282) (xy 31.419254 -432.610702) (xy 31.403898 -432.558404) (xy 31.396142 -432.504453)
			(xy 20.693013 -432.504453) (xy 20.692879 -432.505362) (xy 20.676811 -432.558769) (xy 20.653139 -432.609266)
			(xy 20.622366 -432.655779) (xy 20.585149 -432.697316) (xy 20.542281 -432.732991) (xy 20.494675 -432.762045)
			(xy 20.443346 -432.783857) (xy 20.389389 -432.797963) (xy 20.333952 -432.804063) (xy 20.278218 -432.802026)
			(xy 20.223375 -432.791896) (xy 20.170591 -432.773889) (xy 20.120991 -432.748388) (xy 20.075633 -432.715937)
			(xy 20.035484 -432.677228) (xy 20.001398 -432.633085) (xy 19.974102 -432.58445) (xy 19.954179 -432.532359)
			(xy 19.942053 -432.477922) (xy 19.937982 -432.4223) (xy 19.798284 -432.4223) (xy 19.798284 -433.485755)
			(xy 20.446994 -433.485755) (xy 20.446994 -433.421833) (xy 20.455005 -433.358415) (xy 20.470902 -433.296501)
			(xy 20.494434 -433.237068) (xy 20.525228 -433.181053) (xy 20.562801 -433.129338) (xy 20.606558 -433.082741)
			(xy 20.655811 -433.041996) (xy 20.709782 -433.007745) (xy 20.767621 -432.980528) (xy 20.828414 -432.960775)
			(xy 20.891204 -432.948797) (xy 20.955 -432.944784) (xy 21.018796 -432.948797) (xy 21.081586 -432.960775)
			(xy 21.142379 -432.980528) (xy 21.200218 -433.007745) (xy 21.254189 -433.041996) (xy 21.303442 -433.082741)
			(xy 21.347199 -433.129338) (xy 21.365408 -433.154401) (xy 23.248348 -433.154401) (xy 23.248348 -433.099899)
			(xy 23.256104 -433.045952) (xy 23.271459 -432.993657) (xy 23.2941 -432.94408) (xy 23.323566 -432.89823)
			(xy 23.359257 -432.85704) (xy 23.400447 -432.821348) (xy 23.446297 -432.791882) (xy 23.495873 -432.769241)
			(xy 23.548168 -432.753885) (xy 23.602115 -432.746128) (xy 23.629366 -432.745642) (xy 23.655499 -432.746091)
			(xy 23.707276 -432.753214) (xy 23.757594 -432.767346) (xy 23.805509 -432.788221) (xy 23.850122 -432.815447)
			(xy 23.890597 -432.848513) (xy 23.926174 -432.8868) (xy 23.941532 -432.907948) (xy 23.949896 -432.919161)
			(xy 23.971521 -432.936887) (xy 23.997145 -432.948084) (xy 24.024844 -432.951912) (xy 24.052543 -432.948084)
			(xy 24.078167 -432.936887) (xy 24.099792 -432.919161) (xy 24.108156 -432.907948) (xy 24.12605 -432.883178)
			(xy 24.166767 -432.837612) (xy 24.212655 -432.797258) (xy 24.26305 -432.762698) (xy 24.317227 -432.734431)
			(xy 24.374402 -432.712865) (xy 24.433751 -432.698311) (xy 24.494416 -432.69098) (xy 24.52497 -432.690524)
			(xy 24.556936 -432.690939) (xy 24.620363 -432.698948) (xy 24.682286 -432.714844) (xy 24.741729 -432.738376)
			(xy 24.797754 -432.769173) (xy 24.849476 -432.806749) (xy 24.896081 -432.850512) (xy 24.936834 -432.89977)
			(xy 24.971091 -432.953748) (xy 24.998313 -433.011595) (xy 25.018069 -433.072396) (xy 25.030049 -433.135195)
			(xy 25.034064 -433.199) (xy 25.030049 -433.262805) (xy 25.018069 -433.325604) (xy 24.998313 -433.386405)
			(xy 24.971091 -433.444252) (xy 24.936834 -433.49823) (xy 24.896081 -433.547488) (xy 24.849476 -433.591251)
			(xy 24.797754 -433.628827) (xy 24.741729 -433.659624) (xy 24.682286 -433.683156) (xy 24.620363 -433.699052)
			(xy 24.556936 -433.707061) (xy 24.52497 -433.70754) (xy 24.493285 -433.707044) (xy 24.430407 -433.699167)
			(xy 24.368996 -433.683538) (xy 24.310001 -433.6604) (xy 24.254339 -433.630111) (xy 24.202872 -433.593142)
			(xy 24.156396 -433.550064) (xy 24.115633 -433.501545) (xy 24.081215 -433.448337) (xy 24.067008 -433.420012)
			(xy 24.060523 -433.407635) (xy 24.042032 -433.386701) (xy 24.018559 -433.371563) (xy 23.991861 -433.363355)
			(xy 23.963938 -433.362692) (xy 23.936881 -433.369624) (xy 23.912716 -433.383631) (xy 23.90267 -433.393342)
			(xy 23.884669 -433.411266) (xy 23.844705 -433.442625) (xy 23.800933 -433.468405) (xy 23.754128 -433.488148)
			(xy 23.705116 -433.501506) (xy 23.654766 -433.508242) (xy 23.629366 -433.508658) (xy 23.602115 -433.508172)
			(xy 23.548168 -433.500415) (xy 23.495873 -433.485059) (xy 23.446297 -433.462418) (xy 23.400447 -433.432952)
			(xy 23.359257 -433.39726) (xy 23.323566 -433.35607) (xy 23.2941 -433.31022) (xy 23.271459 -433.260643)
			(xy 23.256104 -433.208348) (xy 23.248348 -433.154401) (xy 21.365408 -433.154401) (xy 21.384772 -433.181053)
			(xy 21.415566 -433.237068) (xy 21.439098 -433.296501) (xy 21.454995 -433.358415) (xy 21.463006 -433.421833)
			(xy 21.463508 -433.453794) (xy 21.463006 -433.485755) (xy 21.454995 -433.549173) (xy 21.439098 -433.611087)
			(xy 21.415566 -433.67052) (xy 21.386022 -433.724261) (xy 26.796994 -433.724261) (xy 26.796994 -433.660339)
			(xy 26.805005 -433.596921) (xy 26.820902 -433.535007) (xy 26.844434 -433.475574) (xy 26.875228 -433.419559)
			(xy 26.912801 -433.367844) (xy 26.956558 -433.321247) (xy 27.005811 -433.280502) (xy 27.059782 -433.246251)
			(xy 27.117621 -433.219034) (xy 27.178414 -433.199281) (xy 27.241204 -433.187303) (xy 27.305 -433.18329)
			(xy 27.368796 -433.187303) (xy 27.431586 -433.199281) (xy 27.492379 -433.219034) (xy 27.550218 -433.246251)
			(xy 27.604189 -433.280502) (xy 27.653442 -433.321247) (xy 27.697199 -433.367844) (xy 27.734772 -433.419559)
			(xy 27.765566 -433.475574) (xy 27.789098 -433.535007) (xy 27.804995 -433.596921) (xy 27.813006 -433.660339)
			(xy 27.813508 -433.6923) (xy 27.813006 -433.724261) (xy 27.804995 -433.787679) (xy 27.789098 -433.849593)
			(xy 27.765566 -433.909026) (xy 27.734772 -433.965041) (xy 27.697199 -434.016756) (xy 27.653442 -434.063353)
			(xy 27.604189 -434.104098) (xy 27.550218 -434.138349) (xy 27.503942 -434.160125) (xy 35.813994 -434.160125)
			(xy 35.813994 -434.096203) (xy 35.822005 -434.032785) (xy 35.837902 -433.970871) (xy 35.861434 -433.911438)
			(xy 35.892228 -433.855423) (xy 35.929801 -433.803708) (xy 35.973558 -433.757111) (xy 36.022811 -433.716366)
			(xy 36.076782 -433.682115) (xy 36.134621 -433.654898) (xy 36.195414 -433.635145) (xy 36.258204 -433.623167)
			(xy 36.322 -433.619154) (xy 36.385796 -433.623167) (xy 36.448586 -433.635145) (xy 36.509379 -433.654898)
			(xy 36.567218 -433.682115) (xy 36.621189 -433.716366) (xy 36.670442 -433.757111) (xy 36.714199 -433.803708)
			(xy 36.751772 -433.855423) (xy 36.782566 -433.911438) (xy 36.794157 -433.940712) (xy 43.286932 -433.940712)
			(xy 43.291003 -433.88509) (xy 43.303129 -433.830653) (xy 43.323052 -433.778562) (xy 43.350348 -433.729927)
			(xy 43.384434 -433.685784) (xy 43.424583 -433.647075) (xy 43.469941 -433.614624) (xy 43.519541 -433.589123)
			(xy 43.572325 -433.571116) (xy 43.627168 -433.560986) (xy 43.682902 -433.558949) (xy 43.738339 -433.565049)
			(xy 43.792296 -433.579155) (xy 43.843625 -433.600967) (xy 43.850109 -433.604924) (xy 48.575722 -433.604924)
			(xy 48.576208 -433.577673) (xy 48.583964 -433.523725) (xy 48.599319 -433.47143) (xy 48.621961 -433.421853)
			(xy 48.651427 -433.376003) (xy 48.687118 -433.334812) (xy 48.728309 -433.299121) (xy 48.774159 -433.269655)
			(xy 48.823736 -433.247013) (xy 48.876031 -433.231658) (xy 48.929979 -433.223902) (xy 48.984481 -433.223902)
			(xy 49.038429 -433.231658) (xy 49.090724 -433.247013) (xy 49.140301 -433.269655) (xy 49.186151 -433.299121)
			(xy 49.227342 -433.334812) (xy 49.263033 -433.376003) (xy 49.292499 -433.421853) (xy 49.315141 -433.47143)
			(xy 49.330496 -433.523725) (xy 49.338252 -433.577673) (xy 49.338738 -433.604924) (xy 49.338361 -433.629223)
			(xy 49.332208 -433.67743) (xy 49.319994 -433.724468) (xy 49.311306 -433.747164) (xy 49.308206 -433.755749)
			(xy 49.30768 -433.773978) (xy 49.31029 -433.782724) (xy 49.320196 -433.81168) (xy 49.323537 -433.820268)
			(xy 49.335249 -433.834472) (xy 49.343056 -433.839366) (xy 49.370802 -433.855745) (xy 49.422334 -433.89442)
			(xy 49.468566 -433.939296) (xy 49.508758 -433.989654) (xy 49.525936 -434.016912) (xy 49.531524 -434.026056)
			(xy 49.54905 -434.038248) (xy 49.644046 -434.056536) (xy 49.664874 -434.051964) (xy 49.67351 -434.04536)
			(xy 49.699954 -434.026231) (xy 49.756814 -433.994188) (xy 49.817307 -433.969683) (xy 49.880437 -433.95312)
			(xy 49.945168 -433.944769) (xy 49.977802 -433.944268) (xy 50.009761 -433.944818) (xy 50.073176 -433.952829)
			(xy 50.135087 -433.968726) (xy 50.194517 -433.992256) (xy 50.25053 -434.023049) (xy 50.302241 -434.06062)
			(xy 50.348836 -434.104375) (xy 50.389579 -434.153626) (xy 50.423829 -434.207594) (xy 50.451044 -434.26543)
			(xy 50.470796 -434.326221) (xy 50.482773 -434.389007) (xy 50.486787 -434.4528) (xy 50.482773 -434.516593)
			(xy 50.470796 -434.579379) (xy 50.451044 -434.64017) (xy 50.423829 -434.698006) (xy 50.389579 -434.751974)
			(xy 50.348836 -434.801225) (xy 50.302241 -434.84498) (xy 50.25053 -434.882551) (xy 50.194517 -434.913344)
			(xy 50.135087 -434.936874) (xy 50.073176 -434.952771) (xy 50.009761 -434.960782) (xy 49.977802 -434.961284)
			(xy 49.945744 -434.960773) (xy 49.882144 -434.952647) (xy 49.820064 -434.936613) (xy 49.790096 -434.925216)
			(xy 49.779174 -434.921152) (xy 49.756314 -434.922676) (xy 49.667414 -434.972714) (xy 49.654206 -434.99151)
			(xy 49.652174 -435.00294) (xy 49.647298 -435.029307) (xy 49.631151 -435.080437) (xy 49.608 -435.128801)
			(xy 49.5783 -435.173444) (xy 49.542639 -435.213485) (xy 49.501719 -435.248135) (xy 49.456348 -435.276709)
			(xy 49.40742 -435.298645) (xy 49.355902 -435.313509) (xy 49.30281 -435.321007) (xy 49.276 -435.321456)
			(xy 49.248751 -435.320922) (xy 49.194807 -435.313167) (xy 49.142516 -435.297814) (xy 49.092942 -435.275177)
			(xy 49.047094 -435.245715) (xy 49.005905 -435.210029) (xy 48.970214 -435.168844) (xy 48.940746 -435.123)
			(xy 48.918102 -435.073429) (xy 48.902743 -435.02114) (xy 48.894981 -434.967197) (xy 48.894492 -434.939948)
			(xy 48.894977 -434.911713) (xy 48.903273 -434.855857) (xy 48.911002 -434.828696) (xy 48.913282 -434.819988)
			(xy 48.912245 -434.802029) (xy 48.90897 -434.793644) (xy 48.897032 -434.765704) (xy 48.893017 -434.757458)
			(xy 48.880267 -434.744298) (xy 48.87214 -434.74005) (xy 48.843696 -434.725867) (xy 48.790225 -434.691506)
			(xy 48.741453 -434.65075) (xy 48.698141 -434.604233) (xy 48.660963 -434.552681) (xy 48.6305 -434.496898)
			(xy 48.607226 -434.437753) (xy 48.591504 -434.376169) (xy 48.58358 -434.313106) (xy 48.583088 -434.281326)
			(xy 48.583644 -434.247699) (xy 48.592521 -434.181032) (xy 48.610111 -434.116119) (xy 48.636106 -434.054091)
			(xy 48.670052 -433.996032) (xy 48.690276 -433.96916) (xy 48.695694 -433.961623) (xy 48.701153 -433.943897)
			(xy 48.700944 -433.934616) (xy 48.698912 -433.904136) (xy 48.697975 -433.895059) (xy 48.690545 -433.878403)
			(xy 48.684434 -433.871624) (xy 48.664189 -433.850094) (xy 48.629882 -433.801976) (xy 48.603407 -433.749143)
			(xy 48.585395 -433.69286) (xy 48.576278 -433.634472) (xy 48.575722 -433.604924) (xy 43.850109 -433.604924)
			(xy 43.891231 -433.630021) (xy 43.934099 -433.665696) (xy 43.971316 -433.707233) (xy 44.002089 -433.753746)
			(xy 44.025761 -433.804243) (xy 44.041829 -433.85765) (xy 44.049949 -433.912826) (xy 44.050458 -433.940712)
			(xy 44.049949 -433.968598) (xy 44.041829 -434.023774) (xy 44.037627 -434.03774) (xy 45.196758 -434.03774)
			(xy 45.200829 -433.982118) (xy 45.212955 -433.927681) (xy 45.232878 -433.87559) (xy 45.260174 -433.826955)
			(xy 45.29426 -433.782812) (xy 45.334409 -433.744103) (xy 45.379767 -433.711652) (xy 45.429367 -433.686151)
			(xy 45.482151 -433.668144) (xy 45.536994 -433.658014) (xy 45.592728 -433.655977) (xy 45.648165 -433.662077)
			(xy 45.702122 -433.676183) (xy 45.753451 -433.697995) (xy 45.801057 -433.727049) (xy 45.843925 -433.762724)
			(xy 45.881142 -433.804261) (xy 45.911915 -433.850774) (xy 45.935587 -433.901271) (xy 45.951655 -433.954678)
			(xy 45.959775 -434.009854) (xy 45.960284 -434.03774) (xy 45.959775 -434.065626) (xy 45.951655 -434.120802)
			(xy 45.935587 -434.174209) (xy 45.911915 -434.224706) (xy 45.881142 -434.271219) (xy 45.843925 -434.312756)
			(xy 45.801057 -434.348431) (xy 45.753451 -434.377485) (xy 45.702122 -434.399297) (xy 45.648165 -434.413403)
			(xy 45.592728 -434.419503) (xy 45.536994 -434.417466) (xy 45.482151 -434.407336) (xy 45.429367 -434.389329)
			(xy 45.379767 -434.363828) (xy 45.334409 -434.331377) (xy 45.29426 -434.292668) (xy 45.260174 -434.248525)
			(xy 45.232878 -434.19989) (xy 45.212955 -434.147799) (xy 45.200829 -434.093362) (xy 45.196758 -434.03774)
			(xy 44.037627 -434.03774) (xy 44.025761 -434.077181) (xy 44.002089 -434.127678) (xy 43.971316 -434.174191)
			(xy 43.934099 -434.215728) (xy 43.891231 -434.251403) (xy 43.843625 -434.280457) (xy 43.792296 -434.302269)
			(xy 43.738339 -434.316375) (xy 43.682902 -434.322475) (xy 43.627168 -434.320438) (xy 43.572325 -434.310308)
			(xy 43.519541 -434.292301) (xy 43.469941 -434.2668) (xy 43.424583 -434.234349) (xy 43.384434 -434.19564)
			(xy 43.350348 -434.151497) (xy 43.323052 -434.102862) (xy 43.303129 -434.050771) (xy 43.291003 -433.996334)
			(xy 43.286932 -433.940712) (xy 36.794157 -433.940712) (xy 36.806098 -433.970871) (xy 36.821995 -434.032785)
			(xy 36.830006 -434.096203) (xy 36.830508 -434.128164) (xy 36.830006 -434.160125) (xy 36.821995 -434.223543)
			(xy 36.806098 -434.285457) (xy 36.782566 -434.34489) (xy 36.751772 -434.400905) (xy 36.714199 -434.45262)
			(xy 36.670442 -434.499217) (xy 36.621189 -434.539962) (xy 36.567218 -434.574213) (xy 36.509379 -434.60143)
			(xy 36.448586 -434.621183) (xy 36.385796 -434.633161) (xy 36.322 -434.637175) (xy 36.258204 -434.633161)
			(xy 36.195414 -434.621183) (xy 36.134621 -434.60143) (xy 36.076782 -434.574213) (xy 36.022811 -434.539962)
			(xy 35.973558 -434.499217) (xy 35.929801 -434.45262) (xy 35.892228 -434.400905) (xy 35.861434 -434.34489)
			(xy 35.837902 -434.285457) (xy 35.822005 -434.223543) (xy 35.813994 -434.160125) (xy 27.503942 -434.160125)
			(xy 27.492379 -434.165566) (xy 27.431586 -434.185319) (xy 27.368796 -434.197297) (xy 27.305 -434.201311)
			(xy 27.241204 -434.197297) (xy 27.178414 -434.185319) (xy 27.117621 -434.165566) (xy 27.059782 -434.138349)
			(xy 27.005811 -434.104098) (xy 26.956558 -434.063353) (xy 26.912801 -434.016756) (xy 26.875228 -433.965041)
			(xy 26.844434 -433.909026) (xy 26.820902 -433.849593) (xy 26.805005 -433.787679) (xy 26.796994 -433.724261)
			(xy 21.386022 -433.724261) (xy 21.384772 -433.726535) (xy 21.347199 -433.77825) (xy 21.303442 -433.824847)
			(xy 21.254189 -433.865592) (xy 21.200218 -433.899843) (xy 21.142379 -433.92706) (xy 21.081586 -433.946813)
			(xy 21.018796 -433.958791) (xy 20.955 -433.962805) (xy 20.891204 -433.958791) (xy 20.828414 -433.946813)
			(xy 20.767621 -433.92706) (xy 20.709782 -433.899843) (xy 20.655811 -433.865592) (xy 20.606558 -433.824847)
			(xy 20.562801 -433.77825) (xy 20.525228 -433.726535) (xy 20.494434 -433.67052) (xy 20.470902 -433.611087)
			(xy 20.455005 -433.549173) (xy 20.446994 -433.485755) (xy 19.798284 -433.485755) (xy 19.798284 -435.290214)
			(xy 23.03475 -435.290214) (xy 23.038821 -435.234592) (xy 23.050947 -435.180155) (xy 23.07087 -435.128064)
			(xy 23.098166 -435.079429) (xy 23.132252 -435.035286) (xy 23.172401 -434.996577) (xy 23.217759 -434.964126)
			(xy 23.267359 -434.938625) (xy 23.320143 -434.920618) (xy 23.374986 -434.910488) (xy 23.43072 -434.908451)
			(xy 23.486157 -434.914551) (xy 23.540114 -434.928657) (xy 23.591443 -434.950469) (xy 23.610829 -434.9623)
			(xy 30.11119 -434.9623) (xy 30.115261 -434.906678) (xy 30.127387 -434.852241) (xy 30.14731 -434.80015)
			(xy 30.174606 -434.751515) (xy 30.208692 -434.707372) (xy 30.248841 -434.668663) (xy 30.294199 -434.636212)
			(xy 30.343799 -434.610711) (xy 30.396583 -434.592704) (xy 30.451426 -434.582574) (xy 30.50716 -434.580537)
			(xy 30.562597 -434.586637) (xy 30.616554 -434.600743) (xy 30.667883 -434.622555) (xy 30.715489 -434.651609)
			(xy 30.758357 -434.687284) (xy 30.795574 -434.728821) (xy 30.826347 -434.775334) (xy 30.842075 -434.808884)
			(xy 33.309304 -434.808884) (xy 33.313375 -434.753262) (xy 33.325501 -434.698825) (xy 33.345424 -434.646734)
			(xy 33.37272 -434.598099) (xy 33.406806 -434.553956) (xy 33.446955 -434.515247) (xy 33.492313 -434.482796)
			(xy 33.541913 -434.457295) (xy 33.594697 -434.439288) (xy 33.64954 -434.429158) (xy 33.705274 -434.427121)
			(xy 33.760711 -434.433221) (xy 33.814668 -434.447327) (xy 33.865997 -434.469139) (xy 33.913603 -434.498193)
			(xy 33.956471 -434.533868) (xy 33.993688 -434.575405) (xy 34.024461 -434.621918) (xy 34.048133 -434.672415)
			(xy 34.064201 -434.725822) (xy 34.072321 -434.780998) (xy 34.07283 -434.808884) (xy 34.072321 -434.83677)
			(xy 34.064201 -434.891946) (xy 34.048133 -434.945353) (xy 34.024461 -434.99585) (xy 33.993688 -435.042363)
			(xy 33.987818 -435.048914) (xy 37.02634 -435.048914) (xy 37.030411 -434.993292) (xy 37.042537 -434.938855)
			(xy 37.06246 -434.886764) (xy 37.089756 -434.838129) (xy 37.123842 -434.793986) (xy 37.163991 -434.755277)
			(xy 37.209349 -434.722826) (xy 37.258949 -434.697325) (xy 37.311733 -434.679318) (xy 37.366576 -434.669188)
			(xy 37.42231 -434.667151) (xy 37.477747 -434.673251) (xy 37.531704 -434.687357) (xy 37.583033 -434.709169)
			(xy 37.630639 -434.738223) (xy 37.673507 -434.773898) (xy 37.710724 -434.815435) (xy 37.741497 -434.861948)
			(xy 37.765169 -434.912445) (xy 37.781237 -434.965852) (xy 37.789357 -435.021028) (xy 37.789866 -435.048914)
			(xy 37.789357 -435.0768) (xy 37.781237 -435.131976) (xy 37.767496 -435.177649) (xy 40.827954 -435.177649)
			(xy 40.827954 -435.113727) (xy 40.835965 -435.050309) (xy 40.851862 -434.988395) (xy 40.875394 -434.928962)
			(xy 40.906188 -434.872947) (xy 40.943761 -434.821232) (xy 40.987518 -434.774635) (xy 41.036771 -434.73389)
			(xy 41.090742 -434.699639) (xy 41.148581 -434.672422) (xy 41.209374 -434.652669) (xy 41.272164 -434.640691)
			(xy 41.33596 -434.636678) (xy 41.399756 -434.640691) (xy 41.462546 -434.652669) (xy 41.523339 -434.672422)
			(xy 41.581178 -434.699639) (xy 41.635149 -434.73389) (xy 41.684402 -434.774635) (xy 41.728159 -434.821232)
			(xy 41.765732 -434.872947) (xy 41.796526 -434.928962) (xy 41.820058 -434.988395) (xy 41.835955 -435.050309)
			(xy 41.838121 -435.067456) (xy 42.162982 -435.067456) (xy 42.167053 -435.011834) (xy 42.179179 -434.957397)
			(xy 42.199102 -434.905306) (xy 42.226398 -434.856671) (xy 42.260484 -434.812528) (xy 42.300633 -434.773819)
			(xy 42.345991 -434.741368) (xy 42.395591 -434.715867) (xy 42.448375 -434.69786) (xy 42.503218 -434.68773)
			(xy 42.558952 -434.685693) (xy 42.614389 -434.691793) (xy 42.668346 -434.705899) (xy 42.719675 -434.727711)
			(xy 42.767281 -434.756765) (xy 42.810149 -434.79244) (xy 42.847366 -434.833977) (xy 42.878139 -434.88049)
			(xy 42.901811 -434.930987) (xy 42.917879 -434.984394) (xy 42.925999 -435.03957) (xy 42.926508 -435.067456)
			(xy 42.925999 -435.095342) (xy 42.918035 -435.149455) (xy 47.691034 -435.149455) (xy 47.691034 -435.085533)
			(xy 47.699045 -435.022115) (xy 47.714942 -434.960201) (xy 47.738474 -434.900768) (xy 47.769268 -434.844753)
			(xy 47.806841 -434.793038) (xy 47.850598 -434.746441) (xy 47.899851 -434.705696) (xy 47.953822 -434.671445)
			(xy 48.011661 -434.644228) (xy 48.072454 -434.624475) (xy 48.135244 -434.612497) (xy 48.19904 -434.608484)
			(xy 48.262836 -434.612497) (xy 48.325626 -434.624475) (xy 48.386419 -434.644228) (xy 48.444258 -434.671445)
			(xy 48.498229 -434.705696) (xy 48.547482 -434.746441) (xy 48.591239 -434.793038) (xy 48.628812 -434.844753)
			(xy 48.659606 -434.900768) (xy 48.683138 -434.960201) (xy 48.699035 -435.022115) (xy 48.707046 -435.085533)
			(xy 48.707548 -435.117494) (xy 48.707046 -435.149455) (xy 48.699035 -435.212873) (xy 48.683138 -435.274787)
			(xy 48.659606 -435.33422) (xy 48.628812 -435.390235) (xy 48.591239 -435.44195) (xy 48.547482 -435.488547)
			(xy 48.498229 -435.529292) (xy 48.444258 -435.563543) (xy 48.386419 -435.59076) (xy 48.325626 -435.610513)
			(xy 48.262836 -435.622491) (xy 48.19904 -435.626505) (xy 48.135244 -435.622491) (xy 48.072454 -435.610513)
			(xy 48.011661 -435.59076) (xy 47.953822 -435.563543) (xy 47.899851 -435.529292) (xy 47.850598 -435.488547)
			(xy 47.806841 -435.44195) (xy 47.769268 -435.390235) (xy 47.738474 -435.33422) (xy 47.714942 -435.274787)
			(xy 47.699045 -435.212873) (xy 47.691034 -435.149455) (xy 42.918035 -435.149455) (xy 42.917879 -435.150518)
			(xy 42.901811 -435.203925) (xy 42.878139 -435.254422) (xy 42.847366 -435.300935) (xy 42.810149 -435.342472)
			(xy 42.767281 -435.378147) (xy 42.719675 -435.407201) (xy 42.668346 -435.429013) (xy 42.614389 -435.443119)
			(xy 42.558952 -435.449219) (xy 42.503218 -435.447182) (xy 42.448375 -435.437052) (xy 42.395591 -435.419045)
			(xy 42.345991 -435.393544) (xy 42.300633 -435.361093) (xy 42.260484 -435.322384) (xy 42.226398 -435.278241)
			(xy 42.199102 -435.229606) (xy 42.179179 -435.177515) (xy 42.167053 -435.123078) (xy 42.162982 -435.067456)
			(xy 41.838121 -435.067456) (xy 41.843966 -435.113727) (xy 41.844468 -435.145688) (xy 41.843966 -435.177649)
			(xy 41.835955 -435.241067) (xy 41.820058 -435.302981) (xy 41.796526 -435.362414) (xy 41.765732 -435.418429)
			(xy 41.728159 -435.470144) (xy 41.684402 -435.516741) (xy 41.635149 -435.557486) (xy 41.581178 -435.591737)
			(xy 41.523339 -435.618954) (xy 41.462546 -435.638707) (xy 41.399756 -435.650685) (xy 41.33596 -435.654699)
			(xy 41.272164 -435.650685) (xy 41.209374 -435.638707) (xy 41.148581 -435.618954) (xy 41.090742 -435.591737)
			(xy 41.036771 -435.557486) (xy 40.987518 -435.516741) (xy 40.943761 -435.470144) (xy 40.906188 -435.418429)
			(xy 40.875394 -435.362414) (xy 40.851862 -435.302981) (xy 40.835965 -435.241067) (xy 40.827954 -435.177649)
			(xy 37.767496 -435.177649) (xy 37.765169 -435.185383) (xy 37.741497 -435.23588) (xy 37.710724 -435.282393)
			(xy 37.673507 -435.32393) (xy 37.630639 -435.359605) (xy 37.583033 -435.388659) (xy 37.531704 -435.410471)
			(xy 37.477747 -435.424577) (xy 37.42231 -435.430677) (xy 37.366576 -435.42864) (xy 37.311733 -435.41851)
			(xy 37.258949 -435.400503) (xy 37.209349 -435.375002) (xy 37.163991 -435.342551) (xy 37.123842 -435.303842)
			(xy 37.089756 -435.259699) (xy 37.06246 -435.211064) (xy 37.042537 -435.158973) (xy 37.030411 -435.104536)
			(xy 37.02634 -435.048914) (xy 33.987818 -435.048914) (xy 33.956471 -435.0839) (xy 33.913603 -435.119575)
			(xy 33.865997 -435.148629) (xy 33.814668 -435.170441) (xy 33.760711 -435.184547) (xy 33.705274 -435.190647)
			(xy 33.64954 -435.18861) (xy 33.594697 -435.17848) (xy 33.541913 -435.160473) (xy 33.492313 -435.134972)
			(xy 33.446955 -435.102521) (xy 33.406806 -435.063812) (xy 33.37272 -435.019669) (xy 33.345424 -434.971034)
			(xy 33.325501 -434.918943) (xy 33.313375 -434.864506) (xy 33.309304 -434.808884) (xy 30.842075 -434.808884)
			(xy 30.850019 -434.825831) (xy 30.866087 -434.879238) (xy 30.874207 -434.934414) (xy 30.874716 -434.9623)
			(xy 30.874207 -434.990186) (xy 30.866087 -435.045362) (xy 30.850019 -435.098769) (xy 30.826347 -435.149266)
			(xy 30.795574 -435.195779) (xy 30.758357 -435.237316) (xy 30.715489 -435.272991) (xy 30.667883 -435.302045)
			(xy 30.616554 -435.323857) (xy 30.562597 -435.337963) (xy 30.50716 -435.344063) (xy 30.451426 -435.342026)
			(xy 30.396583 -435.331896) (xy 30.343799 -435.313889) (xy 30.294199 -435.288388) (xy 30.248841 -435.255937)
			(xy 30.208692 -435.217228) (xy 30.174606 -435.173085) (xy 30.14731 -435.12445) (xy 30.127387 -435.072359)
			(xy 30.115261 -435.017922) (xy 30.11119 -434.9623) (xy 23.610829 -434.9623) (xy 23.639049 -434.979523)
			(xy 23.681917 -435.015198) (xy 23.719134 -435.056735) (xy 23.749907 -435.103248) (xy 23.773579 -435.153745)
			(xy 23.789647 -435.207152) (xy 23.797767 -435.262328) (xy 23.798276 -435.290214) (xy 23.797767 -435.3181)
			(xy 23.789647 -435.373276) (xy 23.773579 -435.426683) (xy 23.749907 -435.47718) (xy 23.719134 -435.523693)
			(xy 23.681917 -435.56523) (xy 23.639049 -435.600905) (xy 23.591443 -435.629959) (xy 23.540114 -435.651771)
			(xy 23.486157 -435.665877) (xy 23.43072 -435.671977) (xy 23.374986 -435.66994) (xy 23.320143 -435.65981)
			(xy 23.267359 -435.641803) (xy 23.217759 -435.616302) (xy 23.172401 -435.583851) (xy 23.132252 -435.545142)
			(xy 23.098166 -435.500999) (xy 23.07087 -435.452364) (xy 23.050947 -435.400273) (xy 23.038821 -435.345836)
			(xy 23.03475 -435.290214) (xy 19.798284 -435.290214) (xy 19.798284 -435.980035) (xy 20.319994 -435.980035)
			(xy 20.319994 -435.916113) (xy 20.328005 -435.852695) (xy 20.343902 -435.790781) (xy 20.367434 -435.731348)
			(xy 20.398228 -435.675333) (xy 20.435801 -435.623618) (xy 20.479558 -435.577021) (xy 20.528811 -435.536276)
			(xy 20.582782 -435.502025) (xy 20.640621 -435.474808) (xy 20.701414 -435.455055) (xy 20.764204 -435.443077)
			(xy 20.828 -435.439064) (xy 20.891796 -435.443077) (xy 20.954586 -435.455055) (xy 21.015379 -435.474808)
			(xy 21.073218 -435.502025) (xy 21.127189 -435.536276) (xy 21.176442 -435.577021) (xy 21.220199 -435.623618)
			(xy 21.257772 -435.675333) (xy 21.288566 -435.731348) (xy 21.312098 -435.790781) (xy 21.327995 -435.852695)
			(xy 21.336006 -435.916113) (xy 21.336508 -435.948074) (xy 21.336006 -435.980035) (xy 21.327995 -436.043453)
			(xy 21.317539 -436.084175) (xy 31.288476 -436.084175) (xy 31.288476 -436.020253) (xy 31.296487 -435.956835)
			(xy 31.312384 -435.894921) (xy 31.335916 -435.835488) (xy 31.36671 -435.779473) (xy 31.404283 -435.727758)
			(xy 31.44804 -435.681161) (xy 31.497293 -435.640416) (xy 31.551264 -435.606165) (xy 31.609103 -435.578948)
			(xy 31.669896 -435.559195) (xy 31.732686 -435.547217) (xy 31.796482 -435.543204) (xy 31.860278 -435.547217)
			(xy 31.923068 -435.559195) (xy 31.983861 -435.578948) (xy 32.0417 -435.606165) (xy 32.095671 -435.640416)
			(xy 32.144924 -435.681161) (xy 32.188681 -435.727758) (xy 32.226254 -435.779473) (xy 32.244492 -435.812649)
			(xy 33.965382 -435.812649) (xy 33.965382 -435.748727) (xy 33.973393 -435.685309) (xy 33.98929 -435.623395)
			(xy 34.012822 -435.563962) (xy 34.043616 -435.507947) (xy 34.081189 -435.456232) (xy 34.124946 -435.409635)
			(xy 34.174199 -435.36889) (xy 34.22817 -435.334639) (xy 34.286009 -435.307422) (xy 34.346802 -435.287669)
			(xy 34.409592 -435.275691) (xy 34.473388 -435.271678) (xy 34.537184 -435.275691) (xy 34.599974 -435.287669)
			(xy 34.660767 -435.307422) (xy 34.718606 -435.334639) (xy 34.772577 -435.36889) (xy 34.82183 -435.409635)
			(xy 34.865587 -435.456232) (xy 34.90316 -435.507947) (xy 34.933954 -435.563962) (xy 34.957486 -435.623395)
			(xy 34.973383 -435.685309) (xy 34.981394 -435.748727) (xy 34.981896 -435.780688) (xy 34.981394 -435.812649)
			(xy 34.973383 -435.876067) (xy 34.972123 -435.880975) (xy 38.253664 -435.880975) (xy 38.253664 -435.817053)
			(xy 38.261675 -435.753635) (xy 38.277572 -435.691721) (xy 38.301104 -435.632288) (xy 38.331898 -435.576273)
			(xy 38.369471 -435.524558) (xy 38.413228 -435.477961) (xy 38.462481 -435.437216) (xy 38.516452 -435.402965)
			(xy 38.574291 -435.375748) (xy 38.635084 -435.355995) (xy 38.697874 -435.344017) (xy 38.76167 -435.340004)
			(xy 38.825466 -435.344017) (xy 38.888256 -435.355995) (xy 38.949049 -435.375748) (xy 39.006888 -435.402965)
			(xy 39.060859 -435.437216) (xy 39.110112 -435.477961) (xy 39.153869 -435.524558) (xy 39.191442 -435.576273)
			(xy 39.222236 -435.632288) (xy 39.245768 -435.691721) (xy 39.261665 -435.753635) (xy 39.261708 -435.753975)
			(xy 44.801784 -435.753975) (xy 44.801784 -435.690053) (xy 44.809795 -435.626635) (xy 44.825692 -435.564721)
			(xy 44.849224 -435.505288) (xy 44.880018 -435.449273) (xy 44.917591 -435.397558) (xy 44.961348 -435.350961)
			(xy 45.010601 -435.310216) (xy 45.064572 -435.275965) (xy 45.122411 -435.248748) (xy 45.183204 -435.228995)
			(xy 45.245994 -435.217017) (xy 45.30979 -435.213004) (xy 45.373586 -435.217017) (xy 45.436376 -435.228995)
			(xy 45.497169 -435.248748) (xy 45.555008 -435.275965) (xy 45.608979 -435.310216) (xy 45.658232 -435.350961)
			(xy 45.701989 -435.397558) (xy 45.739562 -435.449273) (xy 45.770356 -435.505288) (xy 45.793888 -435.564721)
			(xy 45.809785 -435.626635) (xy 45.817796 -435.690053) (xy 45.818298 -435.722014) (xy 45.817796 -435.753975)
			(xy 45.809785 -435.817393) (xy 45.793888 -435.879307) (xy 45.770356 -435.93874) (xy 45.739562 -435.994755)
			(xy 45.701989 -436.04647) (xy 45.658232 -436.093067) (xy 45.608979 -436.133812) (xy 45.555008 -436.168063)
			(xy 45.497169 -436.19528) (xy 45.436376 -436.215033) (xy 45.373586 -436.227011) (xy 45.30979 -436.231025)
			(xy 45.245994 -436.227011) (xy 45.183204 -436.215033) (xy 45.122411 -436.19528) (xy 45.064572 -436.168063)
			(xy 45.010601 -436.133812) (xy 44.961348 -436.093067) (xy 44.917591 -436.04647) (xy 44.880018 -435.994755)
			(xy 44.849224 -435.93874) (xy 44.825692 -435.879307) (xy 44.809795 -435.817393) (xy 44.801784 -435.753975)
			(xy 39.261708 -435.753975) (xy 39.269676 -435.817053) (xy 39.270178 -435.849014) (xy 39.269676 -435.880975)
			(xy 39.261665 -435.944393) (xy 39.245768 -436.006307) (xy 39.222236 -436.06574) (xy 39.191442 -436.121755)
			(xy 39.153869 -436.17347) (xy 39.110112 -436.220067) (xy 39.060859 -436.260812) (xy 39.006888 -436.295063)
			(xy 38.949049 -436.32228) (xy 38.888256 -436.342033) (xy 38.825466 -436.354011) (xy 38.76167 -436.358025)
			(xy 38.697874 -436.354011) (xy 38.635084 -436.342033) (xy 38.574291 -436.32228) (xy 38.516452 -436.295063)
			(xy 38.462481 -436.260812) (xy 38.413228 -436.220067) (xy 38.369471 -436.17347) (xy 38.331898 -436.121755)
			(xy 38.301104 -436.06574) (xy 38.277572 -436.006307) (xy 38.261675 -435.944393) (xy 38.253664 -435.880975)
			(xy 34.972123 -435.880975) (xy 34.957486 -435.937981) (xy 34.933954 -435.997414) (xy 34.90316 -436.053429)
			(xy 34.865587 -436.105144) (xy 34.82183 -436.151741) (xy 34.772577 -436.192486) (xy 34.718606 -436.226737)
			(xy 34.660767 -436.253954) (xy 34.599974 -436.273707) (xy 34.537184 -436.285685) (xy 34.473388 -436.289699)
			(xy 34.409592 -436.285685) (xy 34.346802 -436.273707) (xy 34.286009 -436.253954) (xy 34.22817 -436.226737)
			(xy 34.174199 -436.192486) (xy 34.124946 -436.151741) (xy 34.081189 -436.105144) (xy 34.043616 -436.053429)
			(xy 34.012822 -435.997414) (xy 33.98929 -435.937981) (xy 33.973393 -435.876067) (xy 33.965382 -435.812649)
			(xy 32.244492 -435.812649) (xy 32.257048 -435.835488) (xy 32.28058 -435.894921) (xy 32.296477 -435.956835)
			(xy 32.304488 -436.020253) (xy 32.30499 -436.052214) (xy 32.304488 -436.084175) (xy 32.296477 -436.147593)
			(xy 32.28058 -436.209507) (xy 32.257048 -436.26894) (xy 32.226254 -436.324955) (xy 32.188681 -436.37667)
			(xy 32.144924 -436.423267) (xy 32.095671 -436.464012) (xy 32.0417 -436.498263) (xy 31.983861 -436.52548)
			(xy 31.923068 -436.545233) (xy 31.860278 -436.557211) (xy 31.796482 -436.561225) (xy 31.732686 -436.557211)
			(xy 31.669896 -436.545233) (xy 31.609103 -436.52548) (xy 31.551264 -436.498263) (xy 31.497293 -436.464012)
			(xy 31.44804 -436.423267) (xy 31.404283 -436.37667) (xy 31.36671 -436.324955) (xy 31.335916 -436.26894)
			(xy 31.312384 -436.209507) (xy 31.296487 -436.147593) (xy 31.288476 -436.084175) (xy 21.317539 -436.084175)
			(xy 21.312098 -436.105367) (xy 21.288566 -436.1648) (xy 21.257772 -436.220815) (xy 21.220199 -436.27253)
			(xy 21.176442 -436.319127) (xy 21.127189 -436.359872) (xy 21.073218 -436.394123) (xy 21.015379 -436.42134)
			(xy 20.954586 -436.441093) (xy 20.891796 -436.453071) (xy 20.828 -436.457085) (xy 20.764204 -436.453071)
			(xy 20.701414 -436.441093) (xy 20.640621 -436.42134) (xy 20.582782 -436.394123) (xy 20.528811 -436.359872)
			(xy 20.479558 -436.319127) (xy 20.435801 -436.27253) (xy 20.398228 -436.220815) (xy 20.367434 -436.1648)
			(xy 20.343902 -436.105367) (xy 20.328005 -436.043453) (xy 20.319994 -435.980035) (xy 19.798284 -435.980035)
			(xy 19.798284 -436.610252) (xy 19.798654 -436.619685) (xy 19.805467 -436.637276) (xy 19.818187 -436.651206)
			(xy 19.826478 -436.655718) (xy 19.92122 -436.702708) (xy 19.949922 -436.699914) (xy 19.961606 -436.691024)
			(xy 19.981619 -436.676248) (xy 20.024748 -436.651457) (xy 20.070736 -436.632488) (xy 20.118801 -436.619665)
			(xy 20.168127 -436.613205) (xy 20.193 -436.612792) (xy 20.220251 -436.613278) (xy 20.274199 -436.621034)
			(xy 20.326494 -436.636389) (xy 20.376071 -436.659031) (xy 20.421921 -436.688497) (xy 20.463112 -436.724188)
			(xy 20.498803 -436.765379) (xy 20.528269 -436.811229) (xy 20.534428 -436.824715) (xy 23.722698 -436.824715)
			(xy 23.725306 -436.761687) (xy 23.735689 -436.699465) (xy 23.75369 -436.639005) (xy 23.77903 -436.581236)
			(xy 23.811322 -436.527045) (xy 23.850069 -436.477265) (xy 23.894675 -436.432659) (xy 23.944457 -436.393914)
			(xy 23.998648 -436.361624) (xy 24.056418 -436.336285) (xy 24.116878 -436.318286) (xy 24.1791 -436.307904)
			(xy 24.242129 -436.305298) (xy 24.304996 -436.310509) (xy 24.366736 -436.323456) (xy 24.4264 -436.34394)
			(xy 24.483072 -436.371646) (xy 24.535881 -436.40615) (xy 24.584018 -436.446922) (xy 24.626741 -436.493334)
			(xy 24.663396 -436.544674) (xy 24.693418 -436.600154) (xy 24.716348 -436.658922) (xy 24.731832 -436.720075)
			(xy 24.739633 -436.782673) (xy 24.740108 -436.814214) (xy 24.739644 -436.844273) (xy 24.732507 -436.903967)
			(xy 24.718394 -436.962406) (xy 24.708358 -436.990744) (xy 24.70404 -437.002936) (xy 24.707342 -437.02732)
			(xy 24.770588 -437.116728) (xy 24.792432 -437.127904) (xy 24.805386 -437.12765) (xy 24.811482 -437.12765)
			(xy 24.838731 -437.128195) (xy 24.892674 -437.135948) (xy 24.944965 -437.151299) (xy 24.99454 -437.173935)
			(xy 25.040388 -437.203395) (xy 25.081577 -437.23908) (xy 25.117269 -437.280264) (xy 25.129949 -437.29999)
			(xy 31.791828 -437.29999) (xy 31.797036 -437.237128) (xy 31.809979 -437.175394) (xy 31.830458 -437.115734)
			(xy 31.85816 -437.059066) (xy 31.892658 -437.006259) (xy 31.933423 -436.958124) (xy 31.979828 -436.915402)
			(xy 32.031162 -436.878747) (xy 32.086635 -436.848724) (xy 32.145396 -436.825792) (xy 32.206542 -436.810305)
			(xy 32.269134 -436.802499) (xy 32.300672 -436.802022) (xy 32.334373 -436.80257) (xy 32.401184 -436.811468)
			(xy 32.466235 -436.829111) (xy 32.497522 -436.841646) (xy 32.510997 -436.846816) (xy 32.539665 -436.850086)
			(xy 32.568104 -436.845215) (xy 32.594049 -436.832592) (xy 32.615433 -436.813222) (xy 32.630554 -436.788648)
			(xy 32.638205 -436.760828) (xy 32.638492 -436.746396) (xy 32.638492 -436.7403) (xy 32.638978 -436.713049)
			(xy 32.646734 -436.659101) (xy 32.662089 -436.606806) (xy 32.684731 -436.557229) (xy 32.714197 -436.511379)
			(xy 32.749888 -436.470188) (xy 32.791079 -436.434497) (xy 32.836929 -436.405031) (xy 32.886506 -436.382389)
			(xy 32.938801 -436.367034) (xy 32.992749 -436.359278) (xy 33.047251 -436.359278) (xy 33.101199 -436.367034)
			(xy 33.153494 -436.382389) (xy 33.203071 -436.405031) (xy 33.248921 -436.434497) (xy 33.284326 -436.465175)
			(xy 36.575994 -436.465175) (xy 36.575994 -436.401253) (xy 36.584005 -436.337835) (xy 36.599902 -436.275921)
			(xy 36.623434 -436.216488) (xy 36.654228 -436.160473) (xy 36.691801 -436.108758) (xy 36.735558 -436.062161)
			(xy 36.784811 -436.021416) (xy 36.838782 -435.987165) (xy 36.896621 -435.959948) (xy 36.957414 -435.940195)
			(xy 37.020204 -435.928217) (xy 37.084 -435.924204) (xy 37.147796 -435.928217) (xy 37.210586 -435.940195)
			(xy 37.271379 -435.959948) (xy 37.329218 -435.987165) (xy 37.383189 -436.021416) (xy 37.432442 -436.062161)
			(xy 37.476199 -436.108758) (xy 37.513772 -436.160473) (xy 37.544566 -436.216488) (xy 37.568098 -436.275921)
			(xy 37.583995 -436.337835) (xy 37.592006 -436.401253) (xy 37.592508 -436.433214) (xy 37.592006 -436.465175)
			(xy 37.587733 -436.499) (xy 39.714422 -436.499) (xy 39.718493 -436.443378) (xy 39.730619 -436.388941)
			(xy 39.750542 -436.33685) (xy 39.777838 -436.288215) (xy 39.811924 -436.244072) (xy 39.852073 -436.205363)
			(xy 39.897431 -436.172912) (xy 39.947031 -436.147411) (xy 39.999815 -436.129404) (xy 40.054658 -436.119274)
			(xy 40.110392 -436.117237) (xy 40.165829 -436.123337) (xy 40.219786 -436.137443) (xy 40.271115 -436.159255)
			(xy 40.318721 -436.188309) (xy 40.361589 -436.223984) (xy 40.398806 -436.265521) (xy 40.429579 -436.312034)
			(xy 40.453251 -436.362531) (xy 40.4561 -436.372) (xy 46.440342 -436.372) (xy 46.444413 -436.316378)
			(xy 46.456539 -436.261941) (xy 46.476462 -436.20985) (xy 46.503758 -436.161215) (xy 46.537844 -436.117072)
			(xy 46.577993 -436.078363) (xy 46.623351 -436.045912) (xy 46.672951 -436.020411) (xy 46.725735 -436.002404)
			(xy 46.780578 -435.992274) (xy 46.836312 -435.990237) (xy 46.891749 -435.996337) (xy 46.945706 -436.010443)
			(xy 46.997035 -436.032255) (xy 47.044641 -436.061309) (xy 47.087509 -436.096984) (xy 47.124726 -436.138521)
			(xy 47.155499 -436.185034) (xy 47.179171 -436.235531) (xy 47.195239 -436.288938) (xy 47.203359 -436.344114)
			(xy 47.203868 -436.372) (xy 47.203359 -436.399886) (xy 47.195239 -436.455062) (xy 47.179171 -436.508469)
			(xy 47.155499 -436.558966) (xy 47.124726 -436.605479) (xy 47.087509 -436.647016) (xy 47.044641 -436.682691)
			(xy 46.997035 -436.711745) (xy 46.945706 -436.733557) (xy 46.891749 -436.747663) (xy 46.836312 -436.753763)
			(xy 46.780578 -436.751726) (xy 46.725735 -436.741596) (xy 46.672951 -436.723589) (xy 46.623351 -436.698088)
			(xy 46.577993 -436.665637) (xy 46.537844 -436.626928) (xy 46.503758 -436.582785) (xy 46.476462 -436.53415)
			(xy 46.456539 -436.482059) (xy 46.444413 -436.427622) (xy 46.440342 -436.372) (xy 40.4561 -436.372)
			(xy 40.469319 -436.415938) (xy 40.477439 -436.471114) (xy 40.477948 -436.499) (xy 40.477439 -436.526886)
			(xy 40.469319 -436.582062) (xy 40.453251 -436.635469) (xy 40.429579 -436.685966) (xy 40.398806 -436.732479)
			(xy 40.361589 -436.774016) (xy 40.318721 -436.809691) (xy 40.271115 -436.838745) (xy 40.219786 -436.860557)
			(xy 40.165829 -436.874663) (xy 40.110392 -436.880763) (xy 40.054658 -436.878726) (xy 39.999815 -436.868596)
			(xy 39.947031 -436.850589) (xy 39.897431 -436.825088) (xy 39.852073 -436.792637) (xy 39.811924 -436.753928)
			(xy 39.777838 -436.709785) (xy 39.750542 -436.66115) (xy 39.730619 -436.609059) (xy 39.718493 -436.554622)
			(xy 39.714422 -436.499) (xy 37.587733 -436.499) (xy 37.583995 -436.528593) (xy 37.568098 -436.590507)
			(xy 37.544566 -436.64994) (xy 37.513772 -436.705955) (xy 37.476199 -436.75767) (xy 37.432442 -436.804267)
			(xy 37.383189 -436.845012) (xy 37.329218 -436.879263) (xy 37.271379 -436.90648) (xy 37.210586 -436.926233)
			(xy 37.147796 -436.938211) (xy 37.084 -436.942225) (xy 37.020204 -436.938211) (xy 36.957414 -436.926233)
			(xy 36.896621 -436.90648) (xy 36.838782 -436.879263) (xy 36.784811 -436.845012) (xy 36.735558 -436.804267)
			(xy 36.691801 -436.75767) (xy 36.654228 -436.705955) (xy 36.623434 -436.64994) (xy 36.599902 -436.590507)
			(xy 36.584005 -436.528593) (xy 36.575994 -436.465175) (xy 33.284326 -436.465175) (xy 33.290112 -436.470188)
			(xy 33.325803 -436.511379) (xy 33.355269 -436.557229) (xy 33.377911 -436.606806) (xy 33.393266 -436.659101)
			(xy 33.401022 -436.713049) (xy 33.401022 -436.767551) (xy 33.393266 -436.821499) (xy 33.377911 -436.873794)
			(xy 33.355269 -436.923371) (xy 33.325803 -436.969221) (xy 33.290112 -437.010412) (xy 33.248921 -437.046103)
			(xy 33.236715 -437.053947) (xy 44.799498 -437.053947) (xy 44.799498 -436.990025) (xy 44.807509 -436.926607)
			(xy 44.823406 -436.864693) (xy 44.846938 -436.80526) (xy 44.877732 -436.749245) (xy 44.915305 -436.69753)
			(xy 44.959062 -436.650933) (xy 45.008315 -436.610188) (xy 45.062286 -436.575937) (xy 45.120125 -436.54872)
			(xy 45.180918 -436.528967) (xy 45.243708 -436.516989) (xy 45.307504 -436.512976) (xy 45.3713 -436.516989)
			(xy 45.43409 -436.528967) (xy 45.494883 -436.54872) (xy 45.552722 -436.575937) (xy 45.606693 -436.610188)
			(xy 45.655946 -436.650933) (xy 45.699703 -436.69753) (xy 45.737276 -436.749245) (xy 45.76807 -436.80526)
			(xy 45.791602 -436.864693) (xy 45.794942 -436.8777) (xy 49.975982 -436.8777) (xy 49.979997 -436.8139)
			(xy 49.991976 -436.751106) (xy 50.011731 -436.690309) (xy 50.038951 -436.632468) (xy 50.073206 -436.578494)
			(xy 50.113955 -436.52924) (xy 50.160557 -436.485481) (xy 50.212276 -436.447909) (xy 50.268297 -436.417115)
			(xy 50.327735 -436.393586) (xy 50.389654 -436.377692) (xy 50.453077 -436.369685) (xy 50.48504 -436.369206)
			(xy 50.518189 -436.36975) (xy 50.583926 -436.378356) (xy 50.647988 -436.395429) (xy 50.678842 -436.40756)
			(xy 50.690526 -436.412386) (xy 50.715164 -436.4101) (xy 50.806604 -436.350918) (xy 50.818542 -436.329328)
			(xy 50.81905 -436.316882) (xy 50.820549 -436.284386) (xy 50.830839 -436.22015) (xy 50.84923 -436.157749)
			(xy 50.875421 -436.098199) (xy 50.908986 -436.042472) (xy 50.928778 -436.016654) (xy 50.934874 -436.009288)
			(xy 50.940208 -435.991508) (xy 50.935128 -435.904894) (xy 50.927508 -435.88813) (xy 50.92065 -435.881272)
			(xy 50.899597 -435.859618) (xy 50.863868 -435.810931) (xy 50.836258 -435.757221) (xy 50.817459 -435.699831)
			(xy 50.807941 -435.640195) (xy 50.807366 -435.61) (xy 50.807793 -435.583281) (xy 50.815263 -435.530366)
			(xy 50.830044 -435.479012) (xy 50.851845 -435.430222) (xy 50.880241 -435.384952) (xy 50.914676 -435.344087)
			(xy 50.954476 -435.308426) (xy 50.998863 -435.278667) (xy 51.046967 -435.255393) (xy 51.097849 -435.239059)
			(xy 51.124104 -435.23408) (xy 51.135026 -435.232048) (xy 51.152552 -435.220364) (xy 51.204368 -435.136798)
			(xy 51.207416 -435.115716) (xy 51.204114 -435.105048) (xy 51.194242 -435.069606) (xy 51.183661 -434.9968)
			(xy 51.183032 -434.960014) (xy 51.183453 -434.928472) (xy 51.191254 -434.865874) (xy 51.206738 -434.80472)
			(xy 51.229667 -434.745952) (xy 51.25969 -434.690471) (xy 51.296344 -434.63913) (xy 51.339068 -434.592716)
			(xy 51.387204 -434.551944) (xy 51.440014 -434.517439) (xy 51.496686 -434.489731) (xy 51.55635 -434.469245)
			(xy 51.61809 -434.456297) (xy 51.680957 -434.451085) (xy 51.743987 -434.453689) (xy 51.80621 -434.464069)
			(xy 51.866672 -434.482066) (xy 51.924443 -434.507403) (xy 51.978636 -434.539692) (xy 52.028419 -434.578436)
			(xy 52.073028 -434.62304) (xy 52.111778 -434.672819) (xy 52.144072 -434.727009) (xy 52.169415 -434.784778)
			(xy 52.187419 -434.845237) (xy 52.197806 -434.907459) (xy 52.200416 -434.970488) (xy 52.195211 -435.033356)
			(xy 52.182269 -435.095098) (xy 52.16179 -435.154764) (xy 52.134088 -435.211439) (xy 52.099588 -435.264253)
			(xy 52.058821 -435.312393) (xy 52.012412 -435.355122) (xy 51.961075 -435.391782) (xy 51.905597 -435.42181)
			(xy 51.846831 -435.444745) (xy 51.78568 -435.460236) (xy 51.723082 -435.468044) (xy 51.69154 -435.468522)
			(xy 51.67376 -435.468268) (xy 51.662584 -435.46776) (xy 51.643026 -435.475888) (xy 51.575208 -435.547008)
			(xy 51.568096 -435.567074) (xy 51.569112 -435.57825) (xy 51.570382 -435.61) (xy 51.569953 -435.636234)
			(xy 51.562757 -435.688207) (xy 51.548501 -435.738702) (xy 51.538378 -435.762908) (xy 51.534568 -435.771798)
			(xy 51.533552 -435.790086) (xy 51.56073 -435.872636) (xy 51.572414 -435.887114) (xy 51.580796 -435.891686)
			(xy 51.609458 -435.908758) (xy 51.662438 -435.949304) (xy 51.709664 -435.996427) (xy 51.750325 -436.049318)
			(xy 51.783723 -436.107071) (xy 51.809285 -436.168694) (xy 51.826573 -436.23313) (xy 51.83529 -436.299273)
			(xy 51.835812 -436.33263) (xy 51.835372 -436.363361) (xy 51.82796 -436.424376) (xy 51.813248 -436.484052)
			(xy 51.791451 -436.54152) (xy 51.762885 -436.595942) (xy 51.727969 -436.646524) (xy 51.68721 -436.692528)
			(xy 51.641203 -436.733285) (xy 51.59062 -436.768199) (xy 51.536196 -436.796761) (xy 51.478727 -436.818556)
			(xy 51.41905 -436.833265) (xy 51.358035 -436.840674) (xy 51.327304 -436.841138) (xy 51.294154 -436.840615)
			(xy 51.228416 -436.832002) (xy 51.164355 -436.81492) (xy 51.133502 -436.802784) (xy 51.121818 -436.797958)
			(xy 51.09718 -436.800244) (xy 51.00574 -436.859426) (xy 50.993802 -436.881016) (xy 50.993294 -436.893462)
			(xy 50.991765 -436.926067) (xy 50.98141 -436.990514) (xy 50.962894 -437.053106) (xy 50.936521 -437.112815)
			(xy 50.902724 -437.168658) (xy 50.86206 -437.219717) (xy 50.815196 -437.265153) (xy 50.762904 -437.30422)
			(xy 50.706043 -437.336274) (xy 50.645548 -437.360788) (xy 50.582413 -437.37736) (xy 50.517677 -437.385718)
			(xy 50.48504 -437.386222) (xy 50.453077 -437.385715) (xy 50.389654 -437.377708) (xy 50.327735 -437.361814)
			(xy 50.268297 -437.338285) (xy 50.212276 -437.307491) (xy 50.160557 -437.269919) (xy 50.113955 -437.22616)
			(xy 50.073206 -437.176906) (xy 50.038951 -437.122932) (xy 50.011731 -437.065091) (xy 49.991976 -437.004294)
			(xy 49.979997 -436.9415) (xy 49.975982 -436.8777) (xy 45.794942 -436.8777) (xy 45.807499 -436.926607)
			(xy 45.81551 -436.990025) (xy 45.816012 -437.021986) (xy 45.81551 -437.053947) (xy 45.807499 -437.117365)
			(xy 45.791602 -437.179279) (xy 45.76807 -437.238712) (xy 45.737276 -437.294727) (xy 45.699703 -437.346442)
			(xy 45.655946 -437.393039) (xy 45.606693 -437.433784) (xy 45.552722 -437.468035) (xy 45.494883 -437.495252)
			(xy 45.43409 -437.515005) (xy 45.3713 -437.526983) (xy 45.307504 -437.530997) (xy 45.243708 -437.526983)
			(xy 45.180918 -437.515005) (xy 45.120125 -437.495252) (xy 45.062286 -437.468035) (xy 45.008315 -437.433784)
			(xy 44.959062 -437.393039) (xy 44.915305 -437.346442) (xy 44.877732 -437.294727) (xy 44.846938 -437.238712)
			(xy 44.823406 -437.179279) (xy 44.807509 -437.117365) (xy 44.799498 -437.053947) (xy 33.236715 -437.053947)
			(xy 33.203071 -437.075569) (xy 33.153494 -437.098211) (xy 33.101199 -437.113566) (xy 33.047251 -437.121322)
			(xy 33.02 -437.121808) (xy 32.996517 -437.121472) (xy 32.949902 -437.115737) (xy 32.927036 -437.110378)
			(xy 32.912945 -437.107311) (xy 32.884138 -437.10841) (xy 32.856783 -437.117507) (xy 32.833055 -437.133879)
			(xy 32.814841 -437.156225) (xy 32.803589 -437.182766) (xy 32.800194 -437.211394) (xy 32.802068 -437.225694)
			(xy 32.805398 -437.246745) (xy 32.808956 -437.289219) (xy 32.80918 -437.31053) (xy 32.808701 -437.342068)
			(xy 32.800895 -437.40466) (xy 32.785407 -437.465806) (xy 32.762475 -437.524567) (xy 32.732452 -437.58004)
			(xy 32.695797 -437.631373) (xy 32.653074 -437.677779) (xy 32.60494 -437.718543) (xy 32.552133 -437.753041)
			(xy 32.495464 -437.780743) (xy 32.435804 -437.801222) (xy 32.37407 -437.814165) (xy 32.311208 -437.819372)
			(xy 32.248185 -437.816764) (xy 32.185969 -437.806381) (xy 32.125515 -437.788382) (xy 32.067751 -437.763044)
			(xy 32.013565 -437.730755) (xy 31.963788 -437.692012) (xy 31.919186 -437.64741) (xy 31.880444 -437.597634)
			(xy 31.848155 -437.543447) (xy 31.822817 -437.485684) (xy 31.804819 -437.425229) (xy 31.794436 -437.363013)
			(xy 31.791828 -437.29999) (xy 25.129949 -437.29999) (xy 25.146737 -437.326108) (xy 25.16938 -437.375678)
			(xy 25.184739 -437.427967) (xy 25.192501 -437.481909) (xy 25.19299 -437.509158) (xy 25.192514 -437.536237)
			(xy 25.18486 -437.589852) (xy 25.1697 -437.641846) (xy 25.14734 -437.691173) (xy 25.118227 -437.736842)
			(xy 25.082949 -437.777934) (xy 25.042213 -437.813624) (xy 24.996839 -437.843194) (xy 24.947739 -437.866049)
			(xy 24.895901 -437.881731) (xy 24.842365 -437.889923) (xy 24.815292 -437.890666) (xy 24.802592 -437.890666)
			(xy 24.780748 -437.90235) (xy 24.719788 -437.992266) (xy 24.716994 -438.016904) (xy 24.721566 -438.028588)
			(xy 24.732273 -438.057831) (xy 24.747317 -438.118262) (xy 24.754889 -438.180076) (xy 24.755348 -438.211214)
			(xy 24.754817 -438.242754) (xy 24.747013 -438.305351) (xy 24.731526 -438.366501) (xy 24.708593 -438.425266)
			(xy 24.704156 -438.433464) (xy 31.231076 -438.433464) (xy 31.235147 -438.377842) (xy 31.247273 -438.323405)
			(xy 31.267196 -438.271314) (xy 31.294492 -438.222679) (xy 31.328578 -438.178536) (xy 31.368727 -438.139827)
			(xy 31.414085 -438.107376) (xy 31.463685 -438.081875) (xy 31.516469 -438.063868) (xy 31.571312 -438.053738)
			(xy 31.627046 -438.051701) (xy 31.682483 -438.057801) (xy 31.73644 -438.071907) (xy 31.787769 -438.093719)
			(xy 31.835375 -438.122773) (xy 31.878243 -438.158448) (xy 31.91546 -438.199985) (xy 31.946233 -438.246498)
			(xy 31.969905 -438.296995) (xy 31.985973 -438.350402) (xy 31.994093 -438.405578) (xy 31.994602 -438.433464)
			(xy 31.994093 -438.46135) (xy 31.985973 -438.516526) (xy 31.969905 -438.569933) (xy 31.946233 -438.62043)
			(xy 31.943755 -438.624175) (xy 32.263074 -438.624175) (xy 32.263074 -438.560253) (xy 32.271085 -438.496835)
			(xy 32.286982 -438.434921) (xy 32.310514 -438.375488) (xy 32.341308 -438.319473) (xy 32.378881 -438.267758)
			(xy 32.422638 -438.221161) (xy 32.471891 -438.180416) (xy 32.525862 -438.146165) (xy 32.583701 -438.118948)
			(xy 32.644494 -438.099195) (xy 32.707284 -438.087217) (xy 32.77108 -438.083204) (xy 32.834876 -438.087217)
			(xy 32.897666 -438.099195) (xy 32.958459 -438.118948) (xy 33.016298 -438.146165) (xy 33.070269 -438.180416)
			(xy 33.119522 -438.221161) (xy 33.163279 -438.267758) (xy 33.200852 -438.319473) (xy 33.214063 -438.343505)
			(xy 36.698676 -438.343505) (xy 36.698676 -438.279583) (xy 36.706687 -438.216165) (xy 36.722584 -438.154251)
			(xy 36.746116 -438.094818) (xy 36.77691 -438.038803) (xy 36.814483 -437.987088) (xy 36.85824 -437.940491)
			(xy 36.907493 -437.899746) (xy 36.961464 -437.865495) (xy 37.019303 -437.838278) (xy 37.080096 -437.818525)
			(xy 37.142886 -437.806547) (xy 37.206682 -437.802534) (xy 37.270478 -437.806547) (xy 37.333268 -437.818525)
			(xy 37.394061 -437.838278) (xy 37.412998 -437.847189) (xy 38.928034 -437.847189) (xy 38.928034 -437.783267)
			(xy 38.936045 -437.719849) (xy 38.951942 -437.657935) (xy 38.975474 -437.598502) (xy 39.006268 -437.542487)
			(xy 39.043841 -437.490772) (xy 39.087598 -437.444175) (xy 39.136851 -437.40343) (xy 39.190822 -437.369179)
			(xy 39.248661 -437.341962) (xy 39.309454 -437.322209) (xy 39.372244 -437.310231) (xy 39.43604 -437.306218)
			(xy 39.499836 -437.310231) (xy 39.562626 -437.322209) (xy 39.623419 -437.341962) (xy 39.681258 -437.369179)
			(xy 39.735229 -437.40343) (xy 39.784482 -437.444175) (xy 39.828239 -437.490772) (xy 39.865812 -437.542487)
			(xy 39.896606 -437.598502) (xy 39.920138 -437.657935) (xy 39.936035 -437.719849) (xy 39.944046 -437.783267)
			(xy 39.944548 -437.815228) (xy 39.944046 -437.847189) (xy 39.937501 -437.899005) (xy 40.827954 -437.899005)
			(xy 40.827954 -437.835083) (xy 40.835965 -437.771665) (xy 40.851862 -437.709751) (xy 40.875394 -437.650318)
			(xy 40.906188 -437.594303) (xy 40.943761 -437.542588) (xy 40.987518 -437.495991) (xy 41.036771 -437.455246)
			(xy 41.090742 -437.420995) (xy 41.148581 -437.393778) (xy 41.209374 -437.374025) (xy 41.272164 -437.362047)
			(xy 41.33596 -437.358034) (xy 41.399756 -437.362047) (xy 41.462546 -437.374025) (xy 41.523339 -437.393778)
			(xy 41.581178 -437.420995) (xy 41.635149 -437.455246) (xy 41.684402 -437.495991) (xy 41.728159 -437.542588)
			(xy 41.765732 -437.594303) (xy 41.796526 -437.650318) (xy 41.810011 -437.684375) (xy 47.691034 -437.684375)
			(xy 47.691034 -437.620453) (xy 47.699045 -437.557035) (xy 47.714942 -437.495121) (xy 47.738474 -437.435688)
			(xy 47.769268 -437.379673) (xy 47.806841 -437.327958) (xy 47.850598 -437.281361) (xy 47.899851 -437.240616)
			(xy 47.953822 -437.206365) (xy 48.011661 -437.179148) (xy 48.072454 -437.159395) (xy 48.135244 -437.147417)
			(xy 48.19904 -437.143404) (xy 48.262836 -437.147417) (xy 48.325626 -437.159395) (xy 48.386419 -437.179148)
			(xy 48.444258 -437.206365) (xy 48.498229 -437.240616) (xy 48.547482 -437.281361) (xy 48.591239 -437.327958)
			(xy 48.628812 -437.379673) (xy 48.659606 -437.435688) (xy 48.683138 -437.495121) (xy 48.699035 -437.557035)
			(xy 48.707046 -437.620453) (xy 48.707384 -437.642) (xy 49.186082 -437.642) (xy 49.190153 -437.586378)
			(xy 49.202279 -437.531941) (xy 49.222202 -437.47985) (xy 49.249498 -437.431215) (xy 49.283584 -437.387072)
			(xy 49.323733 -437.348363) (xy 49.369091 -437.315912) (xy 49.418691 -437.290411) (xy 49.471475 -437.272404)
			(xy 49.526318 -437.262274) (xy 49.582052 -437.260237) (xy 49.637489 -437.266337) (xy 49.691446 -437.280443)
			(xy 49.742775 -437.302255) (xy 49.790381 -437.331309) (xy 49.833249 -437.366984) (xy 49.870466 -437.408521)
			(xy 49.901239 -437.455034) (xy 49.924911 -437.505531) (xy 49.940979 -437.558938) (xy 49.949099 -437.614114)
			(xy 49.949608 -437.642) (xy 49.949099 -437.669886) (xy 49.948499 -437.673961) (xy 51.220364 -437.673961)
			(xy 51.220364 -437.610039) (xy 51.228375 -437.546621) (xy 51.244272 -437.484707) (xy 51.267804 -437.425274)
			(xy 51.298598 -437.369259) (xy 51.336171 -437.317544) (xy 51.379928 -437.270947) (xy 51.429181 -437.230202)
			(xy 51.483152 -437.195951) (xy 51.540991 -437.168734) (xy 51.601784 -437.148981) (xy 51.664574 -437.137003)
			(xy 51.72837 -437.13299) (xy 51.792166 -437.137003) (xy 51.854956 -437.148981) (xy 51.915749 -437.168734)
			(xy 51.973588 -437.195951) (xy 52.027559 -437.230202) (xy 52.076812 -437.270947) (xy 52.120569 -437.317544)
			(xy 52.158142 -437.369259) (xy 52.188936 -437.425274) (xy 52.212468 -437.484707) (xy 52.228365 -437.546621)
			(xy 52.236376 -437.610039) (xy 52.236878 -437.642) (xy 52.236376 -437.673961) (xy 52.228365 -437.737379)
			(xy 52.212468 -437.799293) (xy 52.188936 -437.858726) (xy 52.158142 -437.914741) (xy 52.120569 -437.966456)
			(xy 52.076812 -438.013053) (xy 52.027559 -438.053798) (xy 51.973588 -438.088049) (xy 51.915749 -438.115266)
			(xy 51.854956 -438.135019) (xy 51.792166 -438.146997) (xy 51.72837 -438.151011) (xy 51.664574 -438.146997)
			(xy 51.601784 -438.135019) (xy 51.540991 -438.115266) (xy 51.483152 -438.088049) (xy 51.429181 -438.053798)
			(xy 51.379928 -438.013053) (xy 51.336171 -437.966456) (xy 51.298598 -437.914741) (xy 51.267804 -437.858726)
			(xy 51.244272 -437.799293) (xy 51.228375 -437.737379) (xy 51.220364 -437.673961) (xy 49.948499 -437.673961)
			(xy 49.940979 -437.725062) (xy 49.924911 -437.778469) (xy 49.901239 -437.828966) (xy 49.870466 -437.875479)
			(xy 49.833249 -437.917016) (xy 49.790381 -437.952691) (xy 49.742775 -437.981745) (xy 49.691446 -438.003557)
			(xy 49.637489 -438.017663) (xy 49.582052 -438.023763) (xy 49.526318 -438.021726) (xy 49.471475 -438.011596)
			(xy 49.418691 -437.993589) (xy 49.369091 -437.968088) (xy 49.323733 -437.935637) (xy 49.283584 -437.896928)
			(xy 49.249498 -437.852785) (xy 49.222202 -437.80415) (xy 49.202279 -437.752059) (xy 49.190153 -437.697622)
			(xy 49.186082 -437.642) (xy 48.707384 -437.642) (xy 48.707548 -437.652414) (xy 48.707046 -437.684375)
			(xy 48.699035 -437.747793) (xy 48.683138 -437.809707) (xy 48.659606 -437.86914) (xy 48.628812 -437.925155)
			(xy 48.591239 -437.97687) (xy 48.547482 -438.023467) (xy 48.498229 -438.064212) (xy 48.444258 -438.098463)
			(xy 48.386419 -438.12568) (xy 48.325626 -438.145433) (xy 48.262836 -438.157411) (xy 48.19904 -438.161425)
			(xy 48.135244 -438.157411) (xy 48.072454 -438.145433) (xy 48.011661 -438.12568) (xy 47.953822 -438.098463)
			(xy 47.899851 -438.064212) (xy 47.850598 -438.023467) (xy 47.806841 -437.97687) (xy 47.769268 -437.925155)
			(xy 47.738474 -437.86914) (xy 47.714942 -437.809707) (xy 47.699045 -437.747793) (xy 47.691034 -437.684375)
			(xy 41.810011 -437.684375) (xy 41.820058 -437.709751) (xy 41.835955 -437.771665) (xy 41.843966 -437.835083)
			(xy 41.844468 -437.867044) (xy 41.843966 -437.899005) (xy 41.835955 -437.962423) (xy 41.820058 -438.024337)
			(xy 41.796526 -438.08377) (xy 41.765732 -438.139785) (xy 41.728159 -438.1915) (xy 41.684402 -438.238097)
			(xy 41.635149 -438.278842) (xy 41.581178 -438.313093) (xy 41.523339 -438.34031) (xy 41.462546 -438.360063)
			(xy 41.399756 -438.372041) (xy 41.33596 -438.376055) (xy 41.272164 -438.372041) (xy 41.209374 -438.360063)
			(xy 41.148581 -438.34031) (xy 41.090742 -438.313093) (xy 41.036771 -438.278842) (xy 40.987518 -438.238097)
			(xy 40.943761 -438.1915) (xy 40.906188 -438.139785) (xy 40.875394 -438.08377) (xy 40.851862 -438.024337)
			(xy 40.835965 -437.962423) (xy 40.827954 -437.899005) (xy 39.937501 -437.899005) (xy 39.936035 -437.910607)
			(xy 39.920138 -437.972521) (xy 39.896606 -438.031954) (xy 39.865812 -438.087969) (xy 39.828239 -438.139684)
			(xy 39.784482 -438.186281) (xy 39.735229 -438.227026) (xy 39.681258 -438.261277) (xy 39.623419 -438.288494)
			(xy 39.562626 -438.308247) (xy 39.499836 -438.320225) (xy 39.43604 -438.324239) (xy 39.372244 -438.320225)
			(xy 39.309454 -438.308247) (xy 39.248661 -438.288494) (xy 39.190822 -438.261277) (xy 39.136851 -438.227026)
			(xy 39.087598 -438.186281) (xy 39.043841 -438.139684) (xy 39.006268 -438.087969) (xy 38.975474 -438.031954)
			(xy 38.951942 -437.972521) (xy 38.936045 -437.910607) (xy 38.928034 -437.847189) (xy 37.412998 -437.847189)
			(xy 37.4519 -437.865495) (xy 37.505871 -437.899746) (xy 37.555124 -437.940491) (xy 37.598881 -437.987088)
			(xy 37.636454 -438.038803) (xy 37.667248 -438.094818) (xy 37.69078 -438.154251) (xy 37.706677 -438.216165)
			(xy 37.714688 -438.279583) (xy 37.71519 -438.311544) (xy 37.714688 -438.343505) (xy 37.706677 -438.406923)
			(xy 37.69078 -438.468837) (xy 37.667248 -438.52827) (xy 37.636454 -438.584285) (xy 37.598881 -438.636)
			(xy 37.555124 -438.682597) (xy 37.505871 -438.723342) (xy 37.4519 -438.757593) (xy 37.394061 -438.78481)
			(xy 37.333268 -438.804563) (xy 37.270478 -438.816541) (xy 37.206682 -438.820555) (xy 37.142886 -438.816541)
			(xy 37.080096 -438.804563) (xy 37.019303 -438.78481) (xy 36.961464 -438.757593) (xy 36.907493 -438.723342)
			(xy 36.85824 -438.682597) (xy 36.814483 -438.636) (xy 36.77691 -438.584285) (xy 36.746116 -438.52827)
			(xy 36.722584 -438.468837) (xy 36.706687 -438.406923) (xy 36.698676 -438.343505) (xy 33.214063 -438.343505)
			(xy 33.231646 -438.375488) (xy 33.255178 -438.434921) (xy 33.271075 -438.496835) (xy 33.279086 -438.560253)
			(xy 33.279588 -438.592214) (xy 33.279086 -438.624175) (xy 33.271075 -438.687593) (xy 33.255178 -438.749507)
			(xy 33.231646 -438.80894) (xy 33.200852 -438.864955) (xy 33.163279 -438.91667) (xy 33.119522 -438.963267)
			(xy 33.070269 -439.004012) (xy 33.016298 -439.038263) (xy 32.958459 -439.06548) (xy 32.897666 -439.085233)
			(xy 32.834876 -439.097211) (xy 32.77108 -439.101225) (xy 32.707284 -439.097211) (xy 32.644494 -439.085233)
			(xy 32.583701 -439.06548) (xy 32.525862 -439.038263) (xy 32.471891 -439.004012) (xy 32.422638 -438.963267)
			(xy 32.378881 -438.91667) (xy 32.341308 -438.864955) (xy 32.310514 -438.80894) (xy 32.286982 -438.749507)
			(xy 32.271085 -438.687593) (xy 32.263074 -438.624175) (xy 31.943755 -438.624175) (xy 31.91546 -438.666943)
			(xy 31.878243 -438.70848) (xy 31.835375 -438.744155) (xy 31.787769 -438.773209) (xy 31.73644 -438.795021)
			(xy 31.682483 -438.809127) (xy 31.627046 -438.815227) (xy 31.571312 -438.81319) (xy 31.516469 -438.80306)
			(xy 31.463685 -438.785053) (xy 31.414085 -438.759552) (xy 31.368727 -438.727101) (xy 31.328578 -438.688392)
			(xy 31.294492 -438.644249) (xy 31.267196 -438.595614) (xy 31.247273 -438.543523) (xy 31.235147 -438.489086)
			(xy 31.231076 -438.433464) (xy 24.704156 -438.433464) (xy 24.678568 -438.480743) (xy 24.641912 -438.53208)
			(xy 24.599186 -438.578489) (xy 24.551049 -438.619257) (xy 24.498238 -438.653757) (xy 24.441566 -438.681459)
			(xy 24.381902 -438.701939) (xy 24.320163 -438.714882) (xy 24.257297 -438.720088) (xy 24.19427 -438.717479)
			(xy 24.13205 -438.707093) (xy 24.071592 -438.689091) (xy 24.013825 -438.663749) (xy 23.959637 -438.631456)
			(xy 23.909859 -438.592708) (xy 23.865256 -438.5481) (xy 23.826514 -438.498319) (xy 23.794227 -438.444127)
			(xy 23.768891 -438.386357) (xy 23.750895 -438.325898) (xy 23.740516 -438.263676) (xy 23.737913 -438.200649)
			(xy 23.743126 -438.137784) (xy 23.756075 -438.076046) (xy 23.776561 -438.016384) (xy 23.80427 -437.959715)
			(xy 23.838776 -437.906908) (xy 23.879548 -437.858775) (xy 23.925962 -437.816054) (xy 23.977303 -437.779403)
			(xy 24.032783 -437.749384) (xy 24.09155 -437.726458) (xy 24.152702 -437.710977) (xy 24.215299 -437.703179)
			(xy 24.24684 -437.702706) (xy 24.26603 -437.702886) (xy 24.304299 -437.705814) (xy 24.323294 -437.708548)
			(xy 24.33574 -437.710326) (xy 24.359108 -437.702452) (xy 24.433784 -437.623458) (xy 24.440642 -437.599582)
			(xy 24.438102 -437.587136) (xy 24.434303 -437.567865) (xy 24.43023 -437.528798) (xy 24.429974 -437.509158)
			(xy 24.4302 -437.490427) (xy 24.433891 -437.453148) (xy 24.43734 -437.434736) (xy 24.43988 -437.42229)
			(xy 24.432768 -437.398668) (xy 24.35606 -437.320182) (xy 24.332692 -437.312816) (xy 24.319992 -437.315102)
			(xy 24.298072 -437.3187) (xy 24.253812 -437.322519) (xy 24.2316 -437.322722) (xy 24.200059 -437.322232)
			(xy 24.137461 -437.314429) (xy 24.076309 -437.298944) (xy 24.017542 -437.276012) (xy 23.962062 -437.245988)
			(xy 23.910723 -437.209332) (xy 23.864312 -437.166608) (xy 23.823542 -437.11847) (xy 23.789039 -437.06566)
			(xy 23.761334 -437.008987) (xy 23.740852 -436.949322) (xy 23.727907 -436.887582) (xy 23.722698 -436.824715)
			(xy 20.534428 -436.824715) (xy 20.550911 -436.860806) (xy 20.566266 -436.913101) (xy 20.574022 -436.967049)
			(xy 20.574022 -437.021551) (xy 20.566266 -437.075499) (xy 20.550911 -437.127794) (xy 20.528269 -437.177371)
			(xy 20.498803 -437.223221) (xy 20.463112 -437.264412) (xy 20.421921 -437.300103) (xy 20.376071 -437.329569)
			(xy 20.326494 -437.352211) (xy 20.274199 -437.367566) (xy 20.220251 -437.375322) (xy 20.193 -437.375808)
			(xy 20.168126 -437.375406) (xy 20.118801 -437.368938) (xy 20.070736 -437.356112) (xy 20.024746 -437.337146)
			(xy 19.981612 -437.312361) (xy 19.961606 -437.297576) (xy 19.949922 -437.288686) (xy 19.92122 -437.285892)
			(xy 19.826478 -437.332882) (xy 19.818236 -437.337461) (xy 19.805534 -437.351371) (xy 19.798713 -437.36893)
			(xy 19.798284 -437.378348) (xy 19.798284 -438.012035) (xy 20.319994 -438.012035) (xy 20.319994 -437.948113)
			(xy 20.328005 -437.884695) (xy 20.343902 -437.822781) (xy 20.367434 -437.763348) (xy 20.398228 -437.707333)
			(xy 20.435801 -437.655618) (xy 20.479558 -437.609021) (xy 20.528811 -437.568276) (xy 20.582782 -437.534025)
			(xy 20.640621 -437.506808) (xy 20.701414 -437.487055) (xy 20.764204 -437.475077) (xy 20.828 -437.471064)
			(xy 20.891796 -437.475077) (xy 20.954586 -437.487055) (xy 21.015379 -437.506808) (xy 21.073218 -437.534025)
			(xy 21.127189 -437.568276) (xy 21.176442 -437.609021) (xy 21.220199 -437.655618) (xy 21.257772 -437.707333)
			(xy 21.288566 -437.763348) (xy 21.312098 -437.822781) (xy 21.327995 -437.884695) (xy 21.336006 -437.948113)
			(xy 21.336508 -437.980074) (xy 21.336006 -438.012035) (xy 21.327995 -438.075453) (xy 21.312098 -438.137367)
			(xy 21.288566 -438.1968) (xy 21.257772 -438.252815) (xy 21.220199 -438.30453) (xy 21.176442 -438.351127)
			(xy 21.127189 -438.391872) (xy 21.073218 -438.426123) (xy 21.015379 -438.45334) (xy 20.954586 -438.473093)
			(xy 20.891796 -438.485071) (xy 20.828 -438.489085) (xy 20.764204 -438.485071) (xy 20.701414 -438.473093)
			(xy 20.640621 -438.45334) (xy 20.582782 -438.426123) (xy 20.528811 -438.391872) (xy 20.479558 -438.351127)
			(xy 20.435801 -438.30453) (xy 20.398228 -438.252815) (xy 20.367434 -438.1968) (xy 20.343902 -438.137367)
			(xy 20.328005 -438.075453) (xy 20.319994 -438.012035) (xy 19.798284 -438.012035) (xy 19.798284 -438.77611)
			(xy 19.798708 -438.78618) (xy 19.806424 -438.804783) (xy 19.81327 -438.812178) (xy 20.351496 -439.350404)
			(xy 39.175942 -439.350404) (xy 39.180013 -439.294782) (xy 39.192139 -439.240345) (xy 39.212062 -439.188254)
			(xy 39.239358 -439.139619) (xy 39.273444 -439.095476) (xy 39.313593 -439.056767) (xy 39.358951 -439.024316)
			(xy 39.408551 -438.998815) (xy 39.461335 -438.980808) (xy 39.516178 -438.970678) (xy 39.571912 -438.968641)
			(xy 39.627349 -438.974741) (xy 39.681306 -438.988847) (xy 39.732635 -439.010659) (xy 39.780241 -439.039713)
			(xy 39.823109 -439.075388) (xy 39.860326 -439.116925) (xy 39.891099 -439.163438) (xy 39.914771 -439.213935)
			(xy 39.930839 -439.267342) (xy 39.938959 -439.322518) (xy 39.939468 -439.350404) (xy 39.938959 -439.37829)
			(xy 39.930839 -439.433466) (xy 39.914771 -439.486873) (xy 39.891099 -439.53737) (xy 39.860326 -439.583883)
			(xy 39.84945 -439.596022) (xy 43.165522 -439.596022) (xy 43.166019 -439.563057) (xy 43.174531 -439.497679)
			(xy 43.191428 -439.433951) (xy 43.216426 -439.372944) (xy 43.249106 -439.315683) (xy 43.288917 -439.26313)
			(xy 43.335191 -439.216168) (xy 43.360848 -439.195464) (xy 43.368976 -439.189114) (xy 43.378882 -439.17108)
			(xy 43.388788 -439.077862) (xy 43.382946 -439.05805) (xy 43.376342 -439.050176) (xy 43.359641 -439.029507)
			(xy 43.331538 -438.984408) (xy 43.309961 -438.935847) (xy 43.295327 -438.884763) (xy 43.28792 -438.832143)
			(xy 43.287442 -438.805574) (xy 43.287928 -438.778323) (xy 43.295684 -438.724375) (xy 43.311039 -438.67208)
			(xy 43.333681 -438.622503) (xy 43.363147 -438.576653) (xy 43.398838 -438.535462) (xy 43.440029 -438.499771)
			(xy 43.485879 -438.470305) (xy 43.535456 -438.447663) (xy 43.587751 -438.432308) (xy 43.641699 -438.424552)
			(xy 43.696201 -438.424552) (xy 43.750149 -438.432308) (xy 43.802444 -438.447663) (xy 43.852021 -438.470305)
			(xy 43.897871 -438.499771) (xy 43.939062 -438.535462) (xy 43.974753 -438.576653) (xy 44.004219 -438.622503)
			(xy 44.026861 -438.67208) (xy 44.042216 -438.724375) (xy 44.049972 -438.778323) (xy 44.050458 -438.805574)
			(xy 44.050038 -438.831644) (xy 44.042928 -438.883297) (xy 44.028851 -438.933501) (xy 44.00807 -438.981321)
			(xy 43.980971 -439.025865) (xy 43.96486 -439.046366) (xy 43.958256 -439.054494) (xy 43.952414 -439.074306)
			(xy 43.96359 -439.16727) (xy 43.97375 -439.18505) (xy 43.982132 -439.1914) (xy 44.008407 -439.212077)
			(xy 44.055827 -439.259216) (xy 44.096661 -439.312161) (xy 44.130207 -439.37) (xy 44.155884 -439.431736)
			(xy 44.173252 -439.496304) (xy 44.18201 -439.562591) (xy 44.182538 -439.596022) (xy 44.182036 -439.627983)
			(xy 44.174025 -439.691401) (xy 44.158128 -439.753315) (xy 44.154232 -439.763154) (xy 45.785022 -439.763154)
			(xy 45.789093 -439.707532) (xy 45.801219 -439.653095) (xy 45.821142 -439.601004) (xy 45.848438 -439.552369)
			(xy 45.882524 -439.508226) (xy 45.922673 -439.469517) (xy 45.968031 -439.437066) (xy 46.017631 -439.411565)
			(xy 46.070415 -439.393558) (xy 46.125258 -439.383428) (xy 46.180992 -439.381391) (xy 46.236429 -439.387491)
			(xy 46.290386 -439.401597) (xy 46.341715 -439.423409) (xy 46.389321 -439.452463) (xy 46.432189 -439.488138)
			(xy 46.469406 -439.529675) (xy 46.500179 -439.576188) (xy 46.523851 -439.626685) (xy 46.539919 -439.680092)
			(xy 46.548039 -439.735268) (xy 46.548548 -439.763154) (xy 46.548039 -439.79104) (xy 46.539919 -439.846216)
			(xy 46.539016 -439.849217) (xy 47.691034 -439.849217) (xy 47.691034 -439.785295) (xy 47.699045 -439.721877)
			(xy 47.714942 -439.659963) (xy 47.738474 -439.60053) (xy 47.769268 -439.544515) (xy 47.806841 -439.4928)
			(xy 47.850598 -439.446203) (xy 47.899851 -439.405458) (xy 47.953822 -439.371207) (xy 48.011661 -439.34399)
			(xy 48.072454 -439.324237) (xy 48.135244 -439.312259) (xy 48.19904 -439.308246) (xy 48.262836 -439.312259)
			(xy 48.325626 -439.324237) (xy 48.386419 -439.34399) (xy 48.444258 -439.371207) (xy 48.498229 -439.405458)
			(xy 48.547482 -439.446203) (xy 48.591239 -439.4928) (xy 48.628812 -439.544515) (xy 48.659606 -439.60053)
			(xy 48.683138 -439.659963) (xy 48.699035 -439.721877) (xy 48.707046 -439.785295) (xy 48.707548 -439.817256)
			(xy 48.707046 -439.849217) (xy 48.699035 -439.912635) (xy 48.683138 -439.974549) (xy 48.659606 -440.033982)
			(xy 48.628812 -440.089997) (xy 48.591239 -440.141712) (xy 48.547482 -440.188309) (xy 48.498229 -440.229054)
			(xy 48.444258 -440.263305) (xy 48.386419 -440.290522) (xy 48.325626 -440.310275) (xy 48.262836 -440.322253)
			(xy 48.19904 -440.326267) (xy 48.135244 -440.322253) (xy 48.072454 -440.310275) (xy 48.011661 -440.290522)
			(xy 47.953822 -440.263305) (xy 47.899851 -440.229054) (xy 47.850598 -440.188309) (xy 47.806841 -440.141712)
			(xy 47.769268 -440.089997) (xy 47.738474 -440.033982) (xy 47.714942 -439.974549) (xy 47.699045 -439.912635)
			(xy 47.691034 -439.849217) (xy 46.539016 -439.849217) (xy 46.523851 -439.899623) (xy 46.500179 -439.95012)
			(xy 46.469406 -439.996633) (xy 46.432189 -440.03817) (xy 46.389321 -440.073845) (xy 46.341715 -440.102899)
			(xy 46.290386 -440.124711) (xy 46.236429 -440.138817) (xy 46.180992 -440.144917) (xy 46.125258 -440.14288)
			(xy 46.070415 -440.13275) (xy 46.017631 -440.114743) (xy 45.968031 -440.089242) (xy 45.922673 -440.056791)
			(xy 45.882524 -440.018082) (xy 45.848438 -439.973939) (xy 45.821142 -439.925304) (xy 45.801219 -439.873213)
			(xy 45.789093 -439.818776) (xy 45.785022 -439.763154) (xy 44.154232 -439.763154) (xy 44.134596 -439.812748)
			(xy 44.103802 -439.868763) (xy 44.066229 -439.920478) (xy 44.022472 -439.967075) (xy 43.973219 -440.00782)
			(xy 43.919248 -440.042071) (xy 43.861409 -440.069288) (xy 43.800616 -440.089041) (xy 43.737826 -440.101019)
			(xy 43.67403 -440.105033) (xy 43.610234 -440.101019) (xy 43.547444 -440.089041) (xy 43.486651 -440.069288)
			(xy 43.428812 -440.042071) (xy 43.374841 -440.00782) (xy 43.325588 -439.967075) (xy 43.281831 -439.920478)
			(xy 43.244258 -439.868763) (xy 43.213464 -439.812748) (xy 43.189932 -439.753315) (xy 43.174035 -439.691401)
			(xy 43.166024 -439.627983) (xy 43.165522 -439.596022) (xy 39.84945 -439.596022) (xy 39.823109 -439.62542)
			(xy 39.780241 -439.661095) (xy 39.732635 -439.690149) (xy 39.681306 -439.711961) (xy 39.627349 -439.726067)
			(xy 39.571912 -439.732167) (xy 39.516178 -439.73013) (xy 39.461335 -439.72) (xy 39.408551 -439.701993)
			(xy 39.358951 -439.676492) (xy 39.313593 -439.644041) (xy 39.273444 -439.605332) (xy 39.239358 -439.561189)
			(xy 39.212062 -439.512554) (xy 39.192139 -439.460463) (xy 39.180013 -439.406026) (xy 39.175942 -439.350404)
			(xy 20.351496 -439.350404) (xy 21.430488 -440.429396) (xy 21.437886 -440.436245) (xy 21.456484 -440.443984)
			(xy 21.466556 -440.444382) (xy 53.68036 -440.444382) (xy 53.690425 -440.443947) (xy 53.709012 -440.436216)
			(xy 53.716428 -440.429396) (xy 54.510178 -439.635646) (xy 54.517018 -439.628245) (xy 54.524736 -439.609647)
			(xy 54.525164 -439.599578) (xy 54.525164 -433.545234) (xy 54.524642 -433.5347) (xy 54.516177 -433.515409)
			(xy 54.500664 -433.501155) (xy 54.490874 -433.497228) (xy 54.384194 -433.460906) (xy 54.353206 -433.47005)
			(xy 54.343046 -433.483258) (xy 54.324467 -433.506618) (xy 54.282705 -433.549266) (xy 54.236238 -433.586731)
			(xy 54.185703 -433.618497) (xy 54.131796 -433.644128) (xy 54.07526 -433.66327) (xy 54.016871 -433.675661)
			(xy 53.987192 -433.678838) (xy 53.972968 -433.680108) (xy 53.950616 -433.696364) (xy 53.904642 -433.805076)
			(xy 53.908452 -433.832508) (xy 53.917342 -433.843684) (xy 53.933234 -433.864106) (xy 53.959943 -433.908426)
			(xy 53.980414 -433.955951) (xy 53.994272 -434.005807) (xy 54.001261 -434.057079) (xy 54.00167 -434.082952)
			(xy 54.001184 -434.110203) (xy 53.993428 -434.164151) (xy 53.978073 -434.216446) (xy 53.955431 -434.266023)
			(xy 53.925965 -434.311873) (xy 53.890274 -434.353064) (xy 53.849083 -434.388755) (xy 53.803233 -434.418221)
			(xy 53.753656 -434.440863) (xy 53.701361 -434.456218) (xy 53.647413 -434.463974) (xy 53.592911 -434.463974)
			(xy 53.538963 -434.456218) (xy 53.486668 -434.440863) (xy 53.437091 -434.418221) (xy 53.391241 -434.388755)
			(xy 53.35005 -434.353064) (xy 53.314359 -434.311873) (xy 53.284893 -434.266023) (xy 53.262251 -434.216446)
			(xy 53.246896 -434.164151) (xy 53.23914 -434.110203) (xy 53.238654 -434.082952) (xy 53.23917 -434.054223)
			(xy 53.247781 -433.997413) (xy 53.264814 -433.942537) (xy 53.289886 -433.890836) (xy 53.322428 -433.843481)
			(xy 53.361705 -433.801543) (xy 53.406828 -433.76597) (xy 53.456776 -433.737567) (xy 53.510419 -433.716977)
			(xy 53.538374 -433.710334) (xy 53.552344 -433.707286) (xy 53.572664 -433.688236) (xy 53.604668 -433.574698)
			(xy 53.597556 -433.547774) (xy 53.587396 -433.538122) (xy 53.563296 -433.514089) (xy 53.521085 -433.460696)
			(xy 53.486377 -433.402149) (xy 53.459793 -433.339493) (xy 53.441807 -433.273849) (xy 53.432743 -433.206393)
			(xy 53.432202 -433.172362) (xy 53.432684 -433.140325) (xy 53.440725 -433.076759) (xy 53.456688 -433.014706)
			(xy 53.480321 -432.955151) (xy 53.511247 -432.899036) (xy 53.548978 -432.847251) (xy 53.592916 -432.800616)
			(xy 53.642364 -432.75987) (xy 53.669184 -432.74234) (xy 53.68163 -432.734466) (xy 53.69433 -432.70805)
			(xy 53.680106 -432.587908) (xy 53.661818 -432.565048) (xy 53.647848 -432.560476) (xy 53.618173 -432.54977)
			(xy 53.561508 -432.522039) (xy 53.508706 -432.487515) (xy 53.460578 -432.446729) (xy 53.41786 -432.400305)
			(xy 53.381209 -432.348957) (xy 53.351188 -432.293471) (xy 53.328256 -432.2347) (xy 53.312765 -432.173544)
			(xy 53.304954 -432.110943) (xy 53.30444 -432.0794) (xy 53.304942 -432.047439) (xy 53.312953 -431.984021)
			(xy 53.32885 -431.922107) (xy 53.352382 -431.862674) (xy 53.383176 -431.806659) (xy 53.420749 -431.754944)
			(xy 53.464506 -431.708347) (xy 53.513759 -431.667602) (xy 53.56773 -431.633351) (xy 53.625569 -431.606134)
			(xy 53.686362 -431.586381) (xy 53.749152 -431.574403) (xy 53.812948 -431.57039) (xy 53.876744 -431.574403)
			(xy 53.939534 -431.586381) (xy 54.000327 -431.606134) (xy 54.058166 -431.633351) (xy 54.112137 -431.667602)
			(xy 54.16139 -431.708347) (xy 54.205147 -431.754944) (xy 54.24272 -431.806659) (xy 54.273514 -431.862674)
			(xy 54.297046 -431.922107) (xy 54.312943 -431.984021) (xy 54.320954 -432.047439) (xy 54.321456 -432.0794)
			(xy 54.320977 -432.111438) (xy 54.31294 -432.175009) (xy 54.296982 -432.237066) (xy 54.273354 -432.296627)
			(xy 54.242432 -432.352748) (xy 54.204704 -432.404541) (xy 54.16077 -432.451183) (xy 54.111324 -432.491938)
			(xy 54.084474 -432.509422) (xy 54.072028 -432.517296) (xy 54.059328 -432.543712) (xy 54.073552 -432.663854)
			(xy 54.09184 -432.686714) (xy 54.10581 -432.691286) (xy 54.133679 -432.70133) (xy 54.18708 -432.726977)
			(xy 54.237143 -432.758651) (xy 54.283191 -432.795922) (xy 54.3246 -432.838286) (xy 54.343046 -432.861466)
			(xy 54.353206 -432.874674) (xy 54.384194 -432.883818) (xy 54.490874 -432.847496) (xy 54.500661 -432.843572)
			(xy 54.516155 -432.829303) (xy 54.524631 -432.810021) (xy 54.525164 -432.79949) (xy 54.525164 -422.1607)
			(xy 54.525019 -422.154627) (xy 54.522193 -422.142815) (xy 54.519576 -422.137332) (xy 53.38572 -419.95217)
			(xy 53.380495 -419.943204) (xy 53.364432 -419.930096) (xy 53.344499 -419.924393) (xy 53.334158 -419.925246)
			(xy 53.223414 -419.939724) (xy 53.199792 -419.961314) (xy 53.19649 -419.977062) (xy 53.189813 -420.004999)
			(xy 53.169202 -420.058613) (xy 53.140786 -420.108531) (xy 53.105209 -420.153625) (xy 53.063273 -420.192876)
			(xy 53.015927 -420.225396) (xy 52.96424 -420.250451) (xy 52.909382 -420.267474) (xy 52.852592 -420.276081)
			(xy 52.823872 -420.276528) (xy 52.798063 -420.276106) (xy 52.746914 -420.269158) (xy 52.697169 -420.255379)
			(xy 52.649735 -420.23502) (xy 52.605478 -420.208454) (xy 52.565206 -420.176164) (xy 52.529654 -420.138741)
			(xy 52.514246 -420.118032) (xy 52.485544 -420.098474) (xy 52.455826 -420.091108) (xy 52.446978 -420.089243)
			(xy 52.429013 -420.091193) (xy 52.420774 -420.094918) (xy 52.39406 -420.107952) (xy 52.338244 -420.128396)
			(xy 52.280423 -420.142182) (xy 52.221387 -420.14912) (xy 52.191666 -420.149528) (xy 52.160936 -420.149062)
			(xy 52.099924 -420.14165) (xy 52.040251 -420.126939) (xy 51.982785 -420.105142) (xy 51.928366 -420.076578)
			(xy 51.877786 -420.041664) (xy 51.831783 -420.000907) (xy 51.791028 -419.954903) (xy 51.756114 -419.904322)
			(xy 51.727552 -419.849902) (xy 51.705757 -419.792436) (xy 51.691047 -419.732762) (xy 51.683637 -419.67175)
			(xy 51.683158 -419.64102) (xy 51.683736 -419.606064) (xy 51.693302 -419.53681) (xy 51.712258 -419.469518)
			(xy 51.740245 -419.405453) (xy 51.776739 -419.345822) (xy 51.798474 -419.31844) (xy 51.809904 -419.286436)
			(xy 51.809904 -419.132258) (xy 51.809904 -419.132004) (xy 51.798474 -419.1) (xy 51.776759 -419.072602)
			(xy 51.740255 -419.012979) (xy 51.712259 -418.948919) (xy 51.693301 -418.881628) (xy 51.683738 -418.812375)
			(xy 51.683158 -418.77742) (xy 51.683213 -418.765911) (xy 51.684231 -418.742915) (xy 51.68519 -418.731446)
			(xy 51.685444 -418.72662) (xy 51.685146 -418.719361) (xy 51.681021 -418.705437) (xy 51.677316 -418.699188)
			(xy 51.661314 -418.67455) (xy 51.635914 -418.65423) (xy 51.608615 -418.643797) (xy 51.557303 -418.615827)
			(xy 51.510857 -418.580359) (xy 51.470362 -418.538224) (xy 51.436767 -418.490406) (xy 51.410857 -418.438024)
			(xy 51.393237 -418.382303) (xy 51.384321 -418.324548) (xy 51.383692 -418.295328) (xy 51.384153 -418.268074)
			(xy 51.391907 -418.21412) (xy 51.407261 -418.161819) (xy 51.429902 -418.112235) (xy 51.459369 -418.066378)
			(xy 51.495063 -418.025182) (xy 51.536256 -417.989486) (xy 51.58211 -417.960015) (xy 51.631692 -417.937371)
			(xy 51.683992 -417.922013) (xy 51.737946 -417.914255) (xy 51.7652 -417.91382) (xy 51.782508 -417.914037)
			(xy 51.816979 -417.917213) (xy 51.834034 -417.92017) (xy 51.849528 -417.922964) (xy 51.877976 -417.910264)
			(xy 51.936142 -417.816792) (xy 51.941149 -417.807927) (xy 51.944378 -417.787843) (xy 51.93955 -417.768082)
			(xy 51.933856 -417.759642) (xy 49.304702 -414.215072) (xy 49.276807 -414.176721) (xy 49.225805 -414.096759)
			(xy 49.180504 -414.013435) (xy 49.16043 -413.97047) (xy 49.15662 -413.962342) (xy 48.732948 -413.53867)
			(xy 48.723296 -413.53486) (xy 48.696672 -413.523622) (xy 48.647172 -413.493807) (xy 48.603134 -413.456391)
			(xy 48.565715 -413.412358) (xy 48.535894 -413.36286) (xy 48.524668 -413.336232) (xy 48.520858 -413.32658)
			(xy 48.500284 -413.306006) (xy 48.493428 -413.298612) (xy 48.485678 -413.280013) (xy 48.485298 -413.269938)
			(xy 48.485298 -413.040068) (xy 48.469296 -413.015176) (xy 48.455834 -413.00908) (xy 48.434474 -412.998965)
			(xy 48.393636 -412.975171) (xy 48.3743 -412.961582) (xy 48.344582 -412.951676) (xy 48.107346 -412.951676)
			(xy 48.077628 -412.961582) (xy 48.054864 -412.977522) (xy 48.006356 -413.004641) (xy 47.980854 -413.015684)
			(xy 47.972304 -413.019643) (xy 47.958737 -413.032699) (xy 47.954438 -413.041084) (xy 47.94123 -413.069024)
			(xy 47.937681 -413.077527) (xy 47.93626 -413.095883) (xy 47.938436 -413.104838) (xy 47.945056 -413.129132)
			(xy 47.952193 -413.178976) (xy 47.95266 -413.204152) (xy 47.952162 -413.230801) (xy 47.944219 -413.283505)
			(xy 47.928509 -413.334435) (xy 47.905383 -413.382456) (xy 47.875359 -413.426493) (xy 47.839107 -413.465564)
			(xy 47.797436 -413.498795) (xy 47.751278 -413.525444) (xy 47.701664 -413.544916) (xy 47.649702 -413.556776)
			(xy 47.596552 -413.56076) (xy 47.543402 -413.556776) (xy 47.49144 -413.544916) (xy 47.441826 -413.525444)
			(xy 47.395668 -413.498795) (xy 47.353997 -413.465564) (xy 47.317745 -413.426493) (xy 47.287721 -413.382456)
			(xy 47.264595 -413.334435) (xy 47.248885 -413.283505) (xy 47.240942 -413.230801) (xy 47.240444 -413.204152)
			(xy 47.240974 -413.176661) (xy 47.249461 -413.122338) (xy 47.266196 -413.069964) (xy 47.278036 -413.045148)
			(xy 47.283624 -413.033972) (xy 47.283116 -413.00908) (xy 47.2313 -412.914084) (xy 47.210726 -412.900114)
			(xy 47.19828 -412.898844) (xy 47.173093 -412.895532) (xy 47.12408 -412.88218) (xy 47.077685 -412.861489)
			(xy 47.035 -412.833948) (xy 46.997028 -412.800204) (xy 46.964661 -412.761051) (xy 46.938663 -412.717409)
			(xy 46.919643 -412.670305) (xy 46.908049 -412.620846) (xy 46.904155 -412.570196) (xy 46.908051 -412.519547)
			(xy 46.919645 -412.470089) (xy 46.938666 -412.422985) (xy 46.964666 -412.379343) (xy 46.997033 -412.340191)
			(xy 47.035006 -412.306447) (xy 47.077692 -412.278907) (xy 47.124087 -412.258218) (xy 47.1731 -412.244866)
			(xy 47.19828 -412.241492) (xy 47.210726 -412.240222) (xy 47.2313 -412.226252) (xy 47.283116 -412.131256)
			(xy 47.283624 -412.106364) (xy 47.278036 -412.095188) (xy 47.266202 -412.07037) (xy 47.249471 -412.017997)
			(xy 47.240991 -411.963674) (xy 47.240444 -411.936184) (xy 47.240942 -411.909535) (xy 47.248885 -411.856831)
			(xy 47.264595 -411.805901) (xy 47.287721 -411.75788) (xy 47.317745 -411.713843) (xy 47.353997 -411.674772)
			(xy 47.395668 -411.641541) (xy 47.441826 -411.614892) (xy 47.49144 -411.59542) (xy 47.543402 -411.58356)
			(xy 47.596552 -411.579577) (xy 47.649702 -411.58356) (xy 47.701664 -411.59542) (xy 47.751278 -411.614892)
			(xy 47.797436 -411.641541) (xy 47.839107 -411.674772) (xy 47.875359 -411.713843) (xy 47.905383 -411.75788)
			(xy 47.928509 -411.805901) (xy 47.944219 -411.856831) (xy 47.952162 -411.909535) (xy 47.95266 -411.936184)
			(xy 47.952208 -411.961361) (xy 47.945068 -412.011206) (xy 47.938436 -412.035498) (xy 47.936237 -412.044448)
			(xy 47.937676 -412.062808) (xy 47.94123 -412.071312) (xy 47.954438 -412.099252) (xy 47.958822 -412.107574)
			(xy 47.972363 -412.120607) (xy 47.980854 -412.124652) (xy 48.00635 -412.135705) (xy 48.054856 -412.162826)
			(xy 48.077628 -412.178754) (xy 48.107346 -412.18866) (xy 48.344582 -412.18866) (xy 48.3743 -412.178754)
			(xy 48.393618 -412.165137) (xy 48.43446 -412.141343) (xy 48.455834 -412.131256) (xy 48.469296 -412.12516)
			(xy 48.485298 -412.100268) (xy 48.485298 -410.20619) (xy 48.48225 -410.194252) (xy 48.479202 -410.18841)
			(xy 48.466518 -410.163982) (xy 48.448539 -410.111961) (xy 48.439393 -410.057687) (xy 48.438816 -410.030168)
			(xy 48.439355 -410.002644) (xy 48.44847 -409.948356) (xy 48.466475 -409.896337) (xy 48.479202 -409.871926)
			(xy 48.48225 -409.866084) (xy 48.485298 -409.854146) (xy 48.485298 -409.683712) (xy 48.485719 -409.673641)
			(xy 48.49343 -409.655033) (xy 48.500284 -409.647644) (xy 48.765714 -409.382214) (xy 48.77308 -409.36672)
			(xy 48.774096 -409.35783) (xy 48.77735 -409.331965) (xy 48.79045 -409.281508) (xy 48.810767 -409.2335)
			(xy 48.837867 -409.188967) (xy 48.871171 -409.148862) (xy 48.909966 -409.114042) (xy 48.953424 -409.08525)
			(xy 49.000616 -409.063103) (xy 49.050532 -409.048074) (xy 49.102107 -409.040483) (xy 49.128172 -409.040076)
			(xy 49.153835 -409.040522) (xy 49.204631 -409.047884) (xy 49.253845 -409.062461) (xy 49.300457 -409.083949)
			(xy 49.343502 -409.111905) (xy 49.38209 -409.14575) (xy 49.41542 -409.184782) (xy 49.442804 -409.228194)
			(xy 49.463673 -409.275086) (xy 49.471072 -409.299664) (xy 49.475644 -409.316174) (xy 49.502822 -409.336748)
			(xy 50.012346 -409.336748) (xy 50.039524 -409.316174) (xy 50.044096 -409.299664) (xy 50.051968 -409.273654)
			(xy 50.074498 -409.224204) (xy 50.104275 -409.178749) (xy 50.140609 -409.138343) (xy 50.182658 -409.103922)
			(xy 50.229446 -409.076286) (xy 50.279888 -409.056074) (xy 50.332813 -409.043757) (xy 50.386996 -409.039619)
			(xy 50.441179 -409.043757) (xy 50.494104 -409.056074) (xy 50.544546 -409.076286) (xy 50.591334 -409.103922)
			(xy 50.633383 -409.138343) (xy 50.669717 -409.178749) (xy 50.699494 -409.224204) (xy 50.722024 -409.273654)
			(xy 50.729896 -409.299664) (xy 50.734468 -409.316174) (xy 50.761646 -409.336748) (xy 51.816762 -409.336748)
			(xy 51.84394 -409.316174) (xy 51.848512 -409.299664) (xy 51.856384 -409.273654) (xy 51.878914 -409.224204)
			(xy 51.908691 -409.178749) (xy 51.945025 -409.138343) (xy 51.987074 -409.103922) (xy 52.033862 -409.076286)
			(xy 52.084304 -409.056074) (xy 52.137229 -409.043757) (xy 52.191412 -409.039619) (xy 52.245595 -409.043757)
			(xy 52.29852 -409.056074) (xy 52.348962 -409.076286) (xy 52.39575 -409.103922) (xy 52.437799 -409.138343)
			(xy 52.474133 -409.178749) (xy 52.50391 -409.224204) (xy 52.52644 -409.273654) (xy 52.534312 -409.299664)
			(xy 52.538884 -409.316174) (xy 52.566062 -409.336748) (xy 53.075586 -409.336748) (xy 53.102764 -409.316174)
			(xy 53.107336 -409.299664) (xy 53.115208 -409.273654) (xy 53.137738 -409.224204) (xy 53.167515 -409.178749)
			(xy 53.203849 -409.138343) (xy 53.245898 -409.103922) (xy 53.292686 -409.076286) (xy 53.343128 -409.056074)
			(xy 53.396053 -409.043757) (xy 53.450236 -409.039619) (xy 53.504419 -409.043757) (xy 53.557344 -409.056074)
			(xy 53.607786 -409.076286) (xy 53.654574 -409.103922) (xy 53.696623 -409.138343) (xy 53.732957 -409.178749)
			(xy 53.762734 -409.224204) (xy 53.785264 -409.273654) (xy 53.793136 -409.299664) (xy 53.797708 -409.316174)
			(xy 53.824886 -409.336748) (xy 54.880002 -409.336748) (xy 54.90718 -409.316174) (xy 54.911752 -409.299664)
			(xy 54.919624 -409.273654) (xy 54.942154 -409.224204) (xy 54.971931 -409.178749) (xy 55.008265 -409.138343)
			(xy 55.050314 -409.103922) (xy 55.097102 -409.076286) (xy 55.147544 -409.056074) (xy 55.200469 -409.043757)
			(xy 55.254652 -409.039619) (xy 55.308835 -409.043757) (xy 55.36176 -409.056074) (xy 55.412202 -409.076286)
			(xy 55.45899 -409.103922) (xy 55.501039 -409.138343) (xy 55.537373 -409.178749) (xy 55.56715 -409.224204)
			(xy 55.58968 -409.273654) (xy 55.597552 -409.299664) (xy 55.602124 -409.316174) (xy 55.629302 -409.336748)
			(xy 56.138826 -409.336748) (xy 56.166004 -409.316174) (xy 56.170576 -409.299664) (xy 56.178448 -409.273654)
			(xy 56.200978 -409.224204) (xy 56.230755 -409.178749) (xy 56.267089 -409.138343) (xy 56.309138 -409.103922)
			(xy 56.355926 -409.076286) (xy 56.406368 -409.056074) (xy 56.459293 -409.043757) (xy 56.513476 -409.039619)
			(xy 56.567659 -409.043757) (xy 56.620584 -409.056074) (xy 56.671026 -409.076286) (xy 56.717814 -409.103922)
			(xy 56.759863 -409.138343) (xy 56.796197 -409.178749) (xy 56.825974 -409.224204) (xy 56.848504 -409.273654)
			(xy 56.856376 -409.299664) (xy 56.860948 -409.316174) (xy 56.888126 -409.336748) (xy 57.943242 -409.336748)
			(xy 57.97042 -409.316174) (xy 57.974992 -409.299664) (xy 57.982864 -409.273654) (xy 58.005394 -409.224204)
			(xy 58.035171 -409.178749) (xy 58.071505 -409.138343) (xy 58.113554 -409.103922) (xy 58.160342 -409.076286)
			(xy 58.210784 -409.056074) (xy 58.263709 -409.043757) (xy 58.317892 -409.039619) (xy 58.372075 -409.043757)
			(xy 58.425 -409.056074) (xy 58.475442 -409.076286) (xy 58.52223 -409.103922) (xy 58.564279 -409.138343)
			(xy 58.600613 -409.178749) (xy 58.63039 -409.224204) (xy 58.65292 -409.273654) (xy 58.660792 -409.299664)
			(xy 58.665364 -409.316174) (xy 58.692542 -409.336748) (xy 59.202066 -409.336748) (xy 59.229244 -409.316174)
			(xy 59.233816 -409.299664) (xy 59.241688 -409.273654) (xy 59.264218 -409.224204) (xy 59.293995 -409.178749)
			(xy 59.330329 -409.138343) (xy 59.372378 -409.103922) (xy 59.419166 -409.076286) (xy 59.469608 -409.056074)
			(xy 59.522533 -409.043757) (xy 59.576716 -409.039619) (xy 59.630899 -409.043757) (xy 59.683824 -409.056074)
			(xy 59.734266 -409.076286) (xy 59.781054 -409.103922) (xy 59.823103 -409.138343) (xy 59.859437 -409.178749)
			(xy 59.889214 -409.224204) (xy 59.911744 -409.273654) (xy 59.919616 -409.299664) (xy 59.924188 -409.316174)
			(xy 59.951366 -409.336748) (xy 61.006482 -409.336748) (xy 61.03366 -409.316174) (xy 61.038232 -409.299664)
			(xy 61.046104 -409.273654) (xy 61.068634 -409.224204) (xy 61.098411 -409.178749) (xy 61.134745 -409.138343)
			(xy 61.176794 -409.103922) (xy 61.223582 -409.076286) (xy 61.274024 -409.056074) (xy 61.326949 -409.043757)
			(xy 61.381132 -409.039619) (xy 61.435315 -409.043757) (xy 61.48824 -409.056074) (xy 61.538682 -409.076286)
			(xy 61.58547 -409.103922) (xy 61.627519 -409.138343) (xy 61.663853 -409.178749) (xy 61.69363 -409.224204)
			(xy 61.71616 -409.273654) (xy 61.724032 -409.299664) (xy 61.728604 -409.316174) (xy 61.755782 -409.336748)
			(xy 62.265306 -409.336748) (xy 62.292484 -409.316174) (xy 62.297056 -409.299664) (xy 62.304928 -409.273654)
			(xy 62.327458 -409.224204) (xy 62.357235 -409.178749) (xy 62.393569 -409.138343) (xy 62.435618 -409.103922)
			(xy 62.482406 -409.076286) (xy 62.532848 -409.056074) (xy 62.585773 -409.043757) (xy 62.639956 -409.039619)
			(xy 62.694139 -409.043757) (xy 62.747064 -409.056074) (xy 62.797506 -409.076286) (xy 62.844294 -409.103922)
			(xy 62.886343 -409.138343) (xy 62.922677 -409.178749) (xy 62.952454 -409.224204) (xy 62.974984 -409.273654)
			(xy 62.982856 -409.299664) (xy 62.987428 -409.316174) (xy 63.014606 -409.336748) (xy 64.069722 -409.336748)
			(xy 64.0969 -409.316174) (xy 64.101472 -409.299664) (xy 64.109344 -409.273654) (xy 64.131874 -409.224204)
			(xy 64.161651 -409.178749) (xy 64.197985 -409.138343) (xy 64.240034 -409.103922) (xy 64.286822 -409.076286)
			(xy 64.337264 -409.056074) (xy 64.390189 -409.043757) (xy 64.444372 -409.039619) (xy 64.498555 -409.043757)
			(xy 64.55148 -409.056074) (xy 64.601922 -409.076286) (xy 64.64871 -409.103922) (xy 64.690759 -409.138343)
			(xy 64.727093 -409.178749) (xy 64.75687 -409.224204) (xy 64.7794 -409.273654) (xy 64.787272 -409.299664)
			(xy 64.791844 -409.316174) (xy 64.819022 -409.336748) (xy 65.328546 -409.336748) (xy 65.355724 -409.316174)
			(xy 65.360296 -409.299664) (xy 65.368168 -409.273654) (xy 65.390698 -409.224204) (xy 65.420475 -409.178749)
			(xy 65.456809 -409.138343) (xy 65.498858 -409.103922) (xy 65.545646 -409.076286) (xy 65.596088 -409.056074)
			(xy 65.649013 -409.043757) (xy 65.703196 -409.039619) (xy 65.757379 -409.043757) (xy 65.810304 -409.056074)
			(xy 65.860746 -409.076286) (xy 65.907534 -409.103922) (xy 65.949583 -409.138343) (xy 65.985917 -409.178749)
			(xy 66.015694 -409.224204) (xy 66.038224 -409.273654) (xy 66.046096 -409.299664) (xy 66.050668 -409.316174)
			(xy 66.077846 -409.336748) (xy 67.132962 -409.336748) (xy 67.16014 -409.316174) (xy 67.164712 -409.299664)
			(xy 67.172584 -409.273654) (xy 67.195114 -409.224204) (xy 67.224891 -409.178749) (xy 67.261225 -409.138343)
			(xy 67.303274 -409.103922) (xy 67.350062 -409.076286) (xy 67.400504 -409.056074) (xy 67.453429 -409.043757)
			(xy 67.507612 -409.039619) (xy 67.561795 -409.043757) (xy 67.61472 -409.056074) (xy 67.665162 -409.076286)
			(xy 67.71195 -409.103922) (xy 67.753999 -409.138343) (xy 67.790333 -409.178749) (xy 67.82011 -409.224204)
			(xy 67.84264 -409.273654) (xy 67.850512 -409.299664) (xy 67.855084 -409.316174) (xy 67.882262 -409.336748)
			(xy 68.391786 -409.336748) (xy 68.418964 -409.316174) (xy 68.423536 -409.299664) (xy 68.431408 -409.273654)
			(xy 68.453938 -409.224204) (xy 68.483715 -409.178749) (xy 68.520049 -409.138343) (xy 68.562098 -409.103922)
			(xy 68.608886 -409.076286) (xy 68.659328 -409.056074) (xy 68.712253 -409.043757) (xy 68.766436 -409.039619)
			(xy 68.820619 -409.043757) (xy 68.873544 -409.056074) (xy 68.923986 -409.076286) (xy 68.970774 -409.103922)
			(xy 69.012823 -409.138343) (xy 69.049157 -409.178749) (xy 69.078934 -409.224204) (xy 69.101464 -409.273654)
			(xy 69.109336 -409.299664) (xy 69.113908 -409.316174) (xy 69.141086 -409.336748) (xy 70.196202 -409.336748)
			(xy 70.22338 -409.316174) (xy 70.227952 -409.299664) (xy 70.235824 -409.273654) (xy 70.258354 -409.224204)
			(xy 70.288131 -409.178749) (xy 70.324465 -409.138343) (xy 70.366514 -409.103922) (xy 70.413302 -409.076286)
			(xy 70.463744 -409.056074) (xy 70.516669 -409.043757) (xy 70.570852 -409.039619) (xy 70.625035 -409.043757)
			(xy 70.67796 -409.056074) (xy 70.728402 -409.076286) (xy 70.77519 -409.103922) (xy 70.817239 -409.138343)
			(xy 70.853573 -409.178749) (xy 70.88335 -409.224204) (xy 70.90588 -409.273654) (xy 70.913752 -409.299664)
			(xy 70.918324 -409.316174) (xy 70.945502 -409.336748) (xy 71.455026 -409.336748) (xy 71.482204 -409.316174)
			(xy 71.486776 -409.299664) (xy 71.494648 -409.273654) (xy 71.517178 -409.224204) (xy 71.546955 -409.178749)
			(xy 71.583289 -409.138343) (xy 71.625338 -409.103922) (xy 71.672126 -409.076286) (xy 71.722568 -409.056074)
			(xy 71.775493 -409.043757) (xy 71.829676 -409.039619) (xy 71.883859 -409.043757) (xy 71.936784 -409.056074)
			(xy 71.987226 -409.076286) (xy 72.034014 -409.103922) (xy 72.076063 -409.138343) (xy 72.112397 -409.178749)
			(xy 72.142174 -409.224204) (xy 72.164704 -409.273654) (xy 72.172576 -409.299664) (xy 72.177148 -409.316174)
			(xy 72.204326 -409.336748) (xy 73.259442 -409.336748) (xy 73.28662 -409.316174) (xy 73.291192 -409.299664)
			(xy 73.299064 -409.273654) (xy 73.321594 -409.224204) (xy 73.351371 -409.178749) (xy 73.387705 -409.138343)
			(xy 73.429754 -409.103922) (xy 73.476542 -409.076286) (xy 73.526984 -409.056074) (xy 73.579909 -409.043757)
			(xy 73.634092 -409.039619) (xy 73.688275 -409.043757) (xy 73.7412 -409.056074) (xy 73.791642 -409.076286)
			(xy 73.83843 -409.103922) (xy 73.880479 -409.138343) (xy 73.916813 -409.178749) (xy 73.94659 -409.224204)
			(xy 73.96912 -409.273654) (xy 73.976992 -409.299664) (xy 73.981564 -409.316174) (xy 74.008742 -409.336748)
			(xy 74.518266 -409.336748) (xy 74.545444 -409.316174) (xy 74.550016 -409.299664) (xy 74.557888 -409.273654)
			(xy 74.580418 -409.224204) (xy 74.610195 -409.178749) (xy 74.646529 -409.138343) (xy 74.688578 -409.103922)
			(xy 74.735366 -409.076286) (xy 74.785808 -409.056074) (xy 74.838733 -409.043757) (xy 74.892916 -409.039619)
			(xy 74.947099 -409.043757) (xy 75.000024 -409.056074) (xy 75.050466 -409.076286) (xy 75.097254 -409.103922)
			(xy 75.139303 -409.138343) (xy 75.175637 -409.178749) (xy 75.205414 -409.224204) (xy 75.227944 -409.273654)
			(xy 75.235816 -409.299664) (xy 75.240388 -409.316174) (xy 75.267566 -409.336748) (xy 76.322682 -409.336748)
			(xy 76.34986 -409.316174) (xy 76.354432 -409.299664) (xy 76.362304 -409.273654) (xy 76.384834 -409.224204)
			(xy 76.414611 -409.178749) (xy 76.450945 -409.138343) (xy 76.492994 -409.103922) (xy 76.539782 -409.076286)
			(xy 76.590224 -409.056074) (xy 76.643149 -409.043757) (xy 76.697332 -409.039619) (xy 76.751515 -409.043757)
			(xy 76.80444 -409.056074) (xy 76.854882 -409.076286) (xy 76.90167 -409.103922) (xy 76.943719 -409.138343)
			(xy 76.980053 -409.178749) (xy 77.00983 -409.224204) (xy 77.03236 -409.273654) (xy 77.040232 -409.299664)
			(xy 77.044804 -409.316174) (xy 77.071982 -409.336748) (xy 77.581506 -409.336748) (xy 77.608684 -409.316174)
			(xy 77.613256 -409.299664) (xy 77.621128 -409.273654) (xy 77.643658 -409.224204) (xy 77.673435 -409.178749)
			(xy 77.709769 -409.138343) (xy 77.751818 -409.103922) (xy 77.798606 -409.076286) (xy 77.849048 -409.056074)
			(xy 77.901973 -409.043757) (xy 77.956156 -409.039619) (xy 78.010339 -409.043757) (xy 78.063264 -409.056074)
			(xy 78.113706 -409.076286) (xy 78.160494 -409.103922) (xy 78.202543 -409.138343) (xy 78.238877 -409.178749)
			(xy 78.268654 -409.224204) (xy 78.291184 -409.273654) (xy 78.299056 -409.299664) (xy 78.303628 -409.316174)
			(xy 78.330806 -409.336748) (xy 79.385922 -409.336748) (xy 79.4131 -409.316174) (xy 79.417672 -409.299664)
			(xy 79.425544 -409.273654) (xy 79.448074 -409.224204) (xy 79.477851 -409.178749) (xy 79.514185 -409.138343)
			(xy 79.556234 -409.103922) (xy 79.603022 -409.076286) (xy 79.653464 -409.056074) (xy 79.706389 -409.043757)
			(xy 79.760572 -409.039619) (xy 79.814755 -409.043757) (xy 79.86768 -409.056074) (xy 79.918122 -409.076286)
			(xy 79.96491 -409.103922) (xy 80.006959 -409.138343) (xy 80.043293 -409.178749) (xy 80.07307 -409.224204)
			(xy 80.0956 -409.273654) (xy 80.103472 -409.299664) (xy 80.108044 -409.316174) (xy 80.135222 -409.336748)
			(xy 80.644746 -409.336748) (xy 80.671924 -409.316174) (xy 80.676496 -409.299664) (xy 80.684368 -409.273654)
			(xy 80.706898 -409.224204) (xy 80.736675 -409.178749) (xy 80.773009 -409.138343) (xy 80.815058 -409.103922)
			(xy 80.861846 -409.076286) (xy 80.912288 -409.056074) (xy 80.965213 -409.043757) (xy 81.019396 -409.039619)
			(xy 81.073579 -409.043757) (xy 81.126504 -409.056074) (xy 81.176946 -409.076286) (xy 81.223734 -409.103922)
			(xy 81.265783 -409.138343) (xy 81.302117 -409.178749) (xy 81.331894 -409.224204) (xy 81.354424 -409.273654)
			(xy 81.362296 -409.299664) (xy 81.366868 -409.316174) (xy 81.394046 -409.336748) (xy 82.449162 -409.336748)
			(xy 82.47634 -409.316174) (xy 82.480912 -409.299664) (xy 82.488784 -409.273654) (xy 82.511314 -409.224204)
			(xy 82.541091 -409.178749) (xy 82.577425 -409.138343) (xy 82.619474 -409.103922) (xy 82.666262 -409.076286)
			(xy 82.716704 -409.056074) (xy 82.769629 -409.043757) (xy 82.823812 -409.039619) (xy 82.877995 -409.043757)
			(xy 82.93092 -409.056074) (xy 82.981362 -409.076286) (xy 83.02815 -409.103922) (xy 83.070199 -409.138343)
			(xy 83.106533 -409.178749) (xy 83.13631 -409.224204) (xy 83.15884 -409.273654) (xy 83.166712 -409.299664)
			(xy 83.171284 -409.316174) (xy 83.198462 -409.336748) (xy 83.707986 -409.336748) (xy 83.735164 -409.316174)
			(xy 83.739736 -409.299664) (xy 83.747608 -409.273654) (xy 83.770138 -409.224204) (xy 83.799915 -409.178749)
			(xy 83.836249 -409.138343) (xy 83.878298 -409.103922) (xy 83.925086 -409.076286) (xy 83.975528 -409.056074)
			(xy 84.028453 -409.043757) (xy 84.082636 -409.039619) (xy 84.136819 -409.043757) (xy 84.189744 -409.056074)
			(xy 84.240186 -409.076286) (xy 84.286974 -409.103922) (xy 84.329023 -409.138343) (xy 84.365357 -409.178749)
			(xy 84.395134 -409.224204) (xy 84.417664 -409.273654) (xy 84.425536 -409.299664) (xy 84.430108 -409.316174)
			(xy 84.457286 -409.336748) (xy 85.512402 -409.336748) (xy 85.53958 -409.316174) (xy 85.544152 -409.299664)
			(xy 85.552024 -409.273654) (xy 85.574554 -409.224204) (xy 85.604331 -409.178749) (xy 85.640665 -409.138343)
			(xy 85.682714 -409.103922) (xy 85.729502 -409.076286) (xy 85.779944 -409.056074) (xy 85.832869 -409.043757)
			(xy 85.887052 -409.039619) (xy 85.941235 -409.043757) (xy 85.99416 -409.056074) (xy 86.044602 -409.076286)
			(xy 86.09139 -409.103922) (xy 86.133439 -409.138343) (xy 86.169773 -409.178749) (xy 86.19955 -409.224204)
			(xy 86.22208 -409.273654) (xy 86.229952 -409.299664) (xy 86.234524 -409.316174) (xy 86.261702 -409.336748)
			(xy 86.771226 -409.336748) (xy 86.798404 -409.316174) (xy 86.802976 -409.299664) (xy 86.810848 -409.273654)
			(xy 86.833378 -409.224204) (xy 86.863155 -409.178749) (xy 86.899489 -409.138343) (xy 86.941538 -409.103922)
			(xy 86.988326 -409.076286) (xy 87.038768 -409.056074) (xy 87.091693 -409.043757) (xy 87.145876 -409.039619)
			(xy 87.200059 -409.043757) (xy 87.252984 -409.056074) (xy 87.303426 -409.076286) (xy 87.350214 -409.103922)
			(xy 87.392263 -409.138343) (xy 87.428597 -409.178749) (xy 87.458374 -409.224204) (xy 87.480904 -409.273654)
			(xy 87.488776 -409.299664) (xy 87.493348 -409.316174) (xy 87.520526 -409.336748) (xy 88.575642 -409.336748)
			(xy 88.60282 -409.316174) (xy 88.607392 -409.299664) (xy 88.615264 -409.273654) (xy 88.637794 -409.224204)
			(xy 88.667571 -409.178749) (xy 88.703905 -409.138343) (xy 88.745954 -409.103922) (xy 88.792742 -409.076286)
			(xy 88.843184 -409.056074) (xy 88.896109 -409.043757) (xy 88.950292 -409.039619) (xy 89.004475 -409.043757)
			(xy 89.0574 -409.056074) (xy 89.107842 -409.076286) (xy 89.15463 -409.103922) (xy 89.196679 -409.138343)
			(xy 89.233013 -409.178749) (xy 89.26279 -409.224204) (xy 89.28532 -409.273654) (xy 89.293192 -409.299664)
			(xy 89.297764 -409.316174) (xy 89.324942 -409.336748) (xy 89.834466 -409.336748) (xy 89.861644 -409.316174)
			(xy 89.866216 -409.299664) (xy 89.874088 -409.273654) (xy 89.896618 -409.224204) (xy 89.926395 -409.178749)
			(xy 89.962729 -409.138343) (xy 90.004778 -409.103922) (xy 90.051566 -409.076286) (xy 90.102008 -409.056074)
			(xy 90.154933 -409.043757) (xy 90.209116 -409.039619) (xy 90.263299 -409.043757) (xy 90.316224 -409.056074)
			(xy 90.366666 -409.076286) (xy 90.413454 -409.103922) (xy 90.455503 -409.138343) (xy 90.491837 -409.178749)
			(xy 90.521614 -409.224204) (xy 90.544144 -409.273654) (xy 90.552016 -409.299664) (xy 90.556588 -409.316174)
			(xy 90.583766 -409.336748) (xy 91.638882 -409.336748) (xy 91.66606 -409.316174) (xy 91.670632 -409.299664)
			(xy 91.678504 -409.273654) (xy 91.701034 -409.224204) (xy 91.730811 -409.178749) (xy 91.767145 -409.138343)
			(xy 91.809194 -409.103922) (xy 91.855982 -409.076286) (xy 91.906424 -409.056074) (xy 91.959349 -409.043757)
			(xy 92.013532 -409.039619) (xy 92.067715 -409.043757) (xy 92.12064 -409.056074) (xy 92.171082 -409.076286)
			(xy 92.21787 -409.103922) (xy 92.259919 -409.138343) (xy 92.296253 -409.178749) (xy 92.32603 -409.224204)
			(xy 92.34856 -409.273654) (xy 92.356432 -409.299664) (xy 92.361004 -409.316174) (xy 92.388182 -409.336748)
			(xy 92.897706 -409.336748) (xy 92.924884 -409.316174) (xy 92.929456 -409.299664) (xy 92.937328 -409.273654)
			(xy 92.959858 -409.224204) (xy 92.989635 -409.178749) (xy 93.025969 -409.138343) (xy 93.068018 -409.103922)
			(xy 93.114806 -409.076286) (xy 93.165248 -409.056074) (xy 93.218173 -409.043757) (xy 93.272356 -409.039619)
			(xy 93.326539 -409.043757) (xy 93.379464 -409.056074) (xy 93.429906 -409.076286) (xy 93.476694 -409.103922)
			(xy 93.518743 -409.138343) (xy 93.555077 -409.178749) (xy 93.584854 -409.224204) (xy 93.607384 -409.273654)
			(xy 93.615256 -409.299664) (xy 93.619828 -409.316174) (xy 93.647006 -409.336748) (xy 94.702122 -409.336748)
			(xy 94.7293 -409.316174) (xy 94.733872 -409.299664) (xy 94.741744 -409.273654) (xy 94.764274 -409.224204)
			(xy 94.794051 -409.178749) (xy 94.830385 -409.138343) (xy 94.872434 -409.103922) (xy 94.919222 -409.076286)
			(xy 94.969664 -409.056074) (xy 95.022589 -409.043757) (xy 95.076772 -409.039619) (xy 95.130955 -409.043757)
			(xy 95.18388 -409.056074) (xy 95.234322 -409.076286) (xy 95.28111 -409.103922) (xy 95.323159 -409.138343)
			(xy 95.359493 -409.178749) (xy 95.38927 -409.224204) (xy 95.4118 -409.273654) (xy 95.419672 -409.299664)
			(xy 95.424244 -409.316174) (xy 95.451422 -409.336748) (xy 95.960946 -409.336748) (xy 95.988124 -409.316174)
			(xy 95.992696 -409.299664) (xy 96.000098 -409.27509) (xy 96.020982 -409.22821) (xy 96.048375 -409.184809)
			(xy 96.081708 -409.145787) (xy 96.120295 -409.111949) (xy 96.163336 -409.083995) (xy 96.209941 -409.062504)
			(xy 96.259146 -409.047919) (xy 96.309935 -409.040544) (xy 96.335596 -409.040076) (xy 96.36358 -409.040625)
			(xy 96.418858 -409.049379) (xy 96.472087 -409.066673) (xy 96.521955 -409.092081) (xy 96.567234 -409.124976)
			(xy 96.606811 -409.16455) (xy 96.639709 -409.209828) (xy 96.665119 -409.259695) (xy 96.682416 -409.312922)
			(xy 96.691174 -409.3682) (xy 96.691704 -409.396184) (xy 96.691007 -409.428204) (xy 96.679505 -409.491205)
			(xy 96.668844 -409.521406) (xy 96.663764 -409.535376) (xy 96.66986 -409.564586) (xy 96.834706 -409.729432)
			(xy 96.842326 -409.733242) (xy 96.866567 -409.745743) (xy 96.910939 -409.777452) (xy 96.949506 -409.816012)
			(xy 96.981224 -409.860378) (xy 96.99371 -409.884626) (xy 96.99752 -409.892246) (xy 97.000822 -409.895548)
			(xy 97.000822 -409.899612) (xy 97.004378 -409.908756) (xy 97.013101 -409.93206) (xy 97.024241 -409.980554)
			(xy 97.027986 -410.03017) (xy 97.02425 -410.079787) (xy 97.013119 -410.128284) (xy 97.004378 -410.15158)
			(xy 97.000822 -410.160724) (xy 97.000822 -411.892961) (xy 98.297994 -411.892961) (xy 98.297994 -411.829039)
			(xy 98.306005 -411.765621) (xy 98.321902 -411.703707) (xy 98.345434 -411.644274) (xy 98.376228 -411.588259)
			(xy 98.413801 -411.536544) (xy 98.457558 -411.489947) (xy 98.506811 -411.449202) (xy 98.560782 -411.414951)
			(xy 98.618621 -411.387734) (xy 98.679414 -411.367981) (xy 98.742204 -411.356003) (xy 98.806 -411.35199)
			(xy 98.869796 -411.356003) (xy 98.932586 -411.367981) (xy 98.993379 -411.387734) (xy 99.051218 -411.414951)
			(xy 99.105189 -411.449202) (xy 99.154442 -411.489947) (xy 99.198199 -411.536544) (xy 99.235772 -411.588259)
			(xy 99.266566 -411.644274) (xy 99.290098 -411.703707) (xy 99.305995 -411.765621) (xy 99.314006 -411.829039)
			(xy 99.314508 -411.861) (xy 99.314006 -411.892961) (xy 99.567994 -411.892961) (xy 99.567994 -411.829039)
			(xy 99.576005 -411.765621) (xy 99.591902 -411.703707) (xy 99.615434 -411.644274) (xy 99.646228 -411.588259)
			(xy 99.683801 -411.536544) (xy 99.727558 -411.489947) (xy 99.776811 -411.449202) (xy 99.830782 -411.414951)
			(xy 99.888621 -411.387734) (xy 99.949414 -411.367981) (xy 100.012204 -411.356003) (xy 100.076 -411.35199)
			(xy 100.139796 -411.356003) (xy 100.202586 -411.367981) (xy 100.263379 -411.387734) (xy 100.321218 -411.414951)
			(xy 100.375189 -411.449202) (xy 100.424442 -411.489947) (xy 100.468199 -411.536544) (xy 100.505772 -411.588259)
			(xy 100.536566 -411.644274) (xy 100.560098 -411.703707) (xy 100.575995 -411.765621) (xy 100.584006 -411.829039)
			(xy 100.584508 -411.861) (xy 100.584006 -411.892961) (xy 101.188514 -411.892961) (xy 101.188514 -411.829039)
			(xy 101.196525 -411.765621) (xy 101.212422 -411.703707) (xy 101.235954 -411.644274) (xy 101.266748 -411.588259)
			(xy 101.304321 -411.536544) (xy 101.348078 -411.489947) (xy 101.397331 -411.449202) (xy 101.451302 -411.414951)
			(xy 101.509141 -411.387734) (xy 101.569934 -411.367981) (xy 101.632724 -411.356003) (xy 101.69652 -411.35199)
			(xy 101.760316 -411.356003) (xy 101.823106 -411.367981) (xy 101.883899 -411.387734) (xy 101.941738 -411.414951)
			(xy 101.995709 -411.449202) (xy 102.044962 -411.489947) (xy 102.088719 -411.536544) (xy 102.126292 -411.588259)
			(xy 102.157086 -411.644274) (xy 102.180618 -411.703707) (xy 102.196515 -411.765621) (xy 102.204526 -411.829039)
			(xy 102.205028 -411.861) (xy 102.204526 -411.892961) (xy 102.196515 -411.956379) (xy 102.180618 -412.018293)
			(xy 102.157086 -412.077726) (xy 102.126292 -412.133741) (xy 102.088719 -412.185456) (xy 102.044962 -412.232053)
			(xy 101.995709 -412.272798) (xy 101.941738 -412.307049) (xy 101.883899 -412.334266) (xy 101.823106 -412.354019)
			(xy 101.760316 -412.365997) (xy 101.69652 -412.370011) (xy 101.632724 -412.365997) (xy 101.569934 -412.354019)
			(xy 101.509141 -412.334266) (xy 101.451302 -412.307049) (xy 101.397331 -412.272798) (xy 101.348078 -412.232053)
			(xy 101.304321 -412.185456) (xy 101.266748 -412.133741) (xy 101.235954 -412.077726) (xy 101.212422 -412.018293)
			(xy 101.196525 -411.956379) (xy 101.188514 -411.892961) (xy 100.584006 -411.892961) (xy 100.575995 -411.956379)
			(xy 100.560098 -412.018293) (xy 100.536566 -412.077726) (xy 100.505772 -412.133741) (xy 100.468199 -412.185456)
			(xy 100.424442 -412.232053) (xy 100.375189 -412.272798) (xy 100.321218 -412.307049) (xy 100.263379 -412.334266)
			(xy 100.202586 -412.354019) (xy 100.139796 -412.365997) (xy 100.076 -412.370011) (xy 100.012204 -412.365997)
			(xy 99.949414 -412.354019) (xy 99.888621 -412.334266) (xy 99.830782 -412.307049) (xy 99.776811 -412.272798)
			(xy 99.727558 -412.232053) (xy 99.683801 -412.185456) (xy 99.646228 -412.133741) (xy 99.615434 -412.077726)
			(xy 99.591902 -412.018293) (xy 99.576005 -411.956379) (xy 99.567994 -411.892961) (xy 99.314006 -411.892961)
			(xy 99.305995 -411.956379) (xy 99.290098 -412.018293) (xy 99.266566 -412.077726) (xy 99.235772 -412.133741)
			(xy 99.198199 -412.185456) (xy 99.154442 -412.232053) (xy 99.105189 -412.272798) (xy 99.051218 -412.307049)
			(xy 98.993379 -412.334266) (xy 98.932586 -412.354019) (xy 98.869796 -412.365997) (xy 98.806 -412.370011)
			(xy 98.742204 -412.365997) (xy 98.679414 -412.354019) (xy 98.618621 -412.334266) (xy 98.560782 -412.307049)
			(xy 98.506811 -412.272798) (xy 98.457558 -412.232053) (xy 98.413801 -412.185456) (xy 98.376228 -412.133741)
			(xy 98.345434 -412.077726) (xy 98.321902 -412.018293) (xy 98.306005 -411.956379) (xy 98.297994 -411.892961)
			(xy 97.000822 -411.892961) (xy 97.000822 -416.786314) (xy 97.01911 -416.812476) (xy 97.034604 -416.81781)
			(xy 97.053654 -416.825176) (xy 97.065191 -416.829169) (xy 97.089477 -416.82706) (xy 97.100136 -416.821112)
			(xy 97.126044 -416.804348) (xy 97.135765 -416.797466) (xy 97.147973 -416.777054) (xy 97.149412 -416.765232)
			(xy 97.149412 -414.27654) (xy 97.206308 -414.27654) (xy 97.27565 -414.173924) (xy 97.278444 -414.149032)
			(xy 97.273618 -414.137094) (xy 97.261966 -414.106789) (xy 97.245574 -414.043965) (xy 97.237311 -413.979566)
			(xy 97.236788 -413.947102) (xy 97.237252 -413.916371) (xy 97.24466 -413.855357) (xy 97.259369 -413.79568)
			(xy 97.281163 -413.738212) (xy 97.309726 -413.68379) (xy 97.34464 -413.633207) (xy 97.385397 -413.587201)
			(xy 97.431402 -413.546444) (xy 97.481984 -413.511529) (xy 97.536406 -413.482966) (xy 97.593874 -413.461171)
			(xy 97.653551 -413.446461) (xy 97.714565 -413.439052) (xy 97.745296 -413.438594) (xy 97.777791 -413.439108)
			(xy 97.84225 -413.447388) (xy 97.87382 -413.455104) (xy 97.886012 -413.458152) (xy 97.910142 -413.452818)
			(xy 97.992438 -413.382714) (xy 98.001836 -413.359854) (xy 98.00082 -413.347408) (xy 97.999042 -413.311848)
			(xy 97.999528 -413.284597) (xy 98.007284 -413.230649) (xy 98.022639 -413.178354) (xy 98.045281 -413.128777)
			(xy 98.074747 -413.082927) (xy 98.110438 -413.041736) (xy 98.151629 -413.006045) (xy 98.197479 -412.976579)
			(xy 98.247056 -412.953937) (xy 98.299351 -412.938582) (xy 98.353299 -412.930826) (xy 98.407801 -412.930826)
			(xy 98.461749 -412.938582) (xy 98.514044 -412.953937) (xy 98.563621 -412.976579) (xy 98.609471 -413.006045)
			(xy 98.650662 -413.041736) (xy 98.686353 -413.082927) (xy 98.715819 -413.128777) (xy 98.738461 -413.178354)
			(xy 98.753816 -413.230649) (xy 98.761572 -413.284597) (xy 98.762058 -413.311848) (xy 98.760534 -413.347154)
			(xy 98.759264 -413.3596) (xy 98.768662 -413.382714) (xy 98.850958 -413.452564) (xy 98.875088 -413.458152)
			(xy 98.88728 -413.455104) (xy 98.918725 -413.447414) (xy 98.982929 -413.439134) (xy 99.015296 -413.438594)
			(xy 99.046028 -413.439039) (xy 99.107045 -413.446448) (xy 99.166723 -413.461157) (xy 99.224193 -413.482952)
			(xy 99.278618 -413.511516) (xy 99.329202 -413.546431) (xy 99.375209 -413.58719) (xy 99.415967 -413.633196)
			(xy 99.450883 -413.683781) (xy 99.479447 -413.738205) (xy 99.501243 -413.795675) (xy 99.515952 -413.855353)
			(xy 99.52336 -413.91637) (xy 99.523804 -413.947102) (xy 99.523291 -413.979566) (xy 99.515024 -414.043966)
			(xy 99.498625 -414.106788) (xy 99.486974 -414.137094) (xy 99.482148 -414.149032) (xy 99.484942 -414.173924)
			(xy 99.539044 -414.254188) (xy 99.545932 -414.26349) (xy 99.565909 -414.275131) (xy 99.577398 -414.27654)
			(xy 99.723194 -414.27654) (xy 99.734674 -414.27511) (xy 99.75464 -414.263468) (xy 99.761548 -414.254188)
			(xy 99.81565 -414.173924) (xy 99.818444 -414.149032) (xy 99.813618 -414.137094) (xy 99.801966 -414.106789)
			(xy 99.785574 -414.043965) (xy 99.777311 -413.979566) (xy 99.776788 -413.947102) (xy 99.77729 -413.915141)
			(xy 99.785301 -413.851723) (xy 99.801198 -413.789809) (xy 99.82473 -413.730376) (xy 99.855524 -413.674361)
			(xy 99.893097 -413.622646) (xy 99.936854 -413.576049) (xy 99.986107 -413.535304) (xy 100.040078 -413.501053)
			(xy 100.097917 -413.473836) (xy 100.15871 -413.454083) (xy 100.2215 -413.442105) (xy 100.285296 -413.438092)
			(xy 100.349092 -413.442105) (xy 100.411882 -413.454083) (xy 100.472675 -413.473836) (xy 100.530514 -413.501053)
			(xy 100.584485 -413.535304) (xy 100.633738 -413.576049) (xy 100.677495 -413.622646) (xy 100.715068 -413.674361)
			(xy 100.745862 -413.730376) (xy 100.769394 -413.789809) (xy 100.785291 -413.851723) (xy 100.793302 -413.915141)
			(xy 100.793804 -413.947102) (xy 100.793291 -413.979566) (xy 100.785024 -414.043966) (xy 100.768625 -414.106788)
			(xy 100.756974 -414.137094) (xy 100.752148 -414.149032) (xy 100.754942 -414.173924) (xy 100.809044 -414.254188)
			(xy 100.815932 -414.26349) (xy 100.835909 -414.275131) (xy 100.847398 -414.27654) (xy 101.328474 -414.27654)
			(xy 101.340402 -414.274984) (xy 101.360933 -414.262512) (xy 101.367844 -414.252664) (xy 101.420422 -414.168336)
			(xy 101.421692 -414.142174) (xy 101.41585 -414.130236) (xy 101.403542 -414.10393) (xy 101.386131 -414.048525)
			(xy 101.377295 -413.991125) (xy 101.376734 -413.962088) (xy 101.37722 -413.934837) (xy 101.384976 -413.880889)
			(xy 101.400331 -413.828594) (xy 101.422973 -413.779017) (xy 101.452439 -413.733167) (xy 101.48813 -413.691976)
			(xy 101.529321 -413.656285) (xy 101.575171 -413.626819) (xy 101.624748 -413.604177) (xy 101.677043 -413.588822)
			(xy 101.730991 -413.581066) (xy 101.785493 -413.581066) (xy 101.839441 -413.588822) (xy 101.891736 -413.604177)
			(xy 101.941313 -413.626819) (xy 101.987163 -413.656285) (xy 102.028354 -413.691976) (xy 102.034574 -413.699155)
			(xy 102.448862 -413.699155) (xy 102.448862 -413.635233) (xy 102.456873 -413.571815) (xy 102.47277 -413.509901)
			(xy 102.496302 -413.450468) (xy 102.527096 -413.394453) (xy 102.564669 -413.342738) (xy 102.608426 -413.296141)
			(xy 102.657679 -413.255396) (xy 102.71165 -413.221145) (xy 102.769489 -413.193928) (xy 102.830282 -413.174175)
			(xy 102.893072 -413.162197) (xy 102.956868 -413.158184) (xy 103.020664 -413.162197) (xy 103.083454 -413.174175)
			(xy 103.144247 -413.193928) (xy 103.202086 -413.221145) (xy 103.256057 -413.255396) (xy 103.30531 -413.296141)
			(xy 103.349067 -413.342738) (xy 103.38664 -413.394453) (xy 103.417434 -413.450468) (xy 103.440966 -413.509901)
			(xy 103.456863 -413.571815) (xy 103.464874 -413.635233) (xy 103.465376 -413.667194) (xy 103.464874 -413.699155)
			(xy 103.456863 -413.762573) (xy 103.440966 -413.824487) (xy 103.417434 -413.88392) (xy 103.38664 -413.939935)
			(xy 103.349067 -413.99165) (xy 103.30531 -414.038247) (xy 103.256057 -414.078992) (xy 103.202086 -414.113243)
			(xy 103.144247 -414.14046) (xy 103.083454 -414.160213) (xy 103.020664 -414.172191) (xy 102.956868 -414.176205)
			(xy 102.893072 -414.172191) (xy 102.830282 -414.160213) (xy 102.769489 -414.14046) (xy 102.71165 -414.113243)
			(xy 102.657679 -414.078992) (xy 102.608426 -414.038247) (xy 102.564669 -413.99165) (xy 102.527096 -413.939935)
			(xy 102.496302 -413.88392) (xy 102.47277 -413.824487) (xy 102.456873 -413.762573) (xy 102.448862 -413.699155)
			(xy 102.034574 -413.699155) (xy 102.064045 -413.733167) (xy 102.093511 -413.779017) (xy 102.116153 -413.828594)
			(xy 102.131508 -413.880889) (xy 102.139264 -413.934837) (xy 102.13975 -413.962088) (xy 102.13921 -413.991128)
			(xy 102.130399 -414.048536) (xy 102.112965 -414.103938) (xy 102.100634 -414.130236) (xy 102.094792 -414.142174)
			(xy 102.096062 -414.168336) (xy 102.143306 -414.244028) (xy 102.14692 -414.250168) (xy 102.150927 -414.263833)
			(xy 102.15118 -414.270952) (xy 102.15118 -414.27654) (xy 102.15118 -415.90595) (xy 102.270052 -415.90595)
			(xy 102.270549 -415.873746) (xy 102.27867 -415.809853) (xy 102.29479 -415.747495) (xy 102.31865 -415.687669)
			(xy 102.349868 -415.631333) (xy 102.387947 -415.579387) (xy 102.409752 -415.555684) (xy 102.41661 -415.548572)
			(xy 102.423722 -415.531046) (xy 102.42423 -415.441638) (xy 102.417372 -415.424112) (xy 102.410768 -415.416746)
			(xy 102.389629 -415.393173) (xy 102.352703 -415.341736) (xy 102.322451 -415.286111) (xy 102.299343 -415.227159)
			(xy 102.283735 -415.165794) (xy 102.27587 -415.102965) (xy 102.275386 -415.071306) (xy 102.275888 -415.039345)
			(xy 102.283899 -414.975927) (xy 102.299796 -414.914013) (xy 102.323328 -414.85458) (xy 102.354122 -414.798565)
			(xy 102.391695 -414.74685) (xy 102.435452 -414.700253) (xy 102.484705 -414.659508) (xy 102.538676 -414.625257)
			(xy 102.596515 -414.59804) (xy 102.657308 -414.578287) (xy 102.720098 -414.566309) (xy 102.783894 -414.562296)
			(xy 102.84769 -414.566309) (xy 102.91048 -414.578287) (xy 102.971273 -414.59804) (xy 103.029112 -414.625257)
			(xy 103.083083 -414.659508) (xy 103.132336 -414.700253) (xy 103.176093 -414.74685) (xy 103.213666 -414.798565)
			(xy 103.24446 -414.85458) (xy 103.267992 -414.914013) (xy 103.283889 -414.975927) (xy 103.2919 -415.039345)
			(xy 103.292402 -415.071306) (xy 103.29189 -415.10351) (xy 103.283773 -415.167403) (xy 103.267657 -415.229761)
			(xy 103.2438 -415.289586) (xy 103.212584 -415.345922) (xy 103.174507 -415.397868) (xy 103.152702 -415.421572)
			(xy 103.145844 -415.428684) (xy 103.138732 -415.44621) (xy 103.138224 -415.535618) (xy 103.145082 -415.553144)
			(xy 103.151686 -415.56051) (xy 103.172844 -415.584067) (xy 103.20977 -415.635507) (xy 103.24002 -415.691135)
			(xy 103.263125 -415.75009) (xy 103.278728 -415.811458) (xy 103.286588 -415.87429) (xy 103.287068 -415.90595)
			(xy 103.286523 -415.939079) (xy 103.277929 -416.004776) (xy 103.260867 -416.068799) (xy 103.235627 -416.130061)
			(xy 103.202638 -416.187522) (xy 103.162458 -416.240206) (xy 103.139494 -416.26409) (xy 103.12908 -416.274504)
			(xy 103.12273 -416.302444) (xy 103.16083 -416.415982) (xy 103.182674 -416.43427) (xy 103.197152 -416.436302)
			(xy 103.224074 -416.440632) (xy 103.276399 -416.455976) (xy 103.326006 -416.478612) (xy 103.371886 -416.508079)
			(xy 103.413104 -416.543778) (xy 103.448821 -416.58498) (xy 103.478308 -416.630848) (xy 103.500966 -416.680445)
			(xy 103.502891 -416.687) (xy 108.329982 -416.687) (xy 108.334053 -416.631378) (xy 108.346179 -416.576941)
			(xy 108.366102 -416.52485) (xy 108.393398 -416.476215) (xy 108.427484 -416.432072) (xy 108.467633 -416.393363)
			(xy 108.512991 -416.360912) (xy 108.562591 -416.335411) (xy 108.615375 -416.317404) (xy 108.670218 -416.307274)
			(xy 108.725952 -416.305237) (xy 108.781389 -416.311337) (xy 108.835346 -416.325443) (xy 108.886675 -416.347255)
			(xy 108.934281 -416.376309) (xy 108.977149 -416.411984) (xy 109.014366 -416.453521) (xy 109.045139 -416.500034)
			(xy 109.068811 -416.550531) (xy 109.084879 -416.603938) (xy 109.092999 -416.659114) (xy 109.093508 -416.687)
			(xy 109.092999 -416.714886) (xy 109.084879 -416.770062) (xy 109.068811 -416.823469) (xy 109.045139 -416.873966)
			(xy 109.014366 -416.920479) (xy 109.009407 -416.926014) (xy 113.25428 -416.926014) (xy 113.258351 -416.870392)
			(xy 113.270477 -416.815955) (xy 113.2904 -416.763864) (xy 113.317696 -416.715229) (xy 113.351782 -416.671086)
			(xy 113.391931 -416.632377) (xy 113.437289 -416.599926) (xy 113.486889 -416.574425) (xy 113.539673 -416.556418)
			(xy 113.594516 -416.546288) (xy 113.65025 -416.544251) (xy 113.705687 -416.550351) (xy 113.759644 -416.564457)
			(xy 113.810973 -416.586269) (xy 113.858579 -416.615323) (xy 113.901447 -416.650998) (xy 113.938664 -416.692535)
			(xy 113.969437 -416.739048) (xy 113.993109 -416.789545) (xy 114.009177 -416.842952) (xy 114.017297 -416.898128)
			(xy 114.017806 -416.926014) (xy 114.017297 -416.9539) (xy 114.009177 -417.009076) (xy 113.993109 -417.062483)
			(xy 113.969437 -417.11298) (xy 113.938664 -417.159493) (xy 113.901447 -417.20103) (xy 113.858579 -417.236705)
			(xy 113.810973 -417.265759) (xy 113.759644 -417.287571) (xy 113.705687 -417.301677) (xy 113.65025 -417.307777)
			(xy 113.594516 -417.30574) (xy 113.539673 -417.29561) (xy 113.486889 -417.277603) (xy 113.437289 -417.252102)
			(xy 113.391931 -417.219651) (xy 113.351782 -417.180942) (xy 113.317696 -417.136799) (xy 113.2904 -417.088164)
			(xy 113.270477 -417.036073) (xy 113.258351 -416.981636) (xy 113.25428 -416.926014) (xy 109.009407 -416.926014)
			(xy 108.977149 -416.962016) (xy 108.934281 -416.997691) (xy 108.886675 -417.026745) (xy 108.835346 -417.048557)
			(xy 108.781389 -417.062663) (xy 108.725952 -417.068763) (xy 108.670218 -417.066726) (xy 108.615375 -417.056596)
			(xy 108.562591 -417.038589) (xy 108.512991 -417.013088) (xy 108.467633 -416.980637) (xy 108.427484 -416.941928)
			(xy 108.393398 -416.897785) (xy 108.366102 -416.84915) (xy 108.346179 -416.797059) (xy 108.334053 -416.742622)
			(xy 108.329982 -416.687) (xy 103.502891 -416.687) (xy 103.516332 -416.732763) (xy 103.524094 -416.786736)
			(xy 103.524558 -416.814) (xy 103.524072 -416.841251) (xy 103.516316 -416.895199) (xy 103.500961 -416.947494)
			(xy 103.478319 -416.997071) (xy 103.448853 -417.042921) (xy 103.413162 -417.084112) (xy 103.371971 -417.119803)
			(xy 103.326121 -417.149269) (xy 103.276544 -417.171911) (xy 103.224249 -417.187266) (xy 103.170301 -417.195022)
			(xy 103.115799 -417.195022) (xy 103.061851 -417.187266) (xy 103.009556 -417.171911) (xy 102.959979 -417.149269)
			(xy 102.914129 -417.119803) (xy 102.872938 -417.084112) (xy 102.837247 -417.042921) (xy 102.807781 -416.997071)
			(xy 102.785139 -416.947494) (xy 102.769784 -416.895199) (xy 102.762028 -416.841251) (xy 102.761542 -416.814)
			(xy 102.76194 -416.788616) (xy 102.76868 -416.738298) (xy 102.782027 -416.689316) (xy 102.801747 -416.642534)
			(xy 102.827492 -416.598778) (xy 102.842822 -416.578542) (xy 102.851966 -416.567112) (xy 102.855014 -416.538664)
			(xy 102.80396 -416.430206) (xy 102.780084 -416.414712) (xy 102.765606 -416.414204) (xy 102.732877 -416.412853)
			(xy 102.668146 -416.402807) (xy 102.605243 -416.384528) (xy 102.545208 -416.358321) (xy 102.489037 -416.324619)
			(xy 102.437661 -416.283981) (xy 102.391931 -416.23708) (xy 102.352604 -416.184694) (xy 102.320332 -416.127689)
			(xy 102.29565 -416.067012) (xy 102.278966 -416.003666) (xy 102.270558 -415.938703) (xy 102.270052 -415.90595)
			(xy 102.15118 -415.90595) (xy 102.15118 -417.562284) (xy 105.647996 -417.562284) (xy 105.652067 -417.506662)
			(xy 105.664193 -417.452225) (xy 105.684116 -417.400134) (xy 105.711412 -417.351499) (xy 105.745498 -417.307356)
			(xy 105.785647 -417.268647) (xy 105.831005 -417.236196) (xy 105.880605 -417.210695) (xy 105.933389 -417.192688)
			(xy 105.988232 -417.182558) (xy 106.043966 -417.180521) (xy 106.099403 -417.186621) (xy 106.15336 -417.200727)
			(xy 106.204689 -417.222539) (xy 106.252295 -417.251593) (xy 106.295163 -417.287268) (xy 106.33238 -417.328805)
			(xy 106.363153 -417.375318) (xy 106.386825 -417.425815) (xy 106.402893 -417.479222) (xy 106.411013 -417.534398)
			(xy 106.411522 -417.562284) (xy 106.411013 -417.59017) (xy 106.402893 -417.645346) (xy 106.386825 -417.698753)
			(xy 106.363153 -417.74925) (xy 106.33238 -417.795763) (xy 106.295163 -417.8373) (xy 106.252295 -417.872975)
			(xy 106.204689 -417.902029) (xy 106.15336 -417.923841) (xy 106.099403 -417.937947) (xy 106.043966 -417.944047)
			(xy 105.988232 -417.94201) (xy 105.933389 -417.93188) (xy 105.880605 -417.913873) (xy 105.831005 -417.888372)
			(xy 105.785647 -417.855921) (xy 105.745498 -417.817212) (xy 105.711412 -417.773069) (xy 105.684116 -417.724434)
			(xy 105.664193 -417.672343) (xy 105.652067 -417.617906) (xy 105.647996 -417.562284) (xy 102.15118 -417.562284)
			(xy 102.15118 -418.414919) (xy 104.139994 -418.414919) (xy 104.139994 -418.350997) (xy 104.148005 -418.287579)
			(xy 104.163902 -418.225665) (xy 104.187434 -418.166232) (xy 104.218228 -418.110217) (xy 104.255801 -418.058502)
			(xy 104.299558 -418.011905) (xy 104.348811 -417.97116) (xy 104.402782 -417.936909) (xy 104.460621 -417.909692)
			(xy 104.521414 -417.889939) (xy 104.584204 -417.877961) (xy 104.648 -417.873948) (xy 104.711796 -417.877961)
			(xy 104.774586 -417.889939) (xy 104.835379 -417.909692) (xy 104.893218 -417.936909) (xy 104.947189 -417.97116)
			(xy 104.996442 -418.011905) (xy 105.040199 -418.058502) (xy 105.077772 -418.110217) (xy 105.108566 -418.166232)
			(xy 105.132098 -418.225665) (xy 105.147995 -418.287579) (xy 105.156006 -418.350997) (xy 105.156508 -418.382958)
			(xy 105.156006 -418.414919) (xy 105.147995 -418.478337) (xy 105.132098 -418.540251) (xy 105.108566 -418.599684)
			(xy 105.077772 -418.655699) (xy 105.040199 -418.707414) (xy 104.996442 -418.754011) (xy 104.947189 -418.794756)
			(xy 104.893218 -418.829007) (xy 104.835379 -418.856224) (xy 104.774586 -418.875977) (xy 104.711796 -418.887955)
			(xy 104.648 -418.891969) (xy 104.584204 -418.887955) (xy 104.521414 -418.875977) (xy 104.460621 -418.856224)
			(xy 104.402782 -418.829007) (xy 104.348811 -418.794756) (xy 104.299558 -418.754011) (xy 104.255801 -418.707414)
			(xy 104.218228 -418.655699) (xy 104.187434 -418.599684) (xy 104.163902 -418.540251) (xy 104.148005 -418.478337)
			(xy 104.139994 -418.414919) (xy 102.15118 -418.414919) (xy 102.15118 -419.127251) (xy 108.457978 -419.127251)
			(xy 108.457978 -419.072749) (xy 108.465734 -419.018801) (xy 108.481089 -418.966506) (xy 108.503731 -418.916929)
			(xy 108.533197 -418.871079) (xy 108.568888 -418.829888) (xy 108.610079 -418.794197) (xy 108.655929 -418.764731)
			(xy 108.705506 -418.742089) (xy 108.757801 -418.726734) (xy 108.811749 -418.718978) (xy 108.839 -418.718492)
			(xy 108.866379 -418.71895) (xy 108.920574 -418.726791) (xy 108.973091 -418.742297) (xy 109.022853 -418.76515)
			(xy 109.068838 -418.794881) (xy 109.110101 -418.830878) (xy 109.128306 -418.851334) (xy 109.136434 -418.860732)
			(xy 109.15904 -418.869876) (xy 109.265466 -418.860986) (xy 109.28604 -418.848032) (xy 109.29239 -418.837618)
			(xy 109.309679 -418.809851) (xy 109.350343 -418.758614) (xy 109.397241 -418.713013) (xy 109.449599 -418.673802)
			(xy 109.506551 -418.641627) (xy 109.567159 -418.617019) (xy 109.630421 -418.600384) (xy 109.695294 -418.591998)
			(xy 109.728 -418.591492) (xy 109.759961 -418.591994) (xy 109.823379 -418.600005) (xy 109.885293 -418.615902)
			(xy 109.944726 -418.639434) (xy 110.000741 -418.670228) (xy 110.052456 -418.707801) (xy 110.099053 -418.751558)
			(xy 110.139798 -418.800811) (xy 110.174049 -418.854782) (xy 110.201266 -418.912621) (xy 110.221019 -418.973414)
			(xy 110.224574 -418.99205) (xy 114.959128 -418.99205) (xy 114.963199 -418.936428) (xy 114.975325 -418.881991)
			(xy 114.995248 -418.8299) (xy 115.022544 -418.781265) (xy 115.05663 -418.737122) (xy 115.096779 -418.698413)
			(xy 115.142137 -418.665962) (xy 115.191737 -418.640461) (xy 115.244521 -418.622454) (xy 115.299364 -418.612324)
			(xy 115.355098 -418.610287) (xy 115.410535 -418.616387) (xy 115.464492 -418.630493) (xy 115.515821 -418.652305)
			(xy 115.563427 -418.681359) (xy 115.606295 -418.717034) (xy 115.643512 -418.758571) (xy 115.674285 -418.805084)
			(xy 115.697957 -418.855581) (xy 115.714025 -418.908988) (xy 115.722145 -418.964164) (xy 115.722654 -418.99205)
			(xy 115.722145 -419.019936) (xy 115.714025 -419.075112) (xy 115.706537 -419.1) (xy 116.711982 -419.1)
			(xy 116.716053 -419.044378) (xy 116.728179 -418.989941) (xy 116.748102 -418.93785) (xy 116.775398 -418.889215)
			(xy 116.809484 -418.845072) (xy 116.849633 -418.806363) (xy 116.894991 -418.773912) (xy 116.944591 -418.748411)
			(xy 116.997375 -418.730404) (xy 117.052218 -418.720274) (xy 117.107952 -418.718237) (xy 117.163389 -418.724337)
			(xy 117.217346 -418.738443) (xy 117.268675 -418.760255) (xy 117.316281 -418.789309) (xy 117.359149 -418.824984)
			(xy 117.396366 -418.866521) (xy 117.427139 -418.913034) (xy 117.450811 -418.963531) (xy 117.466879 -419.016938)
			(xy 117.474999 -419.072114) (xy 117.475508 -419.1) (xy 117.474999 -419.127886) (xy 117.466879 -419.183062)
			(xy 117.450811 -419.236469) (xy 117.427139 -419.286966) (xy 117.396366 -419.333479) (xy 117.359149 -419.375016)
			(xy 117.316281 -419.410691) (xy 117.268675 -419.439745) (xy 117.217346 -419.461557) (xy 117.163389 -419.475663)
			(xy 117.107952 -419.481763) (xy 117.052218 -419.479726) (xy 116.997375 -419.469596) (xy 116.944591 -419.451589)
			(xy 116.894991 -419.426088) (xy 116.849633 -419.393637) (xy 116.809484 -419.354928) (xy 116.775398 -419.310785)
			(xy 116.748102 -419.26215) (xy 116.728179 -419.210059) (xy 116.716053 -419.155622) (xy 116.711982 -419.1)
			(xy 115.706537 -419.1) (xy 115.697957 -419.128519) (xy 115.674285 -419.179016) (xy 115.643512 -419.225529)
			(xy 115.606295 -419.267066) (xy 115.563427 -419.302741) (xy 115.515821 -419.331795) (xy 115.464492 -419.353607)
			(xy 115.410535 -419.367713) (xy 115.355098 -419.373813) (xy 115.299364 -419.371776) (xy 115.244521 -419.361646)
			(xy 115.191737 -419.343639) (xy 115.142137 -419.318138) (xy 115.096779 -419.285687) (xy 115.05663 -419.246978)
			(xy 115.022544 -419.202835) (xy 114.995248 -419.1542) (xy 114.975325 -419.102109) (xy 114.963199 -419.047672)
			(xy 114.959128 -418.99205) (xy 110.224574 -418.99205) (xy 110.232997 -419.036204) (xy 110.237011 -419.1)
			(xy 110.232997 -419.163796) (xy 110.221019 -419.226586) (xy 110.201266 -419.287379) (xy 110.174049 -419.345218)
			(xy 110.139798 -419.399189) (xy 110.099053 -419.448442) (xy 110.052456 -419.492199) (xy 110.000741 -419.529772)
			(xy 109.944726 -419.560566) (xy 109.885293 -419.584098) (xy 109.823379 -419.599995) (xy 109.759961 -419.608006)
			(xy 109.728 -419.608508) (xy 109.695294 -419.60799) (xy 109.63042 -419.599613) (xy 109.567157 -419.582985)
			(xy 109.506549 -419.558379) (xy 109.449598 -419.526203) (xy 109.397244 -419.486988) (xy 109.350352 -419.441382)
			(xy 109.309697 -419.390138) (xy 109.29239 -419.362382) (xy 109.28604 -419.351968) (xy 109.265466 -419.339014)
			(xy 109.15904 -419.330124) (xy 109.136434 -419.339268) (xy 109.128306 -419.348666) (xy 109.110094 -419.369115)
			(xy 109.068837 -419.405119) (xy 109.022854 -419.434852) (xy 108.973092 -419.457704) (xy 108.920574 -419.473205)
			(xy 108.866379 -419.481035) (xy 108.839 -419.481508) (xy 108.811749 -419.481022) (xy 108.757801 -419.473266)
			(xy 108.705506 -419.457911) (xy 108.655929 -419.435269) (xy 108.610079 -419.405803) (xy 108.568888 -419.370112)
			(xy 108.533197 -419.328921) (xy 108.503731 -419.283071) (xy 108.481089 -419.233494) (xy 108.465734 -419.181199)
			(xy 108.457978 -419.127251) (xy 102.15118 -419.127251) (xy 102.15118 -419.989) (xy 104.138982 -419.989)
			(xy 104.143053 -419.933378) (xy 104.155179 -419.878941) (xy 104.175102 -419.82685) (xy 104.202398 -419.778215)
			(xy 104.236484 -419.734072) (xy 104.276633 -419.695363) (xy 104.321991 -419.662912) (xy 104.371591 -419.637411)
			(xy 104.424375 -419.619404) (xy 104.479218 -419.609274) (xy 104.534952 -419.607237) (xy 104.590389 -419.613337)
			(xy 104.644346 -419.627443) (xy 104.695675 -419.649255) (xy 104.743281 -419.678309) (xy 104.786149 -419.713984)
			(xy 104.823366 -419.755521) (xy 104.830935 -419.766961) (xy 107.060994 -419.766961) (xy 107.060994 -419.703039)
			(xy 107.069005 -419.639621) (xy 107.084902 -419.577707) (xy 107.108434 -419.518274) (xy 107.139228 -419.462259)
			(xy 107.176801 -419.410544) (xy 107.220558 -419.363947) (xy 107.269811 -419.323202) (xy 107.323782 -419.288951)
			(xy 107.381621 -419.261734) (xy 107.442414 -419.241981) (xy 107.505204 -419.230003) (xy 107.569 -419.22599)
			(xy 107.632796 -419.230003) (xy 107.695586 -419.241981) (xy 107.756379 -419.261734) (xy 107.814218 -419.288951)
			(xy 107.868189 -419.323202) (xy 107.917442 -419.363947) (xy 107.961199 -419.410544) (xy 107.998772 -419.462259)
			(xy 108.029566 -419.518274) (xy 108.053098 -419.577707) (xy 108.068995 -419.639621) (xy 108.077006 -419.703039)
			(xy 108.077508 -419.735) (xy 108.077006 -419.766961) (xy 108.068995 -419.830379) (xy 108.053098 -419.892293)
			(xy 108.029566 -419.951726) (xy 107.998772 -420.007741) (xy 107.961199 -420.059456) (xy 107.917442 -420.106053)
			(xy 107.868189 -420.146798) (xy 107.814218 -420.181049) (xy 107.756379 -420.208266) (xy 107.695586 -420.228019)
			(xy 107.632796 -420.239997) (xy 107.569 -420.244011) (xy 107.505204 -420.239997) (xy 107.442414 -420.228019)
			(xy 107.381621 -420.208266) (xy 107.323782 -420.181049) (xy 107.269811 -420.146798) (xy 107.220558 -420.106053)
			(xy 107.176801 -420.059456) (xy 107.139228 -420.007741) (xy 107.108434 -419.951726) (xy 107.084902 -419.892293)
			(xy 107.069005 -419.830379) (xy 107.060994 -419.766961) (xy 104.830935 -419.766961) (xy 104.854139 -419.802034)
			(xy 104.877811 -419.852531) (xy 104.893879 -419.905938) (xy 104.901999 -419.961114) (xy 104.902508 -419.989)
			(xy 104.901999 -420.016886) (xy 104.893879 -420.072062) (xy 104.877811 -420.125469) (xy 104.854139 -420.175966)
			(xy 104.823366 -420.222479) (xy 104.786149 -420.264016) (xy 104.743281 -420.299691) (xy 104.695675 -420.328745)
			(xy 104.644346 -420.350557) (xy 104.590389 -420.364663) (xy 104.534952 -420.370763) (xy 104.479218 -420.368726)
			(xy 104.424375 -420.358596) (xy 104.371591 -420.340589) (xy 104.321991 -420.315088) (xy 104.276633 -420.282637)
			(xy 104.236484 -420.243928) (xy 104.202398 -420.199785) (xy 104.175102 -420.15115) (xy 104.155179 -420.099059)
			(xy 104.143053 -420.044622) (xy 104.138982 -419.989) (xy 102.15118 -419.989) (xy 102.15118 -421.173656)
			(xy 97.149412 -421.173656) (xy 97.149412 -419.423596) (xy 97.148109 -419.4126) (xy 97.137445 -419.393222)
			(xy 97.128838 -419.386258) (xy 97.052638 -419.330632) (xy 97.028762 -419.326822) (xy 97.017078 -419.330632)
			(xy 96.979579 -419.341785) (xy 96.90227 -419.353771) (xy 96.863154 -419.354508) (xy 96.8629 -419.354508)
			(xy 96.829446 -419.353978) (xy 96.763116 -419.345206) (xy 96.698508 -419.327815) (xy 96.636738 -419.302105)
			(xy 96.578871 -419.268519) (xy 96.525906 -419.227636) (xy 96.478758 -419.180163) (xy 96.438241 -419.126919)
			(xy 96.405053 -419.068823) (xy 96.391984 -419.038024) (xy 96.387158 -419.026086) (xy 96.3676 -419.00983)
			(xy 96.272096 -418.990526) (xy 96.259608 -418.988722) (xy 96.235494 -418.996048) (xy 96.226122 -419.004496)
			(xy 95.52559 -419.705028) (xy 95.518738 -419.712424) (xy 95.511 -419.731023) (xy 95.510604 -419.741096)
			(xy 95.510604 -423.457116) (xy 97.53549 -423.457116) (xy 97.539561 -423.401494) (xy 97.551687 -423.347057)
			(xy 97.57161 -423.294966) (xy 97.598906 -423.246331) (xy 97.632992 -423.202188) (xy 97.673141 -423.163479)
			(xy 97.718499 -423.131028) (xy 97.768099 -423.105527) (xy 97.820883 -423.08752) (xy 97.875726 -423.07739)
			(xy 97.93146 -423.075353) (xy 97.986897 -423.081453) (xy 98.040854 -423.095559) (xy 98.092183 -423.117371)
			(xy 98.139789 -423.146425) (xy 98.182657 -423.1821) (xy 98.219874 -423.223637) (xy 98.250647 -423.27015)
			(xy 98.274319 -423.320647) (xy 98.290387 -423.374054) (xy 98.298507 -423.42923) (xy 98.298858 -423.44848)
			(xy 98.633278 -423.44848) (xy 98.637349 -423.392858) (xy 98.649475 -423.338421) (xy 98.669398 -423.28633)
			(xy 98.696694 -423.237695) (xy 98.73078 -423.193552) (xy 98.770929 -423.154843) (xy 98.816287 -423.122392)
			(xy 98.865887 -423.096891) (xy 98.918671 -423.078884) (xy 98.973514 -423.068754) (xy 99.029248 -423.066717)
			(xy 99.084685 -423.072817) (xy 99.138642 -423.086923) (xy 99.189971 -423.108735) (xy 99.237577 -423.137789)
			(xy 99.280445 -423.173464) (xy 99.317662 -423.215001) (xy 99.348435 -423.261514) (xy 99.372107 -423.312011)
			(xy 99.388175 -423.365418) (xy 99.396295 -423.420594) (xy 99.396804 -423.44848) (xy 99.903278 -423.44848)
			(xy 99.907349 -423.392858) (xy 99.919475 -423.338421) (xy 99.939398 -423.28633) (xy 99.966694 -423.237695)
			(xy 100.00078 -423.193552) (xy 100.040929 -423.154843) (xy 100.086287 -423.122392) (xy 100.135887 -423.096891)
			(xy 100.188671 -423.078884) (xy 100.243514 -423.068754) (xy 100.299248 -423.066717) (xy 100.354685 -423.072817)
			(xy 100.408642 -423.086923) (xy 100.459971 -423.108735) (xy 100.507577 -423.137789) (xy 100.550445 -423.173464)
			(xy 100.587662 -423.215001) (xy 100.618435 -423.261514) (xy 100.642107 -423.312011) (xy 100.658175 -423.365418)
			(xy 100.666295 -423.420594) (xy 100.666804 -423.44848) (xy 101.173278 -423.44848) (xy 101.177349 -423.392858)
			(xy 101.189475 -423.338421) (xy 101.209398 -423.28633) (xy 101.236694 -423.237695) (xy 101.27078 -423.193552)
			(xy 101.310929 -423.154843) (xy 101.356287 -423.122392) (xy 101.405887 -423.096891) (xy 101.458671 -423.078884)
			(xy 101.513514 -423.068754) (xy 101.569248 -423.066717) (xy 101.624685 -423.072817) (xy 101.678642 -423.086923)
			(xy 101.729971 -423.108735) (xy 101.776754 -423.137287) (xy 102.06837 -423.137287) (xy 102.06837 -423.073365)
			(xy 102.076381 -423.009947) (xy 102.092278 -422.948033) (xy 102.11581 -422.8886) (xy 102.146604 -422.832585)
			(xy 102.184177 -422.78087) (xy 102.227934 -422.734273) (xy 102.277187 -422.693528) (xy 102.331158 -422.659277)
			(xy 102.388997 -422.63206) (xy 102.44979 -422.612307) (xy 102.51258 -422.600329) (xy 102.576376 -422.596316)
			(xy 102.640172 -422.600329) (xy 102.702962 -422.612307) (xy 102.763755 -422.63206) (xy 102.821594 -422.659277)
			(xy 102.875565 -422.693528) (xy 102.924818 -422.734273) (xy 102.968575 -422.78087) (xy 103.006148 -422.832585)
			(xy 103.036942 -422.8886) (xy 103.060474 -422.948033) (xy 103.076371 -423.009947) (xy 103.084382 -423.073365)
			(xy 103.084884 -423.105326) (xy 103.084382 -423.137287) (xy 103.076371 -423.200705) (xy 103.060474 -423.262619)
			(xy 103.036942 -423.322052) (xy 103.006148 -423.378067) (xy 102.972522 -423.42435) (xy 103.503982 -423.42435)
			(xy 103.508053 -423.368728) (xy 103.520179 -423.314291) (xy 103.540102 -423.2622) (xy 103.567398 -423.213565)
			(xy 103.601484 -423.169422) (xy 103.641633 -423.130713) (xy 103.686991 -423.098262) (xy 103.736591 -423.072761)
			(xy 103.789375 -423.054754) (xy 103.844218 -423.044624) (xy 103.899952 -423.042587) (xy 103.955389 -423.048687)
			(xy 104.009346 -423.062793) (xy 104.060675 -423.084605) (xy 104.108281 -423.113659) (xy 104.151149 -423.149334)
			(xy 104.188366 -423.190871) (xy 104.219139 -423.237384) (xy 104.242811 -423.287881) (xy 104.258879 -423.341288)
			(xy 104.266999 -423.396464) (xy 104.267508 -423.42435) (xy 104.266999 -423.452236) (xy 104.258879 -423.507412)
			(xy 104.242811 -423.560819) (xy 104.219139 -423.611316) (xy 104.188366 -423.657829) (xy 104.1586 -423.69105)
			(xy 106.297982 -423.69105) (xy 106.302053 -423.635428) (xy 106.314179 -423.580991) (xy 106.334102 -423.5289)
			(xy 106.361398 -423.480265) (xy 106.395484 -423.436122) (xy 106.435633 -423.397413) (xy 106.480991 -423.364962)
			(xy 106.530591 -423.339461) (xy 106.583375 -423.321454) (xy 106.638218 -423.311324) (xy 106.693952 -423.309287)
			(xy 106.749389 -423.315387) (xy 106.803346 -423.329493) (xy 106.854675 -423.351305) (xy 106.902281 -423.380359)
			(xy 106.945149 -423.416034) (xy 106.982366 -423.457571) (xy 107.013139 -423.504084) (xy 107.036811 -423.554581)
			(xy 107.052879 -423.607988) (xy 107.060999 -423.663164) (xy 107.061508 -423.69105) (xy 107.060999 -423.718936)
			(xy 107.052879 -423.774112) (xy 107.036811 -423.827519) (xy 107.013139 -423.878016) (xy 106.982366 -423.924529)
			(xy 106.945149 -423.966066) (xy 106.902281 -424.001741) (xy 106.854675 -424.030795) (xy 106.803346 -424.052607)
			(xy 106.749389 -424.066713) (xy 106.693952 -424.072813) (xy 106.638218 -424.070776) (xy 106.583375 -424.060646)
			(xy 106.530591 -424.042639) (xy 106.480991 -424.017138) (xy 106.435633 -423.984687) (xy 106.395484 -423.945978)
			(xy 106.361398 -423.901835) (xy 106.334102 -423.8532) (xy 106.314179 -423.801109) (xy 106.302053 -423.746672)
			(xy 106.297982 -423.69105) (xy 104.1586 -423.69105) (xy 104.151149 -423.699366) (xy 104.108281 -423.735041)
			(xy 104.060675 -423.764095) (xy 104.009346 -423.785907) (xy 103.955389 -423.800013) (xy 103.899952 -423.806113)
			(xy 103.844218 -423.804076) (xy 103.789375 -423.793946) (xy 103.736591 -423.775939) (xy 103.686991 -423.750438)
			(xy 103.641633 -423.717987) (xy 103.601484 -423.679278) (xy 103.567398 -423.635135) (xy 103.540102 -423.5865)
			(xy 103.520179 -423.534409) (xy 103.508053 -423.479972) (xy 103.503982 -423.42435) (xy 102.972522 -423.42435)
			(xy 102.968575 -423.429782) (xy 102.924818 -423.476379) (xy 102.875565 -423.517124) (xy 102.821594 -423.551375)
			(xy 102.763755 -423.578592) (xy 102.702962 -423.598345) (xy 102.640172 -423.610323) (xy 102.576376 -423.614337)
			(xy 102.51258 -423.610323) (xy 102.44979 -423.598345) (xy 102.388997 -423.578592) (xy 102.331158 -423.551375)
			(xy 102.277187 -423.517124) (xy 102.227934 -423.476379) (xy 102.184177 -423.429782) (xy 102.146604 -423.378067)
			(xy 102.11581 -423.322052) (xy 102.092278 -423.262619) (xy 102.076381 -423.200705) (xy 102.06837 -423.137287)
			(xy 101.776754 -423.137287) (xy 101.777577 -423.137789) (xy 101.820445 -423.173464) (xy 101.857662 -423.215001)
			(xy 101.888435 -423.261514) (xy 101.912107 -423.312011) (xy 101.928175 -423.365418) (xy 101.936295 -423.420594)
			(xy 101.936804 -423.44848) (xy 101.936295 -423.476366) (xy 101.928175 -423.531542) (xy 101.912107 -423.584949)
			(xy 101.888435 -423.635446) (xy 101.857662 -423.681959) (xy 101.820445 -423.723496) (xy 101.777577 -423.759171)
			(xy 101.729971 -423.788225) (xy 101.678642 -423.810037) (xy 101.624685 -423.824143) (xy 101.569248 -423.830243)
			(xy 101.513514 -423.828206) (xy 101.458671 -423.818076) (xy 101.405887 -423.800069) (xy 101.356287 -423.774568)
			(xy 101.310929 -423.742117) (xy 101.27078 -423.703408) (xy 101.236694 -423.659265) (xy 101.209398 -423.61063)
			(xy 101.189475 -423.558539) (xy 101.177349 -423.504102) (xy 101.173278 -423.44848) (xy 100.666804 -423.44848)
			(xy 100.666295 -423.476366) (xy 100.658175 -423.531542) (xy 100.642107 -423.584949) (xy 100.618435 -423.635446)
			(xy 100.587662 -423.681959) (xy 100.550445 -423.723496) (xy 100.507577 -423.759171) (xy 100.459971 -423.788225)
			(xy 100.408642 -423.810037) (xy 100.354685 -423.824143) (xy 100.299248 -423.830243) (xy 100.243514 -423.828206)
			(xy 100.188671 -423.818076) (xy 100.135887 -423.800069) (xy 100.086287 -423.774568) (xy 100.040929 -423.742117)
			(xy 100.00078 -423.703408) (xy 99.966694 -423.659265) (xy 99.939398 -423.61063) (xy 99.919475 -423.558539)
			(xy 99.907349 -423.504102) (xy 99.903278 -423.44848) (xy 99.396804 -423.44848) (xy 99.396295 -423.476366)
			(xy 99.388175 -423.531542) (xy 99.372107 -423.584949) (xy 99.348435 -423.635446) (xy 99.317662 -423.681959)
			(xy 99.280445 -423.723496) (xy 99.237577 -423.759171) (xy 99.189971 -423.788225) (xy 99.138642 -423.810037)
			(xy 99.084685 -423.824143) (xy 99.029248 -423.830243) (xy 98.973514 -423.828206) (xy 98.918671 -423.818076)
			(xy 98.865887 -423.800069) (xy 98.816287 -423.774568) (xy 98.770929 -423.742117) (xy 98.73078 -423.703408)
			(xy 98.696694 -423.659265) (xy 98.669398 -423.61063) (xy 98.649475 -423.558539) (xy 98.637349 -423.504102)
			(xy 98.633278 -423.44848) (xy 98.298858 -423.44848) (xy 98.299016 -423.457116) (xy 98.298507 -423.485002)
			(xy 98.290387 -423.540178) (xy 98.274319 -423.593585) (xy 98.250647 -423.644082) (xy 98.219874 -423.690595)
			(xy 98.182657 -423.732132) (xy 98.139789 -423.767807) (xy 98.092183 -423.796861) (xy 98.040854 -423.818673)
			(xy 97.986897 -423.832779) (xy 97.93146 -423.838879) (xy 97.875726 -423.836842) (xy 97.820883 -423.826712)
			(xy 97.768099 -423.808705) (xy 97.718499 -423.783204) (xy 97.673141 -423.750753) (xy 97.632992 -423.712044)
			(xy 97.598906 -423.667901) (xy 97.57161 -423.619266) (xy 97.551687 -423.567175) (xy 97.539561 -423.512738)
			(xy 97.53549 -423.457116) (xy 95.510604 -423.457116) (xy 95.510604 -424.191684) (xy 96.111312 -424.191684)
			(xy 96.115383 -424.136062) (xy 96.127509 -424.081625) (xy 96.147432 -424.029534) (xy 96.174728 -423.980899)
			(xy 96.208814 -423.936756) (xy 96.248963 -423.898047) (xy 96.294321 -423.865596) (xy 96.343921 -423.840095)
			(xy 96.396705 -423.822088) (xy 96.451548 -423.811958) (xy 96.507282 -423.809921) (xy 96.562719 -423.816021)
			(xy 96.616676 -423.830127) (xy 96.668005 -423.851939) (xy 96.715611 -423.880993) (xy 96.758479 -423.916668)
			(xy 96.795696 -423.958205) (xy 96.826469 -424.004718) (xy 96.850141 -424.055215) (xy 96.866209 -424.108622)
			(xy 96.874329 -424.163798) (xy 96.874838 -424.191684) (xy 96.874329 -424.21957) (xy 96.866209 -424.274746)
			(xy 96.850141 -424.328153) (xy 96.826469 -424.37865) (xy 96.795696 -424.425163) (xy 96.758479 -424.4667)
			(xy 96.715611 -424.502375) (xy 96.668005 -424.531429) (xy 96.616676 -424.553241) (xy 96.562719 -424.567347)
			(xy 96.507282 -424.573447) (xy 96.451548 -424.57141) (xy 96.396705 -424.56128) (xy 96.343921 -424.543273)
			(xy 96.294321 -424.517772) (xy 96.248963 -424.485321) (xy 96.208814 -424.446612) (xy 96.174728 -424.402469)
			(xy 96.147432 -424.353834) (xy 96.127509 -424.301743) (xy 96.115383 -424.247306) (xy 96.111312 -424.191684)
			(xy 95.510604 -424.191684) (xy 95.510604 -425.481961) (xy 102.361994 -425.481961) (xy 102.361994 -425.418039)
			(xy 102.370005 -425.354621) (xy 102.385902 -425.292707) (xy 102.409434 -425.233274) (xy 102.440228 -425.177259)
			(xy 102.477801 -425.125544) (xy 102.521558 -425.078947) (xy 102.570811 -425.038202) (xy 102.624782 -425.003951)
			(xy 102.682621 -424.976734) (xy 102.743414 -424.956981) (xy 102.806204 -424.945003) (xy 102.87 -424.94099)
			(xy 102.933796 -424.945003) (xy 102.996586 -424.956981) (xy 103.057379 -424.976734) (xy 103.115218 -425.003951)
			(xy 103.169189 -425.038202) (xy 103.218442 -425.078947) (xy 103.262199 -425.125544) (xy 103.299772 -425.177259)
			(xy 103.330566 -425.233274) (xy 103.354098 -425.292707) (xy 103.369995 -425.354621) (xy 103.378006 -425.418039)
			(xy 103.378508 -425.45) (xy 103.378006 -425.481961) (xy 105.409994 -425.481961) (xy 105.409994 -425.418039)
			(xy 105.418005 -425.354621) (xy 105.433902 -425.292707) (xy 105.457434 -425.233274) (xy 105.488228 -425.177259)
			(xy 105.525801 -425.125544) (xy 105.569558 -425.078947) (xy 105.618811 -425.038202) (xy 105.672782 -425.003951)
			(xy 105.730621 -424.976734) (xy 105.791414 -424.956981) (xy 105.854204 -424.945003) (xy 105.918 -424.94099)
			(xy 105.981796 -424.945003) (xy 106.044586 -424.956981) (xy 106.105379 -424.976734) (xy 106.163218 -425.003951)
			(xy 106.217189 -425.038202) (xy 106.266442 -425.078947) (xy 106.310199 -425.125544) (xy 106.347772 -425.177259)
			(xy 106.378566 -425.233274) (xy 106.402098 -425.292707) (xy 106.417995 -425.354621) (xy 106.426006 -425.418039)
			(xy 106.426508 -425.45) (xy 106.426006 -425.481961) (xy 106.417995 -425.545379) (xy 106.402098 -425.607293)
			(xy 106.378566 -425.666726) (xy 106.347772 -425.722741) (xy 106.310199 -425.774456) (xy 106.266442 -425.821053)
			(xy 106.217189 -425.861798) (xy 106.163218 -425.896049) (xy 106.105379 -425.923266) (xy 106.044586 -425.943019)
			(xy 105.981796 -425.954997) (xy 105.918 -425.959011) (xy 105.854204 -425.954997) (xy 105.791414 -425.943019)
			(xy 105.730621 -425.923266) (xy 105.672782 -425.896049) (xy 105.618811 -425.861798) (xy 105.569558 -425.821053)
			(xy 105.525801 -425.774456) (xy 105.488228 -425.722741) (xy 105.457434 -425.666726) (xy 105.433902 -425.607293)
			(xy 105.418005 -425.545379) (xy 105.409994 -425.481961) (xy 103.378006 -425.481961) (xy 103.369995 -425.545379)
			(xy 103.354098 -425.607293) (xy 103.330566 -425.666726) (xy 103.299772 -425.722741) (xy 103.262199 -425.774456)
			(xy 103.218442 -425.821053) (xy 103.169189 -425.861798) (xy 103.115218 -425.896049) (xy 103.057379 -425.923266)
			(xy 102.996586 -425.943019) (xy 102.933796 -425.954997) (xy 102.87 -425.959011) (xy 102.806204 -425.954997)
			(xy 102.743414 -425.943019) (xy 102.682621 -425.923266) (xy 102.624782 -425.896049) (xy 102.570811 -425.861798)
			(xy 102.521558 -425.821053) (xy 102.477801 -425.774456) (xy 102.440228 -425.722741) (xy 102.409434 -425.666726)
			(xy 102.385902 -425.607293) (xy 102.370005 -425.545379) (xy 102.361994 -425.481961) (xy 95.510604 -425.481961)
			(xy 95.510604 -426.19295) (xy 101.641146 -426.19295) (xy 101.645217 -426.137328) (xy 101.657343 -426.082891)
			(xy 101.677266 -426.0308) (xy 101.704562 -425.982165) (xy 101.738648 -425.938022) (xy 101.778797 -425.899313)
			(xy 101.824155 -425.866862) (xy 101.873755 -425.841361) (xy 101.926539 -425.823354) (xy 101.981382 -425.813224)
			(xy 102.037116 -425.811187) (xy 102.092553 -425.817287) (xy 102.14651 -425.831393) (xy 102.197839 -425.853205)
			(xy 102.245445 -425.882259) (xy 102.288313 -425.917934) (xy 102.32553 -425.959471) (xy 102.356303 -426.005984)
			(xy 102.379975 -426.056481) (xy 102.396043 -426.109888) (xy 102.404163 -426.165064) (xy 102.404672 -426.19295)
			(xy 102.404163 -426.220836) (xy 102.396043 -426.276012) (xy 102.379975 -426.329419) (xy 102.356303 -426.379916)
			(xy 102.32553 -426.426429) (xy 102.288313 -426.467966) (xy 102.245445 -426.503641) (xy 102.197839 -426.532695)
			(xy 102.14651 -426.554507) (xy 102.092553 -426.568613) (xy 102.037116 -426.574713) (xy 101.981382 -426.572676)
			(xy 101.926539 -426.562546) (xy 101.873755 -426.544539) (xy 101.824155 -426.519038) (xy 101.778797 -426.486587)
			(xy 101.738648 -426.447878) (xy 101.704562 -426.403735) (xy 101.677266 -426.3551) (xy 101.657343 -426.303009)
			(xy 101.645217 -426.248572) (xy 101.641146 -426.19295) (xy 95.510604 -426.19295) (xy 95.510604 -427.641469)
			(xy 97.299266 -427.641469) (xy 97.299266 -427.577547) (xy 97.307277 -427.514129) (xy 97.323174 -427.452215)
			(xy 97.346706 -427.392782) (xy 97.3775 -427.336767) (xy 97.415073 -427.285052) (xy 97.45883 -427.238455)
			(xy 97.508083 -427.19771) (xy 97.562054 -427.163459) (xy 97.619893 -427.136242) (xy 97.680686 -427.116489)
			(xy 97.743476 -427.104511) (xy 97.807272 -427.100498) (xy 97.871068 -427.104511) (xy 97.933858 -427.116489)
			(xy 97.994651 -427.136242) (xy 98.05249 -427.163459) (xy 98.106461 -427.19771) (xy 98.155714 -427.238455)
			(xy 98.199471 -427.285052) (xy 98.237044 -427.336767) (xy 98.267838 -427.392782) (xy 98.29137 -427.452215)
			(xy 98.307267 -427.514129) (xy 98.315278 -427.577547) (xy 98.315772 -427.609) (xy 102.487982 -427.609)
			(xy 102.492053 -427.553378) (xy 102.504179 -427.498941) (xy 102.524102 -427.44685) (xy 102.551398 -427.398215)
			(xy 102.585484 -427.354072) (xy 102.625633 -427.315363) (xy 102.670991 -427.282912) (xy 102.720591 -427.257411)
			(xy 102.773375 -427.239404) (xy 102.828218 -427.229274) (xy 102.883952 -427.227237) (xy 102.939389 -427.233337)
			(xy 102.993346 -427.247443) (xy 103.044675 -427.269255) (xy 103.092281 -427.298309) (xy 103.135149 -427.333984)
			(xy 103.172366 -427.375521) (xy 103.203139 -427.422034) (xy 103.226811 -427.472531) (xy 103.242879 -427.525938)
			(xy 103.250999 -427.581114) (xy 103.251508 -427.609) (xy 105.535982 -427.609) (xy 105.540053 -427.553378)
			(xy 105.552179 -427.498941) (xy 105.572102 -427.44685) (xy 105.599398 -427.398215) (xy 105.633484 -427.354072)
			(xy 105.673633 -427.315363) (xy 105.718991 -427.282912) (xy 105.768591 -427.257411) (xy 105.821375 -427.239404)
			(xy 105.876218 -427.229274) (xy 105.931952 -427.227237) (xy 105.987389 -427.233337) (xy 106.041346 -427.247443)
			(xy 106.092675 -427.269255) (xy 106.140281 -427.298309) (xy 106.183149 -427.333984) (xy 106.220366 -427.375521)
			(xy 106.251139 -427.422034) (xy 106.274811 -427.472531) (xy 106.290879 -427.525938) (xy 106.298999 -427.581114)
			(xy 106.299508 -427.609) (xy 106.298999 -427.636886) (xy 106.290879 -427.692062) (xy 106.274811 -427.745469)
			(xy 106.251139 -427.795966) (xy 106.220366 -427.842479) (xy 106.183149 -427.884016) (xy 106.140281 -427.919691)
			(xy 106.092675 -427.948745) (xy 106.041346 -427.970557) (xy 105.987389 -427.984663) (xy 105.931952 -427.990763)
			(xy 105.876218 -427.988726) (xy 105.821375 -427.978596) (xy 105.768591 -427.960589) (xy 105.718991 -427.935088)
			(xy 105.673633 -427.902637) (xy 105.633484 -427.863928) (xy 105.599398 -427.819785) (xy 105.572102 -427.77115)
			(xy 105.552179 -427.719059) (xy 105.540053 -427.664622) (xy 105.535982 -427.609) (xy 103.251508 -427.609)
			(xy 103.250999 -427.636886) (xy 103.242879 -427.692062) (xy 103.226811 -427.745469) (xy 103.203139 -427.795966)
			(xy 103.172366 -427.842479) (xy 103.135149 -427.884016) (xy 103.092281 -427.919691) (xy 103.044675 -427.948745)
			(xy 102.993346 -427.970557) (xy 102.939389 -427.984663) (xy 102.883952 -427.990763) (xy 102.828218 -427.988726)
			(xy 102.773375 -427.978596) (xy 102.720591 -427.960589) (xy 102.670991 -427.935088) (xy 102.625633 -427.902637)
			(xy 102.585484 -427.863928) (xy 102.551398 -427.819785) (xy 102.524102 -427.77115) (xy 102.504179 -427.719059)
			(xy 102.492053 -427.664622) (xy 102.487982 -427.609) (xy 98.315772 -427.609) (xy 98.31578 -427.609508)
			(xy 98.315278 -427.641469) (xy 98.307267 -427.704887) (xy 98.29137 -427.766801) (xy 98.267838 -427.826234)
			(xy 98.237044 -427.882249) (xy 98.199471 -427.933964) (xy 98.155714 -427.980561) (xy 98.106461 -428.021306)
			(xy 98.05249 -428.055557) (xy 97.994651 -428.082774) (xy 97.933858 -428.102527) (xy 97.871068 -428.114505)
			(xy 97.807272 -428.118519) (xy 97.743476 -428.114505) (xy 97.680686 -428.102527) (xy 97.619893 -428.082774)
			(xy 97.562054 -428.055557) (xy 97.508083 -428.021306) (xy 97.45883 -427.980561) (xy 97.415073 -427.933964)
			(xy 97.3775 -427.882249) (xy 97.346706 -427.826234) (xy 97.323174 -427.766801) (xy 97.307277 -427.704887)
			(xy 97.299266 -427.641469) (xy 95.510604 -427.641469) (xy 95.510604 -428.654972) (xy 95.511019 -428.664997)
			(xy 95.518684 -428.683523) (xy 95.532857 -428.697703) (xy 95.551379 -428.705377) (xy 95.561404 -428.705772)
			(xy 106.384852 -428.705772) (xy 106.394917 -428.705339) (xy 106.413506 -428.697608) (xy 106.42092 -428.690786)
			(xy 107.228894 -427.882812) (xy 107.235743 -427.875414) (xy 107.243483 -427.856817) (xy 107.24388 -427.846744)
			(xy 107.24388 -421.929052) (xy 107.244311 -421.918985) (xy 107.252036 -421.900391) (xy 107.258866 -421.892984)
			(xy 108.998004 -420.153846) (xy 109.005401 -420.146995) (xy 109.023999 -420.139255) (xy 109.034072 -420.13886)
			(xy 114.486182 -420.13886) (xy 114.496244 -420.1393) (xy 114.514821 -420.147042) (xy 114.52225 -420.153846)
			(xy 114.865404 -420.497) (xy 117.092982 -420.497) (xy 117.097053 -420.441378) (xy 117.109179 -420.386941)
			(xy 117.129102 -420.33485) (xy 117.156398 -420.286215) (xy 117.190484 -420.242072) (xy 117.230633 -420.203363)
			(xy 117.275991 -420.170912) (xy 117.325591 -420.145411) (xy 117.378375 -420.127404) (xy 117.433218 -420.117274)
			(xy 117.488952 -420.115237) (xy 117.544389 -420.121337) (xy 117.598346 -420.135443) (xy 117.649675 -420.157255)
			(xy 117.697281 -420.186309) (xy 117.740149 -420.221984) (xy 117.777366 -420.263521) (xy 117.808139 -420.310034)
			(xy 117.831811 -420.360531) (xy 117.847879 -420.413938) (xy 117.855999 -420.469114) (xy 117.856508 -420.497)
			(xy 117.855999 -420.524886) (xy 117.847879 -420.580062) (xy 117.831811 -420.633469) (xy 117.808139 -420.683966)
			(xy 117.777366 -420.730479) (xy 117.740149 -420.772016) (xy 117.697281 -420.807691) (xy 117.649675 -420.836745)
			(xy 117.598346 -420.858557) (xy 117.544389 -420.872663) (xy 117.488952 -420.878763) (xy 117.433218 -420.876726)
			(xy 117.378375 -420.866596) (xy 117.325591 -420.848589) (xy 117.275991 -420.823088) (xy 117.230633 -420.790637)
			(xy 117.190484 -420.751928) (xy 117.156398 -420.707785) (xy 117.129102 -420.65915) (xy 117.109179 -420.607059)
			(xy 117.097053 -420.552622) (xy 117.092982 -420.497) (xy 114.865404 -420.497) (xy 115.786365 -421.417961)
			(xy 116.204994 -421.417961) (xy 116.204994 -421.354039) (xy 116.213005 -421.290621) (xy 116.228902 -421.228707)
			(xy 116.252434 -421.169274) (xy 116.283228 -421.113259) (xy 116.320801 -421.061544) (xy 116.364558 -421.014947)
			(xy 116.413811 -420.974202) (xy 116.467782 -420.939951) (xy 116.525621 -420.912734) (xy 116.586414 -420.892981)
			(xy 116.649204 -420.881003) (xy 116.713 -420.87699) (xy 116.776796 -420.881003) (xy 116.839586 -420.892981)
			(xy 116.900379 -420.912734) (xy 116.958218 -420.939951) (xy 117.012189 -420.974202) (xy 117.061442 -421.014947)
			(xy 117.105199 -421.061544) (xy 117.142772 -421.113259) (xy 117.173566 -421.169274) (xy 117.197098 -421.228707)
			(xy 117.212995 -421.290621) (xy 117.221006 -421.354039) (xy 117.221508 -421.386) (xy 117.221006 -421.417961)
			(xy 117.212995 -421.481379) (xy 117.197098 -421.543293) (xy 117.173566 -421.602726) (xy 117.142772 -421.658741)
			(xy 117.105199 -421.710456) (xy 117.061442 -421.757053) (xy 117.012189 -421.797798) (xy 116.958218 -421.832049)
			(xy 116.900379 -421.859266) (xy 116.839586 -421.879019) (xy 116.776796 -421.890997) (xy 116.713 -421.895011)
			(xy 116.649204 -421.890997) (xy 116.586414 -421.879019) (xy 116.525621 -421.859266) (xy 116.467782 -421.832049)
			(xy 116.413811 -421.797798) (xy 116.364558 -421.757053) (xy 116.320801 -421.710456) (xy 116.283228 -421.658741)
			(xy 116.252434 -421.602726) (xy 116.228902 -421.543293) (xy 116.213005 -421.481379) (xy 116.204994 -421.417961)
			(xy 115.786365 -421.417961) (xy 116.354606 -421.986202) (xy 116.361452 -421.993601) (xy 116.369184 -422.012199)
			(xy 116.369592 -422.02227) (xy 116.369592 -422.887902) (xy 117.992906 -422.887902) (xy 117.9934 -422.861031)
			(xy 118.000955 -422.807822) (xy 118.015901 -422.7562) (xy 118.037943 -422.707186) (xy 118.066645 -422.661749)
			(xy 118.101438 -422.62079) (xy 118.141634 -422.585118) (xy 118.186438 -422.555439) (xy 118.234964 -422.53234)
			(xy 118.28625 -422.516279) (xy 118.312692 -422.511474) (xy 118.323106 -422.509696) (xy 118.340886 -422.498266)
			(xy 118.393972 -422.419272) (xy 118.397782 -422.398698) (xy 118.395242 -422.388538) (xy 118.389275 -422.360534)
			(xy 118.382907 -422.30363) (xy 118.382542 -422.275) (xy 118.382968 -422.24346) (xy 118.39077 -422.180863)
			(xy 118.406255 -422.119713) (xy 118.429185 -422.060947) (xy 118.459208 -422.005469) (xy 118.495862 -421.95413)
			(xy 118.538584 -421.907719) (xy 118.58672 -421.86695) (xy 118.639528 -421.832447) (xy 118.696199 -421.80474)
			(xy 118.755861 -421.784257) (xy 118.817599 -421.77131) (xy 118.880464 -421.766099) (xy 118.943491 -421.768703)
			(xy 119.005712 -421.779084) (xy 119.066171 -421.797081) (xy 119.123939 -421.822417) (xy 119.178131 -421.854705)
			(xy 119.227912 -421.893448) (xy 119.272519 -421.938051) (xy 119.311267 -421.987828) (xy 119.34356 -422.042016)
			(xy 119.368902 -422.099782) (xy 119.386905 -422.16024) (xy 119.397292 -422.222459) (xy 119.399902 -422.285486)
			(xy 119.398124 -422.306961) (xy 119.760994 -422.306961) (xy 119.760994 -422.243039) (xy 119.769005 -422.179621)
			(xy 119.784902 -422.117707) (xy 119.808434 -422.058274) (xy 119.839228 -422.002259) (xy 119.876801 -421.950544)
			(xy 119.920558 -421.903947) (xy 119.969811 -421.863202) (xy 120.023782 -421.828951) (xy 120.081621 -421.801734)
			(xy 120.142414 -421.781981) (xy 120.205204 -421.770003) (xy 120.269 -421.76599) (xy 120.332796 -421.770003)
			(xy 120.395586 -421.781981) (xy 120.456379 -421.801734) (xy 120.514218 -421.828951) (xy 120.568189 -421.863202)
			(xy 120.617442 -421.903947) (xy 120.661199 -421.950544) (xy 120.698772 -422.002259) (xy 120.729566 -422.058274)
			(xy 120.753098 -422.117707) (xy 120.768995 -422.179621) (xy 120.777006 -422.243039) (xy 120.777508 -422.275)
			(xy 120.777006 -422.306961) (xy 120.768995 -422.370379) (xy 120.753098 -422.432293) (xy 120.729566 -422.491726)
			(xy 120.698772 -422.547741) (xy 120.661199 -422.599456) (xy 120.617442 -422.646053) (xy 120.568189 -422.686798)
			(xy 120.514218 -422.721049) (xy 120.456379 -422.748266) (xy 120.395586 -422.768019) (xy 120.332796 -422.779997)
			(xy 120.269 -422.784011) (xy 120.205204 -422.779997) (xy 120.142414 -422.768019) (xy 120.081621 -422.748266)
			(xy 120.023782 -422.721049) (xy 119.969811 -422.686798) (xy 119.920558 -422.646053) (xy 119.876801 -422.599456)
			(xy 119.839228 -422.547741) (xy 119.808434 -422.491726) (xy 119.784902 -422.432293) (xy 119.769005 -422.370379)
			(xy 119.760994 -422.306961) (xy 119.398124 -422.306961) (xy 119.394698 -422.348352) (xy 119.381757 -422.410091)
			(xy 119.361279 -422.469755) (xy 119.333578 -422.526428) (xy 119.29908 -422.57924) (xy 119.258315 -422.627379)
			(xy 119.211909 -422.670107) (xy 119.160574 -422.706766) (xy 119.105098 -422.736794) (xy 119.046335 -422.75973)
			(xy 118.985186 -422.775221) (xy 118.92259 -422.783029) (xy 118.89105 -422.783508) (xy 118.86311 -422.782746)
			(xy 118.852442 -422.782238) (xy 118.832884 -422.78935) (xy 118.76405 -422.855136) (xy 118.755922 -422.87444)
			(xy 118.755922 -422.887902) (xy 118.755436 -422.915153) (xy 118.74768 -422.969101) (xy 118.732325 -423.021396)
			(xy 118.709683 -423.070973) (xy 118.680217 -423.116823) (xy 118.644526 -423.158014) (xy 118.603335 -423.193705)
			(xy 118.557485 -423.223171) (xy 118.507908 -423.245813) (xy 118.455613 -423.261168) (xy 118.401665 -423.268924)
			(xy 118.347163 -423.268924) (xy 118.293215 -423.261168) (xy 118.24092 -423.245813) (xy 118.191343 -423.223171)
			(xy 118.145493 -423.193705) (xy 118.104302 -423.158014) (xy 118.068611 -423.116823) (xy 118.039145 -423.070973)
			(xy 118.016503 -423.021396) (xy 118.001148 -422.969101) (xy 117.993392 -422.915153) (xy 117.992906 -422.887902)
			(xy 116.369592 -422.887902) (xy 116.369592 -423.322961) (xy 121.284994 -423.322961) (xy 121.284994 -423.259039)
			(xy 121.293005 -423.195621) (xy 121.308902 -423.133707) (xy 121.332434 -423.074274) (xy 121.363228 -423.018259)
			(xy 121.400801 -422.966544) (xy 121.444558 -422.919947) (xy 121.493811 -422.879202) (xy 121.547782 -422.844951)
			(xy 121.605621 -422.817734) (xy 121.666414 -422.797981) (xy 121.729204 -422.786003) (xy 121.793 -422.78199)
			(xy 121.856796 -422.786003) (xy 121.919586 -422.797981) (xy 121.980379 -422.817734) (xy 122.038218 -422.844951)
			(xy 122.092189 -422.879202) (xy 122.141442 -422.919947) (xy 122.185199 -422.966544) (xy 122.222772 -423.018259)
			(xy 122.253566 -423.074274) (xy 122.277098 -423.133707) (xy 122.292995 -423.195621) (xy 122.301006 -423.259039)
			(xy 122.301508 -423.291) (xy 122.301006 -423.322961) (xy 122.292995 -423.386379) (xy 122.277098 -423.448293)
			(xy 122.253566 -423.507726) (xy 122.222772 -423.563741) (xy 122.185199 -423.615456) (xy 122.141442 -423.662053)
			(xy 122.092189 -423.702798) (xy 122.038218 -423.737049) (xy 121.980379 -423.764266) (xy 121.919586 -423.784019)
			(xy 121.856796 -423.795997) (xy 121.793 -423.800011) (xy 121.729204 -423.795997) (xy 121.666414 -423.784019)
			(xy 121.605621 -423.764266) (xy 121.547782 -423.737049) (xy 121.493811 -423.702798) (xy 121.444558 -423.662053)
			(xy 121.400801 -423.615456) (xy 121.363228 -423.563741) (xy 121.332434 -423.507726) (xy 121.308902 -423.448293)
			(xy 121.293005 -423.386379) (xy 121.284994 -423.322961) (xy 116.369592 -423.322961) (xy 116.369592 -425.21505)
			(xy 119.124982 -425.21505) (xy 119.129053 -425.159428) (xy 119.141179 -425.104991) (xy 119.161102 -425.0529)
			(xy 119.188398 -425.004265) (xy 119.222484 -424.960122) (xy 119.262633 -424.921413) (xy 119.307991 -424.888962)
			(xy 119.357591 -424.863461) (xy 119.410375 -424.845454) (xy 119.465218 -424.835324) (xy 119.520952 -424.833287)
			(xy 119.576389 -424.839387) (xy 119.630346 -424.853493) (xy 119.681675 -424.875305) (xy 119.729281 -424.904359)
			(xy 119.772149 -424.940034) (xy 119.809366 -424.981571) (xy 119.840139 -425.028084) (xy 119.863811 -425.078581)
			(xy 119.879879 -425.131988) (xy 119.887999 -425.187164) (xy 119.888508 -425.21505) (xy 119.887999 -425.242936)
			(xy 119.879879 -425.298112) (xy 119.863811 -425.351519) (xy 119.840139 -425.402016) (xy 119.809366 -425.448529)
			(xy 119.772149 -425.490066) (xy 119.729281 -425.525741) (xy 119.681675 -425.554795) (xy 119.630346 -425.576607)
			(xy 119.576389 -425.590713) (xy 119.520952 -425.596813) (xy 119.465218 -425.594776) (xy 119.410375 -425.584646)
			(xy 119.357591 -425.566639) (xy 119.307991 -425.541138) (xy 119.262633 -425.508687) (xy 119.222484 -425.469978)
			(xy 119.188398 -425.425835) (xy 119.161102 -425.3772) (xy 119.141179 -425.325109) (xy 119.129053 -425.270672)
			(xy 119.124982 -425.21505) (xy 116.369592 -425.21505) (xy 116.369592 -426.72) (xy 120.521982 -426.72)
			(xy 120.526053 -426.664378) (xy 120.538179 -426.609941) (xy 120.558102 -426.55785) (xy 120.585398 -426.509215)
			(xy 120.619484 -426.465072) (xy 120.659633 -426.426363) (xy 120.704991 -426.393912) (xy 120.754591 -426.368411)
			(xy 120.807375 -426.350404) (xy 120.862218 -426.340274) (xy 120.917952 -426.338237) (xy 120.973389 -426.344337)
			(xy 121.027346 -426.358443) (xy 121.078675 -426.380255) (xy 121.126281 -426.409309) (xy 121.169149 -426.444984)
			(xy 121.206366 -426.486521) (xy 121.237139 -426.533034) (xy 121.260811 -426.583531) (xy 121.276879 -426.636938)
			(xy 121.284999 -426.692114) (xy 121.285508 -426.72) (xy 121.284999 -426.747886) (xy 121.276879 -426.803062)
			(xy 121.260811 -426.856469) (xy 121.237139 -426.906966) (xy 121.206366 -426.953479) (xy 121.169149 -426.995016)
			(xy 121.126281 -427.030691) (xy 121.078675 -427.059745) (xy 121.027346 -427.081557) (xy 120.973389 -427.095663)
			(xy 120.917952 -427.101763) (xy 120.862218 -427.099726) (xy 120.807375 -427.089596) (xy 120.754591 -427.071589)
			(xy 120.704991 -427.046088) (xy 120.659633 -427.013637) (xy 120.619484 -426.974928) (xy 120.585398 -426.930785)
			(xy 120.558102 -426.88215) (xy 120.538179 -426.830059) (xy 120.526053 -426.775622) (xy 120.521982 -426.72)
			(xy 116.369592 -426.72) (xy 116.369592 -429.006) (xy 119.076468 -429.006) (xy 119.080539 -428.950378)
			(xy 119.092665 -428.895941) (xy 119.112588 -428.84385) (xy 119.139884 -428.795215) (xy 119.17397 -428.751072)
			(xy 119.214119 -428.712363) (xy 119.259477 -428.679912) (xy 119.309077 -428.654411) (xy 119.361861 -428.636404)
			(xy 119.416704 -428.626274) (xy 119.472438 -428.624237) (xy 119.527875 -428.630337) (xy 119.581832 -428.644443)
			(xy 119.633161 -428.666255) (xy 119.680767 -428.695309) (xy 119.723635 -428.730984) (xy 119.760852 -428.772521)
			(xy 119.791625 -428.819034) (xy 119.815297 -428.869531) (xy 119.831365 -428.922938) (xy 119.839485 -428.978114)
			(xy 119.839994 -429.006) (xy 119.839485 -429.033886) (xy 119.831365 -429.089062) (xy 119.815297 -429.142469)
			(xy 119.791625 -429.192966) (xy 119.760852 -429.239479) (xy 119.723635 -429.281016) (xy 119.680767 -429.316691)
			(xy 119.633161 -429.345745) (xy 119.581832 -429.367557) (xy 119.527875 -429.381663) (xy 119.472438 -429.387763)
			(xy 119.416704 -429.385726) (xy 119.361861 -429.375596) (xy 119.309077 -429.357589) (xy 119.259477 -429.332088)
			(xy 119.214119 -429.299637) (xy 119.17397 -429.260928) (xy 119.139884 -429.216785) (xy 119.112588 -429.16815)
			(xy 119.092665 -429.116059) (xy 119.080539 -429.061622) (xy 119.076468 -429.006) (xy 116.369592 -429.006)
			(xy 116.369592 -432.054) (xy 117.092982 -432.054) (xy 117.097053 -431.998378) (xy 117.109179 -431.943941)
			(xy 117.129102 -431.89185) (xy 117.156398 -431.843215) (xy 117.190484 -431.799072) (xy 117.230633 -431.760363)
			(xy 117.275991 -431.727912) (xy 117.325591 -431.702411) (xy 117.378375 -431.684404) (xy 117.433218 -431.674274)
			(xy 117.488952 -431.672237) (xy 117.544389 -431.678337) (xy 117.598346 -431.692443) (xy 117.649675 -431.714255)
			(xy 117.697281 -431.743309) (xy 117.740149 -431.778984) (xy 117.777366 -431.820521) (xy 117.808139 -431.867034)
			(xy 117.831811 -431.917531) (xy 117.847879 -431.970938) (xy 117.855999 -432.026114) (xy 117.856508 -432.054)
			(xy 121.156982 -432.054) (xy 121.161053 -431.998378) (xy 121.173179 -431.943941) (xy 121.193102 -431.89185)
			(xy 121.220398 -431.843215) (xy 121.254484 -431.799072) (xy 121.294633 -431.760363) (xy 121.339991 -431.727912)
			(xy 121.389591 -431.702411) (xy 121.442375 -431.684404) (xy 121.497218 -431.674274) (xy 121.552952 -431.672237)
			(xy 121.608389 -431.678337) (xy 121.662346 -431.692443) (xy 121.713675 -431.714255) (xy 121.761281 -431.743309)
			(xy 121.804149 -431.778984) (xy 121.841366 -431.820521) (xy 121.872139 -431.867034) (xy 121.895811 -431.917531)
			(xy 121.911879 -431.970938) (xy 121.919999 -432.026114) (xy 121.920508 -432.054) (xy 121.919999 -432.081886)
			(xy 121.911879 -432.137062) (xy 121.895811 -432.190469) (xy 121.872139 -432.240966) (xy 121.841366 -432.287479)
			(xy 121.804149 -432.329016) (xy 121.761281 -432.364691) (xy 121.713675 -432.393745) (xy 121.662346 -432.415557)
			(xy 121.608389 -432.429663) (xy 121.552952 -432.435763) (xy 121.497218 -432.433726) (xy 121.442375 -432.423596)
			(xy 121.389591 -432.405589) (xy 121.339991 -432.380088) (xy 121.294633 -432.347637) (xy 121.254484 -432.308928)
			(xy 121.220398 -432.264785) (xy 121.193102 -432.21615) (xy 121.173179 -432.164059) (xy 121.161053 -432.109622)
			(xy 121.156982 -432.054) (xy 117.856508 -432.054) (xy 117.855999 -432.081886) (xy 117.847879 -432.137062)
			(xy 117.831811 -432.190469) (xy 117.808139 -432.240966) (xy 117.777366 -432.287479) (xy 117.740149 -432.329016)
			(xy 117.697281 -432.364691) (xy 117.649675 -432.393745) (xy 117.598346 -432.415557) (xy 117.544389 -432.429663)
			(xy 117.488952 -432.435763) (xy 117.433218 -432.433726) (xy 117.378375 -432.423596) (xy 117.325591 -432.405589)
			(xy 117.275991 -432.380088) (xy 117.230633 -432.347637) (xy 117.190484 -432.308928) (xy 117.156398 -432.264785)
			(xy 117.129102 -432.21615) (xy 117.109179 -432.164059) (xy 117.097053 -432.109622) (xy 117.092982 -432.054)
			(xy 116.369592 -432.054) (xy 116.369592 -432.847961) (xy 118.510044 -432.847961) (xy 118.510044 -432.784039)
			(xy 118.518055 -432.720621) (xy 118.533952 -432.658707) (xy 118.557484 -432.599274) (xy 118.588278 -432.543259)
			(xy 118.625851 -432.491544) (xy 118.669608 -432.444947) (xy 118.718861 -432.404202) (xy 118.772832 -432.369951)
			(xy 118.830671 -432.342734) (xy 118.891464 -432.322981) (xy 118.954254 -432.311003) (xy 119.01805 -432.30699)
			(xy 119.081846 -432.311003) (xy 119.144636 -432.322981) (xy 119.205429 -432.342734) (xy 119.263268 -432.369951)
			(xy 119.317239 -432.404202) (xy 119.366492 -432.444947) (xy 119.410249 -432.491544) (xy 119.447822 -432.543259)
			(xy 119.478616 -432.599274) (xy 119.502148 -432.658707) (xy 119.518045 -432.720621) (xy 119.526056 -432.784039)
			(xy 119.526558 -432.816) (xy 119.526056 -432.847961) (xy 119.887994 -432.847961) (xy 119.887994 -432.784039)
			(xy 119.896005 -432.720621) (xy 119.911902 -432.658707) (xy 119.935434 -432.599274) (xy 119.966228 -432.543259)
			(xy 120.003801 -432.491544) (xy 120.047558 -432.444947) (xy 120.096811 -432.404202) (xy 120.150782 -432.369951)
			(xy 120.208621 -432.342734) (xy 120.269414 -432.322981) (xy 120.332204 -432.311003) (xy 120.396 -432.30699)
			(xy 120.459796 -432.311003) (xy 120.522586 -432.322981) (xy 120.583379 -432.342734) (xy 120.641218 -432.369951)
			(xy 120.695189 -432.404202) (xy 120.744442 -432.444947) (xy 120.788199 -432.491544) (xy 120.825772 -432.543259)
			(xy 120.856566 -432.599274) (xy 120.880098 -432.658707) (xy 120.895995 -432.720621) (xy 120.904006 -432.784039)
			(xy 120.904508 -432.816) (xy 120.904006 -432.847961) (xy 120.895995 -432.911379) (xy 120.880098 -432.973293)
			(xy 120.856566 -433.032726) (xy 120.825772 -433.088741) (xy 120.788199 -433.140456) (xy 120.744442 -433.187053)
			(xy 120.695189 -433.227798) (xy 120.641218 -433.262049) (xy 120.583379 -433.289266) (xy 120.522586 -433.309019)
			(xy 120.459796 -433.320997) (xy 120.396 -433.325011) (xy 120.332204 -433.320997) (xy 120.269414 -433.309019)
			(xy 120.208621 -433.289266) (xy 120.150782 -433.262049) (xy 120.096811 -433.227798) (xy 120.047558 -433.187053)
			(xy 120.003801 -433.140456) (xy 119.966228 -433.088741) (xy 119.935434 -433.032726) (xy 119.911902 -432.973293)
			(xy 119.896005 -432.911379) (xy 119.887994 -432.847961) (xy 119.526056 -432.847961) (xy 119.518045 -432.911379)
			(xy 119.502148 -432.973293) (xy 119.478616 -433.032726) (xy 119.447822 -433.088741) (xy 119.410249 -433.140456)
			(xy 119.366492 -433.187053) (xy 119.317239 -433.227798) (xy 119.263268 -433.262049) (xy 119.205429 -433.289266)
			(xy 119.144636 -433.309019) (xy 119.081846 -433.320997) (xy 119.01805 -433.325011) (xy 118.954254 -433.320997)
			(xy 118.891464 -433.309019) (xy 118.830671 -433.289266) (xy 118.772832 -433.262049) (xy 118.718861 -433.227798)
			(xy 118.669608 -433.187053) (xy 118.625851 -433.140456) (xy 118.588278 -433.088741) (xy 118.557484 -433.032726)
			(xy 118.533952 -432.973293) (xy 118.518055 -432.911379) (xy 118.510044 -432.847961) (xy 116.369592 -432.847961)
			(xy 116.369592 -433.959) (xy 118.616982 -433.959) (xy 118.621053 -433.903378) (xy 118.633179 -433.848941)
			(xy 118.653102 -433.79685) (xy 118.680398 -433.748215) (xy 118.714484 -433.704072) (xy 118.754633 -433.665363)
			(xy 118.799991 -433.632912) (xy 118.849591 -433.607411) (xy 118.902375 -433.589404) (xy 118.957218 -433.579274)
			(xy 119.012952 -433.577237) (xy 119.068389 -433.583337) (xy 119.122346 -433.597443) (xy 119.173675 -433.619255)
			(xy 119.221281 -433.648309) (xy 119.264149 -433.683984) (xy 119.301366 -433.725521) (xy 119.332139 -433.772034)
			(xy 119.355811 -433.822531) (xy 119.371879 -433.875938) (xy 119.379999 -433.931114) (xy 119.380508 -433.959)
			(xy 119.379999 -433.986886) (xy 119.371879 -434.042062) (xy 119.355811 -434.095469) (xy 119.332139 -434.145966)
			(xy 119.301366 -434.192479) (xy 119.264149 -434.234016) (xy 119.221281 -434.269691) (xy 119.173675 -434.298745)
			(xy 119.122346 -434.320557) (xy 119.068389 -434.334663) (xy 119.012952 -434.340763) (xy 118.957218 -434.338726)
			(xy 118.902375 -434.328596) (xy 118.849591 -434.310589) (xy 118.799991 -434.285088) (xy 118.754633 -434.252637)
			(xy 118.714484 -434.213928) (xy 118.680398 -434.169785) (xy 118.653102 -434.12115) (xy 118.633179 -434.069059)
			(xy 118.621053 -434.014622) (xy 118.616982 -433.959) (xy 116.369592 -433.959) (xy 116.369592 -435.483)
			(xy 121.156982 -435.483) (xy 121.161053 -435.427378) (xy 121.173179 -435.372941) (xy 121.193102 -435.32085)
			(xy 121.220398 -435.272215) (xy 121.254484 -435.228072) (xy 121.294633 -435.189363) (xy 121.339991 -435.156912)
			(xy 121.389591 -435.131411) (xy 121.442375 -435.113404) (xy 121.497218 -435.103274) (xy 121.552952 -435.101237)
			(xy 121.608389 -435.107337) (xy 121.662346 -435.121443) (xy 121.713675 -435.143255) (xy 121.761281 -435.172309)
			(xy 121.804149 -435.207984) (xy 121.841366 -435.249521) (xy 121.872139 -435.296034) (xy 121.895811 -435.346531)
			(xy 121.911879 -435.399938) (xy 121.919999 -435.455114) (xy 121.920508 -435.483) (xy 121.919999 -435.510886)
			(xy 121.911879 -435.566062) (xy 121.895811 -435.619469) (xy 121.872139 -435.669966) (xy 121.841366 -435.716479)
			(xy 121.804149 -435.758016) (xy 121.761281 -435.793691) (xy 121.713675 -435.822745) (xy 121.662346 -435.844557)
			(xy 121.608389 -435.858663) (xy 121.552952 -435.864763) (xy 121.497218 -435.862726) (xy 121.442375 -435.852596)
			(xy 121.389591 -435.834589) (xy 121.339991 -435.809088) (xy 121.294633 -435.776637) (xy 121.254484 -435.737928)
			(xy 121.220398 -435.693785) (xy 121.193102 -435.64515) (xy 121.173179 -435.593059) (xy 121.161053 -435.538622)
			(xy 121.156982 -435.483) (xy 116.369592 -435.483) (xy 116.369592 -438.128447) (xy 118.34271 -438.128447)
			(xy 118.34271 -438.073953) (xy 118.350465 -438.020013) (xy 118.365817 -437.967725) (xy 118.388454 -437.918155)
			(xy 118.417914 -437.87231) (xy 118.453599 -437.831124) (xy 118.494781 -437.795436) (xy 118.540623 -437.765971)
			(xy 118.590192 -437.74333) (xy 118.642478 -437.727973) (xy 118.696417 -437.720213) (xy 118.723664 -437.719724)
			(xy 118.751821 -437.720264) (xy 118.80752 -437.728557) (xy 118.861393 -437.744954) (xy 118.912269 -437.769096)
			(xy 118.95904 -437.80046) (xy 118.980204 -437.819038) (xy 118.987316 -437.825388) (xy 119.005096 -437.832246)
			(xy 119.092218 -437.832246) (xy 119.109998 -437.825388) (xy 119.11711 -437.819038) (xy 119.138299 -437.80049)
			(xy 119.18507 -437.769133) (xy 119.235939 -437.744987) (xy 119.289804 -437.728575) (xy 119.345496 -437.720252)
			(xy 119.37365 -437.719724) (xy 119.400907 -437.72012) (xy 119.454868 -437.727871) (xy 119.507177 -437.743224)
			(xy 119.556767 -437.765866) (xy 119.602631 -437.795335) (xy 119.643833 -437.831032) (xy 119.679535 -437.872229)
			(xy 119.70901 -437.918089) (xy 119.731658 -437.967676) (xy 119.747018 -438.019983) (xy 119.754777 -438.073943)
			(xy 119.754777 -438.128457) (xy 119.747018 -438.182417) (xy 119.731658 -438.234724) (xy 119.70901 -438.284311)
			(xy 119.679535 -438.330171) (xy 119.643833 -438.371368) (xy 119.602631 -438.407065) (xy 119.556767 -438.436534)
			(xy 119.507177 -438.459176) (xy 119.454868 -438.474529) (xy 119.400908 -438.48228) (xy 119.37365 -438.48274)
			(xy 119.345491 -438.48226) (xy 119.289789 -438.473954) (xy 119.235914 -438.457544) (xy 119.185039 -438.433388)
			(xy 119.138272 -438.40201) (xy 119.11711 -438.383426) (xy 119.109998 -438.377076) (xy 119.092218 -438.370218)
			(xy 119.005096 -438.370218) (xy 118.987316 -438.377076) (xy 118.980204 -438.383426) (xy 118.959044 -438.402008)
			(xy 118.912266 -438.433361) (xy 118.861389 -438.457502) (xy 118.807517 -438.473906) (xy 118.75182 -438.482217)
			(xy 118.723664 -438.48274) (xy 118.696417 -438.482187) (xy 118.642478 -438.474427) (xy 118.590192 -438.45907)
			(xy 118.540623 -438.436429) (xy 118.494781 -438.406964) (xy 118.453599 -438.371276) (xy 118.417914 -438.33009)
			(xy 118.388454 -438.284245) (xy 118.365817 -438.234675) (xy 118.350465 -438.182387) (xy 118.34271 -438.128447)
			(xy 116.369592 -438.128447) (xy 116.369592 -439.020966) (xy 116.370027 -439.031031) (xy 116.377757 -439.049619)
			(xy 116.384578 -439.057034) (xy 116.906401 -439.578857) (xy 117.661327 -439.578857) (xy 117.661327 -439.524343)
			(xy 117.669086 -439.470385) (xy 117.684444 -439.418081) (xy 117.707091 -439.368495) (xy 117.736565 -439.322636)
			(xy 117.772265 -439.28144) (xy 117.813465 -439.245743) (xy 117.859326 -439.216274) (xy 117.908915 -439.193632)
			(xy 117.961221 -439.178278) (xy 118.015179 -439.170524) (xy 118.042436 -439.170064) (xy 118.070661 -439.170618)
			(xy 118.126495 -439.178935) (xy 118.180496 -439.195384) (xy 118.231487 -439.219604) (xy 118.278355 -439.251068)
			(xy 118.320079 -439.289091) (xy 118.35575 -439.332842) (xy 118.38459 -439.38137) (xy 118.39575 -439.4073)
			(xy 118.401489 -439.420274) (xy 118.419011 -439.442576) (xy 118.441996 -439.459192) (xy 118.468666 -439.468839)
			(xy 118.496962 -439.470772) (xy 118.524696 -439.464841) (xy 118.549727 -439.451505) (xy 118.570119 -439.431794)
			(xy 118.577614 -439.419746) (xy 118.594732 -439.391182) (xy 118.635281 -439.338359) (xy 118.682376 -439.291278)
			(xy 118.735212 -439.250745) (xy 118.792885 -439.217453) (xy 118.854409 -439.191971) (xy 118.918732 -439.174735)
			(xy 118.984754 -439.166039) (xy 119.01805 -439.165492) (xy 119.050014 -439.16597) (xy 119.11344 -439.173977)
			(xy 119.175361 -439.18987) (xy 119.234802 -439.213399) (xy 119.290826 -439.244193) (xy 119.342547 -439.281767)
			(xy 119.389152 -439.325526) (xy 119.429903 -439.374783) (xy 119.46416 -439.428758) (xy 119.491381 -439.486602)
			(xy 119.511137 -439.547401) (xy 119.523117 -439.610197) (xy 119.527132 -439.674) (xy 119.523117 -439.737803)
			(xy 119.511137 -439.800599) (xy 119.491381 -439.861398) (xy 119.46416 -439.919242) (xy 119.429903 -439.973217)
			(xy 119.389152 -440.022474) (xy 119.342547 -440.066233) (xy 119.290826 -440.103807) (xy 119.234802 -440.134601)
			(xy 119.175361 -440.15813) (xy 119.11344 -440.174023) (xy 119.050014 -440.18203) (xy 119.01805 -440.182508)
			(xy 118.985074 -440.181988) (xy 118.919677 -440.173444) (xy 118.855933 -440.156519) (xy 118.794912 -440.131496)
			(xy 118.737637 -440.098795) (xy 118.68507 -440.058966) (xy 118.638092 -440.012675) (xy 118.597491 -439.960701)
			(xy 118.563949 -439.903915) (xy 118.538028 -439.84327) (xy 118.528592 -439.811668) (xy 118.524249 -439.798136)
			(xy 118.50937 -439.773944) (xy 118.488401 -439.754787) (xy 118.462966 -439.742149) (xy 118.435033 -439.737007)
			(xy 118.406765 -439.739761) (xy 118.380349 -439.750196) (xy 118.357831 -439.767506) (xy 118.349014 -439.778648)
			(xy 118.330883 -439.802162) (xy 118.288577 -439.84382) (xy 118.240328 -439.878423) (xy 118.187302 -439.905134)
			(xy 118.130779 -439.92331) (xy 118.072123 -439.932512) (xy 118.042436 -439.93308) (xy 118.015179 -439.932676)
			(xy 117.961221 -439.924922) (xy 117.908915 -439.909568) (xy 117.859326 -439.886926) (xy 117.813465 -439.857457)
			(xy 117.772265 -439.82176) (xy 117.736565 -439.780564) (xy 117.707091 -439.734705) (xy 117.684444 -439.685119)
			(xy 117.669086 -439.632815) (xy 117.661327 -439.578857) (xy 116.906401 -439.578857) (xy 117.284246 -439.956702)
			(xy 117.314472 -439.962544) (xy 117.328696 -439.956702) (xy 117.351976 -439.947485) (xy 117.40033 -439.934493)
			(xy 117.449966 -439.927921) (xy 117.475 -439.927492) (xy 117.502251 -439.927978) (xy 117.556199 -439.935734)
			(xy 117.608494 -439.951089) (xy 117.658071 -439.973731) (xy 117.703921 -440.003197) (xy 117.745112 -440.038888)
			(xy 117.780803 -440.080079) (xy 117.810269 -440.125929) (xy 117.832911 -440.175506) (xy 117.848266 -440.227801)
			(xy 117.856022 -440.281749) (xy 117.856508 -440.309) (xy 117.856117 -440.334037) (xy 117.849562 -440.383681)
			(xy 117.836552 -440.432036) (xy 117.827298 -440.455304) (xy 117.821456 -440.469528) (xy 117.827298 -440.499754)
			(xy 118.031006 -440.703462) (xy 118.038403 -440.710312) (xy 118.057001 -440.71805) (xy 118.067074 -440.718448)
		)
		(stroke
			(width 0)
			(type solid)
		)
		(fill yes)
		(layer "In6.Cu")
		(net "P3V3_AUX")
	)
	(gr_poly
		(pts
			(xy 124.640594 -251.2822) (xy 124.647198 -251.2695) (xy 124.687838 -251.19203) (xy 124.691803 -251.183643)
			(xy 124.694035 -251.165242) (xy 124.689547 -251.147257) (xy 124.684536 -251.139452) (xy 124.684282 -251.139198)
			(xy 124.671348 -251.119857) (xy 124.650856 -251.078088) (xy 124.636924 -251.033697) (xy 124.629873 -250.987709)
			(xy 124.629418 -250.964446) (xy 124.62988 -250.94062) (xy 124.637289 -250.893548) (xy 124.651921 -250.848199)
			(xy 124.673418 -250.805672) (xy 124.701261 -250.767) (xy 124.734772 -250.733123) (xy 124.773138 -250.704862)
			(xy 124.815428 -250.682903) (xy 124.860616 -250.667779) (xy 124.907605 -250.659857) (xy 124.931424 -250.659138)
			(xy 124.934726 -250.659138) (xy 124.959563 -250.659627) (xy 125.008581 -250.667674) (xy 125.05565 -250.683552)
			(xy 125.099526 -250.706841) (xy 125.139053 -250.736926) (xy 125.156468 -250.754642) (xy 125.156722 -250.754642)
			(xy 125.164014 -250.761755) (xy 125.182622 -250.77) (xy 125.19279 -250.770644) (xy 125.26391 -250.771406)
			(xy 125.273918 -250.771021) (xy 125.292488 -250.763575) (xy 125.299978 -250.756928) (xy 125.300232 -250.756674)
			(xy 125.634242 -250.422664) (xy 125.641483 -250.415958) (xy 125.659688 -250.408379) (xy 125.669548 -250.407932)
			(xy 125.969014 -250.407932) (xy 125.981455 -250.407242) (xy 126.003415 -250.395525) (xy 126.010924 -250.38558)
			(xy 126.064264 -250.306586) (xy 126.066804 -250.281694) (xy 126.061978 -250.269756) (xy 126.051538 -250.242402)
			(xy 126.040157 -250.184978) (xy 126.039372 -250.15571) (xy 126.039372 -250.150122) (xy 126.040159 -250.126353)
			(xy 126.048192 -250.079481) (xy 126.063396 -250.034421) (xy 126.085403 -249.992265) (xy 126.113682 -249.954031)
			(xy 126.147548 -249.920645) (xy 126.186182 -249.892915) (xy 126.228648 -249.871511) (xy 126.27392 -249.856952)
			(xy 126.320902 -249.84959) (xy 126.34468 -249.849132) (xy 126.369526 -249.849624) (xy 126.418563 -249.857672)
			(xy 126.465653 -249.873545) (xy 126.509557 -249.896822) (xy 126.549119 -249.926894) (xy 126.583297 -249.962966)
			(xy 126.597664 -249.983244) (xy 126.597664 -249.983498) (xy 126.597918 -249.984006) (xy 126.604739 -249.992947)
			(xy 126.624118 -250.004303) (xy 126.635256 -250.00585) (xy 126.646432 -250.006866) (xy 126.667514 -249.999246)
			(xy 126.692914 -249.973846) (xy 126.693422 -249.973338) (xy 126.700006 -249.965958) (xy 126.707458 -249.947658)
			(xy 126.7079 -249.937778) (xy 126.7079 -249.649234) (xy 126.69266 -249.624596) (xy 126.679706 -249.618246)
			(xy 126.658141 -249.607085) (xy 126.618544 -249.578983) (xy 126.583893 -249.544968) (xy 126.555062 -249.505899)
			(xy 126.532778 -249.462759) (xy 126.517601 -249.416636) (xy 126.509914 -249.368693) (xy 126.509912 -249.320137)
			(xy 126.517594 -249.272193) (xy 126.532766 -249.226069) (xy 126.555046 -249.182927) (xy 126.583874 -249.143855)
			(xy 126.618521 -249.109837) (xy 126.658115 -249.081731) (xy 126.679706 -249.070622) (xy 126.69266 -249.064272)
			(xy 126.7079 -249.039634) (xy 126.7079 -248.029222) (xy 126.69266 -248.004584) (xy 126.679706 -247.998234)
			(xy 126.658142 -247.987073) (xy 126.618547 -247.958971) (xy 126.583898 -247.924957) (xy 126.555069 -247.885888)
			(xy 126.532785 -247.84275) (xy 126.51761 -247.796628) (xy 126.509925 -247.748687) (xy 126.509923 -247.700133)
			(xy 126.517605 -247.65219) (xy 126.532778 -247.606068) (xy 126.555058 -247.562928) (xy 126.583885 -247.523858)
			(xy 126.618532 -247.489842) (xy 126.658125 -247.461737) (xy 126.679706 -247.45061) (xy 126.69266 -247.44426)
			(xy 126.7079 -247.419622) (xy 126.7079 -247.226074) (xy 126.707485 -247.216426) (xy 126.700328 -247.198506)
			(xy 126.687015 -247.184539) (xy 126.678436 -247.1801) (xy 126.595124 -247.141238) (xy 126.58622 -247.137506)
			(xy 126.566964 -247.136351) (xy 126.548662 -247.142446) (xy 126.541022 -247.14835) (xy 126.540768 -247.14835)
			(xy 126.520009 -247.165056) (xy 126.473865 -247.191698) (xy 126.423795 -247.209921) (xy 126.371321 -247.219171)
			(xy 126.34468 -247.219724) (xy 126.336806 -247.219724) (xy 126.31322 -247.218681) (xy 126.266775 -247.210223)
			(xy 126.222185 -247.194715) (xy 126.180516 -247.172526) (xy 126.142759 -247.144187) (xy 126.109816 -247.110371)
			(xy 126.082473 -247.071887) (xy 126.061381 -247.029651) (xy 126.047044 -246.984672) (xy 126.039803 -246.938021)
			(xy 126.039372 -246.914416) (xy 126.039841 -246.890423) (xy 126.047345 -246.843029) (xy 126.062171 -246.797391)
			(xy 126.083954 -246.754635) (xy 126.112156 -246.715812) (xy 126.146085 -246.68188) (xy 126.184904 -246.653672)
			(xy 126.227658 -246.631885) (xy 126.273294 -246.617054) (xy 126.320687 -246.609544) (xy 126.34468 -246.609108)
			(xy 126.344934 -246.609108) (xy 126.371542 -246.609699) (xy 126.423947 -246.618961) (xy 126.473949 -246.63718)
			(xy 126.520028 -246.663803) (xy 126.540768 -246.680482) (xy 126.541022 -246.680482) (xy 126.548685 -246.686329)
			(xy 126.566979 -246.692358) (xy 126.586208 -246.691259) (xy 126.595124 -246.687594) (xy 126.678436 -246.648732)
			(xy 126.686988 -246.644279) (xy 126.700221 -246.630274) (xy 126.707387 -246.612389) (xy 126.7079 -246.602758)
			(xy 126.7079 -246.40921) (xy 126.69266 -246.384572) (xy 126.679706 -246.378222) (xy 126.658143 -246.367061)
			(xy 126.61855 -246.338959) (xy 126.583903 -246.304946) (xy 126.555075 -246.265878) (xy 126.532793 -246.222741)
			(xy 126.517619 -246.176621) (xy 126.509935 -246.128681) (xy 126.509934 -246.080128) (xy 126.517617 -246.032188)
			(xy 126.53279 -245.986067) (xy 126.55507 -245.942929) (xy 126.583897 -245.903861) (xy 126.618543 -245.869846)
			(xy 126.658135 -245.841744) (xy 126.679706 -245.830598) (xy 126.69266 -245.824248) (xy 126.7079 -245.79961)
			(xy 126.7079 -244.789198) (xy 126.69266 -244.76456) (xy 126.679706 -244.75821) (xy 126.658144 -244.747049)
			(xy 126.618552 -244.718948) (xy 126.583907 -244.684935) (xy 126.555081 -244.645868) (xy 126.532801 -244.602732)
			(xy 126.517628 -244.556613) (xy 126.509945 -244.508674) (xy 126.509945 -244.460124) (xy 126.517629 -244.412185)
			(xy 126.532802 -244.366067) (xy 126.555082 -244.32293) (xy 126.583908 -244.283864) (xy 126.618554 -244.249851)
			(xy 126.658145 -244.22175) (xy 126.679706 -244.210586) (xy 126.69266 -244.204236) (xy 126.7079 -244.179598)
			(xy 126.7079 -243.98605) (xy 126.707498 -243.976394) (xy 126.700358 -243.958452) (xy 126.687047 -243.944462)
			(xy 126.678436 -243.940076) (xy 126.595124 -243.901214) (xy 126.586219 -243.897483) (xy 126.566964 -243.896328)
			(xy 126.548661 -243.902421) (xy 126.541022 -243.908326) (xy 126.540768 -243.908326) (xy 126.519987 -243.925001)
			(xy 126.473847 -243.951633) (xy 126.423783 -243.969849) (xy 126.371317 -243.979096) (xy 126.34468 -243.9797)
			(xy 126.336806 -243.9797) (xy 126.313221 -243.978657) (xy 126.266777 -243.970199) (xy 126.222189 -243.95469)
			(xy 126.180521 -243.932501) (xy 126.142766 -243.904161) (xy 126.109826 -243.870345) (xy 126.082485 -243.831861)
			(xy 126.061396 -243.789625) (xy 126.047062 -243.744646) (xy 126.039825 -243.697996) (xy 126.039372 -243.674392)
			(xy 126.039843 -243.650401) (xy 126.04735 -243.603009) (xy 126.062178 -243.557374) (xy 126.083962 -243.514621)
			(xy 126.112165 -243.475802) (xy 126.146093 -243.441873) (xy 126.184911 -243.413668) (xy 126.227663 -243.391883)
			(xy 126.273297 -243.377053) (xy 126.320689 -243.369544) (xy 126.34468 -243.369084) (xy 126.344934 -243.369084)
			(xy 126.371543 -243.369675) (xy 126.423948 -243.378936) (xy 126.47395 -243.397154) (xy 126.520031 -243.423776)
			(xy 126.540768 -243.440458) (xy 126.541022 -243.440458) (xy 126.548685 -243.446307) (xy 126.566978 -243.452339)
			(xy 126.58621 -243.451239) (xy 126.595124 -243.44757) (xy 126.678436 -243.408708) (xy 126.686997 -243.404258)
			(xy 126.70025 -243.390258) (xy 126.707441 -243.372371) (xy 126.7079 -243.362734) (xy 126.7079 -243.169186)
			(xy 126.69266 -243.144548) (xy 126.679706 -243.138198) (xy 126.658145 -243.127037) (xy 126.618555 -243.098936)
			(xy 126.583912 -243.064924) (xy 126.555088 -243.025858) (xy 126.532809 -242.982723) (xy 126.517638 -242.936605)
			(xy 126.509955 -242.888668) (xy 126.509956 -242.840119) (xy 126.51764 -242.792183) (xy 126.532814 -242.746066)
			(xy 126.555094 -242.702932) (xy 126.58392 -242.663867) (xy 126.618565 -242.629856) (xy 126.658155 -242.601757)
			(xy 126.679706 -242.590574) (xy 126.69266 -242.584224) (xy 126.7079 -242.559586) (xy 126.7079 -241.549174)
			(xy 126.69266 -241.524536) (xy 126.679706 -241.518186) (xy 126.658145 -241.507025) (xy 126.618558 -241.478924)
			(xy 126.583916 -241.444913) (xy 126.555094 -241.405848) (xy 126.532817 -241.362714) (xy 126.517647 -241.316598)
			(xy 126.509966 -241.268662) (xy 126.509968 -241.220115) (xy 126.517652 -241.17218) (xy 126.532826 -241.126065)
			(xy 126.555106 -241.082933) (xy 126.583932 -241.04387) (xy 126.618576 -241.009861) (xy 126.658165 -240.981763)
			(xy 126.679706 -240.970562) (xy 126.69266 -240.964212) (xy 126.7079 -240.939574) (xy 126.7079 -240.746026)
			(xy 126.707494 -240.736372) (xy 126.700348 -240.718438) (xy 126.687037 -240.704455) (xy 126.678436 -240.700052)
			(xy 126.595124 -240.66119) (xy 126.586219 -240.65746) (xy 126.566963 -240.656307) (xy 126.54866 -240.662397)
			(xy 126.541022 -240.668302) (xy 126.540768 -240.668302) (xy 126.519988 -240.684978) (xy 126.473848 -240.711612)
			(xy 126.423784 -240.72983) (xy 126.371318 -240.739077) (xy 126.34468 -240.739676) (xy 126.336806 -240.739676)
			(xy 126.313219 -240.738633) (xy 126.26677 -240.730176) (xy 126.222178 -240.714668) (xy 126.180504 -240.692481)
			(xy 126.142743 -240.664142) (xy 126.109795 -240.630327) (xy 126.082446 -240.591843) (xy 126.061348 -240.549607)
			(xy 126.047003 -240.504627) (xy 126.039755 -240.457974) (xy 126.039372 -240.434368) (xy 126.039845 -240.410378)
			(xy 126.047355 -240.362989) (xy 126.062185 -240.317358) (xy 126.08397 -240.274608) (xy 126.112173 -240.235792)
			(xy 126.146101 -240.201866) (xy 126.184918 -240.173664) (xy 126.227669 -240.15188) (xy 126.273301 -240.137052)
			(xy 126.32069 -240.129544) (xy 126.34468 -240.12906) (xy 126.344934 -240.12906) (xy 126.371543 -240.129651)
			(xy 126.423949 -240.138912) (xy 126.473952 -240.157128) (xy 126.520033 -240.183748) (xy 126.540768 -240.200434)
			(xy 126.541022 -240.200434) (xy 126.548684 -240.206285) (xy 126.566978 -240.21232) (xy 126.586211 -240.211219)
			(xy 126.595124 -240.207546) (xy 126.678436 -240.168684) (xy 126.686994 -240.164233) (xy 126.700241 -240.150232)
			(xy 126.707424 -240.132345) (xy 126.7079 -240.12271) (xy 126.7079 -239.929162) (xy 126.69266 -239.904524)
			(xy 126.679706 -239.898174) (xy 126.658146 -239.887013) (xy 126.618561 -239.858913) (xy 126.583921 -239.824902)
			(xy 126.5551 -239.785838) (xy 126.532825 -239.742705) (xy 126.517656 -239.69659) (xy 126.509976 -239.648656)
			(xy 126.509979 -239.600111) (xy 126.517664 -239.552177) (xy 126.532838 -239.506064) (xy 126.555118 -239.462934)
			(xy 126.583943 -239.423873) (xy 126.618587 -239.389866) (xy 126.658175 -239.36177) (xy 126.679706 -239.35055)
			(xy 126.69266 -239.3442) (xy 126.7079 -239.319562) (xy 126.7079 -238.824262) (xy 126.70747 -238.814195)
			(xy 126.699746 -238.795601) (xy 126.692914 -238.788194) (xy 126.397766 -238.493046) (xy 126.390921 -238.485648)
			(xy 126.383196 -238.467049) (xy 126.38278 -238.456978) (xy 126.38278 -237.570772) (xy 126.382338 -237.560983)
			(xy 126.375031 -237.542819) (xy 126.368556 -237.535466) (xy 126.353824 -237.520226) (xy 126.350627 -237.517029)
			(xy 126.343342 -237.511674) (xy 126.339346 -237.509558) (xy 126.315978 -237.498636) (xy 126.30785 -237.49762)
			(xy 126.283483 -237.494138) (xy 126.23622 -237.480401) (xy 126.19177 -237.459267) (xy 126.151281 -237.431282)
			(xy 126.115802 -237.397168) (xy 126.086249 -237.357809) (xy 126.063387 -237.314222) (xy 126.047807 -237.267535)
			(xy 126.039911 -237.218953) (xy 126.039372 -237.194344) (xy 126.039815 -237.170348) (xy 126.047316 -237.122946)
			(xy 126.06214 -237.077301) (xy 126.083923 -237.034538) (xy 126.112128 -236.995708) (xy 126.146059 -236.961769)
			(xy 126.184883 -236.933557) (xy 126.227642 -236.911765) (xy 126.273284 -236.896931) (xy 126.320684 -236.88942)
			(xy 126.34468 -236.889036) (xy 126.372025 -236.889646) (xy 126.425843 -236.899374) (xy 126.477077 -236.918507)
			(xy 126.50089 -236.931962) (xy 126.508761 -236.936231) (xy 126.52635 -236.939533) (xy 126.544005 -236.936608)
			(xy 126.551944 -236.93247) (xy 126.628652 -236.889036) (xy 126.634748 -236.885226) (xy 126.643374 -236.877856)
			(xy 126.653671 -236.857674) (xy 126.65456 -236.846364) (xy 126.65456 -236.671104) (xy 126.653909 -236.659172)
			(xy 126.643172 -236.637855) (xy 126.633986 -236.63021) (xy 126.615042 -236.615725) (xy 126.581469 -236.581862)
			(xy 126.553572 -236.543188) (xy 126.532032 -236.500645) (xy 126.517372 -236.455269) (xy 126.50995 -236.408165)
			(xy 126.509947 -236.36048) (xy 126.517362 -236.313375) (xy 126.532015 -236.267996) (xy 126.553549 -236.22545)
			(xy 126.581439 -236.186772) (xy 126.615008 -236.152904) (xy 126.633986 -236.138466) (xy 126.643225 -236.130861)
			(xy 126.653985 -236.109522) (xy 126.65456 -236.097572) (xy 126.65456 -235.923836) (xy 126.65456 -235.922312)
			(xy 126.65362 -235.911013) (xy 126.643355 -235.890827) (xy 126.634748 -235.88345) (xy 126.628652 -235.87964)
			(xy 126.551944 -235.836206) (xy 126.543997 -235.832086) (xy 126.52635 -235.829142) (xy 126.508772 -235.832465)
			(xy 126.50089 -235.836714) (xy 126.477082 -235.850183) (xy 126.425853 -235.869337) (xy 126.372027 -235.879041)
			(xy 126.34468 -235.87964) (xy 126.338584 -235.87964) (xy 126.314904 -235.878726) (xy 126.268239 -235.870483)
			(xy 126.223408 -235.855129) (xy 126.181488 -235.833032) (xy 126.143486 -235.804724) (xy 126.110314 -235.770884)
			(xy 126.082769 -235.732325) (xy 126.061512 -235.689973) (xy 126.047054 -235.644845) (xy 126.039743 -235.598026)
			(xy 126.039372 -235.574332) (xy 126.039816 -235.550337) (xy 126.047318 -235.502936) (xy 126.062144 -235.457293)
			(xy 126.083927 -235.414531) (xy 126.112132 -235.375703) (xy 126.146064 -235.341766) (xy 126.184886 -235.313554)
			(xy 126.227645 -235.291764) (xy 126.273285 -235.276931) (xy 126.320685 -235.26942) (xy 126.34468 -235.269024)
			(xy 126.372025 -235.269634) (xy 126.425843 -235.279362) (xy 126.477078 -235.298493) (xy 126.50089 -235.31195)
			(xy 126.508761 -235.31622) (xy 126.52635 -235.319522) (xy 126.544005 -235.316597) (xy 126.551944 -235.312458)
			(xy 126.628652 -235.269024) (xy 126.634748 -235.265214) (xy 126.643372 -235.257843) (xy 126.653664 -235.237661)
			(xy 126.65456 -235.226352) (xy 126.65456 -235.051092) (xy 126.653906 -235.039161) (xy 126.643167 -235.017849)
			(xy 126.633986 -235.010198) (xy 126.615043 -234.995713) (xy 126.581471 -234.96185) (xy 126.553577 -234.923177)
			(xy 126.532038 -234.880635) (xy 126.51738 -234.83526) (xy 126.509959 -234.788157) (xy 126.509957 -234.740473)
			(xy 126.517373 -234.69337) (xy 126.532026 -234.647993) (xy 126.553561 -234.605449) (xy 126.581451 -234.566773)
			(xy 126.61502 -234.532907) (xy 126.633986 -234.518454) (xy 126.643223 -234.510848) (xy 126.653978 -234.489509)
			(xy 126.65456 -234.47756) (xy 126.65456 -233.43108) (xy 126.653925 -233.419139) (xy 126.643207 -233.397797)
			(xy 126.633986 -233.390186) (xy 126.615044 -233.375701) (xy 126.581474 -233.341839) (xy 126.553581 -233.303166)
			(xy 126.532044 -233.260625) (xy 126.517388 -233.215251) (xy 126.509968 -233.168149) (xy 126.509967 -233.120467)
			(xy 126.517384 -233.073365) (xy 126.532038 -233.027991) (xy 126.553572 -232.985448) (xy 126.581463 -232.946774)
			(xy 126.615031 -232.912909) (xy 126.633986 -232.898442) (xy 126.643221 -232.890835) (xy 126.653971 -232.869497)
			(xy 126.65456 -232.857548) (xy 126.65456 -232.683812) (xy 126.65456 -232.682288) (xy 126.653615 -232.670991)
			(xy 126.643344 -232.650814) (xy 126.634748 -232.643426) (xy 126.628652 -232.639616) (xy 126.551944 -232.596182)
			(xy 126.543996 -232.592064) (xy 126.52635 -232.589121) (xy 126.508772 -232.592443) (xy 126.50089 -232.59669)
			(xy 126.477083 -232.61016) (xy 126.425853 -232.629315) (xy 126.372027 -232.63902) (xy 126.34468 -232.639616)
			(xy 126.338584 -232.639616) (xy 126.314905 -232.638702) (xy 126.268241 -232.630459) (xy 126.223412 -232.615104)
			(xy 126.181494 -232.593007) (xy 126.143493 -232.564699) (xy 126.110324 -232.530858) (xy 126.082781 -232.492299)
			(xy 126.061527 -232.449947) (xy 126.047073 -232.40482) (xy 126.039765 -232.358001) (xy 126.039372 -232.334308)
			(xy 126.039842 -232.310316) (xy 126.047347 -232.262922) (xy 126.062173 -232.217286) (xy 126.083956 -232.17453)
			(xy 126.112159 -232.135709) (xy 126.146088 -232.101777) (xy 126.184906 -232.073571) (xy 126.22766 -232.051784)
			(xy 126.273295 -232.036954) (xy 126.320688 -232.029444) (xy 126.34468 -232.029) (xy 126.372025 -232.02961)
			(xy 126.425843 -232.039337) (xy 126.477079 -232.058467) (xy 126.50089 -232.071926) (xy 126.508762 -232.076191)
			(xy 126.52635 -232.079488) (xy 126.544004 -232.076568) (xy 126.551944 -232.072434) (xy 126.628652 -232.029)
			(xy 126.634748 -232.02519) (xy 126.643368 -232.017818) (xy 126.653651 -231.997635) (xy 126.65456 -231.986328)
			(xy 126.65456 -231.811068) (xy 126.653922 -231.799128) (xy 126.643201 -231.77779) (xy 126.633986 -231.770174)
			(xy 126.615045 -231.755689) (xy 126.581477 -231.721827) (xy 126.553586 -231.683155) (xy 126.53205 -231.640615)
			(xy 126.517395 -231.595242) (xy 126.509977 -231.548142) (xy 126.509977 -231.500461) (xy 126.517395 -231.453361)
			(xy 126.532049 -231.407988) (xy 126.553584 -231.365447) (xy 126.581475 -231.326775) (xy 126.615043 -231.292912)
			(xy 126.633986 -231.27843) (xy 126.643219 -231.270823) (xy 126.653964 -231.249484) (xy 126.65456 -231.237536)
			(xy 126.65456 -230.191056) (xy 126.65392 -230.179118) (xy 126.643196 -230.157784) (xy 126.633986 -230.150162)
			(xy 126.615046 -230.135677) (xy 126.58148 -230.101815) (xy 126.55359 -230.063144) (xy 126.532057 -230.020604)
			(xy 126.517403 -229.975233) (xy 126.509986 -229.928134) (xy 126.509987 -229.880454) (xy 126.517406 -229.833356)
			(xy 126.532061 -229.787985) (xy 126.553596 -229.745446) (xy 126.581487 -229.706776) (xy 126.615055 -229.672915)
			(xy 126.633986 -229.658418) (xy 126.643217 -229.650809) (xy 126.653956 -229.629471) (xy 126.65456 -229.617524)
			(xy 126.65456 -229.444042) (xy 126.65456 -229.442518) (xy 126.653602 -229.431229) (xy 126.643314 -229.411073)
			(xy 126.634748 -229.403656) (xy 126.628652 -229.399846) (xy 126.551944 -229.356412) (xy 126.543997 -229.352291)
			(xy 126.52635 -229.349347) (xy 126.508772 -229.352671) (xy 126.50089 -229.35692) (xy 126.477082 -229.370388)
			(xy 126.425853 -229.389542) (xy 126.372027 -229.399246) (xy 126.34468 -229.399846) (xy 126.338584 -229.399846)
			(xy 126.314904 -229.398932) (xy 126.268239 -229.390689) (xy 126.223408 -229.375335) (xy 126.181487 -229.353239)
			(xy 126.143484 -229.324931) (xy 126.110311 -229.291091) (xy 126.082765 -229.252532) (xy 126.061508 -229.21018)
			(xy 126.04705 -229.165052) (xy 126.039737 -229.118232) (xy 126.039372 -229.094538) (xy 126.039815 -229.070542)
			(xy 126.047317 -229.023141) (xy 126.062142 -228.977497) (xy 126.083925 -228.934734) (xy 126.11213 -228.895906)
			(xy 126.146061 -228.861968) (xy 126.184885 -228.833756) (xy 126.227643 -228.811964) (xy 126.273285 -228.797131)
			(xy 126.320684 -228.78962) (xy 126.34468 -228.78923) (xy 126.372025 -228.78984) (xy 126.425843 -228.799568)
			(xy 126.477077 -228.8187) (xy 126.50089 -228.832156) (xy 126.508761 -228.836426) (xy 126.52635 -228.839727)
			(xy 126.544005 -228.836803) (xy 126.551944 -228.832664) (xy 126.628652 -228.78923) (xy 126.634748 -228.78542)
			(xy 126.643373 -228.778049) (xy 126.653667 -228.757867) (xy 126.65456 -228.746558) (xy 126.65456 -228.571298)
			(xy 126.653908 -228.559366) (xy 126.643169 -228.538052) (xy 126.633986 -228.530404) (xy 126.615042 -228.515919)
			(xy 126.58147 -228.482056) (xy 126.553574 -228.443383) (xy 126.532035 -228.40084) (xy 126.517376 -228.355465)
			(xy 126.509955 -228.308361) (xy 126.509952 -228.260677) (xy 126.517367 -228.213572) (xy 126.53202 -228.168195)
			(xy 126.553555 -228.12565) (xy 126.581445 -228.086973) (xy 126.615014 -228.053105) (xy 126.633986 -228.03866)
			(xy 126.643224 -228.031054) (xy 126.653981 -228.009716) (xy 126.65456 -227.997766) (xy 126.65456 -227.691442)
			(xy 126.654995 -227.681378) (xy 126.662731 -227.662794) (xy 126.669546 -227.655374) (xy 127.47371 -226.85121)
			(xy 127.479044 -226.818952) (xy 127.471678 -226.804474) (xy 127.461375 -226.782595) (xy 127.446791 -226.736488)
			(xy 127.439388 -226.688699) (xy 127.438912 -226.66452) (xy 127.439373 -226.639714) (xy 127.447134 -226.590713)
			(xy 127.46247 -226.543531) (xy 127.485001 -226.499331) (xy 127.514172 -226.459202) (xy 127.549265 -226.424133)
			(xy 127.589414 -226.394989) (xy 127.633629 -226.372488) (xy 127.680822 -226.357184) (xy 127.729828 -226.349456)
			(xy 127.754634 -226.349052) (xy 127.779764 -226.349542) (xy 127.829389 -226.357512) (xy 127.877123 -226.373245)
			(xy 127.899668 -226.384358) (xy 127.907101 -226.387811) (xy 127.923295 -226.390276) (xy 127.931418 -226.389184)
			(xy 127.936498 -226.388422) (xy 128.061466 -226.263454) (xy 128.068981 -226.255191) (xy 128.076616 -226.234231)
			(xy 128.076198 -226.223068) (xy 128.069086 -226.141788) (xy 128.057656 -226.122484) (xy 128.048004 -226.11588)
			(xy 128.02703 -226.101061) (xy 127.98974 -226.065756) (xy 127.958652 -226.024883) (xy 127.934584 -225.979521)
			(xy 127.918172 -225.930862) (xy 127.909847 -225.88019) (xy 127.90932 -225.854514) (xy 127.909805 -225.829718)
			(xy 127.917558 -225.780735) (xy 127.932875 -225.733566) (xy 127.955379 -225.689374) (xy 127.984517 -225.649244)
			(xy 128.019572 -225.614164) (xy 128.059681 -225.584997) (xy 128.103857 -225.562461) (xy 128.151015 -225.54711)
			(xy 128.199992 -225.539323) (xy 128.224788 -225.538792) (xy 128.250475 -225.539319) (xy 128.301165 -225.547681)
			(xy 128.349833 -225.564137) (xy 128.395195 -225.588254) (xy 128.436056 -225.619396) (xy 128.471337 -225.65674)
			(xy 128.486154 -225.67773) (xy 128.492758 -225.687382) (xy 128.512062 -225.698812) (xy 128.593342 -225.705924)
			(xy 128.604496 -225.706301) (xy 128.625444 -225.69867) (xy 128.633728 -225.691192) (xy 129.315972 -225.008948)
			(xy 129.32283 -224.99574) (xy 129.324354 -224.987866) (xy 129.329071 -224.964464) (xy 129.344618 -224.91933)
			(xy 129.366788 -224.877054) (xy 129.395074 -224.838601) (xy 129.428831 -224.804848) (xy 129.467288 -224.776567)
			(xy 129.509567 -224.754402) (xy 129.554703 -224.738861) (xy 129.5781 -224.73412) (xy 129.585974 -224.732596)
			(xy 129.599182 -224.725738) (xy 129.86258 -224.46234) (xy 129.865628 -224.42551) (xy 129.85496 -224.41027)
			(xy 129.841858 -224.390853) (xy 129.821083 -224.348872) (xy 129.806956 -224.304213) (xy 129.799809 -224.257922)
			(xy 129.799334 -224.234502) (xy 129.79978 -224.21051) (xy 129.807287 -224.163117) (xy 129.822116 -224.117481)
			(xy 129.843902 -224.074728) (xy 129.872108 -224.03591) (xy 129.90604 -224.001982) (xy 129.944862 -223.973781)
			(xy 129.987618 -223.952) (xy 130.033256 -223.937177) (xy 130.08065 -223.929677) (xy 130.104642 -223.929194)
			(xy 130.128066 -223.929615) (xy 130.174367 -223.936758) (xy 130.219035 -223.950886) (xy 130.261023 -223.971668)
			(xy 130.28041 -223.98482) (xy 130.29565 -223.995488) (xy 130.33248 -223.99244) (xy 130.46456 -223.86036)
			(xy 130.472614 -223.851362) (xy 130.480059 -223.828425) (xy 130.478784 -223.816418) (xy 130.46583 -223.735138)
			(xy 130.46327 -223.723242) (xy 130.448944 -223.703617) (xy 130.438398 -223.697546) (xy 130.438144 -223.697546)
			(xy 130.41675 -223.686329) (xy 130.377494 -223.658181) (xy 130.343163 -223.624202) (xy 130.314612 -223.585238)
			(xy 130.292555 -223.542264) (xy 130.277543 -223.496352) (xy 130.269951 -223.448648) (xy 130.269488 -223.424496)
			(xy 130.269942 -223.400718) (xy 130.277314 -223.353736) (xy 130.291879 -223.308464) (xy 130.313286 -223.265998)
			(xy 130.341016 -223.227363) (xy 130.374399 -223.193493) (xy 130.412629 -223.165206) (xy 130.454782 -223.143188)
			(xy 130.499837 -223.127969) (xy 130.546708 -223.119918) (xy 130.570478 -223.119188) (xy 130.57505 -223.119188)
			(xy 130.603546 -223.119845) (xy 130.659543 -223.130453) (xy 130.686302 -223.14027) (xy 130.69824 -223.144842)
			(xy 130.722878 -223.142302) (xy 130.802888 -223.087692) (xy 130.812861 -223.080209) (xy 130.824577 -223.058233)
			(xy 130.82524 -223.045782) (xy 130.82524 -222.855536) (xy 130.82519 -222.850998) (xy 130.82365 -222.842054)
			(xy 130.822192 -222.837756) (xy 130.813048 -222.813626) (xy 130.807968 -222.807276) (xy 130.791898 -222.786702)
			(xy 130.766293 -222.741211) (xy 130.748792 -222.69203) (xy 130.739904 -222.640591) (xy 130.739388 -222.61449)
			(xy 130.739974 -222.587396) (xy 130.749536 -222.53406) (xy 130.768358 -222.483246) (xy 130.795849 -222.436551)
			(xy 130.813048 -222.415608) (xy 130.81889 -222.40875) (xy 130.821938 -222.400368) (xy 130.823463 -222.396081)
			(xy 130.82512 -222.387136) (xy 130.82524 -222.382588) (xy 130.82524 -222.334582) (xy 130.824812 -222.324515)
			(xy 130.817086 -222.305921) (xy 130.810254 -222.298514) (xy 130.611626 -222.099886) (xy 130.604514 -222.09252)
			(xy 130.585718 -222.0849) (xy 124.11583 -222.0849) (xy 124.10694 -222.088456) (xy 124.080003 -222.098373)
			(xy 124.023622 -222.10911) (xy 123.994926 -222.109792) (xy 123.994672 -222.109792) (xy 123.965973 -222.109136)
			(xy 123.909591 -222.098388) (xy 123.882658 -222.088456) (xy 123.873514 -222.0849) (xy 123.175776 -222.0849)
			(xy 123.166886 -222.088456) (xy 123.13995 -222.098377) (xy 123.083569 -222.109122) (xy 123.054872 -222.109792)
			(xy 123.054618 -222.109792) (xy 123.025918 -222.10914) (xy 122.969533 -222.098401) (xy 122.942604 -222.088456)
			(xy 122.93346 -222.0849) (xy 122.235976 -222.0849) (xy 122.227086 -222.088456) (xy 122.20015 -222.098377)
			(xy 122.143769 -222.109122) (xy 122.115072 -222.109792) (xy 122.114818 -222.109792) (xy 122.086118 -222.10914)
			(xy 122.029733 -222.098401) (xy 122.002804 -222.088456) (xy 121.99366 -222.0849) (xy 121.295922 -222.0849)
			(xy 121.287032 -222.088456) (xy 121.260095 -222.098373) (xy 121.203714 -222.109108) (xy 121.175018 -222.109792)
			(xy 121.174764 -222.109792) (xy 121.146064 -222.109145) (xy 121.089675 -222.098413) (xy 121.06275 -222.088456)
			(xy 121.053606 -222.0849) (xy 120.355868 -222.0849) (xy 120.346978 -222.088456) (xy 120.320042 -222.098377)
			(xy 120.263661 -222.10912) (xy 120.234964 -222.109792) (xy 120.23471 -222.109792) (xy 120.206011 -222.10914)
			(xy 120.149626 -222.098399) (xy 120.122696 -222.088456) (xy 120.113552 -222.0849) (xy 118.476014 -222.0849)
			(xy 118.467124 -222.088456) (xy 118.440187 -222.098372) (xy 118.383806 -222.109105) (xy 118.35511 -222.109792)
			(xy 118.354856 -222.109792) (xy 118.326156 -222.109144) (xy 118.269768 -222.098411) (xy 118.242842 -222.088456)
			(xy 118.233698 -222.0849) (xy 118.024402 -222.0849) (xy 118.014332 -222.085323) (xy 117.995727 -222.093037)
			(xy 117.988334 -222.099886) (xy 117.695726 -222.392494) (xy 117.68836 -222.399606) (xy 117.68074 -222.418402)
			(xy 117.68074 -222.61449) (xy 119.459006 -222.61449) (xy 119.462966 -222.565436) (xy 119.474743 -222.517652)
			(xy 119.494034 -222.472376) (xy 119.520337 -222.43078) (xy 119.552972 -222.393943) (xy 119.591093 -222.362818)
			(xy 119.633714 -222.338211) (xy 119.67973 -222.320759) (xy 119.727949 -222.310915) (xy 119.777124 -222.308934)
			(xy 119.825979 -222.314866) (xy 119.87325 -222.328558) (xy 119.917712 -222.349656) (xy 119.958215 -222.377612)
			(xy 119.993708 -222.411704) (xy 120.023273 -222.451048) (xy 120.046144 -222.494625) (xy 120.061728 -222.541306)
			(xy 120.069623 -222.589883) (xy 120.070118 -222.61449) (xy 122.278914 -222.61449) (xy 122.282874 -222.565436)
			(xy 122.294651 -222.517652) (xy 122.313942 -222.472376) (xy 122.340245 -222.43078) (xy 122.37288 -222.393943)
			(xy 122.411001 -222.362818) (xy 122.453622 -222.338211) (xy 122.499638 -222.320759) (xy 122.547857 -222.310915)
			(xy 122.597032 -222.308934) (xy 122.645887 -222.314866) (xy 122.693158 -222.328558) (xy 122.73762 -222.349656)
			(xy 122.778123 -222.377612) (xy 122.813616 -222.411704) (xy 122.843181 -222.451048) (xy 122.866052 -222.494625)
			(xy 122.881636 -222.541306) (xy 122.889531 -222.589883) (xy 122.890026 -222.61449) (xy 125.098822 -222.61449)
			(xy 125.102782 -222.565436) (xy 125.114559 -222.517652) (xy 125.13385 -222.472376) (xy 125.160153 -222.43078)
			(xy 125.192788 -222.393943) (xy 125.230909 -222.362818) (xy 125.27353 -222.338211) (xy 125.319546 -222.320759)
			(xy 125.367765 -222.310915) (xy 125.41694 -222.308934) (xy 125.465795 -222.314866) (xy 125.513066 -222.328558)
			(xy 125.557528 -222.349656) (xy 125.598031 -222.377612) (xy 125.633524 -222.411704) (xy 125.663089 -222.451048)
			(xy 125.68596 -222.494625) (xy 125.701544 -222.541306) (xy 125.709439 -222.589883) (xy 125.709934 -222.61449)
			(xy 125.709439 -222.639097) (xy 125.701544 -222.687674) (xy 125.68596 -222.734355) (xy 125.663089 -222.777932)
			(xy 125.633524 -222.817276) (xy 125.598031 -222.851368) (xy 125.557528 -222.879324) (xy 125.513066 -222.900422)
			(xy 125.465795 -222.914114) (xy 125.41694 -222.920046) (xy 125.367765 -222.918065) (xy 125.319546 -222.908221)
			(xy 125.27353 -222.890769) (xy 125.230909 -222.866162) (xy 125.192788 -222.835037) (xy 125.160153 -222.7982)
			(xy 125.13385 -222.756604) (xy 125.114559 -222.711328) (xy 125.102782 -222.663544) (xy 125.098822 -222.61449)
			(xy 122.890026 -222.61449) (xy 122.889531 -222.639097) (xy 122.881636 -222.687674) (xy 122.866052 -222.734355)
			(xy 122.843181 -222.777932) (xy 122.813616 -222.817276) (xy 122.778123 -222.851368) (xy 122.73762 -222.879324)
			(xy 122.693158 -222.900422) (xy 122.645887 -222.914114) (xy 122.597032 -222.920046) (xy 122.547857 -222.918065)
			(xy 122.499638 -222.908221) (xy 122.453622 -222.890769) (xy 122.411001 -222.866162) (xy 122.37288 -222.835037)
			(xy 122.340245 -222.7982) (xy 122.313942 -222.756604) (xy 122.294651 -222.711328) (xy 122.282874 -222.663544)
			(xy 122.278914 -222.61449) (xy 120.070118 -222.61449) (xy 120.069623 -222.639097) (xy 120.061728 -222.687674)
			(xy 120.046144 -222.734355) (xy 120.023273 -222.777932) (xy 119.993708 -222.817276) (xy 119.958215 -222.851368)
			(xy 119.917712 -222.879324) (xy 119.87325 -222.900422) (xy 119.825979 -222.914114) (xy 119.777124 -222.920046)
			(xy 119.727949 -222.918065) (xy 119.67973 -222.908221) (xy 119.633714 -222.890769) (xy 119.591093 -222.866162)
			(xy 119.552972 -222.835037) (xy 119.520337 -222.7982) (xy 119.494034 -222.756604) (xy 119.474743 -222.711328)
			(xy 119.462966 -222.663544) (xy 119.459006 -222.61449) (xy 117.68074 -222.61449) (xy 117.68074 -223.268032)
			(xy 117.683534 -223.279462) (xy 117.686328 -223.28505) (xy 117.696978 -223.306735) (xy 117.712042 -223.352637)
			(xy 117.71967 -223.400341) (xy 117.72011 -223.424496) (xy 118.049052 -223.424496) (xy 118.053012 -223.375442)
			(xy 118.064789 -223.327658) (xy 118.08408 -223.282382) (xy 118.110383 -223.240786) (xy 118.143018 -223.203949)
			(xy 118.181139 -223.172824) (xy 118.22376 -223.148217) (xy 118.269776 -223.130765) (xy 118.317995 -223.120921)
			(xy 118.36717 -223.11894) (xy 118.416025 -223.124872) (xy 118.463296 -223.138564) (xy 118.507758 -223.159662)
			(xy 118.548261 -223.187618) (xy 118.583754 -223.22171) (xy 118.613319 -223.261054) (xy 118.63619 -223.304631)
			(xy 118.651774 -223.351312) (xy 118.659669 -223.399889) (xy 118.660164 -223.424496) (xy 118.988852 -223.424496)
			(xy 118.992812 -223.375442) (xy 119.004589 -223.327658) (xy 119.02388 -223.282382) (xy 119.050183 -223.240786)
			(xy 119.082818 -223.203949) (xy 119.120939 -223.172824) (xy 119.16356 -223.148217) (xy 119.209576 -223.130765)
			(xy 119.257795 -223.120921) (xy 119.30697 -223.11894) (xy 119.355825 -223.124872) (xy 119.403096 -223.138564)
			(xy 119.447558 -223.159662) (xy 119.488061 -223.187618) (xy 119.523554 -223.22171) (xy 119.553119 -223.261054)
			(xy 119.57599 -223.304631) (xy 119.591574 -223.351312) (xy 119.599469 -223.399889) (xy 119.599964 -223.424496)
			(xy 119.928906 -223.424496) (xy 119.932866 -223.375442) (xy 119.944643 -223.327658) (xy 119.963934 -223.282382)
			(xy 119.990237 -223.240786) (xy 120.022872 -223.203949) (xy 120.060993 -223.172824) (xy 120.103614 -223.148217)
			(xy 120.14963 -223.130765) (xy 120.197849 -223.120921) (xy 120.247024 -223.11894) (xy 120.295879 -223.124872)
			(xy 120.34315 -223.138564) (xy 120.387612 -223.159662) (xy 120.428115 -223.187618) (xy 120.463608 -223.22171)
			(xy 120.493173 -223.261054) (xy 120.516044 -223.304631) (xy 120.531628 -223.351312) (xy 120.539523 -223.399889)
			(xy 120.540018 -223.424496) (xy 120.86896 -223.424496) (xy 120.87292 -223.375442) (xy 120.884697 -223.327658)
			(xy 120.903988 -223.282382) (xy 120.930291 -223.240786) (xy 120.962926 -223.203949) (xy 121.001047 -223.172824)
			(xy 121.043668 -223.148217) (xy 121.089684 -223.130765) (xy 121.137903 -223.120921) (xy 121.187078 -223.11894)
			(xy 121.235933 -223.124872) (xy 121.283204 -223.138564) (xy 121.327666 -223.159662) (xy 121.368169 -223.187618)
			(xy 121.403662 -223.22171) (xy 121.433227 -223.261054) (xy 121.456098 -223.304631) (xy 121.471682 -223.351312)
			(xy 121.479577 -223.399889) (xy 121.480072 -223.424496) (xy 121.809014 -223.424496) (xy 121.812974 -223.375442)
			(xy 121.824751 -223.327658) (xy 121.844042 -223.282382) (xy 121.870345 -223.240786) (xy 121.90298 -223.203949)
			(xy 121.941101 -223.172824) (xy 121.983722 -223.148217) (xy 122.029738 -223.130765) (xy 122.077957 -223.120921)
			(xy 122.127132 -223.11894) (xy 122.175987 -223.124872) (xy 122.223258 -223.138564) (xy 122.26772 -223.159662)
			(xy 122.308223 -223.187618) (xy 122.343716 -223.22171) (xy 122.373281 -223.261054) (xy 122.396152 -223.304631)
			(xy 122.411736 -223.351312) (xy 122.419631 -223.399889) (xy 122.420126 -223.424496) (xy 122.748814 -223.424496)
			(xy 122.752774 -223.375442) (xy 122.764551 -223.327658) (xy 122.783842 -223.282382) (xy 122.810145 -223.240786)
			(xy 122.84278 -223.203949) (xy 122.880901 -223.172824) (xy 122.923522 -223.148217) (xy 122.969538 -223.130765)
			(xy 123.017757 -223.120921) (xy 123.066932 -223.11894) (xy 123.115787 -223.124872) (xy 123.163058 -223.138564)
			(xy 123.20752 -223.159662) (xy 123.248023 -223.187618) (xy 123.283516 -223.22171) (xy 123.313081 -223.261054)
			(xy 123.335952 -223.304631) (xy 123.351536 -223.351312) (xy 123.359431 -223.399889) (xy 123.359926 -223.424496)
			(xy 123.688868 -223.424496) (xy 123.692828 -223.375442) (xy 123.704605 -223.327658) (xy 123.723896 -223.282382)
			(xy 123.750199 -223.240786) (xy 123.782834 -223.203949) (xy 123.820955 -223.172824) (xy 123.863576 -223.148217)
			(xy 123.909592 -223.130765) (xy 123.957811 -223.120921) (xy 124.006986 -223.11894) (xy 124.055841 -223.124872)
			(xy 124.103112 -223.138564) (xy 124.147574 -223.159662) (xy 124.188077 -223.187618) (xy 124.22357 -223.22171)
			(xy 124.253135 -223.261054) (xy 124.276006 -223.304631) (xy 124.29159 -223.351312) (xy 124.299485 -223.399889)
			(xy 124.29998 -223.424496) (xy 124.628922 -223.424496) (xy 124.632882 -223.375442) (xy 124.644659 -223.327658)
			(xy 124.66395 -223.282382) (xy 124.690253 -223.240786) (xy 124.722888 -223.203949) (xy 124.761009 -223.172824)
			(xy 124.80363 -223.148217) (xy 124.849646 -223.130765) (xy 124.897865 -223.120921) (xy 124.94704 -223.11894)
			(xy 124.995895 -223.124872) (xy 125.043166 -223.138564) (xy 125.087628 -223.159662) (xy 125.128131 -223.187618)
			(xy 125.163624 -223.22171) (xy 125.193189 -223.261054) (xy 125.21606 -223.304631) (xy 125.231644 -223.351312)
			(xy 125.239539 -223.399889) (xy 125.240034 -223.424496) (xy 125.568976 -223.424496) (xy 125.572936 -223.375442)
			(xy 125.584713 -223.327658) (xy 125.604004 -223.282382) (xy 125.630307 -223.240786) (xy 125.662942 -223.203949)
			(xy 125.701063 -223.172824) (xy 125.743684 -223.148217) (xy 125.7897 -223.130765) (xy 125.837919 -223.120921)
			(xy 125.887094 -223.11894) (xy 125.935949 -223.124872) (xy 125.98322 -223.138564) (xy 126.027682 -223.159662)
			(xy 126.068185 -223.187618) (xy 126.103678 -223.22171) (xy 126.133243 -223.261054) (xy 126.156114 -223.304631)
			(xy 126.171698 -223.351312) (xy 126.179593 -223.399889) (xy 126.180088 -223.424496) (xy 126.50903 -223.424496)
			(xy 126.51299 -223.375442) (xy 126.524767 -223.327658) (xy 126.544058 -223.282382) (xy 126.570361 -223.240786)
			(xy 126.602996 -223.203949) (xy 126.641117 -223.172824) (xy 126.683738 -223.148217) (xy 126.729754 -223.130765)
			(xy 126.777973 -223.120921) (xy 126.827148 -223.11894) (xy 126.876003 -223.124872) (xy 126.923274 -223.138564)
			(xy 126.967736 -223.159662) (xy 127.008239 -223.187618) (xy 127.043732 -223.22171) (xy 127.073297 -223.261054)
			(xy 127.096168 -223.304631) (xy 127.111752 -223.351312) (xy 127.119647 -223.399889) (xy 127.120142 -223.424496)
			(xy 127.44883 -223.424496) (xy 127.45279 -223.375442) (xy 127.464567 -223.327658) (xy 127.483858 -223.282382)
			(xy 127.510161 -223.240786) (xy 127.542796 -223.203949) (xy 127.580917 -223.172824) (xy 127.623538 -223.148217)
			(xy 127.669554 -223.130765) (xy 127.717773 -223.120921) (xy 127.766948 -223.11894) (xy 127.815803 -223.124872)
			(xy 127.863074 -223.138564) (xy 127.907536 -223.159662) (xy 127.948039 -223.187618) (xy 127.983532 -223.22171)
			(xy 128.013097 -223.261054) (xy 128.035968 -223.304631) (xy 128.051552 -223.351312) (xy 128.059447 -223.399889)
			(xy 128.059942 -223.424496) (xy 129.328938 -223.424496) (xy 129.332898 -223.375442) (xy 129.344675 -223.327658)
			(xy 129.363966 -223.282382) (xy 129.390269 -223.240786) (xy 129.422904 -223.203949) (xy 129.461025 -223.172824)
			(xy 129.503646 -223.148217) (xy 129.549662 -223.130765) (xy 129.597881 -223.120921) (xy 129.647056 -223.11894)
			(xy 129.695911 -223.124872) (xy 129.743182 -223.138564) (xy 129.787644 -223.159662) (xy 129.828147 -223.187618)
			(xy 129.86364 -223.22171) (xy 129.893205 -223.261054) (xy 129.916076 -223.304631) (xy 129.93166 -223.351312)
			(xy 129.939555 -223.399889) (xy 129.94005 -223.424496) (xy 129.939555 -223.449103) (xy 129.93166 -223.49768)
			(xy 129.916076 -223.544361) (xy 129.893205 -223.587938) (xy 129.86364 -223.627282) (xy 129.828147 -223.661374)
			(xy 129.787644 -223.68933) (xy 129.743182 -223.710428) (xy 129.695911 -223.72412) (xy 129.647056 -223.730052)
			(xy 129.597881 -223.728071) (xy 129.549662 -223.718227) (xy 129.503646 -223.700775) (xy 129.461025 -223.676168)
			(xy 129.422904 -223.645043) (xy 129.390269 -223.608206) (xy 129.363966 -223.56661) (xy 129.344675 -223.521334)
			(xy 129.332898 -223.47355) (xy 129.328938 -223.424496) (xy 128.059942 -223.424496) (xy 128.059447 -223.449103)
			(xy 128.051552 -223.49768) (xy 128.035968 -223.544361) (xy 128.013097 -223.587938) (xy 127.983532 -223.627282)
			(xy 127.948039 -223.661374) (xy 127.907536 -223.68933) (xy 127.863074 -223.710428) (xy 127.815803 -223.72412)
			(xy 127.766948 -223.730052) (xy 127.717773 -223.728071) (xy 127.669554 -223.718227) (xy 127.623538 -223.700775)
			(xy 127.580917 -223.676168) (xy 127.542796 -223.645043) (xy 127.510161 -223.608206) (xy 127.483858 -223.56661)
			(xy 127.464567 -223.521334) (xy 127.45279 -223.47355) (xy 127.44883 -223.424496) (xy 127.120142 -223.424496)
			(xy 127.119647 -223.449103) (xy 127.111752 -223.49768) (xy 127.096168 -223.544361) (xy 127.073297 -223.587938)
			(xy 127.043732 -223.627282) (xy 127.008239 -223.661374) (xy 126.967736 -223.68933) (xy 126.923274 -223.710428)
			(xy 126.876003 -223.72412) (xy 126.827148 -223.730052) (xy 126.777973 -223.728071) (xy 126.729754 -223.718227)
			(xy 126.683738 -223.700775) (xy 126.641117 -223.676168) (xy 126.602996 -223.645043) (xy 126.570361 -223.608206)
			(xy 126.544058 -223.56661) (xy 126.524767 -223.521334) (xy 126.51299 -223.47355) (xy 126.50903 -223.424496)
			(xy 126.180088 -223.424496) (xy 126.179593 -223.449103) (xy 126.171698 -223.49768) (xy 126.156114 -223.544361)
			(xy 126.133243 -223.587938) (xy 126.103678 -223.627282) (xy 126.068185 -223.661374) (xy 126.027682 -223.68933)
			(xy 125.98322 -223.710428) (xy 125.935949 -223.72412) (xy 125.887094 -223.730052) (xy 125.837919 -223.728071)
			(xy 125.7897 -223.718227) (xy 125.743684 -223.700775) (xy 125.701063 -223.676168) (xy 125.662942 -223.645043)
			(xy 125.630307 -223.608206) (xy 125.604004 -223.56661) (xy 125.584713 -223.521334) (xy 125.572936 -223.47355)
			(xy 125.568976 -223.424496) (xy 125.240034 -223.424496) (xy 125.239539 -223.449103) (xy 125.231644 -223.49768)
			(xy 125.21606 -223.544361) (xy 125.193189 -223.587938) (xy 125.163624 -223.627282) (xy 125.128131 -223.661374)
			(xy 125.087628 -223.68933) (xy 125.043166 -223.710428) (xy 124.995895 -223.72412) (xy 124.94704 -223.730052)
			(xy 124.897865 -223.728071) (xy 124.849646 -223.718227) (xy 124.80363 -223.700775) (xy 124.761009 -223.676168)
			(xy 124.722888 -223.645043) (xy 124.690253 -223.608206) (xy 124.66395 -223.56661) (xy 124.644659 -223.521334)
			(xy 124.632882 -223.47355) (xy 124.628922 -223.424496) (xy 124.29998 -223.424496) (xy 124.299485 -223.449103)
			(xy 124.29159 -223.49768) (xy 124.276006 -223.544361) (xy 124.253135 -223.587938) (xy 124.22357 -223.627282)
			(xy 124.188077 -223.661374) (xy 124.147574 -223.68933) (xy 124.103112 -223.710428) (xy 124.055841 -223.72412)
			(xy 124.006986 -223.730052) (xy 123.957811 -223.728071) (xy 123.909592 -223.718227) (xy 123.863576 -223.700775)
			(xy 123.820955 -223.676168) (xy 123.782834 -223.645043) (xy 123.750199 -223.608206) (xy 123.723896 -223.56661)
			(xy 123.704605 -223.521334) (xy 123.692828 -223.47355) (xy 123.688868 -223.424496) (xy 123.359926 -223.424496)
			(xy 123.359431 -223.449103) (xy 123.351536 -223.49768) (xy 123.335952 -223.544361) (xy 123.313081 -223.587938)
			(xy 123.283516 -223.627282) (xy 123.248023 -223.661374) (xy 123.20752 -223.68933) (xy 123.163058 -223.710428)
			(xy 123.115787 -223.72412) (xy 123.066932 -223.730052) (xy 123.017757 -223.728071) (xy 122.969538 -223.718227)
			(xy 122.923522 -223.700775) (xy 122.880901 -223.676168) (xy 122.84278 -223.645043) (xy 122.810145 -223.608206)
			(xy 122.783842 -223.56661) (xy 122.764551 -223.521334) (xy 122.752774 -223.47355) (xy 122.748814 -223.424496)
			(xy 122.420126 -223.424496) (xy 122.419631 -223.449103) (xy 122.411736 -223.49768) (xy 122.396152 -223.544361)
			(xy 122.373281 -223.587938) (xy 122.343716 -223.627282) (xy 122.308223 -223.661374) (xy 122.26772 -223.68933)
			(xy 122.223258 -223.710428) (xy 122.175987 -223.72412) (xy 122.127132 -223.730052) (xy 122.077957 -223.728071)
			(xy 122.029738 -223.718227) (xy 121.983722 -223.700775) (xy 121.941101 -223.676168) (xy 121.90298 -223.645043)
			(xy 121.870345 -223.608206) (xy 121.844042 -223.56661) (xy 121.824751 -223.521334) (xy 121.812974 -223.47355)
			(xy 121.809014 -223.424496) (xy 121.480072 -223.424496) (xy 121.479577 -223.449103) (xy 121.471682 -223.49768)
			(xy 121.456098 -223.544361) (xy 121.433227 -223.587938) (xy 121.403662 -223.627282) (xy 121.368169 -223.661374)
			(xy 121.327666 -223.68933) (xy 121.283204 -223.710428) (xy 121.235933 -223.72412) (xy 121.187078 -223.730052)
			(xy 121.137903 -223.728071) (xy 121.089684 -223.718227) (xy 121.043668 -223.700775) (xy 121.001047 -223.676168)
			(xy 120.962926 -223.645043) (xy 120.930291 -223.608206) (xy 120.903988 -223.56661) (xy 120.884697 -223.521334)
			(xy 120.87292 -223.47355) (xy 120.86896 -223.424496) (xy 120.540018 -223.424496) (xy 120.539523 -223.449103)
			(xy 120.531628 -223.49768) (xy 120.516044 -223.544361) (xy 120.493173 -223.587938) (xy 120.463608 -223.627282)
			(xy 120.428115 -223.661374) (xy 120.387612 -223.68933) (xy 120.34315 -223.710428) (xy 120.295879 -223.72412)
			(xy 120.247024 -223.730052) (xy 120.197849 -223.728071) (xy 120.14963 -223.718227) (xy 120.103614 -223.700775)
			(xy 120.060993 -223.676168) (xy 120.022872 -223.645043) (xy 119.990237 -223.608206) (xy 119.963934 -223.56661)
			(xy 119.944643 -223.521334) (xy 119.932866 -223.47355) (xy 119.928906 -223.424496) (xy 119.599964 -223.424496)
			(xy 119.599469 -223.449103) (xy 119.591574 -223.49768) (xy 119.57599 -223.544361) (xy 119.553119 -223.587938)
			(xy 119.523554 -223.627282) (xy 119.488061 -223.661374) (xy 119.447558 -223.68933) (xy 119.403096 -223.710428)
			(xy 119.355825 -223.72412) (xy 119.30697 -223.730052) (xy 119.257795 -223.728071) (xy 119.209576 -223.718227)
			(xy 119.16356 -223.700775) (xy 119.120939 -223.676168) (xy 119.082818 -223.645043) (xy 119.050183 -223.608206)
			(xy 119.02388 -223.56661) (xy 119.004589 -223.521334) (xy 118.992812 -223.47355) (xy 118.988852 -223.424496)
			(xy 118.660164 -223.424496) (xy 118.659669 -223.449103) (xy 118.651774 -223.49768) (xy 118.63619 -223.544361)
			(xy 118.613319 -223.587938) (xy 118.583754 -223.627282) (xy 118.548261 -223.661374) (xy 118.507758 -223.68933)
			(xy 118.463296 -223.710428) (xy 118.416025 -223.72412) (xy 118.36717 -223.730052) (xy 118.317995 -223.728071)
			(xy 118.269776 -223.718227) (xy 118.22376 -223.700775) (xy 118.181139 -223.676168) (xy 118.143018 -223.645043)
			(xy 118.110383 -223.608206) (xy 118.08408 -223.56661) (xy 118.064789 -223.521334) (xy 118.053012 -223.47355)
			(xy 118.049052 -223.424496) (xy 117.72011 -223.424496) (xy 117.719624 -223.448647) (xy 117.711979 -223.49634)
			(xy 117.696941 -223.542243) (xy 117.686328 -223.563942) (xy 117.683534 -223.56953) (xy 117.68074 -223.58096)
			(xy 117.68074 -223.840802) (xy 117.681285 -223.852336) (xy 117.691333 -223.8731) (xy 117.700044 -223.88068)
			(xy 117.700298 -223.88068) (xy 117.77345 -223.937322) (xy 117.79631 -223.942148) (xy 117.807994 -223.9391)
			(xy 117.826835 -223.934486) (xy 117.865307 -223.929517) (xy 117.884702 -223.929194) (xy 117.909957 -223.929716)
			(xy 117.959778 -223.93803) (xy 118.007551 -223.954431) (xy 118.051974 -223.978471) (xy 118.091833 -224.009495)
			(xy 118.126043 -224.046657) (xy 118.153669 -224.088942) (xy 118.173958 -224.135198) (xy 118.186358 -224.184162)
			(xy 118.190529 -224.2345) (xy 118.190529 -224.234502) (xy 118.518952 -224.234502) (xy 118.522912 -224.185448)
			(xy 118.534689 -224.137664) (xy 118.55398 -224.092388) (xy 118.580283 -224.050792) (xy 118.612918 -224.013955)
			(xy 118.651039 -223.98283) (xy 118.69366 -223.958223) (xy 118.739676 -223.940771) (xy 118.787895 -223.930927)
			(xy 118.83707 -223.928946) (xy 118.885925 -223.934878) (xy 118.933196 -223.94857) (xy 118.977658 -223.969668)
			(xy 119.018161 -223.997624) (xy 119.053654 -224.031716) (xy 119.083219 -224.07106) (xy 119.10609 -224.114637)
			(xy 119.121674 -224.161318) (xy 119.129569 -224.209895) (xy 119.130064 -224.234502) (xy 119.459006 -224.234502)
			(xy 119.462966 -224.185448) (xy 119.474743 -224.137664) (xy 119.494034 -224.092388) (xy 119.520337 -224.050792)
			(xy 119.552972 -224.013955) (xy 119.591093 -223.98283) (xy 119.633714 -223.958223) (xy 119.67973 -223.940771)
			(xy 119.727949 -223.930927) (xy 119.777124 -223.928946) (xy 119.825979 -223.934878) (xy 119.87325 -223.94857)
			(xy 119.917712 -223.969668) (xy 119.958215 -223.997624) (xy 119.993708 -224.031716) (xy 120.023273 -224.07106)
			(xy 120.046144 -224.114637) (xy 120.061728 -224.161318) (xy 120.069623 -224.209895) (xy 120.070118 -224.234502)
			(xy 120.398806 -224.234502) (xy 120.402766 -224.185448) (xy 120.414543 -224.137664) (xy 120.433834 -224.092388)
			(xy 120.460137 -224.050792) (xy 120.492772 -224.013955) (xy 120.530893 -223.98283) (xy 120.573514 -223.958223)
			(xy 120.61953 -223.940771) (xy 120.667749 -223.930927) (xy 120.716924 -223.928946) (xy 120.765779 -223.934878)
			(xy 120.81305 -223.94857) (xy 120.857512 -223.969668) (xy 120.898015 -223.997624) (xy 120.933508 -224.031716)
			(xy 120.963073 -224.07106) (xy 120.985944 -224.114637) (xy 121.001528 -224.161318) (xy 121.009423 -224.209895)
			(xy 121.009918 -224.234502) (xy 121.33886 -224.234502) (xy 121.34282 -224.185448) (xy 121.354597 -224.137664)
			(xy 121.373888 -224.092388) (xy 121.400191 -224.050792) (xy 121.432826 -224.013955) (xy 121.470947 -223.98283)
			(xy 121.513568 -223.958223) (xy 121.559584 -223.940771) (xy 121.607803 -223.930927) (xy 121.656978 -223.928946)
			(xy 121.705833 -223.934878) (xy 121.753104 -223.94857) (xy 121.797566 -223.969668) (xy 121.838069 -223.997624)
			(xy 121.873562 -224.031716) (xy 121.903127 -224.07106) (xy 121.925998 -224.114637) (xy 121.941582 -224.161318)
			(xy 121.949477 -224.209895) (xy 121.949972 -224.234502) (xy 122.278914 -224.234502) (xy 122.282874 -224.185448)
			(xy 122.294651 -224.137664) (xy 122.313942 -224.092388) (xy 122.340245 -224.050792) (xy 122.37288 -224.013955)
			(xy 122.411001 -223.98283) (xy 122.453622 -223.958223) (xy 122.499638 -223.940771) (xy 122.547857 -223.930927)
			(xy 122.597032 -223.928946) (xy 122.645887 -223.934878) (xy 122.693158 -223.94857) (xy 122.73762 -223.969668)
			(xy 122.778123 -223.997624) (xy 122.813616 -224.031716) (xy 122.843181 -224.07106) (xy 122.866052 -224.114637)
			(xy 122.881636 -224.161318) (xy 122.889531 -224.209895) (xy 122.890026 -224.234502) (xy 123.218968 -224.234502)
			(xy 123.222928 -224.185448) (xy 123.234705 -224.137664) (xy 123.253996 -224.092388) (xy 123.280299 -224.050792)
			(xy 123.312934 -224.013955) (xy 123.351055 -223.98283) (xy 123.393676 -223.958223) (xy 123.439692 -223.940771)
			(xy 123.487911 -223.930927) (xy 123.537086 -223.928946) (xy 123.585941 -223.934878) (xy 123.633212 -223.94857)
			(xy 123.677674 -223.969668) (xy 123.718177 -223.997624) (xy 123.75367 -224.031716) (xy 123.783235 -224.07106)
			(xy 123.806106 -224.114637) (xy 123.82169 -224.161318) (xy 123.829585 -224.209895) (xy 123.83008 -224.234502)
			(xy 124.159022 -224.234502) (xy 124.162982 -224.185448) (xy 124.174759 -224.137664) (xy 124.19405 -224.092388)
			(xy 124.220353 -224.050792) (xy 124.252988 -224.013955) (xy 124.291109 -223.98283) (xy 124.33373 -223.958223)
			(xy 124.379746 -223.940771) (xy 124.427965 -223.930927) (xy 124.47714 -223.928946) (xy 124.525995 -223.934878)
			(xy 124.573266 -223.94857) (xy 124.617728 -223.969668) (xy 124.658231 -223.997624) (xy 124.693724 -224.031716)
			(xy 124.723289 -224.07106) (xy 124.74616 -224.114637) (xy 124.761744 -224.161318) (xy 124.769639 -224.209895)
			(xy 124.770134 -224.234502) (xy 125.098822 -224.234502) (xy 125.102782 -224.185448) (xy 125.114559 -224.137664)
			(xy 125.13385 -224.092388) (xy 125.160153 -224.050792) (xy 125.192788 -224.013955) (xy 125.230909 -223.98283)
			(xy 125.27353 -223.958223) (xy 125.319546 -223.940771) (xy 125.367765 -223.930927) (xy 125.41694 -223.928946)
			(xy 125.465795 -223.934878) (xy 125.513066 -223.94857) (xy 125.557528 -223.969668) (xy 125.598031 -223.997624)
			(xy 125.633524 -224.031716) (xy 125.663089 -224.07106) (xy 125.68596 -224.114637) (xy 125.701544 -224.161318)
			(xy 125.709439 -224.209895) (xy 125.709934 -224.234502) (xy 126.038876 -224.234502) (xy 126.042836 -224.185448)
			(xy 126.054613 -224.137664) (xy 126.073904 -224.092388) (xy 126.100207 -224.050792) (xy 126.132842 -224.013955)
			(xy 126.170963 -223.98283) (xy 126.213584 -223.958223) (xy 126.2596 -223.940771) (xy 126.307819 -223.930927)
			(xy 126.356994 -223.928946) (xy 126.405849 -223.934878) (xy 126.45312 -223.94857) (xy 126.497582 -223.969668)
			(xy 126.538085 -223.997624) (xy 126.573578 -224.031716) (xy 126.603143 -224.07106) (xy 126.626014 -224.114637)
			(xy 126.641598 -224.161318) (xy 126.649493 -224.209895) (xy 126.649988 -224.234502) (xy 126.97893 -224.234502)
			(xy 126.98289 -224.185448) (xy 126.994667 -224.137664) (xy 127.013958 -224.092388) (xy 127.040261 -224.050792)
			(xy 127.072896 -224.013955) (xy 127.111017 -223.98283) (xy 127.153638 -223.958223) (xy 127.199654 -223.940771)
			(xy 127.247873 -223.930927) (xy 127.297048 -223.928946) (xy 127.345903 -223.934878) (xy 127.393174 -223.94857)
			(xy 127.437636 -223.969668) (xy 127.478139 -223.997624) (xy 127.513632 -224.031716) (xy 127.543197 -224.07106)
			(xy 127.566068 -224.114637) (xy 127.581652 -224.161318) (xy 127.589547 -224.209895) (xy 127.590042 -224.234502)
			(xy 127.918984 -224.234502) (xy 127.922944 -224.185448) (xy 127.934721 -224.137664) (xy 127.954012 -224.092388)
			(xy 127.980315 -224.050792) (xy 128.01295 -224.013955) (xy 128.051071 -223.98283) (xy 128.093692 -223.958223)
			(xy 128.139708 -223.940771) (xy 128.187927 -223.930927) (xy 128.237102 -223.928946) (xy 128.285957 -223.934878)
			(xy 128.333228 -223.94857) (xy 128.37769 -223.969668) (xy 128.418193 -223.997624) (xy 128.453686 -224.031716)
			(xy 128.483251 -224.07106) (xy 128.506122 -224.114637) (xy 128.521706 -224.161318) (xy 128.529601 -224.209895)
			(xy 128.530096 -224.234502) (xy 128.859038 -224.234502) (xy 128.862998 -224.185448) (xy 128.874775 -224.137664)
			(xy 128.894066 -224.092388) (xy 128.920369 -224.050792) (xy 128.953004 -224.013955) (xy 128.991125 -223.98283)
			(xy 129.033746 -223.958223) (xy 129.079762 -223.940771) (xy 129.127981 -223.930927) (xy 129.177156 -223.928946)
			(xy 129.226011 -223.934878) (xy 129.273282 -223.94857) (xy 129.317744 -223.969668) (xy 129.358247 -223.997624)
			(xy 129.39374 -224.031716) (xy 129.423305 -224.07106) (xy 129.446176 -224.114637) (xy 129.46176 -224.161318)
			(xy 129.469655 -224.209895) (xy 129.47015 -224.234502) (xy 129.469655 -224.259109) (xy 129.46176 -224.307686)
			(xy 129.446176 -224.354367) (xy 129.423305 -224.397944) (xy 129.39374 -224.437288) (xy 129.358247 -224.47138)
			(xy 129.317744 -224.499336) (xy 129.273282 -224.520434) (xy 129.226011 -224.534126) (xy 129.177156 -224.540058)
			(xy 129.127981 -224.538077) (xy 129.079762 -224.528233) (xy 129.033746 -224.510781) (xy 128.991125 -224.486174)
			(xy 128.953004 -224.455049) (xy 128.920369 -224.418212) (xy 128.894066 -224.376616) (xy 128.874775 -224.33134)
			(xy 128.862998 -224.283556) (xy 128.859038 -224.234502) (xy 128.530096 -224.234502) (xy 128.529601 -224.259109)
			(xy 128.521706 -224.307686) (xy 128.506122 -224.354367) (xy 128.483251 -224.397944) (xy 128.453686 -224.437288)
			(xy 128.418193 -224.47138) (xy 128.37769 -224.499336) (xy 128.333228 -224.520434) (xy 128.285957 -224.534126)
			(xy 128.237102 -224.540058) (xy 128.187927 -224.538077) (xy 128.139708 -224.528233) (xy 128.093692 -224.510781)
			(xy 128.051071 -224.486174) (xy 128.01295 -224.455049) (xy 127.980315 -224.418212) (xy 127.954012 -224.376616)
			(xy 127.934721 -224.33134) (xy 127.922944 -224.283556) (xy 127.918984 -224.234502) (xy 127.590042 -224.234502)
			(xy 127.589547 -224.259109) (xy 127.581652 -224.307686) (xy 127.566068 -224.354367) (xy 127.543197 -224.397944)
			(xy 127.513632 -224.437288) (xy 127.478139 -224.47138) (xy 127.437636 -224.499336) (xy 127.393174 -224.520434)
			(xy 127.345903 -224.534126) (xy 127.297048 -224.540058) (xy 127.247873 -224.538077) (xy 127.199654 -224.528233)
			(xy 127.153638 -224.510781) (xy 127.111017 -224.486174) (xy 127.072896 -224.455049) (xy 127.040261 -224.418212)
			(xy 127.013958 -224.376616) (xy 126.994667 -224.33134) (xy 126.98289 -224.283556) (xy 126.97893 -224.234502)
			(xy 126.649988 -224.234502) (xy 126.649493 -224.259109) (xy 126.641598 -224.307686) (xy 126.626014 -224.354367)
			(xy 126.603143 -224.397944) (xy 126.573578 -224.437288) (xy 126.538085 -224.47138) (xy 126.497582 -224.499336)
			(xy 126.45312 -224.520434) (xy 126.405849 -224.534126) (xy 126.356994 -224.540058) (xy 126.307819 -224.538077)
			(xy 126.2596 -224.528233) (xy 126.213584 -224.510781) (xy 126.170963 -224.486174) (xy 126.132842 -224.455049)
			(xy 126.100207 -224.418212) (xy 126.073904 -224.376616) (xy 126.054613 -224.33134) (xy 126.042836 -224.283556)
			(xy 126.038876 -224.234502) (xy 125.709934 -224.234502) (xy 125.709439 -224.259109) (xy 125.701544 -224.307686)
			(xy 125.68596 -224.354367) (xy 125.663089 -224.397944) (xy 125.633524 -224.437288) (xy 125.598031 -224.47138)
			(xy 125.557528 -224.499336) (xy 125.513066 -224.520434) (xy 125.465795 -224.534126) (xy 125.41694 -224.540058)
			(xy 125.367765 -224.538077) (xy 125.319546 -224.528233) (xy 125.27353 -224.510781) (xy 125.230909 -224.486174)
			(xy 125.192788 -224.455049) (xy 125.160153 -224.418212) (xy 125.13385 -224.376616) (xy 125.114559 -224.33134)
			(xy 125.102782 -224.283556) (xy 125.098822 -224.234502) (xy 124.770134 -224.234502) (xy 124.769639 -224.259109)
			(xy 124.761744 -224.307686) (xy 124.74616 -224.354367) (xy 124.723289 -224.397944) (xy 124.693724 -224.437288)
			(xy 124.658231 -224.47138) (xy 124.617728 -224.499336) (xy 124.573266 -224.520434) (xy 124.525995 -224.534126)
			(xy 124.47714 -224.540058) (xy 124.427965 -224.538077) (xy 124.379746 -224.528233) (xy 124.33373 -224.510781)
			(xy 124.291109 -224.486174) (xy 124.252988 -224.455049) (xy 124.220353 -224.418212) (xy 124.19405 -224.376616)
			(xy 124.174759 -224.33134) (xy 124.162982 -224.283556) (xy 124.159022 -224.234502) (xy 123.83008 -224.234502)
			(xy 123.829585 -224.259109) (xy 123.82169 -224.307686) (xy 123.806106 -224.354367) (xy 123.783235 -224.397944)
			(xy 123.75367 -224.437288) (xy 123.718177 -224.47138) (xy 123.677674 -224.499336) (xy 123.633212 -224.520434)
			(xy 123.585941 -224.534126) (xy 123.537086 -224.540058) (xy 123.487911 -224.538077) (xy 123.439692 -224.528233)
			(xy 123.393676 -224.510781) (xy 123.351055 -224.486174) (xy 123.312934 -224.455049) (xy 123.280299 -224.418212)
			(xy 123.253996 -224.376616) (xy 123.234705 -224.33134) (xy 123.222928 -224.283556) (xy 123.218968 -224.234502)
			(xy 122.890026 -224.234502) (xy 122.889531 -224.259109) (xy 122.881636 -224.307686) (xy 122.866052 -224.354367)
			(xy 122.843181 -224.397944) (xy 122.813616 -224.437288) (xy 122.778123 -224.47138) (xy 122.73762 -224.499336)
			(xy 122.693158 -224.520434) (xy 122.645887 -224.534126) (xy 122.597032 -224.540058) (xy 122.547857 -224.538077)
			(xy 122.499638 -224.528233) (xy 122.453622 -224.510781) (xy 122.411001 -224.486174) (xy 122.37288 -224.455049)
			(xy 122.340245 -224.418212) (xy 122.313942 -224.376616) (xy 122.294651 -224.33134) (xy 122.282874 -224.283556)
			(xy 122.278914 -224.234502) (xy 121.949972 -224.234502) (xy 121.949477 -224.259109) (xy 121.941582 -224.307686)
			(xy 121.925998 -224.354367) (xy 121.903127 -224.397944) (xy 121.873562 -224.437288) (xy 121.838069 -224.47138)
			(xy 121.797566 -224.499336) (xy 121.753104 -224.520434) (xy 121.705833 -224.534126) (xy 121.656978 -224.540058)
			(xy 121.607803 -224.538077) (xy 121.559584 -224.528233) (xy 121.513568 -224.510781) (xy 121.470947 -224.486174)
			(xy 121.432826 -224.455049) (xy 121.400191 -224.418212) (xy 121.373888 -224.376616) (xy 121.354597 -224.33134)
			(xy 121.34282 -224.283556) (xy 121.33886 -224.234502) (xy 121.009918 -224.234502) (xy 121.009423 -224.259109)
			(xy 121.001528 -224.307686) (xy 120.985944 -224.354367) (xy 120.963073 -224.397944) (xy 120.933508 -224.437288)
			(xy 120.898015 -224.47138) (xy 120.857512 -224.499336) (xy 120.81305 -224.520434) (xy 120.765779 -224.534126)
			(xy 120.716924 -224.540058) (xy 120.667749 -224.538077) (xy 120.61953 -224.528233) (xy 120.573514 -224.510781)
			(xy 120.530893 -224.486174) (xy 120.492772 -224.455049) (xy 120.460137 -224.418212) (xy 120.433834 -224.376616)
			(xy 120.414543 -224.33134) (xy 120.402766 -224.283556) (xy 120.398806 -224.234502) (xy 120.070118 -224.234502)
			(xy 120.069623 -224.259109) (xy 120.061728 -224.307686) (xy 120.046144 -224.354367) (xy 120.023273 -224.397944)
			(xy 119.993708 -224.437288) (xy 119.958215 -224.47138) (xy 119.917712 -224.499336) (xy 119.87325 -224.520434)
			(xy 119.825979 -224.534126) (xy 119.777124 -224.540058) (xy 119.727949 -224.538077) (xy 119.67973 -224.528233)
			(xy 119.633714 -224.510781) (xy 119.591093 -224.486174) (xy 119.552972 -224.455049) (xy 119.520337 -224.418212)
			(xy 119.494034 -224.376616) (xy 119.474743 -224.33134) (xy 119.462966 -224.283556) (xy 119.459006 -224.234502)
			(xy 119.130064 -224.234502) (xy 119.129569 -224.259109) (xy 119.121674 -224.307686) (xy 119.10609 -224.354367)
			(xy 119.083219 -224.397944) (xy 119.053654 -224.437288) (xy 119.018161 -224.47138) (xy 118.977658 -224.499336)
			(xy 118.933196 -224.520434) (xy 118.885925 -224.534126) (xy 118.83707 -224.540058) (xy 118.787895 -224.538077)
			(xy 118.739676 -224.528233) (xy 118.69366 -224.510781) (xy 118.651039 -224.486174) (xy 118.612918 -224.455049)
			(xy 118.580283 -224.418212) (xy 118.55398 -224.376616) (xy 118.534689 -224.33134) (xy 118.522912 -224.283556)
			(xy 118.518952 -224.234502) (xy 118.190529 -224.234502) (xy 118.186358 -224.284838) (xy 118.173958 -224.333802)
			(xy 118.153669 -224.380058) (xy 118.126043 -224.422343) (xy 118.091833 -224.459505) (xy 118.051974 -224.490529)
			(xy 118.007551 -224.514569) (xy 117.959778 -224.53097) (xy 117.909957 -224.539284) (xy 117.884702 -224.53981)
			(xy 117.860625 -224.539357) (xy 117.813069 -224.531796) (xy 117.767291 -224.516861) (xy 117.724425 -224.494924)
			(xy 117.685536 -224.466527) (xy 117.651588 -224.432376) (xy 117.623424 -224.393318) (xy 117.601743 -224.350322)
			(xy 117.587081 -224.304455) (xy 117.58295 -224.28073) (xy 117.580664 -224.266252) (xy 117.562122 -224.244662)
			(xy 117.4623 -224.21215) (xy 117.453254 -224.209643) (xy 117.434523 -224.210612) (xy 117.417387 -224.218237)
			(xy 117.410484 -224.224596) (xy 116.755164 -224.879916) (xy 116.749322 -224.910142) (xy 116.755418 -224.92462)
			(xy 116.766843 -224.953269) (xy 116.779255 -225.013675) (xy 116.780056 -225.044508) (xy 117.108998 -225.044508)
			(xy 117.112958 -224.995454) (xy 117.124735 -224.94767) (xy 117.144026 -224.902394) (xy 117.170329 -224.860798)
			(xy 117.202964 -224.823961) (xy 117.241085 -224.792836) (xy 117.283706 -224.768229) (xy 117.329722 -224.750777)
			(xy 117.377941 -224.740933) (xy 117.427116 -224.738952) (xy 117.475971 -224.744884) (xy 117.523242 -224.758576)
			(xy 117.567704 -224.779674) (xy 117.608207 -224.80763) (xy 117.6437 -224.841722) (xy 117.673265 -224.881066)
			(xy 117.696136 -224.924643) (xy 117.71172 -224.971324) (xy 117.719615 -225.019901) (xy 117.72011 -225.044508)
			(xy 118.988852 -225.044508) (xy 118.992812 -224.995454) (xy 119.004589 -224.94767) (xy 119.02388 -224.902394)
			(xy 119.050183 -224.860798) (xy 119.082818 -224.823961) (xy 119.120939 -224.792836) (xy 119.16356 -224.768229)
			(xy 119.209576 -224.750777) (xy 119.257795 -224.740933) (xy 119.30697 -224.738952) (xy 119.355825 -224.744884)
			(xy 119.403096 -224.758576) (xy 119.447558 -224.779674) (xy 119.488061 -224.80763) (xy 119.523554 -224.841722)
			(xy 119.553119 -224.881066) (xy 119.57599 -224.924643) (xy 119.591574 -224.971324) (xy 119.599469 -225.019901)
			(xy 119.599964 -225.044508) (xy 119.928906 -225.044508) (xy 119.932866 -224.995454) (xy 119.944643 -224.94767)
			(xy 119.963934 -224.902394) (xy 119.990237 -224.860798) (xy 120.022872 -224.823961) (xy 120.060993 -224.792836)
			(xy 120.103614 -224.768229) (xy 120.14963 -224.750777) (xy 120.197849 -224.740933) (xy 120.247024 -224.738952)
			(xy 120.295879 -224.744884) (xy 120.34315 -224.758576) (xy 120.387612 -224.779674) (xy 120.428115 -224.80763)
			(xy 120.463608 -224.841722) (xy 120.493173 -224.881066) (xy 120.516044 -224.924643) (xy 120.531628 -224.971324)
			(xy 120.539523 -225.019901) (xy 120.540018 -225.044508) (xy 121.809014 -225.044508) (xy 121.812974 -224.995454)
			(xy 121.824751 -224.94767) (xy 121.844042 -224.902394) (xy 121.870345 -224.860798) (xy 121.90298 -224.823961)
			(xy 121.941101 -224.792836) (xy 121.983722 -224.768229) (xy 122.029738 -224.750777) (xy 122.077957 -224.740933)
			(xy 122.127132 -224.738952) (xy 122.175987 -224.744884) (xy 122.223258 -224.758576) (xy 122.26772 -224.779674)
			(xy 122.308223 -224.80763) (xy 122.343716 -224.841722) (xy 122.373281 -224.881066) (xy 122.396152 -224.924643)
			(xy 122.411736 -224.971324) (xy 122.419631 -225.019901) (xy 122.420126 -225.044508) (xy 122.748814 -225.044508)
			(xy 122.752774 -224.995454) (xy 122.764551 -224.94767) (xy 122.783842 -224.902394) (xy 122.810145 -224.860798)
			(xy 122.84278 -224.823961) (xy 122.880901 -224.792836) (xy 122.923522 -224.768229) (xy 122.969538 -224.750777)
			(xy 123.017757 -224.740933) (xy 123.066932 -224.738952) (xy 123.115787 -224.744884) (xy 123.163058 -224.758576)
			(xy 123.20752 -224.779674) (xy 123.248023 -224.80763) (xy 123.283516 -224.841722) (xy 123.313081 -224.881066)
			(xy 123.335952 -224.924643) (xy 123.351536 -224.971324) (xy 123.359431 -225.019901) (xy 123.359926 -225.044508)
			(xy 124.628922 -225.044508) (xy 124.632882 -224.995454) (xy 124.644659 -224.94767) (xy 124.66395 -224.902394)
			(xy 124.690253 -224.860798) (xy 124.722888 -224.823961) (xy 124.761009 -224.792836) (xy 124.80363 -224.768229)
			(xy 124.849646 -224.750777) (xy 124.897865 -224.740933) (xy 124.94704 -224.738952) (xy 124.995895 -224.744884)
			(xy 125.043166 -224.758576) (xy 125.087628 -224.779674) (xy 125.128131 -224.80763) (xy 125.163624 -224.841722)
			(xy 125.193189 -224.881066) (xy 125.21606 -224.924643) (xy 125.231644 -224.971324) (xy 125.239539 -225.019901)
			(xy 125.240034 -225.044508) (xy 125.568976 -225.044508) (xy 125.572936 -224.995454) (xy 125.584713 -224.94767)
			(xy 125.604004 -224.902394) (xy 125.630307 -224.860798) (xy 125.662942 -224.823961) (xy 125.701063 -224.792836)
			(xy 125.743684 -224.768229) (xy 125.7897 -224.750777) (xy 125.837919 -224.740933) (xy 125.887094 -224.738952)
			(xy 125.935949 -224.744884) (xy 125.98322 -224.758576) (xy 126.027682 -224.779674) (xy 126.068185 -224.80763)
			(xy 126.103678 -224.841722) (xy 126.133243 -224.881066) (xy 126.156114 -224.924643) (xy 126.171698 -224.971324)
			(xy 126.179593 -225.019901) (xy 126.180088 -225.044508) (xy 127.44883 -225.044508) (xy 127.45279 -224.995454)
			(xy 127.464567 -224.94767) (xy 127.483858 -224.902394) (xy 127.510161 -224.860798) (xy 127.542796 -224.823961)
			(xy 127.580917 -224.792836) (xy 127.623538 -224.768229) (xy 127.669554 -224.750777) (xy 127.717773 -224.740933)
			(xy 127.766948 -224.738952) (xy 127.815803 -224.744884) (xy 127.863074 -224.758576) (xy 127.907536 -224.779674)
			(xy 127.948039 -224.80763) (xy 127.983532 -224.841722) (xy 128.013097 -224.881066) (xy 128.035968 -224.924643)
			(xy 128.051552 -224.971324) (xy 128.059447 -225.019901) (xy 128.059942 -225.044508) (xy 128.388884 -225.044508)
			(xy 128.392844 -224.995454) (xy 128.404621 -224.94767) (xy 128.423912 -224.902394) (xy 128.450215 -224.860798)
			(xy 128.48285 -224.823961) (xy 128.520971 -224.792836) (xy 128.563592 -224.768229) (xy 128.609608 -224.750777)
			(xy 128.657827 -224.740933) (xy 128.707002 -224.738952) (xy 128.755857 -224.744884) (xy 128.803128 -224.758576)
			(xy 128.84759 -224.779674) (xy 128.888093 -224.80763) (xy 128.923586 -224.841722) (xy 128.953151 -224.881066)
			(xy 128.976022 -224.924643) (xy 128.991606 -224.971324) (xy 128.999501 -225.019901) (xy 128.999996 -225.044508)
			(xy 128.999501 -225.069115) (xy 128.991606 -225.117692) (xy 128.976022 -225.164373) (xy 128.953151 -225.20795)
			(xy 128.923586 -225.247294) (xy 128.888093 -225.281386) (xy 128.84759 -225.309342) (xy 128.803128 -225.33044)
			(xy 128.755857 -225.344132) (xy 128.707002 -225.350064) (xy 128.657827 -225.348083) (xy 128.609608 -225.338239)
			(xy 128.563592 -225.320787) (xy 128.520971 -225.29618) (xy 128.48285 -225.265055) (xy 128.450215 -225.228218)
			(xy 128.423912 -225.186622) (xy 128.404621 -225.141346) (xy 128.392844 -225.093562) (xy 128.388884 -225.044508)
			(xy 128.059942 -225.044508) (xy 128.059447 -225.069115) (xy 128.051552 -225.117692) (xy 128.035968 -225.164373)
			(xy 128.013097 -225.20795) (xy 127.983532 -225.247294) (xy 127.948039 -225.281386) (xy 127.907536 -225.309342)
			(xy 127.863074 -225.33044) (xy 127.815803 -225.344132) (xy 127.766948 -225.350064) (xy 127.717773 -225.348083)
			(xy 127.669554 -225.338239) (xy 127.623538 -225.320787) (xy 127.580917 -225.29618) (xy 127.542796 -225.265055)
			(xy 127.510161 -225.228218) (xy 127.483858 -225.186622) (xy 127.464567 -225.141346) (xy 127.45279 -225.093562)
			(xy 127.44883 -225.044508) (xy 126.180088 -225.044508) (xy 126.179593 -225.069115) (xy 126.171698 -225.117692)
			(xy 126.156114 -225.164373) (xy 126.133243 -225.20795) (xy 126.103678 -225.247294) (xy 126.068185 -225.281386)
			(xy 126.027682 -225.309342) (xy 125.98322 -225.33044) (xy 125.935949 -225.344132) (xy 125.887094 -225.350064)
			(xy 125.837919 -225.348083) (xy 125.7897 -225.338239) (xy 125.743684 -225.320787) (xy 125.701063 -225.29618)
			(xy 125.662942 -225.265055) (xy 125.630307 -225.228218) (xy 125.604004 -225.186622) (xy 125.584713 -225.141346)
			(xy 125.572936 -225.093562) (xy 125.568976 -225.044508) (xy 125.240034 -225.044508) (xy 125.239539 -225.069115)
			(xy 125.231644 -225.117692) (xy 125.21606 -225.164373) (xy 125.193189 -225.20795) (xy 125.163624 -225.247294)
			(xy 125.128131 -225.281386) (xy 125.087628 -225.309342) (xy 125.043166 -225.33044) (xy 124.995895 -225.344132)
			(xy 124.94704 -225.350064) (xy 124.897865 -225.348083) (xy 124.849646 -225.338239) (xy 124.80363 -225.320787)
			(xy 124.761009 -225.29618) (xy 124.722888 -225.265055) (xy 124.690253 -225.228218) (xy 124.66395 -225.186622)
			(xy 124.644659 -225.141346) (xy 124.632882 -225.093562) (xy 124.628922 -225.044508) (xy 123.359926 -225.044508)
			(xy 123.359431 -225.069115) (xy 123.351536 -225.117692) (xy 123.335952 -225.164373) (xy 123.313081 -225.20795)
			(xy 123.283516 -225.247294) (xy 123.248023 -225.281386) (xy 123.20752 -225.309342) (xy 123.163058 -225.33044)
			(xy 123.115787 -225.344132) (xy 123.066932 -225.350064) (xy 123.017757 -225.348083) (xy 122.969538 -225.338239)
			(xy 122.923522 -225.320787) (xy 122.880901 -225.29618) (xy 122.84278 -225.265055) (xy 122.810145 -225.228218)
			(xy 122.783842 -225.186622) (xy 122.764551 -225.141346) (xy 122.752774 -225.093562) (xy 122.748814 -225.044508)
			(xy 122.420126 -225.044508) (xy 122.419631 -225.069115) (xy 122.411736 -225.117692) (xy 122.396152 -225.164373)
			(xy 122.373281 -225.20795) (xy 122.343716 -225.247294) (xy 122.308223 -225.281386) (xy 122.26772 -225.309342)
			(xy 122.223258 -225.33044) (xy 122.175987 -225.344132) (xy 122.127132 -225.350064) (xy 122.077957 -225.348083)
			(xy 122.029738 -225.338239) (xy 121.983722 -225.320787) (xy 121.941101 -225.29618) (xy 121.90298 -225.265055)
			(xy 121.870345 -225.228218) (xy 121.844042 -225.186622) (xy 121.824751 -225.141346) (xy 121.812974 -225.093562)
			(xy 121.809014 -225.044508) (xy 120.540018 -225.044508) (xy 120.539523 -225.069115) (xy 120.531628 -225.117692)
			(xy 120.516044 -225.164373) (xy 120.493173 -225.20795) (xy 120.463608 -225.247294) (xy 120.428115 -225.281386)
			(xy 120.387612 -225.309342) (xy 120.34315 -225.33044) (xy 120.295879 -225.344132) (xy 120.247024 -225.350064)
			(xy 120.197849 -225.348083) (xy 120.14963 -225.338239) (xy 120.103614 -225.320787) (xy 120.060993 -225.29618)
			(xy 120.022872 -225.265055) (xy 119.990237 -225.228218) (xy 119.963934 -225.186622) (xy 119.944643 -225.141346)
			(xy 119.932866 -225.093562) (xy 119.928906 -225.044508) (xy 119.599964 -225.044508) (xy 119.599469 -225.069115)
			(xy 119.591574 -225.117692) (xy 119.57599 -225.164373) (xy 119.553119 -225.20795) (xy 119.523554 -225.247294)
			(xy 119.488061 -225.281386) (xy 119.447558 -225.309342) (xy 119.403096 -225.33044) (xy 119.355825 -225.344132)
			(xy 119.30697 -225.350064) (xy 119.257795 -225.348083) (xy 119.209576 -225.338239) (xy 119.16356 -225.320787)
			(xy 119.120939 -225.29618) (xy 119.082818 -225.265055) (xy 119.050183 -225.228218) (xy 119.02388 -225.186622)
			(xy 119.004589 -225.141346) (xy 118.992812 -225.093562) (xy 118.988852 -225.044508) (xy 117.72011 -225.044508)
			(xy 117.719615 -225.069115) (xy 117.71172 -225.117692) (xy 117.696136 -225.164373) (xy 117.673265 -225.20795)
			(xy 117.6437 -225.247294) (xy 117.608207 -225.281386) (xy 117.567704 -225.309342) (xy 117.523242 -225.33044)
			(xy 117.475971 -225.344132) (xy 117.427116 -225.350064) (xy 117.377941 -225.348083) (xy 117.329722 -225.338239)
			(xy 117.283706 -225.320787) (xy 117.241085 -225.29618) (xy 117.202964 -225.265055) (xy 117.170329 -225.228218)
			(xy 117.144026 -225.186622) (xy 117.124735 -225.141346) (xy 117.112958 -225.093562) (xy 117.108998 -225.044508)
			(xy 116.780056 -225.044508) (xy 116.779585 -225.0685) (xy 116.772078 -225.115894) (xy 116.757251 -225.16153)
			(xy 116.735467 -225.204285) (xy 116.707265 -225.243106) (xy 116.673337 -225.277039) (xy 116.634519 -225.305246)
			(xy 116.591767 -225.327035) (xy 116.546133 -225.341869) (xy 116.49874 -225.349382) (xy 116.474748 -225.349816)
			(xy 116.443915 -225.34902) (xy 116.383509 -225.336606) (xy 116.35486 -225.325178) (xy 116.340382 -225.319082)
			(xy 116.310156 -225.324924) (xy 115.780566 -225.854514) (xy 116.638844 -225.854514) (xy 116.642804 -225.80546)
			(xy 116.654581 -225.757676) (xy 116.673872 -225.7124) (xy 116.700175 -225.670804) (xy 116.73281 -225.633967)
			(xy 116.770931 -225.602842) (xy 116.813552 -225.578235) (xy 116.859568 -225.560783) (xy 116.907787 -225.550939)
			(xy 116.956962 -225.548958) (xy 117.005817 -225.55489) (xy 117.053088 -225.568582) (xy 117.09755 -225.58968)
			(xy 117.138053 -225.617636) (xy 117.173546 -225.651728) (xy 117.203111 -225.691072) (xy 117.225982 -225.734649)
			(xy 117.241566 -225.78133) (xy 117.249461 -225.829907) (xy 117.249956 -225.854514) (xy 117.578898 -225.854514)
			(xy 117.582858 -225.80546) (xy 117.594635 -225.757676) (xy 117.613926 -225.7124) (xy 117.640229 -225.670804)
			(xy 117.672864 -225.633967) (xy 117.710985 -225.602842) (xy 117.753606 -225.578235) (xy 117.799622 -225.560783)
			(xy 117.847841 -225.550939) (xy 117.897016 -225.548958) (xy 117.945871 -225.55489) (xy 117.993142 -225.568582)
			(xy 118.037604 -225.58968) (xy 118.078107 -225.617636) (xy 118.1136 -225.651728) (xy 118.143165 -225.691072)
			(xy 118.166036 -225.734649) (xy 118.18162 -225.78133) (xy 118.189515 -225.829907) (xy 118.19001 -225.854514)
			(xy 119.459006 -225.854514) (xy 119.462966 -225.80546) (xy 119.474743 -225.757676) (xy 119.494034 -225.7124)
			(xy 119.520337 -225.670804) (xy 119.552972 -225.633967) (xy 119.591093 -225.602842) (xy 119.633714 -225.578235)
			(xy 119.67973 -225.560783) (xy 119.727949 -225.550939) (xy 119.777124 -225.548958) (xy 119.825979 -225.55489)
			(xy 119.87325 -225.568582) (xy 119.917712 -225.58968) (xy 119.958215 -225.617636) (xy 119.993708 -225.651728)
			(xy 120.023273 -225.691072) (xy 120.046144 -225.734649) (xy 120.061728 -225.78133) (xy 120.069623 -225.829907)
			(xy 120.070118 -225.854514) (xy 120.398806 -225.854514) (xy 120.402766 -225.80546) (xy 120.414543 -225.757676)
			(xy 120.433834 -225.7124) (xy 120.460137 -225.670804) (xy 120.492772 -225.633967) (xy 120.530893 -225.602842)
			(xy 120.573514 -225.578235) (xy 120.61953 -225.560783) (xy 120.667749 -225.550939) (xy 120.716924 -225.548958)
			(xy 120.765779 -225.55489) (xy 120.81305 -225.568582) (xy 120.857512 -225.58968) (xy 120.898015 -225.617636)
			(xy 120.933508 -225.651728) (xy 120.963073 -225.691072) (xy 120.985944 -225.734649) (xy 121.001528 -225.78133)
			(xy 121.009423 -225.829907) (xy 121.009918 -225.854514) (xy 122.278914 -225.854514) (xy 122.282874 -225.80546)
			(xy 122.294651 -225.757676) (xy 122.313942 -225.7124) (xy 122.340245 -225.670804) (xy 122.37288 -225.633967)
			(xy 122.411001 -225.602842) (xy 122.453622 -225.578235) (xy 122.499638 -225.560783) (xy 122.547857 -225.550939)
			(xy 122.597032 -225.548958) (xy 122.645887 -225.55489) (xy 122.693158 -225.568582) (xy 122.73762 -225.58968)
			(xy 122.778123 -225.617636) (xy 122.813616 -225.651728) (xy 122.843181 -225.691072) (xy 122.866052 -225.734649)
			(xy 122.881636 -225.78133) (xy 122.889531 -225.829907) (xy 122.890026 -225.854514) (xy 123.218968 -225.854514)
			(xy 123.222928 -225.80546) (xy 123.234705 -225.757676) (xy 123.253996 -225.7124) (xy 123.280299 -225.670804)
			(xy 123.312934 -225.633967) (xy 123.351055 -225.602842) (xy 123.393676 -225.578235) (xy 123.439692 -225.560783)
			(xy 123.487911 -225.550939) (xy 123.537086 -225.548958) (xy 123.585941 -225.55489) (xy 123.633212 -225.568582)
			(xy 123.677674 -225.58968) (xy 123.718177 -225.617636) (xy 123.75367 -225.651728) (xy 123.783235 -225.691072)
			(xy 123.806106 -225.734649) (xy 123.82169 -225.78133) (xy 123.829585 -225.829907) (xy 123.83008 -225.854514)
			(xy 125.098822 -225.854514) (xy 125.102782 -225.80546) (xy 125.114559 -225.757676) (xy 125.13385 -225.7124)
			(xy 125.160153 -225.670804) (xy 125.192788 -225.633967) (xy 125.230909 -225.602842) (xy 125.27353 -225.578235)
			(xy 125.319546 -225.560783) (xy 125.367765 -225.550939) (xy 125.41694 -225.548958) (xy 125.465795 -225.55489)
			(xy 125.513066 -225.568582) (xy 125.557528 -225.58968) (xy 125.598031 -225.617636) (xy 125.633524 -225.651728)
			(xy 125.663089 -225.691072) (xy 125.68596 -225.734649) (xy 125.701544 -225.78133) (xy 125.709439 -225.829907)
			(xy 125.709934 -225.854514) (xy 126.038876 -225.854514) (xy 126.042836 -225.80546) (xy 126.054613 -225.757676)
			(xy 126.073904 -225.7124) (xy 126.100207 -225.670804) (xy 126.132842 -225.633967) (xy 126.170963 -225.602842)
			(xy 126.213584 -225.578235) (xy 126.2596 -225.560783) (xy 126.307819 -225.550939) (xy 126.356994 -225.548958)
			(xy 126.405849 -225.55489) (xy 126.45312 -225.568582) (xy 126.497582 -225.58968) (xy 126.538085 -225.617636)
			(xy 126.573578 -225.651728) (xy 126.603143 -225.691072) (xy 126.626014 -225.734649) (xy 126.641598 -225.78133)
			(xy 126.649493 -225.829907) (xy 126.649988 -225.854514) (xy 126.649493 -225.879121) (xy 126.641598 -225.927698)
			(xy 126.626014 -225.974379) (xy 126.603143 -226.017956) (xy 126.573578 -226.0573) (xy 126.538085 -226.091392)
			(xy 126.497582 -226.119348) (xy 126.45312 -226.140446) (xy 126.405849 -226.154138) (xy 126.356994 -226.16007)
			(xy 126.307819 -226.158089) (xy 126.2596 -226.148245) (xy 126.213584 -226.130793) (xy 126.170963 -226.106186)
			(xy 126.132842 -226.075061) (xy 126.100207 -226.038224) (xy 126.073904 -225.996628) (xy 126.054613 -225.951352)
			(xy 126.042836 -225.903568) (xy 126.038876 -225.854514) (xy 125.709934 -225.854514) (xy 125.709439 -225.879121)
			(xy 125.701544 -225.927698) (xy 125.68596 -225.974379) (xy 125.663089 -226.017956) (xy 125.633524 -226.0573)
			(xy 125.598031 -226.091392) (xy 125.557528 -226.119348) (xy 125.513066 -226.140446) (xy 125.465795 -226.154138)
			(xy 125.41694 -226.16007) (xy 125.367765 -226.158089) (xy 125.319546 -226.148245) (xy 125.27353 -226.130793)
			(xy 125.230909 -226.106186) (xy 125.192788 -226.075061) (xy 125.160153 -226.038224) (xy 125.13385 -225.996628)
			(xy 125.114559 -225.951352) (xy 125.102782 -225.903568) (xy 125.098822 -225.854514) (xy 123.83008 -225.854514)
			(xy 123.829585 -225.879121) (xy 123.82169 -225.927698) (xy 123.806106 -225.974379) (xy 123.783235 -226.017956)
			(xy 123.75367 -226.0573) (xy 123.718177 -226.091392) (xy 123.677674 -226.119348) (xy 123.633212 -226.140446)
			(xy 123.585941 -226.154138) (xy 123.537086 -226.16007) (xy 123.487911 -226.158089) (xy 123.439692 -226.148245)
			(xy 123.393676 -226.130793) (xy 123.351055 -226.106186) (xy 123.312934 -226.075061) (xy 123.280299 -226.038224)
			(xy 123.253996 -225.996628) (xy 123.234705 -225.951352) (xy 123.222928 -225.903568) (xy 123.218968 -225.854514)
			(xy 122.890026 -225.854514) (xy 122.889531 -225.879121) (xy 122.881636 -225.927698) (xy 122.866052 -225.974379)
			(xy 122.843181 -226.017956) (xy 122.813616 -226.0573) (xy 122.778123 -226.091392) (xy 122.73762 -226.119348)
			(xy 122.693158 -226.140446) (xy 122.645887 -226.154138) (xy 122.597032 -226.16007) (xy 122.547857 -226.158089)
			(xy 122.499638 -226.148245) (xy 122.453622 -226.130793) (xy 122.411001 -226.106186) (xy 122.37288 -226.075061)
			(xy 122.340245 -226.038224) (xy 122.313942 -225.996628) (xy 122.294651 -225.951352) (xy 122.282874 -225.903568)
			(xy 122.278914 -225.854514) (xy 121.009918 -225.854514) (xy 121.009423 -225.879121) (xy 121.001528 -225.927698)
			(xy 120.985944 -225.974379) (xy 120.963073 -226.017956) (xy 120.933508 -226.0573) (xy 120.898015 -226.091392)
			(xy 120.857512 -226.119348) (xy 120.81305 -226.140446) (xy 120.765779 -226.154138) (xy 120.716924 -226.16007)
			(xy 120.667749 -226.158089) (xy 120.61953 -226.148245) (xy 120.573514 -226.130793) (xy 120.530893 -226.106186)
			(xy 120.492772 -226.075061) (xy 120.460137 -226.038224) (xy 120.433834 -225.996628) (xy 120.414543 -225.951352)
			(xy 120.402766 -225.903568) (xy 120.398806 -225.854514) (xy 120.070118 -225.854514) (xy 120.069623 -225.879121)
			(xy 120.061728 -225.927698) (xy 120.046144 -225.974379) (xy 120.023273 -226.017956) (xy 119.993708 -226.0573)
			(xy 119.958215 -226.091392) (xy 119.917712 -226.119348) (xy 119.87325 -226.140446) (xy 119.825979 -226.154138)
			(xy 119.777124 -226.16007) (xy 119.727949 -226.158089) (xy 119.67973 -226.148245) (xy 119.633714 -226.130793)
			(xy 119.591093 -226.106186) (xy 119.552972 -226.075061) (xy 119.520337 -226.038224) (xy 119.494034 -225.996628)
			(xy 119.474743 -225.951352) (xy 119.462966 -225.903568) (xy 119.459006 -225.854514) (xy 118.19001 -225.854514)
			(xy 118.189515 -225.879121) (xy 118.18162 -225.927698) (xy 118.166036 -225.974379) (xy 118.143165 -226.017956)
			(xy 118.1136 -226.0573) (xy 118.078107 -226.091392) (xy 118.037604 -226.119348) (xy 117.993142 -226.140446)
			(xy 117.945871 -226.154138) (xy 117.897016 -226.16007) (xy 117.847841 -226.158089) (xy 117.799622 -226.148245)
			(xy 117.753606 -226.130793) (xy 117.710985 -226.106186) (xy 117.672864 -226.075061) (xy 117.640229 -226.038224)
			(xy 117.613926 -225.996628) (xy 117.594635 -225.951352) (xy 117.582858 -225.903568) (xy 117.578898 -225.854514)
			(xy 117.249956 -225.854514) (xy 117.249461 -225.879121) (xy 117.241566 -225.927698) (xy 117.225982 -225.974379)
			(xy 117.203111 -226.017956) (xy 117.173546 -226.0573) (xy 117.138053 -226.091392) (xy 117.09755 -226.119348)
			(xy 117.053088 -226.140446) (xy 117.005817 -226.154138) (xy 116.956962 -226.16007) (xy 116.907787 -226.158089)
			(xy 116.859568 -226.148245) (xy 116.813552 -226.130793) (xy 116.770931 -226.106186) (xy 116.73281 -226.075061)
			(xy 116.700175 -226.038224) (xy 116.673872 -225.996628) (xy 116.654581 -225.951352) (xy 116.642804 -225.903568)
			(xy 116.638844 -225.854514) (xy 115.780566 -225.854514) (xy 115.409472 -226.225608) (xy 115.403122 -226.236022)
			(xy 115.401344 -226.242118) (xy 115.39093 -226.274884) (xy 115.38966 -226.278694) (xy 115.388136 -226.287584)
			(xy 115.386859 -226.299409) (xy 115.394031 -226.322054) (xy 115.401852 -226.331018) (xy 115.421918 -226.351846)
			(xy 115.431316 -226.361498) (xy 115.456208 -226.369118) (xy 115.469416 -226.366324) (xy 115.485532 -226.363006)
			(xy 115.518242 -226.359442) (xy 115.534694 -226.359212) (xy 115.55995 -226.359704) (xy 115.609774 -226.368017)
			(xy 115.65755 -226.384418) (xy 115.701975 -226.408459) (xy 115.741837 -226.439484) (xy 115.776049 -226.476647)
			(xy 115.803677 -226.518935) (xy 115.823968 -226.565193) (xy 115.836369 -226.61416) (xy 115.84054 -226.6645)
			(xy 115.840538 -226.66452) (xy 116.158513 -226.66452) (xy 116.162608 -226.613792) (xy 116.174787 -226.564378)
			(xy 116.194735 -226.517558) (xy 116.221936 -226.474544) (xy 116.255684 -226.43645) (xy 116.295106 -226.404263)
			(xy 116.33918 -226.378817) (xy 116.386766 -226.36077) (xy 116.43663 -226.35059) (xy 116.487482 -226.348541)
			(xy 116.538003 -226.354675) (xy 116.586887 -226.368835) (xy 116.632866 -226.390652) (xy 116.67475 -226.419562)
			(xy 116.711454 -226.454817) (xy 116.742027 -226.495503) (xy 116.765678 -226.540566) (xy 116.781794 -226.58884)
			(xy 116.789958 -226.639074) (xy 116.79047 -226.66452) (xy 117.098567 -226.66452) (xy 117.102662 -226.613792)
			(xy 117.114841 -226.564378) (xy 117.134789 -226.517558) (xy 117.16199 -226.474544) (xy 117.195738 -226.43645)
			(xy 117.23516 -226.404263) (xy 117.279234 -226.378817) (xy 117.32682 -226.36077) (xy 117.376684 -226.35059)
			(xy 117.427536 -226.348541) (xy 117.478057 -226.354675) (xy 117.526941 -226.368835) (xy 117.57292 -226.390652)
			(xy 117.614804 -226.419562) (xy 117.651508 -226.454817) (xy 117.682081 -226.495503) (xy 117.705732 -226.540566)
			(xy 117.721848 -226.58884) (xy 117.730012 -226.639074) (xy 117.730524 -226.66452) (xy 118.049052 -226.66452)
			(xy 118.053012 -226.615466) (xy 118.064789 -226.567682) (xy 118.08408 -226.522406) (xy 118.110383 -226.48081)
			(xy 118.143018 -226.443973) (xy 118.181139 -226.412848) (xy 118.22376 -226.388241) (xy 118.269776 -226.370789)
			(xy 118.317995 -226.360945) (xy 118.36717 -226.358964) (xy 118.416025 -226.364896) (xy 118.463296 -226.378588)
			(xy 118.507758 -226.399686) (xy 118.548261 -226.427642) (xy 118.583754 -226.461734) (xy 118.613319 -226.501078)
			(xy 118.63619 -226.544655) (xy 118.651774 -226.591336) (xy 118.659669 -226.639913) (xy 118.660164 -226.66452)
			(xy 118.978421 -226.66452) (xy 118.982516 -226.613792) (xy 118.994695 -226.564378) (xy 119.014643 -226.517558)
			(xy 119.041844 -226.474544) (xy 119.075592 -226.43645) (xy 119.115014 -226.404263) (xy 119.159088 -226.378817)
			(xy 119.206674 -226.36077) (xy 119.256538 -226.35059) (xy 119.30739 -226.348541) (xy 119.357911 -226.354675)
			(xy 119.406795 -226.368835) (xy 119.452774 -226.390652) (xy 119.494658 -226.419562) (xy 119.531362 -226.454817)
			(xy 119.561935 -226.495503) (xy 119.585586 -226.540566) (xy 119.601702 -226.58884) (xy 119.609866 -226.639074)
			(xy 119.610378 -226.66452) (xy 119.918475 -226.66452) (xy 119.92257 -226.613792) (xy 119.934749 -226.564378)
			(xy 119.954697 -226.517558) (xy 119.981898 -226.474544) (xy 120.015646 -226.43645) (xy 120.055068 -226.404263)
			(xy 120.099142 -226.378817) (xy 120.146728 -226.36077) (xy 120.196592 -226.35059) (xy 120.247444 -226.348541)
			(xy 120.297965 -226.354675) (xy 120.346849 -226.368835) (xy 120.392828 -226.390652) (xy 120.434712 -226.419562)
			(xy 120.471416 -226.454817) (xy 120.501989 -226.495503) (xy 120.52564 -226.540566) (xy 120.541756 -226.58884)
			(xy 120.54992 -226.639074) (xy 120.550432 -226.66452) (xy 120.86896 -226.66452) (xy 120.87292 -226.615466)
			(xy 120.884697 -226.567682) (xy 120.903988 -226.522406) (xy 120.930291 -226.48081) (xy 120.962926 -226.443973)
			(xy 121.001047 -226.412848) (xy 121.043668 -226.388241) (xy 121.089684 -226.370789) (xy 121.137903 -226.360945)
			(xy 121.187078 -226.358964) (xy 121.235933 -226.364896) (xy 121.283204 -226.378588) (xy 121.327666 -226.399686)
			(xy 121.368169 -226.427642) (xy 121.403662 -226.461734) (xy 121.433227 -226.501078) (xy 121.456098 -226.544655)
			(xy 121.471682 -226.591336) (xy 121.479577 -226.639913) (xy 121.480072 -226.66452) (xy 121.798583 -226.66452)
			(xy 121.802678 -226.613792) (xy 121.814857 -226.564378) (xy 121.834805 -226.517558) (xy 121.862006 -226.474544)
			(xy 121.895754 -226.43645) (xy 121.935176 -226.404263) (xy 121.97925 -226.378817) (xy 122.026836 -226.36077)
			(xy 122.0767 -226.35059) (xy 122.127552 -226.348541) (xy 122.178073 -226.354675) (xy 122.226957 -226.368835)
			(xy 122.272936 -226.390652) (xy 122.31482 -226.419562) (xy 122.351524 -226.454817) (xy 122.382097 -226.495503)
			(xy 122.405748 -226.540566) (xy 122.421864 -226.58884) (xy 122.430028 -226.639074) (xy 122.43054 -226.66452)
			(xy 122.738383 -226.66452) (xy 122.742478 -226.613792) (xy 122.754657 -226.564378) (xy 122.774605 -226.517558)
			(xy 122.801806 -226.474544) (xy 122.835554 -226.43645) (xy 122.874976 -226.404263) (xy 122.91905 -226.378817)
			(xy 122.966636 -226.36077) (xy 123.0165 -226.35059) (xy 123.067352 -226.348541) (xy 123.117873 -226.354675)
			(xy 123.166757 -226.368835) (xy 123.212736 -226.390652) (xy 123.25462 -226.419562) (xy 123.291324 -226.454817)
			(xy 123.321897 -226.495503) (xy 123.345548 -226.540566) (xy 123.361664 -226.58884) (xy 123.369828 -226.639074)
			(xy 123.37034 -226.66452) (xy 123.688868 -226.66452) (xy 123.692828 -226.615466) (xy 123.704605 -226.567682)
			(xy 123.723896 -226.522406) (xy 123.750199 -226.48081) (xy 123.782834 -226.443973) (xy 123.820955 -226.412848)
			(xy 123.863576 -226.388241) (xy 123.909592 -226.370789) (xy 123.957811 -226.360945) (xy 124.006986 -226.358964)
			(xy 124.055841 -226.364896) (xy 124.103112 -226.378588) (xy 124.147574 -226.399686) (xy 124.188077 -226.427642)
			(xy 124.22357 -226.461734) (xy 124.253135 -226.501078) (xy 124.276006 -226.544655) (xy 124.29159 -226.591336)
			(xy 124.299485 -226.639913) (xy 124.29998 -226.66452) (xy 124.618491 -226.66452) (xy 124.622586 -226.613792)
			(xy 124.634765 -226.564378) (xy 124.654713 -226.517558) (xy 124.681914 -226.474544) (xy 124.715662 -226.43645)
			(xy 124.755084 -226.404263) (xy 124.799158 -226.378817) (xy 124.846744 -226.36077) (xy 124.896608 -226.35059)
			(xy 124.94746 -226.348541) (xy 124.997981 -226.354675) (xy 125.046865 -226.368835) (xy 125.092844 -226.390652)
			(xy 125.134728 -226.419562) (xy 125.171432 -226.454817) (xy 125.202005 -226.495503) (xy 125.225656 -226.540566)
			(xy 125.241772 -226.58884) (xy 125.249936 -226.639074) (xy 125.250448 -226.66452) (xy 125.558545 -226.66452)
			(xy 125.56264 -226.613792) (xy 125.574819 -226.564378) (xy 125.594767 -226.517558) (xy 125.621968 -226.474544)
			(xy 125.655716 -226.43645) (xy 125.695138 -226.404263) (xy 125.739212 -226.378817) (xy 125.786798 -226.36077)
			(xy 125.836662 -226.35059) (xy 125.887514 -226.348541) (xy 125.938035 -226.354675) (xy 125.986919 -226.368835)
			(xy 126.032898 -226.390652) (xy 126.074782 -226.419562) (xy 126.111486 -226.454817) (xy 126.142059 -226.495503)
			(xy 126.16571 -226.540566) (xy 126.181826 -226.58884) (xy 126.18999 -226.639074) (xy 126.190502 -226.66452)
			(xy 126.50903 -226.66452) (xy 126.51299 -226.615466) (xy 126.524767 -226.567682) (xy 126.544058 -226.522406)
			(xy 126.570361 -226.48081) (xy 126.602996 -226.443973) (xy 126.641117 -226.412848) (xy 126.683738 -226.388241)
			(xy 126.729754 -226.370789) (xy 126.777973 -226.360945) (xy 126.827148 -226.358964) (xy 126.876003 -226.364896)
			(xy 126.923274 -226.378588) (xy 126.967736 -226.399686) (xy 127.008239 -226.427642) (xy 127.043732 -226.461734)
			(xy 127.073297 -226.501078) (xy 127.096168 -226.544655) (xy 127.111752 -226.591336) (xy 127.119647 -226.639913)
			(xy 127.120142 -226.66452) (xy 127.119647 -226.689127) (xy 127.111752 -226.737704) (xy 127.096168 -226.784385)
			(xy 127.073297 -226.827962) (xy 127.043732 -226.867306) (xy 127.008239 -226.901398) (xy 126.967736 -226.929354)
			(xy 126.923274 -226.950452) (xy 126.876003 -226.964144) (xy 126.827148 -226.970076) (xy 126.777973 -226.968095)
			(xy 126.729754 -226.958251) (xy 126.683738 -226.940799) (xy 126.641117 -226.916192) (xy 126.602996 -226.885067)
			(xy 126.570361 -226.84823) (xy 126.544058 -226.806634) (xy 126.524767 -226.761358) (xy 126.51299 -226.713574)
			(xy 126.50903 -226.66452) (xy 126.190502 -226.66452) (xy 126.18999 -226.689966) (xy 126.181826 -226.7402)
			(xy 126.16571 -226.788474) (xy 126.142059 -226.833537) (xy 126.111486 -226.874223) (xy 126.074782 -226.909478)
			(xy 126.032898 -226.938388) (xy 125.986919 -226.960205) (xy 125.938035 -226.974365) (xy 125.887514 -226.980499)
			(xy 125.836662 -226.97845) (xy 125.786798 -226.96827) (xy 125.739212 -226.950223) (xy 125.695138 -226.924777)
			(xy 125.655716 -226.89259) (xy 125.621968 -226.854496) (xy 125.594767 -226.811482) (xy 125.574819 -226.764662)
			(xy 125.56264 -226.715248) (xy 125.558545 -226.66452) (xy 125.250448 -226.66452) (xy 125.249936 -226.689966)
			(xy 125.241772 -226.7402) (xy 125.225656 -226.788474) (xy 125.202005 -226.833537) (xy 125.171432 -226.874223)
			(xy 125.134728 -226.909478) (xy 125.092844 -226.938388) (xy 125.046865 -226.960205) (xy 124.997981 -226.974365)
			(xy 124.94746 -226.980499) (xy 124.896608 -226.97845) (xy 124.846744 -226.96827) (xy 124.799158 -226.950223)
			(xy 124.755084 -226.924777) (xy 124.715662 -226.89259) (xy 124.681914 -226.854496) (xy 124.654713 -226.811482)
			(xy 124.634765 -226.764662) (xy 124.622586 -226.715248) (xy 124.618491 -226.66452) (xy 124.29998 -226.66452)
			(xy 124.299485 -226.689127) (xy 124.29159 -226.737704) (xy 124.276006 -226.784385) (xy 124.253135 -226.827962)
			(xy 124.22357 -226.867306) (xy 124.188077 -226.901398) (xy 124.147574 -226.929354) (xy 124.103112 -226.950452)
			(xy 124.055841 -226.964144) (xy 124.006986 -226.970076) (xy 123.957811 -226.968095) (xy 123.909592 -226.958251)
			(xy 123.863576 -226.940799) (xy 123.820955 -226.916192) (xy 123.782834 -226.885067) (xy 123.750199 -226.84823)
			(xy 123.723896 -226.806634) (xy 123.704605 -226.761358) (xy 123.692828 -226.713574) (xy 123.688868 -226.66452)
			(xy 123.37034 -226.66452) (xy 123.369828 -226.689966) (xy 123.361664 -226.7402) (xy 123.345548 -226.788474)
			(xy 123.321897 -226.833537) (xy 123.291324 -226.874223) (xy 123.25462 -226.909478) (xy 123.212736 -226.938388)
			(xy 123.166757 -226.960205) (xy 123.117873 -226.974365) (xy 123.067352 -226.980499) (xy 123.0165 -226.97845)
			(xy 122.966636 -226.96827) (xy 122.91905 -226.950223) (xy 122.874976 -226.924777) (xy 122.835554 -226.89259)
			(xy 122.801806 -226.854496) (xy 122.774605 -226.811482) (xy 122.754657 -226.764662) (xy 122.742478 -226.715248)
			(xy 122.738383 -226.66452) (xy 122.43054 -226.66452) (xy 122.430028 -226.689966) (xy 122.421864 -226.7402)
			(xy 122.405748 -226.788474) (xy 122.382097 -226.833537) (xy 122.351524 -226.874223) (xy 122.31482 -226.909478)
			(xy 122.272936 -226.938388) (xy 122.226957 -226.960205) (xy 122.178073 -226.974365) (xy 122.127552 -226.980499)
			(xy 122.0767 -226.97845) (xy 122.026836 -226.96827) (xy 121.97925 -226.950223) (xy 121.935176 -226.924777)
			(xy 121.895754 -226.89259) (xy 121.862006 -226.854496) (xy 121.834805 -226.811482) (xy 121.814857 -226.764662)
			(xy 121.802678 -226.715248) (xy 121.798583 -226.66452) (xy 121.480072 -226.66452) (xy 121.479577 -226.689127)
			(xy 121.471682 -226.737704) (xy 121.456098 -226.784385) (xy 121.433227 -226.827962) (xy 121.403662 -226.867306)
			(xy 121.368169 -226.901398) (xy 121.327666 -226.929354) (xy 121.283204 -226.950452) (xy 121.235933 -226.964144)
			(xy 121.187078 -226.970076) (xy 121.137903 -226.968095) (xy 121.089684 -226.958251) (xy 121.043668 -226.940799)
			(xy 121.001047 -226.916192) (xy 120.962926 -226.885067) (xy 120.930291 -226.84823) (xy 120.903988 -226.806634)
			(xy 120.884697 -226.761358) (xy 120.87292 -226.713574) (xy 120.86896 -226.66452) (xy 120.550432 -226.66452)
			(xy 120.54992 -226.689966) (xy 120.541756 -226.7402) (xy 120.52564 -226.788474) (xy 120.501989 -226.833537)
			(xy 120.471416 -226.874223) (xy 120.434712 -226.909478) (xy 120.392828 -226.938388) (xy 120.346849 -226.960205)
			(xy 120.297965 -226.974365) (xy 120.247444 -226.980499) (xy 120.196592 -226.97845) (xy 120.146728 -226.96827)
			(xy 120.099142 -226.950223) (xy 120.055068 -226.924777) (xy 120.015646 -226.89259) (xy 119.981898 -226.854496)
			(xy 119.954697 -226.811482) (xy 119.934749 -226.764662) (xy 119.92257 -226.715248) (xy 119.918475 -226.66452)
			(xy 119.610378 -226.66452) (xy 119.609866 -226.689966) (xy 119.601702 -226.7402) (xy 119.585586 -226.788474)
			(xy 119.561935 -226.833537) (xy 119.531362 -226.874223) (xy 119.494658 -226.909478) (xy 119.452774 -226.938388)
			(xy 119.406795 -226.960205) (xy 119.357911 -226.974365) (xy 119.30739 -226.980499) (xy 119.256538 -226.97845)
			(xy 119.206674 -226.96827) (xy 119.159088 -226.950223) (xy 119.115014 -226.924777) (xy 119.075592 -226.89259)
			(xy 119.041844 -226.854496) (xy 119.014643 -226.811482) (xy 118.994695 -226.764662) (xy 118.982516 -226.715248)
			(xy 118.978421 -226.66452) (xy 118.660164 -226.66452) (xy 118.659669 -226.689127) (xy 118.651774 -226.737704)
			(xy 118.63619 -226.784385) (xy 118.613319 -226.827962) (xy 118.583754 -226.867306) (xy 118.548261 -226.901398)
			(xy 118.507758 -226.929354) (xy 118.463296 -226.950452) (xy 118.416025 -226.964144) (xy 118.36717 -226.970076)
			(xy 118.317995 -226.968095) (xy 118.269776 -226.958251) (xy 118.22376 -226.940799) (xy 118.181139 -226.916192)
			(xy 118.143018 -226.885067) (xy 118.110383 -226.84823) (xy 118.08408 -226.806634) (xy 118.064789 -226.761358)
			(xy 118.053012 -226.713574) (xy 118.049052 -226.66452) (xy 117.730524 -226.66452) (xy 117.730012 -226.689966)
			(xy 117.721848 -226.7402) (xy 117.705732 -226.788474) (xy 117.682081 -226.833537) (xy 117.651508 -226.874223)
			(xy 117.614804 -226.909478) (xy 117.57292 -226.938388) (xy 117.526941 -226.960205) (xy 117.478057 -226.974365)
			(xy 117.427536 -226.980499) (xy 117.376684 -226.97845) (xy 117.32682 -226.96827) (xy 117.279234 -226.950223)
			(xy 117.23516 -226.924777) (xy 117.195738 -226.89259) (xy 117.16199 -226.854496) (xy 117.134789 -226.811482)
			(xy 117.114841 -226.764662) (xy 117.102662 -226.715248) (xy 117.098567 -226.66452) (xy 116.79047 -226.66452)
			(xy 116.789958 -226.689966) (xy 116.781794 -226.7402) (xy 116.765678 -226.788474) (xy 116.742027 -226.833537)
			(xy 116.711454 -226.874223) (xy 116.67475 -226.909478) (xy 116.632866 -226.938388) (xy 116.586887 -226.960205)
			(xy 116.538003 -226.974365) (xy 116.487482 -226.980499) (xy 116.43663 -226.97845) (xy 116.386766 -226.96827)
			(xy 116.33918 -226.950223) (xy 116.295106 -226.924777) (xy 116.255684 -226.89259) (xy 116.221936 -226.854496)
			(xy 116.194735 -226.811482) (xy 116.174787 -226.764662) (xy 116.162608 -226.715248) (xy 116.158513 -226.66452)
			(xy 115.840538 -226.66452) (xy 115.836369 -226.71484) (xy 115.823968 -226.763807) (xy 115.803677 -226.810065)
			(xy 115.776049 -226.852353) (xy 115.741837 -226.889516) (xy 115.701975 -226.920541) (xy 115.65755 -226.944582)
			(xy 115.609774 -226.960983) (xy 115.55995 -226.969296) (xy 115.534694 -226.969828) (xy 115.510202 -226.969349)
			(xy 115.461846 -226.961539) (xy 115.415358 -226.946103) (xy 115.371933 -226.923439) (xy 115.332687 -226.894129)
			(xy 115.298628 -226.858925) (xy 115.27063 -226.818732) (xy 115.259612 -226.796854) (xy 115.254024 -226.785424)
			(xy 115.234212 -226.770692) (xy 115.138962 -226.755706) (xy 115.126643 -226.754392) (xy 115.103225 -226.762395)
			(xy 115.094258 -226.770946) (xy 115.094004 -226.7712) (xy 115.062024 -226.804419) (xy 114.994157 -226.866859)
			(xy 114.922143 -226.924465) (xy 114.884454 -226.951032) (xy 114.872521 -226.95918) (xy 114.84813 -226.974677)
			(xy 114.835686 -226.98202) (xy 114.797586 -227.004372) (xy 114.782092 -227.013262) (xy 114.781838 -227.013516)
			(xy 114.739474 -227.037043) (xy 114.651926 -227.078605) (xy 114.56159 -227.113696) (xy 114.515392 -227.128324)
			(xy 114.50955 -227.130102) (xy 114.503708 -227.133404) (xy 114.493802 -227.141278) (xy 114.39144 -227.24364)
			(xy 114.385545 -227.249981) (xy 114.378022 -227.265562) (xy 114.376708 -227.27412) (xy 114.375946 -227.283264)
			(xy 114.391066 -227.304035) (xy 114.415084 -227.349447) (xy 114.431454 -227.398141) (xy 114.439745 -227.44884)
			(xy 114.440208 -227.474526) (xy 114.748559 -227.474526) (xy 114.752654 -227.423798) (xy 114.764833 -227.374384)
			(xy 114.784781 -227.327564) (xy 114.811982 -227.28455) (xy 114.84573 -227.246456) (xy 114.885152 -227.214269)
			(xy 114.929226 -227.188823) (xy 114.976812 -227.170776) (xy 115.026676 -227.160596) (xy 115.077528 -227.158547)
			(xy 115.128049 -227.164681) (xy 115.176933 -227.178841) (xy 115.222912 -227.200658) (xy 115.264796 -227.229568)
			(xy 115.3015 -227.264823) (xy 115.332073 -227.305509) (xy 115.355724 -227.350572) (xy 115.37184 -227.398846)
			(xy 115.380004 -227.44908) (xy 115.380516 -227.474526) (xy 115.699044 -227.474526) (xy 115.703004 -227.425472)
			(xy 115.714781 -227.377688) (xy 115.734072 -227.332412) (xy 115.760375 -227.290816) (xy 115.79301 -227.253979)
			(xy 115.831131 -227.222854) (xy 115.873752 -227.198247) (xy 115.919768 -227.180795) (xy 115.967987 -227.170951)
			(xy 116.017162 -227.16897) (xy 116.066017 -227.174902) (xy 116.113288 -227.188594) (xy 116.15775 -227.209692)
			(xy 116.198253 -227.237648) (xy 116.233746 -227.27174) (xy 116.263311 -227.311084) (xy 116.286182 -227.354661)
			(xy 116.301766 -227.401342) (xy 116.309661 -227.449919) (xy 116.310156 -227.474526) (xy 118.518952 -227.474526)
			(xy 118.522912 -227.425472) (xy 118.534689 -227.377688) (xy 118.55398 -227.332412) (xy 118.580283 -227.290816)
			(xy 118.612918 -227.253979) (xy 118.651039 -227.222854) (xy 118.69366 -227.198247) (xy 118.739676 -227.180795)
			(xy 118.787895 -227.170951) (xy 118.83707 -227.16897) (xy 118.885925 -227.174902) (xy 118.933196 -227.188594)
			(xy 118.977658 -227.209692) (xy 119.018161 -227.237648) (xy 119.053654 -227.27174) (xy 119.083219 -227.311084)
			(xy 119.10609 -227.354661) (xy 119.121674 -227.401342) (xy 119.129569 -227.449919) (xy 119.130064 -227.474526)
			(xy 121.33886 -227.474526) (xy 121.34282 -227.425472) (xy 121.354597 -227.377688) (xy 121.373888 -227.332412)
			(xy 121.400191 -227.290816) (xy 121.432826 -227.253979) (xy 121.470947 -227.222854) (xy 121.513568 -227.198247)
			(xy 121.559584 -227.180795) (xy 121.607803 -227.170951) (xy 121.656978 -227.16897) (xy 121.705833 -227.174902)
			(xy 121.753104 -227.188594) (xy 121.797566 -227.209692) (xy 121.838069 -227.237648) (xy 121.873562 -227.27174)
			(xy 121.903127 -227.311084) (xy 121.925998 -227.354661) (xy 121.941582 -227.401342) (xy 121.949477 -227.449919)
			(xy 121.949972 -227.474526) (xy 124.159022 -227.474526) (xy 124.162982 -227.425472) (xy 124.174759 -227.377688)
			(xy 124.19405 -227.332412) (xy 124.220353 -227.290816) (xy 124.252988 -227.253979) (xy 124.291109 -227.222854)
			(xy 124.33373 -227.198247) (xy 124.379746 -227.180795) (xy 124.427965 -227.170951) (xy 124.47714 -227.16897)
			(xy 124.525995 -227.174902) (xy 124.573266 -227.188594) (xy 124.617728 -227.209692) (xy 124.658231 -227.237648)
			(xy 124.693724 -227.27174) (xy 124.723289 -227.311084) (xy 124.74616 -227.354661) (xy 124.761744 -227.401342)
			(xy 124.769639 -227.449919) (xy 124.770134 -227.474526) (xy 124.769639 -227.499133) (xy 124.761744 -227.54771)
			(xy 124.74616 -227.594391) (xy 124.723289 -227.637968) (xy 124.693724 -227.677312) (xy 124.658231 -227.711404)
			(xy 124.617728 -227.73936) (xy 124.573266 -227.760458) (xy 124.525995 -227.77415) (xy 124.47714 -227.780082)
			(xy 124.427965 -227.778101) (xy 124.379746 -227.768257) (xy 124.33373 -227.750805) (xy 124.291109 -227.726198)
			(xy 124.252988 -227.695073) (xy 124.220353 -227.658236) (xy 124.19405 -227.61664) (xy 124.174759 -227.571364)
			(xy 124.162982 -227.52358) (xy 124.159022 -227.474526) (xy 121.949972 -227.474526) (xy 121.949477 -227.499133)
			(xy 121.941582 -227.54771) (xy 121.925998 -227.594391) (xy 121.903127 -227.637968) (xy 121.873562 -227.677312)
			(xy 121.838069 -227.711404) (xy 121.797566 -227.73936) (xy 121.753104 -227.760458) (xy 121.705833 -227.77415)
			(xy 121.656978 -227.780082) (xy 121.607803 -227.778101) (xy 121.559584 -227.768257) (xy 121.513568 -227.750805)
			(xy 121.470947 -227.726198) (xy 121.432826 -227.695073) (xy 121.400191 -227.658236) (xy 121.373888 -227.61664)
			(xy 121.354597 -227.571364) (xy 121.34282 -227.52358) (xy 121.33886 -227.474526) (xy 119.130064 -227.474526)
			(xy 119.129569 -227.499133) (xy 119.121674 -227.54771) (xy 119.10609 -227.594391) (xy 119.083219 -227.637968)
			(xy 119.053654 -227.677312) (xy 119.018161 -227.711404) (xy 118.977658 -227.73936) (xy 118.933196 -227.760458)
			(xy 118.885925 -227.77415) (xy 118.83707 -227.780082) (xy 118.787895 -227.778101) (xy 118.739676 -227.768257)
			(xy 118.69366 -227.750805) (xy 118.651039 -227.726198) (xy 118.612918 -227.695073) (xy 118.580283 -227.658236)
			(xy 118.55398 -227.61664) (xy 118.534689 -227.571364) (xy 118.522912 -227.52358) (xy 118.518952 -227.474526)
			(xy 116.310156 -227.474526) (xy 116.309661 -227.499133) (xy 116.301766 -227.54771) (xy 116.286182 -227.594391)
			(xy 116.263311 -227.637968) (xy 116.233746 -227.677312) (xy 116.198253 -227.711404) (xy 116.15775 -227.73936)
			(xy 116.113288 -227.760458) (xy 116.066017 -227.77415) (xy 116.017162 -227.780082) (xy 115.967987 -227.778101)
			(xy 115.919768 -227.768257) (xy 115.873752 -227.750805) (xy 115.831131 -227.726198) (xy 115.79301 -227.695073)
			(xy 115.760375 -227.658236) (xy 115.734072 -227.61664) (xy 115.714781 -227.571364) (xy 115.703004 -227.52358)
			(xy 115.699044 -227.474526) (xy 115.380516 -227.474526) (xy 115.380004 -227.499972) (xy 115.37184 -227.550206)
			(xy 115.355724 -227.59848) (xy 115.332073 -227.643543) (xy 115.3015 -227.684229) (xy 115.264796 -227.719484)
			(xy 115.222912 -227.748394) (xy 115.176933 -227.770211) (xy 115.128049 -227.784371) (xy 115.077528 -227.790505)
			(xy 115.026676 -227.788456) (xy 114.976812 -227.778276) (xy 114.929226 -227.760229) (xy 114.885152 -227.734783)
			(xy 114.84573 -227.702596) (xy 114.811982 -227.664502) (xy 114.784781 -227.621488) (xy 114.764833 -227.574668)
			(xy 114.752654 -227.525254) (xy 114.748559 -227.474526) (xy 114.440208 -227.474526) (xy 114.43972 -227.499321)
			(xy 114.431963 -227.548301) (xy 114.416643 -227.595466) (xy 114.394137 -227.639655) (xy 114.364998 -227.679782)
			(xy 114.329944 -227.714859) (xy 114.289837 -227.744025) (xy 114.245663 -227.76656) (xy 114.198509 -227.781913)
			(xy 114.149535 -227.789703) (xy 114.12474 -227.790248) (xy 114.101307 -227.789803) (xy 114.054961 -227.782844)
			(xy 114.01015 -227.769117) (xy 113.967857 -227.748923) (xy 113.94821 -227.736146) (xy 113.940631 -227.73144)
			(xy 113.923328 -227.727149) (xy 113.914428 -227.727764) (xy 113.906554 -227.728526) (xy 113.580926 -228.054154)
			(xy 113.574121 -228.061501) (xy 113.566404 -228.079964) (xy 113.56594 -228.089968) (xy 113.56594 -228.284532)
			(xy 115.22889 -228.284532) (xy 115.23285 -228.235478) (xy 115.244627 -228.187694) (xy 115.263918 -228.142418)
			(xy 115.290221 -228.100822) (xy 115.322856 -228.063985) (xy 115.360977 -228.03286) (xy 115.403598 -228.008253)
			(xy 115.449614 -227.990801) (xy 115.497833 -227.980957) (xy 115.547008 -227.978976) (xy 115.595863 -227.984908)
			(xy 115.643134 -227.9986) (xy 115.687596 -228.019698) (xy 115.728099 -228.047654) (xy 115.763592 -228.081746)
			(xy 115.793157 -228.12109) (xy 115.816028 -228.164667) (xy 115.831612 -228.211348) (xy 115.839507 -228.259925)
			(xy 115.840002 -228.284532) (xy 116.158513 -228.284532) (xy 116.162608 -228.233804) (xy 116.174787 -228.18439)
			(xy 116.194735 -228.13757) (xy 116.221936 -228.094556) (xy 116.255684 -228.056462) (xy 116.295106 -228.024275)
			(xy 116.33918 -227.998829) (xy 116.386766 -227.980782) (xy 116.43663 -227.970602) (xy 116.487482 -227.968553)
			(xy 116.538003 -227.974687) (xy 116.586887 -227.988847) (xy 116.632866 -228.010664) (xy 116.67475 -228.039574)
			(xy 116.711454 -228.074829) (xy 116.742027 -228.115515) (xy 116.765678 -228.160578) (xy 116.781794 -228.208852)
			(xy 116.789958 -228.259086) (xy 116.79047 -228.284532) (xy 117.098567 -228.284532) (xy 117.102662 -228.233804)
			(xy 117.114841 -228.18439) (xy 117.134789 -228.13757) (xy 117.16199 -228.094556) (xy 117.195738 -228.056462)
			(xy 117.23516 -228.024275) (xy 117.279234 -227.998829) (xy 117.32682 -227.980782) (xy 117.376684 -227.970602)
			(xy 117.427536 -227.968553) (xy 117.478057 -227.974687) (xy 117.526941 -227.988847) (xy 117.57292 -228.010664)
			(xy 117.614804 -228.039574) (xy 117.651508 -228.074829) (xy 117.682081 -228.115515) (xy 117.705732 -228.160578)
			(xy 117.721848 -228.208852) (xy 117.730012 -228.259086) (xy 117.730524 -228.284532) (xy 118.049052 -228.284532)
			(xy 118.053012 -228.235478) (xy 118.064789 -228.187694) (xy 118.08408 -228.142418) (xy 118.110383 -228.100822)
			(xy 118.143018 -228.063985) (xy 118.181139 -228.03286) (xy 118.22376 -228.008253) (xy 118.269776 -227.990801)
			(xy 118.317995 -227.980957) (xy 118.36717 -227.978976) (xy 118.416025 -227.984908) (xy 118.463296 -227.9986)
			(xy 118.507758 -228.019698) (xy 118.548261 -228.047654) (xy 118.583754 -228.081746) (xy 118.613319 -228.12109)
			(xy 118.63619 -228.164667) (xy 118.651774 -228.211348) (xy 118.659669 -228.259925) (xy 118.660164 -228.284532)
			(xy 118.978421 -228.284532) (xy 118.982516 -228.233804) (xy 118.994695 -228.18439) (xy 119.014643 -228.13757)
			(xy 119.041844 -228.094556) (xy 119.075592 -228.056462) (xy 119.115014 -228.024275) (xy 119.159088 -227.998829)
			(xy 119.206674 -227.980782) (xy 119.256538 -227.970602) (xy 119.30739 -227.968553) (xy 119.357911 -227.974687)
			(xy 119.406795 -227.988847) (xy 119.452774 -228.010664) (xy 119.494658 -228.039574) (xy 119.531362 -228.074829)
			(xy 119.561935 -228.115515) (xy 119.585586 -228.160578) (xy 119.601702 -228.208852) (xy 119.609866 -228.259086)
			(xy 119.610378 -228.284532) (xy 119.918475 -228.284532) (xy 119.92257 -228.233804) (xy 119.934749 -228.18439)
			(xy 119.954697 -228.13757) (xy 119.981898 -228.094556) (xy 120.015646 -228.056462) (xy 120.055068 -228.024275)
			(xy 120.099142 -227.998829) (xy 120.146728 -227.980782) (xy 120.196592 -227.970602) (xy 120.247444 -227.968553)
			(xy 120.297965 -227.974687) (xy 120.346849 -227.988847) (xy 120.392828 -228.010664) (xy 120.434712 -228.039574)
			(xy 120.471416 -228.074829) (xy 120.501989 -228.115515) (xy 120.52564 -228.160578) (xy 120.541756 -228.208852)
			(xy 120.54992 -228.259086) (xy 120.550432 -228.284532) (xy 120.86896 -228.284532) (xy 120.87292 -228.235478)
			(xy 120.884697 -228.187694) (xy 120.903988 -228.142418) (xy 120.930291 -228.100822) (xy 120.962926 -228.063985)
			(xy 121.001047 -228.03286) (xy 121.043668 -228.008253) (xy 121.089684 -227.990801) (xy 121.137903 -227.980957)
			(xy 121.187078 -227.978976) (xy 121.235933 -227.984908) (xy 121.283204 -227.9986) (xy 121.327666 -228.019698)
			(xy 121.368169 -228.047654) (xy 121.403662 -228.081746) (xy 121.433227 -228.12109) (xy 121.456098 -228.164667)
			(xy 121.471682 -228.211348) (xy 121.479577 -228.259925) (xy 121.480072 -228.284532) (xy 121.798583 -228.284532)
			(xy 121.802678 -228.233804) (xy 121.814857 -228.18439) (xy 121.834805 -228.13757) (xy 121.862006 -228.094556)
			(xy 121.895754 -228.056462) (xy 121.935176 -228.024275) (xy 121.97925 -227.998829) (xy 122.026836 -227.980782)
			(xy 122.0767 -227.970602) (xy 122.127552 -227.968553) (xy 122.178073 -227.974687) (xy 122.226957 -227.988847)
			(xy 122.272936 -228.010664) (xy 122.31482 -228.039574) (xy 122.351524 -228.074829) (xy 122.382097 -228.115515)
			(xy 122.405748 -228.160578) (xy 122.421864 -228.208852) (xy 122.430028 -228.259086) (xy 122.43054 -228.284532)
			(xy 122.738383 -228.284532) (xy 122.742478 -228.233804) (xy 122.754657 -228.18439) (xy 122.774605 -228.13757)
			(xy 122.801806 -228.094556) (xy 122.835554 -228.056462) (xy 122.874976 -228.024275) (xy 122.91905 -227.998829)
			(xy 122.966636 -227.980782) (xy 123.0165 -227.970602) (xy 123.067352 -227.968553) (xy 123.117873 -227.974687)
			(xy 123.166757 -227.988847) (xy 123.212736 -228.010664) (xy 123.25462 -228.039574) (xy 123.291324 -228.074829)
			(xy 123.321897 -228.115515) (xy 123.345548 -228.160578) (xy 123.361664 -228.208852) (xy 123.369828 -228.259086)
			(xy 123.37034 -228.284532) (xy 123.688868 -228.284532) (xy 123.692828 -228.235478) (xy 123.704605 -228.187694)
			(xy 123.723896 -228.142418) (xy 123.750199 -228.100822) (xy 123.782834 -228.063985) (xy 123.820955 -228.03286)
			(xy 123.863576 -228.008253) (xy 123.909592 -227.990801) (xy 123.957811 -227.980957) (xy 124.006986 -227.978976)
			(xy 124.055841 -227.984908) (xy 124.103112 -227.9986) (xy 124.147574 -228.019698) (xy 124.188077 -228.047654)
			(xy 124.22357 -228.081746) (xy 124.253135 -228.12109) (xy 124.276006 -228.164667) (xy 124.29159 -228.211348)
			(xy 124.299485 -228.259925) (xy 124.29998 -228.284532) (xy 124.618491 -228.284532) (xy 124.622586 -228.233804)
			(xy 124.634765 -228.18439) (xy 124.654713 -228.13757) (xy 124.681914 -228.094556) (xy 124.715662 -228.056462)
			(xy 124.755084 -228.024275) (xy 124.799158 -227.998829) (xy 124.846744 -227.980782) (xy 124.896608 -227.970602)
			(xy 124.94746 -227.968553) (xy 124.997981 -227.974687) (xy 125.046865 -227.988847) (xy 125.092844 -228.010664)
			(xy 125.134728 -228.039574) (xy 125.171432 -228.074829) (xy 125.202005 -228.115515) (xy 125.225656 -228.160578)
			(xy 125.241772 -228.208852) (xy 125.249936 -228.259086) (xy 125.250448 -228.284532) (xy 125.558545 -228.284532)
			(xy 125.56264 -228.233804) (xy 125.574819 -228.18439) (xy 125.594767 -228.13757) (xy 125.621968 -228.094556)
			(xy 125.655716 -228.056462) (xy 125.695138 -228.024275) (xy 125.739212 -227.998829) (xy 125.786798 -227.980782)
			(xy 125.836662 -227.970602) (xy 125.887514 -227.968553) (xy 125.938035 -227.974687) (xy 125.986919 -227.988847)
			(xy 126.032898 -228.010664) (xy 126.074782 -228.039574) (xy 126.111486 -228.074829) (xy 126.142059 -228.115515)
			(xy 126.16571 -228.160578) (xy 126.181826 -228.208852) (xy 126.18999 -228.259086) (xy 126.190502 -228.284532)
			(xy 126.18999 -228.309978) (xy 126.181826 -228.360212) (xy 126.16571 -228.408486) (xy 126.142059 -228.453549)
			(xy 126.111486 -228.494235) (xy 126.074782 -228.52949) (xy 126.032898 -228.5584) (xy 125.986919 -228.580217)
			(xy 125.938035 -228.594377) (xy 125.887514 -228.600511) (xy 125.836662 -228.598462) (xy 125.786798 -228.588282)
			(xy 125.739212 -228.570235) (xy 125.695138 -228.544789) (xy 125.655716 -228.512602) (xy 125.621968 -228.474508)
			(xy 125.594767 -228.431494) (xy 125.574819 -228.384674) (xy 125.56264 -228.33526) (xy 125.558545 -228.284532)
			(xy 125.250448 -228.284532) (xy 125.249936 -228.309978) (xy 125.241772 -228.360212) (xy 125.225656 -228.408486)
			(xy 125.202005 -228.453549) (xy 125.171432 -228.494235) (xy 125.134728 -228.52949) (xy 125.092844 -228.5584)
			(xy 125.046865 -228.580217) (xy 124.997981 -228.594377) (xy 124.94746 -228.600511) (xy 124.896608 -228.598462)
			(xy 124.846744 -228.588282) (xy 124.799158 -228.570235) (xy 124.755084 -228.544789) (xy 124.715662 -228.512602)
			(xy 124.681914 -228.474508) (xy 124.654713 -228.431494) (xy 124.634765 -228.384674) (xy 124.622586 -228.33526)
			(xy 124.618491 -228.284532) (xy 124.29998 -228.284532) (xy 124.299485 -228.309139) (xy 124.29159 -228.357716)
			(xy 124.276006 -228.404397) (xy 124.253135 -228.447974) (xy 124.22357 -228.487318) (xy 124.188077 -228.52141)
			(xy 124.147574 -228.549366) (xy 124.103112 -228.570464) (xy 124.055841 -228.584156) (xy 124.006986 -228.590088)
			(xy 123.957811 -228.588107) (xy 123.909592 -228.578263) (xy 123.863576 -228.560811) (xy 123.820955 -228.536204)
			(xy 123.782834 -228.505079) (xy 123.750199 -228.468242) (xy 123.723896 -228.426646) (xy 123.704605 -228.38137)
			(xy 123.692828 -228.333586) (xy 123.688868 -228.284532) (xy 123.37034 -228.284532) (xy 123.369828 -228.309978)
			(xy 123.361664 -228.360212) (xy 123.345548 -228.408486) (xy 123.321897 -228.453549) (xy 123.291324 -228.494235)
			(xy 123.25462 -228.52949) (xy 123.212736 -228.5584) (xy 123.166757 -228.580217) (xy 123.117873 -228.594377)
			(xy 123.067352 -228.600511) (xy 123.0165 -228.598462) (xy 122.966636 -228.588282) (xy 122.91905 -228.570235)
			(xy 122.874976 -228.544789) (xy 122.835554 -228.512602) (xy 122.801806 -228.474508) (xy 122.774605 -228.431494)
			(xy 122.754657 -228.384674) (xy 122.742478 -228.33526) (xy 122.738383 -228.284532) (xy 122.43054 -228.284532)
			(xy 122.430028 -228.309978) (xy 122.421864 -228.360212) (xy 122.405748 -228.408486) (xy 122.382097 -228.453549)
			(xy 122.351524 -228.494235) (xy 122.31482 -228.52949) (xy 122.272936 -228.5584) (xy 122.226957 -228.580217)
			(xy 122.178073 -228.594377) (xy 122.127552 -228.600511) (xy 122.0767 -228.598462) (xy 122.026836 -228.588282)
			(xy 121.97925 -228.570235) (xy 121.935176 -228.544789) (xy 121.895754 -228.512602) (xy 121.862006 -228.474508)
			(xy 121.834805 -228.431494) (xy 121.814857 -228.384674) (xy 121.802678 -228.33526) (xy 121.798583 -228.284532)
			(xy 121.480072 -228.284532) (xy 121.479577 -228.309139) (xy 121.471682 -228.357716) (xy 121.456098 -228.404397)
			(xy 121.433227 -228.447974) (xy 121.403662 -228.487318) (xy 121.368169 -228.52141) (xy 121.327666 -228.549366)
			(xy 121.283204 -228.570464) (xy 121.235933 -228.584156) (xy 121.187078 -228.590088) (xy 121.137903 -228.588107)
			(xy 121.089684 -228.578263) (xy 121.043668 -228.560811) (xy 121.001047 -228.536204) (xy 120.962926 -228.505079)
			(xy 120.930291 -228.468242) (xy 120.903988 -228.426646) (xy 120.884697 -228.38137) (xy 120.87292 -228.333586)
			(xy 120.86896 -228.284532) (xy 120.550432 -228.284532) (xy 120.54992 -228.309978) (xy 120.541756 -228.360212)
			(xy 120.52564 -228.408486) (xy 120.501989 -228.453549) (xy 120.471416 -228.494235) (xy 120.434712 -228.52949)
			(xy 120.392828 -228.5584) (xy 120.346849 -228.580217) (xy 120.297965 -228.594377) (xy 120.247444 -228.600511)
			(xy 120.196592 -228.598462) (xy 120.146728 -228.588282) (xy 120.099142 -228.570235) (xy 120.055068 -228.544789)
			(xy 120.015646 -228.512602) (xy 119.981898 -228.474508) (xy 119.954697 -228.431494) (xy 119.934749 -228.384674)
			(xy 119.92257 -228.33526) (xy 119.918475 -228.284532) (xy 119.610378 -228.284532) (xy 119.609866 -228.309978)
			(xy 119.601702 -228.360212) (xy 119.585586 -228.408486) (xy 119.561935 -228.453549) (xy 119.531362 -228.494235)
			(xy 119.494658 -228.52949) (xy 119.452774 -228.5584) (xy 119.406795 -228.580217) (xy 119.357911 -228.594377)
			(xy 119.30739 -228.600511) (xy 119.256538 -228.598462) (xy 119.206674 -228.588282) (xy 119.159088 -228.570235)
			(xy 119.115014 -228.544789) (xy 119.075592 -228.512602) (xy 119.041844 -228.474508) (xy 119.014643 -228.431494)
			(xy 118.994695 -228.384674) (xy 118.982516 -228.33526) (xy 118.978421 -228.284532) (xy 118.660164 -228.284532)
			(xy 118.659669 -228.309139) (xy 118.651774 -228.357716) (xy 118.63619 -228.404397) (xy 118.613319 -228.447974)
			(xy 118.583754 -228.487318) (xy 118.548261 -228.52141) (xy 118.507758 -228.549366) (xy 118.463296 -228.570464)
			(xy 118.416025 -228.584156) (xy 118.36717 -228.590088) (xy 118.317995 -228.588107) (xy 118.269776 -228.578263)
			(xy 118.22376 -228.560811) (xy 118.181139 -228.536204) (xy 118.143018 -228.505079) (xy 118.110383 -228.468242)
			(xy 118.08408 -228.426646) (xy 118.064789 -228.38137) (xy 118.053012 -228.333586) (xy 118.049052 -228.284532)
			(xy 117.730524 -228.284532) (xy 117.730012 -228.309978) (xy 117.721848 -228.360212) (xy 117.705732 -228.408486)
			(xy 117.682081 -228.453549) (xy 117.651508 -228.494235) (xy 117.614804 -228.52949) (xy 117.57292 -228.5584)
			(xy 117.526941 -228.580217) (xy 117.478057 -228.594377) (xy 117.427536 -228.600511) (xy 117.376684 -228.598462)
			(xy 117.32682 -228.588282) (xy 117.279234 -228.570235) (xy 117.23516 -228.544789) (xy 117.195738 -228.512602)
			(xy 117.16199 -228.474508) (xy 117.134789 -228.431494) (xy 117.114841 -228.384674) (xy 117.102662 -228.33526)
			(xy 117.098567 -228.284532) (xy 116.79047 -228.284532) (xy 116.789958 -228.309978) (xy 116.781794 -228.360212)
			(xy 116.765678 -228.408486) (xy 116.742027 -228.453549) (xy 116.711454 -228.494235) (xy 116.67475 -228.52949)
			(xy 116.632866 -228.5584) (xy 116.586887 -228.580217) (xy 116.538003 -228.594377) (xy 116.487482 -228.600511)
			(xy 116.43663 -228.598462) (xy 116.386766 -228.588282) (xy 116.33918 -228.570235) (xy 116.295106 -228.544789)
			(xy 116.255684 -228.512602) (xy 116.221936 -228.474508) (xy 116.194735 -228.431494) (xy 116.174787 -228.384674)
			(xy 116.162608 -228.33526) (xy 116.158513 -228.284532) (xy 115.840002 -228.284532) (xy 115.839507 -228.309139)
			(xy 115.831612 -228.357716) (xy 115.816028 -228.404397) (xy 115.793157 -228.447974) (xy 115.763592 -228.487318)
			(xy 115.728099 -228.52141) (xy 115.687596 -228.549366) (xy 115.643134 -228.570464) (xy 115.595863 -228.584156)
			(xy 115.547008 -228.590088) (xy 115.497833 -228.588107) (xy 115.449614 -228.578263) (xy 115.403598 -228.560811)
			(xy 115.360977 -228.536204) (xy 115.322856 -228.505079) (xy 115.290221 -228.468242) (xy 115.263918 -228.426646)
			(xy 115.244627 -228.38137) (xy 115.23285 -228.333586) (xy 115.22889 -228.284532) (xy 113.56594 -228.284532)
			(xy 113.56594 -229.094538) (xy 113.808505 -229.094538) (xy 113.8126 -229.04381) (xy 113.824779 -228.994396)
			(xy 113.844727 -228.947576) (xy 113.871928 -228.904562) (xy 113.905676 -228.866468) (xy 113.945098 -228.834281)
			(xy 113.989172 -228.808835) (xy 114.036758 -228.790788) (xy 114.086622 -228.780608) (xy 114.137474 -228.778559)
			(xy 114.187995 -228.784693) (xy 114.236879 -228.798853) (xy 114.282858 -228.82067) (xy 114.324742 -228.84958)
			(xy 114.361446 -228.884835) (xy 114.392019 -228.925521) (xy 114.41567 -228.970584) (xy 114.431786 -229.018858)
			(xy 114.43995 -229.069092) (xy 114.440462 -229.094538) (xy 114.748559 -229.094538) (xy 114.752654 -229.04381)
			(xy 114.764833 -228.994396) (xy 114.784781 -228.947576) (xy 114.811982 -228.904562) (xy 114.84573 -228.866468)
			(xy 114.885152 -228.834281) (xy 114.929226 -228.808835) (xy 114.976812 -228.790788) (xy 115.026676 -228.780608)
			(xy 115.077528 -228.778559) (xy 115.128049 -228.784693) (xy 115.176933 -228.798853) (xy 115.222912 -228.82067)
			(xy 115.264796 -228.84958) (xy 115.3015 -228.884835) (xy 115.332073 -228.925521) (xy 115.355724 -228.970584)
			(xy 115.37184 -229.018858) (xy 115.380004 -229.069092) (xy 115.380516 -229.094538) (xy 115.699044 -229.094538)
			(xy 115.703004 -229.045484) (xy 115.714781 -228.9977) (xy 115.734072 -228.952424) (xy 115.760375 -228.910828)
			(xy 115.79301 -228.873991) (xy 115.831131 -228.842866) (xy 115.873752 -228.818259) (xy 115.919768 -228.800807)
			(xy 115.967987 -228.790963) (xy 116.017162 -228.788982) (xy 116.066017 -228.794914) (xy 116.113288 -228.808606)
			(xy 116.15775 -228.829704) (xy 116.198253 -228.85766) (xy 116.233746 -228.891752) (xy 116.263311 -228.931096)
			(xy 116.286182 -228.974673) (xy 116.301766 -229.021354) (xy 116.309661 -229.069931) (xy 116.310156 -229.094538)
			(xy 116.638844 -229.094538) (xy 116.642804 -229.045484) (xy 116.654581 -228.9977) (xy 116.673872 -228.952424)
			(xy 116.700175 -228.910828) (xy 116.73281 -228.873991) (xy 116.770931 -228.842866) (xy 116.813552 -228.818259)
			(xy 116.859568 -228.800807) (xy 116.907787 -228.790963) (xy 116.956962 -228.788982) (xy 117.005817 -228.794914)
			(xy 117.053088 -228.808606) (xy 117.09755 -228.829704) (xy 117.138053 -228.85766) (xy 117.173546 -228.891752)
			(xy 117.203111 -228.931096) (xy 117.225982 -228.974673) (xy 117.241566 -229.021354) (xy 117.249461 -229.069931)
			(xy 117.249956 -229.094538) (xy 117.578898 -229.094538) (xy 117.582858 -229.045484) (xy 117.594635 -228.9977)
			(xy 117.613926 -228.952424) (xy 117.640229 -228.910828) (xy 117.672864 -228.873991) (xy 117.710985 -228.842866)
			(xy 117.753606 -228.818259) (xy 117.799622 -228.800807) (xy 117.847841 -228.790963) (xy 117.897016 -228.788982)
			(xy 117.945871 -228.794914) (xy 117.993142 -228.808606) (xy 118.037604 -228.829704) (xy 118.078107 -228.85766)
			(xy 118.1136 -228.891752) (xy 118.143165 -228.931096) (xy 118.166036 -228.974673) (xy 118.18162 -229.021354)
			(xy 118.189515 -229.069931) (xy 118.19001 -229.094538) (xy 118.518952 -229.094538) (xy 118.522912 -229.045484)
			(xy 118.534689 -228.9977) (xy 118.55398 -228.952424) (xy 118.580283 -228.910828) (xy 118.612918 -228.873991)
			(xy 118.651039 -228.842866) (xy 118.69366 -228.818259) (xy 118.739676 -228.800807) (xy 118.787895 -228.790963)
			(xy 118.83707 -228.788982) (xy 118.885925 -228.794914) (xy 118.933196 -228.808606) (xy 118.977658 -228.829704)
			(xy 119.018161 -228.85766) (xy 119.053654 -228.891752) (xy 119.083219 -228.931096) (xy 119.10609 -228.974673)
			(xy 119.121674 -229.021354) (xy 119.129569 -229.069931) (xy 119.130064 -229.094538) (xy 119.459006 -229.094538)
			(xy 119.462966 -229.045484) (xy 119.474743 -228.9977) (xy 119.494034 -228.952424) (xy 119.520337 -228.910828)
			(xy 119.552972 -228.873991) (xy 119.591093 -228.842866) (xy 119.633714 -228.818259) (xy 119.67973 -228.800807)
			(xy 119.727949 -228.790963) (xy 119.777124 -228.788982) (xy 119.825979 -228.794914) (xy 119.87325 -228.808606)
			(xy 119.917712 -228.829704) (xy 119.958215 -228.85766) (xy 119.993708 -228.891752) (xy 120.023273 -228.931096)
			(xy 120.046144 -228.974673) (xy 120.061728 -229.021354) (xy 120.069623 -229.069931) (xy 120.070118 -229.094538)
			(xy 120.398806 -229.094538) (xy 120.402766 -229.045484) (xy 120.414543 -228.9977) (xy 120.433834 -228.952424)
			(xy 120.460137 -228.910828) (xy 120.492772 -228.873991) (xy 120.530893 -228.842866) (xy 120.573514 -228.818259)
			(xy 120.61953 -228.800807) (xy 120.667749 -228.790963) (xy 120.716924 -228.788982) (xy 120.765779 -228.794914)
			(xy 120.81305 -228.808606) (xy 120.857512 -228.829704) (xy 120.898015 -228.85766) (xy 120.933508 -228.891752)
			(xy 120.963073 -228.931096) (xy 120.985944 -228.974673) (xy 121.001528 -229.021354) (xy 121.009423 -229.069931)
			(xy 121.009918 -229.094538) (xy 121.33886 -229.094538) (xy 121.34282 -229.045484) (xy 121.354597 -228.9977)
			(xy 121.373888 -228.952424) (xy 121.400191 -228.910828) (xy 121.432826 -228.873991) (xy 121.470947 -228.842866)
			(xy 121.513568 -228.818259) (xy 121.559584 -228.800807) (xy 121.607803 -228.790963) (xy 121.656978 -228.788982)
			(xy 121.705833 -228.794914) (xy 121.753104 -228.808606) (xy 121.797566 -228.829704) (xy 121.838069 -228.85766)
			(xy 121.873562 -228.891752) (xy 121.903127 -228.931096) (xy 121.925998 -228.974673) (xy 121.941582 -229.021354)
			(xy 121.949477 -229.069931) (xy 121.949972 -229.094538) (xy 122.278914 -229.094538) (xy 122.282874 -229.045484)
			(xy 122.294651 -228.9977) (xy 122.313942 -228.952424) (xy 122.340245 -228.910828) (xy 122.37288 -228.873991)
			(xy 122.411001 -228.842866) (xy 122.453622 -228.818259) (xy 122.499638 -228.800807) (xy 122.547857 -228.790963)
			(xy 122.597032 -228.788982) (xy 122.645887 -228.794914) (xy 122.693158 -228.808606) (xy 122.73762 -228.829704)
			(xy 122.778123 -228.85766) (xy 122.813616 -228.891752) (xy 122.843181 -228.931096) (xy 122.866052 -228.974673)
			(xy 122.881636 -229.021354) (xy 122.889531 -229.069931) (xy 122.890026 -229.094538) (xy 123.218968 -229.094538)
			(xy 123.222928 -229.045484) (xy 123.234705 -228.9977) (xy 123.253996 -228.952424) (xy 123.280299 -228.910828)
			(xy 123.312934 -228.873991) (xy 123.351055 -228.842866) (xy 123.393676 -228.818259) (xy 123.439692 -228.800807)
			(xy 123.487911 -228.790963) (xy 123.537086 -228.788982) (xy 123.585941 -228.794914) (xy 123.633212 -228.808606)
			(xy 123.677674 -228.829704) (xy 123.718177 -228.85766) (xy 123.75367 -228.891752) (xy 123.783235 -228.931096)
			(xy 123.806106 -228.974673) (xy 123.82169 -229.021354) (xy 123.829585 -229.069931) (xy 123.83008 -229.094538)
			(xy 124.159022 -229.094538) (xy 124.162982 -229.045484) (xy 124.174759 -228.9977) (xy 124.19405 -228.952424)
			(xy 124.220353 -228.910828) (xy 124.252988 -228.873991) (xy 124.291109 -228.842866) (xy 124.33373 -228.818259)
			(xy 124.379746 -228.800807) (xy 124.427965 -228.790963) (xy 124.47714 -228.788982) (xy 124.525995 -228.794914)
			(xy 124.573266 -228.808606) (xy 124.617728 -228.829704) (xy 124.658231 -228.85766) (xy 124.693724 -228.891752)
			(xy 124.723289 -228.931096) (xy 124.74616 -228.974673) (xy 124.761744 -229.021354) (xy 124.769639 -229.069931)
			(xy 124.770134 -229.094538) (xy 125.098822 -229.094538) (xy 125.102782 -229.045484) (xy 125.114559 -228.9977)
			(xy 125.13385 -228.952424) (xy 125.160153 -228.910828) (xy 125.192788 -228.873991) (xy 125.230909 -228.842866)
			(xy 125.27353 -228.818259) (xy 125.319546 -228.800807) (xy 125.367765 -228.790963) (xy 125.41694 -228.788982)
			(xy 125.465795 -228.794914) (xy 125.513066 -228.808606) (xy 125.557528 -228.829704) (xy 125.598031 -228.85766)
			(xy 125.633524 -228.891752) (xy 125.663089 -228.931096) (xy 125.68596 -228.974673) (xy 125.701544 -229.021354)
			(xy 125.709439 -229.069931) (xy 125.709934 -229.094538) (xy 125.709439 -229.119145) (xy 125.701544 -229.167722)
			(xy 125.68596 -229.214403) (xy 125.663089 -229.25798) (xy 125.633524 -229.297324) (xy 125.598031 -229.331416)
			(xy 125.557528 -229.359372) (xy 125.513066 -229.38047) (xy 125.465795 -229.394162) (xy 125.41694 -229.400094)
			(xy 125.367765 -229.398113) (xy 125.319546 -229.388269) (xy 125.27353 -229.370817) (xy 125.230909 -229.34621)
			(xy 125.192788 -229.315085) (xy 125.160153 -229.278248) (xy 125.13385 -229.236652) (xy 125.114559 -229.191376)
			(xy 125.102782 -229.143592) (xy 125.098822 -229.094538) (xy 124.770134 -229.094538) (xy 124.769639 -229.119145)
			(xy 124.761744 -229.167722) (xy 124.74616 -229.214403) (xy 124.723289 -229.25798) (xy 124.693724 -229.297324)
			(xy 124.658231 -229.331416) (xy 124.617728 -229.359372) (xy 124.573266 -229.38047) (xy 124.525995 -229.394162)
			(xy 124.47714 -229.400094) (xy 124.427965 -229.398113) (xy 124.379746 -229.388269) (xy 124.33373 -229.370817)
			(xy 124.291109 -229.34621) (xy 124.252988 -229.315085) (xy 124.220353 -229.278248) (xy 124.19405 -229.236652)
			(xy 124.174759 -229.191376) (xy 124.162982 -229.143592) (xy 124.159022 -229.094538) (xy 123.83008 -229.094538)
			(xy 123.829585 -229.119145) (xy 123.82169 -229.167722) (xy 123.806106 -229.214403) (xy 123.783235 -229.25798)
			(xy 123.75367 -229.297324) (xy 123.718177 -229.331416) (xy 123.677674 -229.359372) (xy 123.633212 -229.38047)
			(xy 123.585941 -229.394162) (xy 123.537086 -229.400094) (xy 123.487911 -229.398113) (xy 123.439692 -229.388269)
			(xy 123.393676 -229.370817) (xy 123.351055 -229.34621) (xy 123.312934 -229.315085) (xy 123.280299 -229.278248)
			(xy 123.253996 -229.236652) (xy 123.234705 -229.191376) (xy 123.222928 -229.143592) (xy 123.218968 -229.094538)
			(xy 122.890026 -229.094538) (xy 122.889531 -229.119145) (xy 122.881636 -229.167722) (xy 122.866052 -229.214403)
			(xy 122.843181 -229.25798) (xy 122.813616 -229.297324) (xy 122.778123 -229.331416) (xy 122.73762 -229.359372)
			(xy 122.693158 -229.38047) (xy 122.645887 -229.394162) (xy 122.597032 -229.400094) (xy 122.547857 -229.398113)
			(xy 122.499638 -229.388269) (xy 122.453622 -229.370817) (xy 122.411001 -229.34621) (xy 122.37288 -229.315085)
			(xy 122.340245 -229.278248) (xy 122.313942 -229.236652) (xy 122.294651 -229.191376) (xy 122.282874 -229.143592)
			(xy 122.278914 -229.094538) (xy 121.949972 -229.094538) (xy 121.949477 -229.119145) (xy 121.941582 -229.167722)
			(xy 121.925998 -229.214403) (xy 121.903127 -229.25798) (xy 121.873562 -229.297324) (xy 121.838069 -229.331416)
			(xy 121.797566 -229.359372) (xy 121.753104 -229.38047) (xy 121.705833 -229.394162) (xy 121.656978 -229.400094)
			(xy 121.607803 -229.398113) (xy 121.559584 -229.388269) (xy 121.513568 -229.370817) (xy 121.470947 -229.34621)
			(xy 121.432826 -229.315085) (xy 121.400191 -229.278248) (xy 121.373888 -229.236652) (xy 121.354597 -229.191376)
			(xy 121.34282 -229.143592) (xy 121.33886 -229.094538) (xy 121.009918 -229.094538) (xy 121.009423 -229.119145)
			(xy 121.001528 -229.167722) (xy 120.985944 -229.214403) (xy 120.963073 -229.25798) (xy 120.933508 -229.297324)
			(xy 120.898015 -229.331416) (xy 120.857512 -229.359372) (xy 120.81305 -229.38047) (xy 120.765779 -229.394162)
			(xy 120.716924 -229.400094) (xy 120.667749 -229.398113) (xy 120.61953 -229.388269) (xy 120.573514 -229.370817)
			(xy 120.530893 -229.34621) (xy 120.492772 -229.315085) (xy 120.460137 -229.278248) (xy 120.433834 -229.236652)
			(xy 120.414543 -229.191376) (xy 120.402766 -229.143592) (xy 120.398806 -229.094538) (xy 120.070118 -229.094538)
			(xy 120.069623 -229.119145) (xy 120.061728 -229.167722) (xy 120.046144 -229.214403) (xy 120.023273 -229.25798)
			(xy 119.993708 -229.297324) (xy 119.958215 -229.331416) (xy 119.917712 -229.359372) (xy 119.87325 -229.38047)
			(xy 119.825979 -229.394162) (xy 119.777124 -229.400094) (xy 119.727949 -229.398113) (xy 119.67973 -229.388269)
			(xy 119.633714 -229.370817) (xy 119.591093 -229.34621) (xy 119.552972 -229.315085) (xy 119.520337 -229.278248)
			(xy 119.494034 -229.236652) (xy 119.474743 -229.191376) (xy 119.462966 -229.143592) (xy 119.459006 -229.094538)
			(xy 119.130064 -229.094538) (xy 119.129569 -229.119145) (xy 119.121674 -229.167722) (xy 119.10609 -229.214403)
			(xy 119.083219 -229.25798) (xy 119.053654 -229.297324) (xy 119.018161 -229.331416) (xy 118.977658 -229.359372)
			(xy 118.933196 -229.38047) (xy 118.885925 -229.394162) (xy 118.83707 -229.400094) (xy 118.787895 -229.398113)
			(xy 118.739676 -229.388269) (xy 118.69366 -229.370817) (xy 118.651039 -229.34621) (xy 118.612918 -229.315085)
			(xy 118.580283 -229.278248) (xy 118.55398 -229.236652) (xy 118.534689 -229.191376) (xy 118.522912 -229.143592)
			(xy 118.518952 -229.094538) (xy 118.19001 -229.094538) (xy 118.189515 -229.119145) (xy 118.18162 -229.167722)
			(xy 118.166036 -229.214403) (xy 118.143165 -229.25798) (xy 118.1136 -229.297324) (xy 118.078107 -229.331416)
			(xy 118.037604 -229.359372) (xy 117.993142 -229.38047) (xy 117.945871 -229.394162) (xy 117.897016 -229.400094)
			(xy 117.847841 -229.398113) (xy 117.799622 -229.388269) (xy 117.753606 -229.370817) (xy 117.710985 -229.34621)
			(xy 117.672864 -229.315085) (xy 117.640229 -229.278248) (xy 117.613926 -229.236652) (xy 117.594635 -229.191376)
			(xy 117.582858 -229.143592) (xy 117.578898 -229.094538) (xy 117.249956 -229.094538) (xy 117.249461 -229.119145)
			(xy 117.241566 -229.167722) (xy 117.225982 -229.214403) (xy 117.203111 -229.25798) (xy 117.173546 -229.297324)
			(xy 117.138053 -229.331416) (xy 117.09755 -229.359372) (xy 117.053088 -229.38047) (xy 117.005817 -229.394162)
			(xy 116.956962 -229.400094) (xy 116.907787 -229.398113) (xy 116.859568 -229.388269) (xy 116.813552 -229.370817)
			(xy 116.770931 -229.34621) (xy 116.73281 -229.315085) (xy 116.700175 -229.278248) (xy 116.673872 -229.236652)
			(xy 116.654581 -229.191376) (xy 116.642804 -229.143592) (xy 116.638844 -229.094538) (xy 116.310156 -229.094538)
			(xy 116.309661 -229.119145) (xy 116.301766 -229.167722) (xy 116.286182 -229.214403) (xy 116.263311 -229.25798)
			(xy 116.233746 -229.297324) (xy 116.198253 -229.331416) (xy 116.15775 -229.359372) (xy 116.113288 -229.38047)
			(xy 116.066017 -229.394162) (xy 116.017162 -229.400094) (xy 115.967987 -229.398113) (xy 115.919768 -229.388269)
			(xy 115.873752 -229.370817) (xy 115.831131 -229.34621) (xy 115.79301 -229.315085) (xy 115.760375 -229.278248)
			(xy 115.734072 -229.236652) (xy 115.714781 -229.191376) (xy 115.703004 -229.143592) (xy 115.699044 -229.094538)
			(xy 115.380516 -229.094538) (xy 115.380004 -229.119984) (xy 115.37184 -229.170218) (xy 115.355724 -229.218492)
			(xy 115.332073 -229.263555) (xy 115.3015 -229.304241) (xy 115.264796 -229.339496) (xy 115.222912 -229.368406)
			(xy 115.176933 -229.390223) (xy 115.128049 -229.404383) (xy 115.077528 -229.410517) (xy 115.026676 -229.408468)
			(xy 114.976812 -229.398288) (xy 114.929226 -229.380241) (xy 114.885152 -229.354795) (xy 114.84573 -229.322608)
			(xy 114.811982 -229.284514) (xy 114.784781 -229.2415) (xy 114.764833 -229.19468) (xy 114.752654 -229.145266)
			(xy 114.748559 -229.094538) (xy 114.440462 -229.094538) (xy 114.43995 -229.119984) (xy 114.431786 -229.170218)
			(xy 114.41567 -229.218492) (xy 114.392019 -229.263555) (xy 114.361446 -229.304241) (xy 114.324742 -229.339496)
			(xy 114.282858 -229.368406) (xy 114.236879 -229.390223) (xy 114.187995 -229.404383) (xy 114.137474 -229.410517)
			(xy 114.086622 -229.408468) (xy 114.036758 -229.398288) (xy 113.989172 -229.380241) (xy 113.945098 -229.354795)
			(xy 113.905676 -229.322608) (xy 113.871928 -229.284514) (xy 113.844727 -229.2415) (xy 113.824779 -229.19468)
			(xy 113.8126 -229.145266) (xy 113.808505 -229.094538) (xy 113.56594 -229.094538) (xy 113.56594 -229.497636)
			(xy 113.566449 -229.507442) (xy 113.573911 -229.525586) (xy 113.580418 -229.532942) (xy 113.629694 -229.583742)
			(xy 113.63319 -229.587198) (xy 113.641249 -229.592824) (xy 113.645696 -229.594918) (xy 113.655094 -229.598982)
			(xy 113.67907 -229.599475) (xy 113.726427 -229.607017) (xy 113.772023 -229.62187) (xy 113.814735 -229.643669)
			(xy 113.853515 -229.671878) (xy 113.887407 -229.705802) (xy 113.915579 -229.744607) (xy 113.937339 -229.78734)
			(xy 113.952149 -229.832949) (xy 113.959648 -229.880313) (xy 113.960148 -229.90429) (xy 114.288836 -229.90429)
			(xy 114.292796 -229.855236) (xy 114.304573 -229.807452) (xy 114.323864 -229.762176) (xy 114.350167 -229.72058)
			(xy 114.382802 -229.683743) (xy 114.420923 -229.652618) (xy 114.463544 -229.628011) (xy 114.50956 -229.610559)
			(xy 114.557779 -229.600715) (xy 114.606954 -229.598734) (xy 114.655809 -229.604666) (xy 114.70308 -229.618358)
			(xy 114.747542 -229.639456) (xy 114.788045 -229.667412) (xy 114.823538 -229.701504) (xy 114.853103 -229.740848)
			(xy 114.875974 -229.784425) (xy 114.891558 -229.831106) (xy 114.899453 -229.879683) (xy 114.899948 -229.90429)
			(xy 115.22889 -229.90429) (xy 115.23285 -229.855236) (xy 115.244627 -229.807452) (xy 115.263918 -229.762176)
			(xy 115.290221 -229.72058) (xy 115.322856 -229.683743) (xy 115.360977 -229.652618) (xy 115.403598 -229.628011)
			(xy 115.449614 -229.610559) (xy 115.497833 -229.600715) (xy 115.547008 -229.598734) (xy 115.595863 -229.604666)
			(xy 115.643134 -229.618358) (xy 115.687596 -229.639456) (xy 115.728099 -229.667412) (xy 115.763592 -229.701504)
			(xy 115.793157 -229.740848) (xy 115.816028 -229.784425) (xy 115.831612 -229.831106) (xy 115.839507 -229.879683)
			(xy 115.840002 -229.90429) (xy 116.158513 -229.90429) (xy 116.162608 -229.853562) (xy 116.174787 -229.804148)
			(xy 116.194735 -229.757328) (xy 116.221936 -229.714314) (xy 116.255684 -229.67622) (xy 116.295106 -229.644033)
			(xy 116.33918 -229.618587) (xy 116.386766 -229.60054) (xy 116.43663 -229.59036) (xy 116.487482 -229.588311)
			(xy 116.538003 -229.594445) (xy 116.586887 -229.608605) (xy 116.632866 -229.630422) (xy 116.67475 -229.659332)
			(xy 116.711454 -229.694587) (xy 116.742027 -229.735273) (xy 116.765678 -229.780336) (xy 116.781794 -229.82861)
			(xy 116.789958 -229.878844) (xy 116.79047 -229.90429) (xy 117.098567 -229.90429) (xy 117.102662 -229.853562)
			(xy 117.114841 -229.804148) (xy 117.134789 -229.757328) (xy 117.16199 -229.714314) (xy 117.195738 -229.67622)
			(xy 117.23516 -229.644033) (xy 117.279234 -229.618587) (xy 117.32682 -229.60054) (xy 117.376684 -229.59036)
			(xy 117.427536 -229.588311) (xy 117.478057 -229.594445) (xy 117.526941 -229.608605) (xy 117.57292 -229.630422)
			(xy 117.614804 -229.659332) (xy 117.651508 -229.694587) (xy 117.682081 -229.735273) (xy 117.705732 -229.780336)
			(xy 117.721848 -229.82861) (xy 117.730012 -229.878844) (xy 117.730524 -229.90429) (xy 118.049052 -229.90429)
			(xy 118.053012 -229.855236) (xy 118.064789 -229.807452) (xy 118.08408 -229.762176) (xy 118.110383 -229.72058)
			(xy 118.143018 -229.683743) (xy 118.181139 -229.652618) (xy 118.22376 -229.628011) (xy 118.269776 -229.610559)
			(xy 118.317995 -229.600715) (xy 118.36717 -229.598734) (xy 118.416025 -229.604666) (xy 118.463296 -229.618358)
			(xy 118.507758 -229.639456) (xy 118.548261 -229.667412) (xy 118.583754 -229.701504) (xy 118.613319 -229.740848)
			(xy 118.63619 -229.784425) (xy 118.651774 -229.831106) (xy 118.659669 -229.879683) (xy 118.660164 -229.90429)
			(xy 118.978421 -229.90429) (xy 118.982516 -229.853562) (xy 118.994695 -229.804148) (xy 119.014643 -229.757328)
			(xy 119.041844 -229.714314) (xy 119.075592 -229.67622) (xy 119.115014 -229.644033) (xy 119.159088 -229.618587)
			(xy 119.206674 -229.60054) (xy 119.256538 -229.59036) (xy 119.30739 -229.588311) (xy 119.357911 -229.594445)
			(xy 119.406795 -229.608605) (xy 119.452774 -229.630422) (xy 119.494658 -229.659332) (xy 119.531362 -229.694587)
			(xy 119.561935 -229.735273) (xy 119.585586 -229.780336) (xy 119.601702 -229.82861) (xy 119.609866 -229.878844)
			(xy 119.610378 -229.90429) (xy 119.918475 -229.90429) (xy 119.92257 -229.853562) (xy 119.934749 -229.804148)
			(xy 119.954697 -229.757328) (xy 119.981898 -229.714314) (xy 120.015646 -229.67622) (xy 120.055068 -229.644033)
			(xy 120.099142 -229.618587) (xy 120.146728 -229.60054) (xy 120.196592 -229.59036) (xy 120.247444 -229.588311)
			(xy 120.297965 -229.594445) (xy 120.346849 -229.608605) (xy 120.392828 -229.630422) (xy 120.434712 -229.659332)
			(xy 120.471416 -229.694587) (xy 120.501989 -229.735273) (xy 120.52564 -229.780336) (xy 120.541756 -229.82861)
			(xy 120.54992 -229.878844) (xy 120.550432 -229.90429) (xy 120.86896 -229.90429) (xy 120.87292 -229.855236)
			(xy 120.884697 -229.807452) (xy 120.903988 -229.762176) (xy 120.930291 -229.72058) (xy 120.962926 -229.683743)
			(xy 121.001047 -229.652618) (xy 121.043668 -229.628011) (xy 121.089684 -229.610559) (xy 121.137903 -229.600715)
			(xy 121.187078 -229.598734) (xy 121.235933 -229.604666) (xy 121.283204 -229.618358) (xy 121.327666 -229.639456)
			(xy 121.368169 -229.667412) (xy 121.403662 -229.701504) (xy 121.433227 -229.740848) (xy 121.456098 -229.784425)
			(xy 121.471682 -229.831106) (xy 121.479577 -229.879683) (xy 121.480072 -229.90429) (xy 121.798583 -229.90429)
			(xy 121.802678 -229.853562) (xy 121.814857 -229.804148) (xy 121.834805 -229.757328) (xy 121.862006 -229.714314)
			(xy 121.895754 -229.67622) (xy 121.935176 -229.644033) (xy 121.97925 -229.618587) (xy 122.026836 -229.60054)
			(xy 122.0767 -229.59036) (xy 122.127552 -229.588311) (xy 122.178073 -229.594445) (xy 122.226957 -229.608605)
			(xy 122.272936 -229.630422) (xy 122.31482 -229.659332) (xy 122.351524 -229.694587) (xy 122.382097 -229.735273)
			(xy 122.405748 -229.780336) (xy 122.421864 -229.82861) (xy 122.430028 -229.878844) (xy 122.43054 -229.90429)
			(xy 122.738383 -229.90429) (xy 122.742478 -229.853562) (xy 122.754657 -229.804148) (xy 122.774605 -229.757328)
			(xy 122.801806 -229.714314) (xy 122.835554 -229.67622) (xy 122.874976 -229.644033) (xy 122.91905 -229.618587)
			(xy 122.966636 -229.60054) (xy 123.0165 -229.59036) (xy 123.067352 -229.588311) (xy 123.117873 -229.594445)
			(xy 123.166757 -229.608605) (xy 123.212736 -229.630422) (xy 123.25462 -229.659332) (xy 123.291324 -229.694587)
			(xy 123.321897 -229.735273) (xy 123.345548 -229.780336) (xy 123.361664 -229.82861) (xy 123.369828 -229.878844)
			(xy 123.37034 -229.90429) (xy 123.688868 -229.90429) (xy 123.692828 -229.855236) (xy 123.704605 -229.807452)
			(xy 123.723896 -229.762176) (xy 123.750199 -229.72058) (xy 123.782834 -229.683743) (xy 123.820955 -229.652618)
			(xy 123.863576 -229.628011) (xy 123.909592 -229.610559) (xy 123.957811 -229.600715) (xy 124.006986 -229.598734)
			(xy 124.055841 -229.604666) (xy 124.103112 -229.618358) (xy 124.147574 -229.639456) (xy 124.188077 -229.667412)
			(xy 124.22357 -229.701504) (xy 124.253135 -229.740848) (xy 124.276006 -229.784425) (xy 124.29159 -229.831106)
			(xy 124.299485 -229.879683) (xy 124.29998 -229.90429) (xy 124.618491 -229.90429) (xy 124.622586 -229.853562)
			(xy 124.634765 -229.804148) (xy 124.654713 -229.757328) (xy 124.681914 -229.714314) (xy 124.715662 -229.67622)
			(xy 124.755084 -229.644033) (xy 124.799158 -229.618587) (xy 124.846744 -229.60054) (xy 124.896608 -229.59036)
			(xy 124.94746 -229.588311) (xy 124.997981 -229.594445) (xy 125.046865 -229.608605) (xy 125.092844 -229.630422)
			(xy 125.134728 -229.659332) (xy 125.171432 -229.694587) (xy 125.202005 -229.735273) (xy 125.225656 -229.780336)
			(xy 125.241772 -229.82861) (xy 125.249936 -229.878844) (xy 125.250448 -229.90429) (xy 125.558545 -229.90429)
			(xy 125.56264 -229.853562) (xy 125.574819 -229.804148) (xy 125.594767 -229.757328) (xy 125.621968 -229.714314)
			(xy 125.655716 -229.67622) (xy 125.695138 -229.644033) (xy 125.739212 -229.618587) (xy 125.786798 -229.60054)
			(xy 125.836662 -229.59036) (xy 125.887514 -229.588311) (xy 125.938035 -229.594445) (xy 125.986919 -229.608605)
			(xy 126.032898 -229.630422) (xy 126.074782 -229.659332) (xy 126.111486 -229.694587) (xy 126.142059 -229.735273)
			(xy 126.16571 -229.780336) (xy 126.181826 -229.82861) (xy 126.18999 -229.878844) (xy 126.190502 -229.90429)
			(xy 126.18999 -229.929736) (xy 126.181826 -229.97997) (xy 126.16571 -230.028244) (xy 126.142059 -230.073307)
			(xy 126.111486 -230.113993) (xy 126.074782 -230.149248) (xy 126.032898 -230.178158) (xy 125.986919 -230.199975)
			(xy 125.938035 -230.214135) (xy 125.887514 -230.220269) (xy 125.836662 -230.21822) (xy 125.786798 -230.20804)
			(xy 125.739212 -230.189993) (xy 125.695138 -230.164547) (xy 125.655716 -230.13236) (xy 125.621968 -230.094266)
			(xy 125.594767 -230.051252) (xy 125.574819 -230.004432) (xy 125.56264 -229.955018) (xy 125.558545 -229.90429)
			(xy 125.250448 -229.90429) (xy 125.249936 -229.929736) (xy 125.241772 -229.97997) (xy 125.225656 -230.028244)
			(xy 125.202005 -230.073307) (xy 125.171432 -230.113993) (xy 125.134728 -230.149248) (xy 125.092844 -230.178158)
			(xy 125.046865 -230.199975) (xy 124.997981 -230.214135) (xy 124.94746 -230.220269) (xy 124.896608 -230.21822)
			(xy 124.846744 -230.20804) (xy 124.799158 -230.189993) (xy 124.755084 -230.164547) (xy 124.715662 -230.13236)
			(xy 124.681914 -230.094266) (xy 124.654713 -230.051252) (xy 124.634765 -230.004432) (xy 124.622586 -229.955018)
			(xy 124.618491 -229.90429) (xy 124.29998 -229.90429) (xy 124.299485 -229.928897) (xy 124.29159 -229.977474)
			(xy 124.276006 -230.024155) (xy 124.253135 -230.067732) (xy 124.22357 -230.107076) (xy 124.188077 -230.141168)
			(xy 124.147574 -230.169124) (xy 124.103112 -230.190222) (xy 124.055841 -230.203914) (xy 124.006986 -230.209846)
			(xy 123.957811 -230.207865) (xy 123.909592 -230.198021) (xy 123.863576 -230.180569) (xy 123.820955 -230.155962)
			(xy 123.782834 -230.124837) (xy 123.750199 -230.088) (xy 123.723896 -230.046404) (xy 123.704605 -230.001128)
			(xy 123.692828 -229.953344) (xy 123.688868 -229.90429) (xy 123.37034 -229.90429) (xy 123.369828 -229.929736)
			(xy 123.361664 -229.97997) (xy 123.345548 -230.028244) (xy 123.321897 -230.073307) (xy 123.291324 -230.113993)
			(xy 123.25462 -230.149248) (xy 123.212736 -230.178158) (xy 123.166757 -230.199975) (xy 123.117873 -230.214135)
			(xy 123.067352 -230.220269) (xy 123.0165 -230.21822) (xy 122.966636 -230.20804) (xy 122.91905 -230.189993)
			(xy 122.874976 -230.164547) (xy 122.835554 -230.13236) (xy 122.801806 -230.094266) (xy 122.774605 -230.051252)
			(xy 122.754657 -230.004432) (xy 122.742478 -229.955018) (xy 122.738383 -229.90429) (xy 122.43054 -229.90429)
			(xy 122.430028 -229.929736) (xy 122.421864 -229.97997) (xy 122.405748 -230.028244) (xy 122.382097 -230.073307)
			(xy 122.351524 -230.113993) (xy 122.31482 -230.149248) (xy 122.272936 -230.178158) (xy 122.226957 -230.199975)
			(xy 122.178073 -230.214135) (xy 122.127552 -230.220269) (xy 122.0767 -230.21822) (xy 122.026836 -230.20804)
			(xy 121.97925 -230.189993) (xy 121.935176 -230.164547) (xy 121.895754 -230.13236) (xy 121.862006 -230.094266)
			(xy 121.834805 -230.051252) (xy 121.814857 -230.004432) (xy 121.802678 -229.955018) (xy 121.798583 -229.90429)
			(xy 121.480072 -229.90429) (xy 121.479577 -229.928897) (xy 121.471682 -229.977474) (xy 121.456098 -230.024155)
			(xy 121.433227 -230.067732) (xy 121.403662 -230.107076) (xy 121.368169 -230.141168) (xy 121.327666 -230.169124)
			(xy 121.283204 -230.190222) (xy 121.235933 -230.203914) (xy 121.187078 -230.209846) (xy 121.137903 -230.207865)
			(xy 121.089684 -230.198021) (xy 121.043668 -230.180569) (xy 121.001047 -230.155962) (xy 120.962926 -230.124837)
			(xy 120.930291 -230.088) (xy 120.903988 -230.046404) (xy 120.884697 -230.001128) (xy 120.87292 -229.953344)
			(xy 120.86896 -229.90429) (xy 120.550432 -229.90429) (xy 120.54992 -229.929736) (xy 120.541756 -229.97997)
			(xy 120.52564 -230.028244) (xy 120.501989 -230.073307) (xy 120.471416 -230.113993) (xy 120.434712 -230.149248)
			(xy 120.392828 -230.178158) (xy 120.346849 -230.199975) (xy 120.297965 -230.214135) (xy 120.247444 -230.220269)
			(xy 120.196592 -230.21822) (xy 120.146728 -230.20804) (xy 120.099142 -230.189993) (xy 120.055068 -230.164547)
			(xy 120.015646 -230.13236) (xy 119.981898 -230.094266) (xy 119.954697 -230.051252) (xy 119.934749 -230.004432)
			(xy 119.92257 -229.955018) (xy 119.918475 -229.90429) (xy 119.610378 -229.90429) (xy 119.609866 -229.929736)
			(xy 119.601702 -229.97997) (xy 119.585586 -230.028244) (xy 119.561935 -230.073307) (xy 119.531362 -230.113993)
			(xy 119.494658 -230.149248) (xy 119.452774 -230.178158) (xy 119.406795 -230.199975) (xy 119.357911 -230.214135)
			(xy 119.30739 -230.220269) (xy 119.256538 -230.21822) (xy 119.206674 -230.20804) (xy 119.159088 -230.189993)
			(xy 119.115014 -230.164547) (xy 119.075592 -230.13236) (xy 119.041844 -230.094266) (xy 119.014643 -230.051252)
			(xy 118.994695 -230.004432) (xy 118.982516 -229.955018) (xy 118.978421 -229.90429) (xy 118.660164 -229.90429)
			(xy 118.659669 -229.928897) (xy 118.651774 -229.977474) (xy 118.63619 -230.024155) (xy 118.613319 -230.067732)
			(xy 118.583754 -230.107076) (xy 118.548261 -230.141168) (xy 118.507758 -230.169124) (xy 118.463296 -230.190222)
			(xy 118.416025 -230.203914) (xy 118.36717 -230.209846) (xy 118.317995 -230.207865) (xy 118.269776 -230.198021)
			(xy 118.22376 -230.180569) (xy 118.181139 -230.155962) (xy 118.143018 -230.124837) (xy 118.110383 -230.088)
			(xy 118.08408 -230.046404) (xy 118.064789 -230.001128) (xy 118.053012 -229.953344) (xy 118.049052 -229.90429)
			(xy 117.730524 -229.90429) (xy 117.730012 -229.929736) (xy 117.721848 -229.97997) (xy 117.705732 -230.028244)
			(xy 117.682081 -230.073307) (xy 117.651508 -230.113993) (xy 117.614804 -230.149248) (xy 117.57292 -230.178158)
			(xy 117.526941 -230.199975) (xy 117.478057 -230.214135) (xy 117.427536 -230.220269) (xy 117.376684 -230.21822)
			(xy 117.32682 -230.20804) (xy 117.279234 -230.189993) (xy 117.23516 -230.164547) (xy 117.195738 -230.13236)
			(xy 117.16199 -230.094266) (xy 117.134789 -230.051252) (xy 117.114841 -230.004432) (xy 117.102662 -229.955018)
			(xy 117.098567 -229.90429) (xy 116.79047 -229.90429) (xy 116.789958 -229.929736) (xy 116.781794 -229.97997)
			(xy 116.765678 -230.028244) (xy 116.742027 -230.073307) (xy 116.711454 -230.113993) (xy 116.67475 -230.149248)
			(xy 116.632866 -230.178158) (xy 116.586887 -230.199975) (xy 116.538003 -230.214135) (xy 116.487482 -230.220269)
			(xy 116.43663 -230.21822) (xy 116.386766 -230.20804) (xy 116.33918 -230.189993) (xy 116.295106 -230.164547)
			(xy 116.255684 -230.13236) (xy 116.221936 -230.094266) (xy 116.194735 -230.051252) (xy 116.174787 -230.004432)
			(xy 116.162608 -229.955018) (xy 116.158513 -229.90429) (xy 115.840002 -229.90429) (xy 115.839507 -229.928897)
			(xy 115.831612 -229.977474) (xy 115.816028 -230.024155) (xy 115.793157 -230.067732) (xy 115.763592 -230.107076)
			(xy 115.728099 -230.141168) (xy 115.687596 -230.169124) (xy 115.643134 -230.190222) (xy 115.595863 -230.203914)
			(xy 115.547008 -230.209846) (xy 115.497833 -230.207865) (xy 115.449614 -230.198021) (xy 115.403598 -230.180569)
			(xy 115.360977 -230.155962) (xy 115.322856 -230.124837) (xy 115.290221 -230.088) (xy 115.263918 -230.046404)
			(xy 115.244627 -230.001128) (xy 115.23285 -229.953344) (xy 115.22889 -229.90429) (xy 114.899948 -229.90429)
			(xy 114.899453 -229.928897) (xy 114.891558 -229.977474) (xy 114.875974 -230.024155) (xy 114.853103 -230.067732)
			(xy 114.823538 -230.107076) (xy 114.788045 -230.141168) (xy 114.747542 -230.169124) (xy 114.70308 -230.190222)
			(xy 114.655809 -230.203914) (xy 114.606954 -230.209846) (xy 114.557779 -230.207865) (xy 114.50956 -230.198021)
			(xy 114.463544 -230.180569) (xy 114.420923 -230.155962) (xy 114.382802 -230.124837) (xy 114.350167 -230.088)
			(xy 114.323864 -230.046404) (xy 114.304573 -230.001128) (xy 114.292796 -229.953344) (xy 114.288836 -229.90429)
			(xy 113.960148 -229.90429) (xy 113.959723 -229.9278) (xy 113.952527 -229.974267) (xy 113.938288 -230.019079)
			(xy 113.917344 -230.061177) (xy 113.89019 -230.099564) (xy 113.857469 -230.133332) (xy 113.819956 -230.16168)
			(xy 113.778538 -230.183939) (xy 113.734196 -230.199581) (xy 113.687979 -230.208235) (xy 113.664492 -230.209344)
			(xy 113.659709 -230.209646) (xy 113.650375 -230.211821) (xy 113.64595 -230.213662) (xy 113.636552 -230.217726)
			(xy 113.580418 -230.275638) (xy 113.573871 -230.282966) (xy 113.566422 -230.30113) (xy 113.56594 -230.310944)
			(xy 113.56594 -230.71455) (xy 113.808505 -230.71455) (xy 113.8126 -230.663822) (xy 113.824779 -230.614408)
			(xy 113.844727 -230.567588) (xy 113.871928 -230.524574) (xy 113.905676 -230.48648) (xy 113.945098 -230.454293)
			(xy 113.989172 -230.428847) (xy 114.036758 -230.4108) (xy 114.086622 -230.40062) (xy 114.137474 -230.398571)
			(xy 114.187995 -230.404705) (xy 114.236879 -230.418865) (xy 114.282858 -230.440682) (xy 114.324742 -230.469592)
			(xy 114.361446 -230.504847) (xy 114.392019 -230.545533) (xy 114.41567 -230.590596) (xy 114.431786 -230.63887)
			(xy 114.43995 -230.689104) (xy 114.440462 -230.71455) (xy 114.748559 -230.71455) (xy 114.752654 -230.663822)
			(xy 114.764833 -230.614408) (xy 114.784781 -230.567588) (xy 114.811982 -230.524574) (xy 114.84573 -230.48648)
			(xy 114.885152 -230.454293) (xy 114.929226 -230.428847) (xy 114.976812 -230.4108) (xy 115.026676 -230.40062)
			(xy 115.077528 -230.398571) (xy 115.128049 -230.404705) (xy 115.176933 -230.418865) (xy 115.222912 -230.440682)
			(xy 115.264796 -230.469592) (xy 115.3015 -230.504847) (xy 115.332073 -230.545533) (xy 115.355724 -230.590596)
			(xy 115.37184 -230.63887) (xy 115.380004 -230.689104) (xy 115.380511 -230.714296) (xy 115.699044 -230.714296)
			(xy 115.703004 -230.665242) (xy 115.714781 -230.617458) (xy 115.734072 -230.572182) (xy 115.760375 -230.530586)
			(xy 115.79301 -230.493749) (xy 115.831131 -230.462624) (xy 115.873752 -230.438017) (xy 115.919768 -230.420565)
			(xy 115.967987 -230.410721) (xy 116.017162 -230.40874) (xy 116.066017 -230.414672) (xy 116.113288 -230.428364)
			(xy 116.15775 -230.449462) (xy 116.198253 -230.477418) (xy 116.233746 -230.51151) (xy 116.263311 -230.550854)
			(xy 116.286182 -230.594431) (xy 116.301766 -230.641112) (xy 116.309661 -230.689689) (xy 116.310156 -230.714296)
			(xy 116.310151 -230.71455) (xy 118.518952 -230.71455) (xy 118.522912 -230.665496) (xy 118.534689 -230.617712)
			(xy 118.55398 -230.572436) (xy 118.580283 -230.53084) (xy 118.612918 -230.494003) (xy 118.651039 -230.462878)
			(xy 118.69366 -230.438271) (xy 118.739676 -230.420819) (xy 118.787895 -230.410975) (xy 118.83707 -230.408994)
			(xy 118.885925 -230.414926) (xy 118.933196 -230.428618) (xy 118.977658 -230.449716) (xy 119.018161 -230.477672)
			(xy 119.053654 -230.511764) (xy 119.083219 -230.551108) (xy 119.10609 -230.594685) (xy 119.121674 -230.641366)
			(xy 119.129569 -230.689943) (xy 119.130064 -230.71455) (xy 121.33886 -230.71455) (xy 121.34282 -230.665496)
			(xy 121.354597 -230.617712) (xy 121.373888 -230.572436) (xy 121.400191 -230.53084) (xy 121.432826 -230.494003)
			(xy 121.470947 -230.462878) (xy 121.513568 -230.438271) (xy 121.559584 -230.420819) (xy 121.607803 -230.410975)
			(xy 121.656978 -230.408994) (xy 121.705833 -230.414926) (xy 121.753104 -230.428618) (xy 121.797566 -230.449716)
			(xy 121.838069 -230.477672) (xy 121.873562 -230.511764) (xy 121.903127 -230.551108) (xy 121.925998 -230.594685)
			(xy 121.941582 -230.641366) (xy 121.949477 -230.689943) (xy 121.949967 -230.714296) (xy 124.159022 -230.714296)
			(xy 124.162982 -230.665242) (xy 124.174759 -230.617458) (xy 124.19405 -230.572182) (xy 124.220353 -230.530586)
			(xy 124.252988 -230.493749) (xy 124.291109 -230.462624) (xy 124.33373 -230.438017) (xy 124.379746 -230.420565)
			(xy 124.427965 -230.410721) (xy 124.47714 -230.40874) (xy 124.525995 -230.414672) (xy 124.573266 -230.428364)
			(xy 124.617728 -230.449462) (xy 124.658231 -230.477418) (xy 124.693724 -230.51151) (xy 124.723289 -230.550854)
			(xy 124.74616 -230.594431) (xy 124.761744 -230.641112) (xy 124.769639 -230.689689) (xy 124.770134 -230.714296)
			(xy 124.769639 -230.738903) (xy 124.761744 -230.78748) (xy 124.74616 -230.834161) (xy 124.723289 -230.877738)
			(xy 124.693724 -230.917082) (xy 124.658231 -230.951174) (xy 124.617728 -230.97913) (xy 124.573266 -231.000228)
			(xy 124.525995 -231.01392) (xy 124.47714 -231.019852) (xy 124.427965 -231.017871) (xy 124.379746 -231.008027)
			(xy 124.33373 -230.990575) (xy 124.291109 -230.965968) (xy 124.252988 -230.934843) (xy 124.220353 -230.898006)
			(xy 124.19405 -230.85641) (xy 124.174759 -230.811134) (xy 124.162982 -230.76335) (xy 124.159022 -230.714296)
			(xy 121.949967 -230.714296) (xy 121.949972 -230.71455) (xy 121.949477 -230.739157) (xy 121.941582 -230.787734)
			(xy 121.925998 -230.834415) (xy 121.903127 -230.877992) (xy 121.873562 -230.917336) (xy 121.838069 -230.951428)
			(xy 121.797566 -230.979384) (xy 121.753104 -231.000482) (xy 121.705833 -231.014174) (xy 121.656978 -231.020106)
			(xy 121.607803 -231.018125) (xy 121.559584 -231.008281) (xy 121.513568 -230.990829) (xy 121.470947 -230.966222)
			(xy 121.432826 -230.935097) (xy 121.400191 -230.89826) (xy 121.373888 -230.856664) (xy 121.354597 -230.811388)
			(xy 121.34282 -230.763604) (xy 121.33886 -230.71455) (xy 119.130064 -230.71455) (xy 119.129569 -230.739157)
			(xy 119.121674 -230.787734) (xy 119.10609 -230.834415) (xy 119.083219 -230.877992) (xy 119.053654 -230.917336)
			(xy 119.018161 -230.951428) (xy 118.977658 -230.979384) (xy 118.933196 -231.000482) (xy 118.885925 -231.014174)
			(xy 118.83707 -231.020106) (xy 118.787895 -231.018125) (xy 118.739676 -231.008281) (xy 118.69366 -230.990829)
			(xy 118.651039 -230.966222) (xy 118.612918 -230.935097) (xy 118.580283 -230.89826) (xy 118.55398 -230.856664)
			(xy 118.534689 -230.811388) (xy 118.522912 -230.763604) (xy 118.518952 -230.71455) (xy 116.310151 -230.71455)
			(xy 116.309661 -230.738903) (xy 116.301766 -230.78748) (xy 116.286182 -230.834161) (xy 116.263311 -230.877738)
			(xy 116.233746 -230.917082) (xy 116.198253 -230.951174) (xy 116.15775 -230.97913) (xy 116.113288 -231.000228)
			(xy 116.066017 -231.01392) (xy 116.017162 -231.019852) (xy 115.967987 -231.017871) (xy 115.919768 -231.008027)
			(xy 115.873752 -230.990575) (xy 115.831131 -230.965968) (xy 115.79301 -230.934843) (xy 115.760375 -230.898006)
			(xy 115.734072 -230.85641) (xy 115.714781 -230.811134) (xy 115.703004 -230.76335) (xy 115.699044 -230.714296)
			(xy 115.380511 -230.714296) (xy 115.380516 -230.71455) (xy 115.380004 -230.739996) (xy 115.37184 -230.79023)
			(xy 115.355724 -230.838504) (xy 115.332073 -230.883567) (xy 115.3015 -230.924253) (xy 115.264796 -230.959508)
			(xy 115.222912 -230.988418) (xy 115.176933 -231.010235) (xy 115.128049 -231.024395) (xy 115.077528 -231.030529)
			(xy 115.026676 -231.02848) (xy 114.976812 -231.0183) (xy 114.929226 -231.000253) (xy 114.885152 -230.974807)
			(xy 114.84573 -230.94262) (xy 114.811982 -230.904526) (xy 114.784781 -230.861512) (xy 114.764833 -230.814692)
			(xy 114.752654 -230.765278) (xy 114.748559 -230.71455) (xy 114.440462 -230.71455) (xy 114.43995 -230.739996)
			(xy 114.431786 -230.79023) (xy 114.41567 -230.838504) (xy 114.392019 -230.883567) (xy 114.361446 -230.924253)
			(xy 114.324742 -230.959508) (xy 114.282858 -230.988418) (xy 114.236879 -231.010235) (xy 114.187995 -231.024395)
			(xy 114.137474 -231.030529) (xy 114.086622 -231.02848) (xy 114.036758 -231.0183) (xy 113.989172 -231.000253)
			(xy 113.945098 -230.974807) (xy 113.905676 -230.94262) (xy 113.871928 -230.904526) (xy 113.844727 -230.861512)
			(xy 113.824779 -230.814692) (xy 113.8126 -230.765278) (xy 113.808505 -230.71455) (xy 113.56594 -230.71455)
			(xy 113.56594 -231.524302) (xy 115.22889 -231.524302) (xy 115.23285 -231.475248) (xy 115.244627 -231.427464)
			(xy 115.263918 -231.382188) (xy 115.290221 -231.340592) (xy 115.322856 -231.303755) (xy 115.360977 -231.27263)
			(xy 115.403598 -231.248023) (xy 115.449614 -231.230571) (xy 115.497833 -231.220727) (xy 115.547008 -231.218746)
			(xy 115.595863 -231.224678) (xy 115.643134 -231.23837) (xy 115.687596 -231.259468) (xy 115.728099 -231.287424)
			(xy 115.763592 -231.321516) (xy 115.793157 -231.36086) (xy 115.816028 -231.404437) (xy 115.831612 -231.451118)
			(xy 115.839507 -231.499695) (xy 115.840002 -231.524302) (xy 116.168944 -231.524302) (xy 116.172904 -231.475248)
			(xy 116.184681 -231.427464) (xy 116.203972 -231.382188) (xy 116.230275 -231.340592) (xy 116.26291 -231.303755)
			(xy 116.301031 -231.27263) (xy 116.343652 -231.248023) (xy 116.389668 -231.230571) (xy 116.437887 -231.220727)
			(xy 116.487062 -231.218746) (xy 116.535917 -231.224678) (xy 116.583188 -231.23837) (xy 116.62765 -231.259468)
			(xy 116.668153 -231.287424) (xy 116.703646 -231.321516) (xy 116.733211 -231.36086) (xy 116.756082 -231.404437)
			(xy 116.771666 -231.451118) (xy 116.779561 -231.499695) (xy 116.780056 -231.524302) (xy 117.108998 -231.524302)
			(xy 117.112958 -231.475248) (xy 117.124735 -231.427464) (xy 117.144026 -231.382188) (xy 117.170329 -231.340592)
			(xy 117.202964 -231.303755) (xy 117.241085 -231.27263) (xy 117.283706 -231.248023) (xy 117.329722 -231.230571)
			(xy 117.377941 -231.220727) (xy 117.427116 -231.218746) (xy 117.475971 -231.224678) (xy 117.523242 -231.23837)
			(xy 117.567704 -231.259468) (xy 117.608207 -231.287424) (xy 117.6437 -231.321516) (xy 117.673265 -231.36086)
			(xy 117.696136 -231.404437) (xy 117.71172 -231.451118) (xy 117.719615 -231.499695) (xy 117.72011 -231.524302)
			(xy 118.049052 -231.524302) (xy 118.053012 -231.475248) (xy 118.064789 -231.427464) (xy 118.08408 -231.382188)
			(xy 118.110383 -231.340592) (xy 118.143018 -231.303755) (xy 118.181139 -231.27263) (xy 118.22376 -231.248023)
			(xy 118.269776 -231.230571) (xy 118.317995 -231.220727) (xy 118.36717 -231.218746) (xy 118.416025 -231.224678)
			(xy 118.463296 -231.23837) (xy 118.507758 -231.259468) (xy 118.548261 -231.287424) (xy 118.583754 -231.321516)
			(xy 118.613319 -231.36086) (xy 118.63619 -231.404437) (xy 118.651774 -231.451118) (xy 118.659669 -231.499695)
			(xy 118.660164 -231.524302) (xy 118.988852 -231.524302) (xy 118.992812 -231.475248) (xy 119.004589 -231.427464)
			(xy 119.02388 -231.382188) (xy 119.050183 -231.340592) (xy 119.082818 -231.303755) (xy 119.120939 -231.27263)
			(xy 119.16356 -231.248023) (xy 119.209576 -231.230571) (xy 119.257795 -231.220727) (xy 119.30697 -231.218746)
			(xy 119.355825 -231.224678) (xy 119.403096 -231.23837) (xy 119.447558 -231.259468) (xy 119.488061 -231.287424)
			(xy 119.523554 -231.321516) (xy 119.553119 -231.36086) (xy 119.57599 -231.404437) (xy 119.591574 -231.451118)
			(xy 119.599469 -231.499695) (xy 119.599964 -231.524302) (xy 119.928906 -231.524302) (xy 119.932866 -231.475248)
			(xy 119.944643 -231.427464) (xy 119.963934 -231.382188) (xy 119.990237 -231.340592) (xy 120.022872 -231.303755)
			(xy 120.060993 -231.27263) (xy 120.103614 -231.248023) (xy 120.14963 -231.230571) (xy 120.197849 -231.220727)
			(xy 120.247024 -231.218746) (xy 120.295879 -231.224678) (xy 120.34315 -231.23837) (xy 120.387612 -231.259468)
			(xy 120.428115 -231.287424) (xy 120.463608 -231.321516) (xy 120.493173 -231.36086) (xy 120.516044 -231.404437)
			(xy 120.531628 -231.451118) (xy 120.539523 -231.499695) (xy 120.540018 -231.524302) (xy 120.86896 -231.524302)
			(xy 120.87292 -231.475248) (xy 120.884697 -231.427464) (xy 120.903988 -231.382188) (xy 120.930291 -231.340592)
			(xy 120.962926 -231.303755) (xy 121.001047 -231.27263) (xy 121.043668 -231.248023) (xy 121.089684 -231.230571)
			(xy 121.137903 -231.220727) (xy 121.187078 -231.218746) (xy 121.235933 -231.224678) (xy 121.283204 -231.23837)
			(xy 121.327666 -231.259468) (xy 121.368169 -231.287424) (xy 121.403662 -231.321516) (xy 121.433227 -231.36086)
			(xy 121.456098 -231.404437) (xy 121.471682 -231.451118) (xy 121.479577 -231.499695) (xy 121.480072 -231.524302)
			(xy 121.809014 -231.524302) (xy 121.812974 -231.475248) (xy 121.824751 -231.427464) (xy 121.844042 -231.382188)
			(xy 121.870345 -231.340592) (xy 121.90298 -231.303755) (xy 121.941101 -231.27263) (xy 121.983722 -231.248023)
			(xy 122.029738 -231.230571) (xy 122.077957 -231.220727) (xy 122.127132 -231.218746) (xy 122.175987 -231.224678)
			(xy 122.223258 -231.23837) (xy 122.26772 -231.259468) (xy 122.308223 -231.287424) (xy 122.343716 -231.321516)
			(xy 122.373281 -231.36086) (xy 122.396152 -231.404437) (xy 122.411736 -231.451118) (xy 122.419631 -231.499695)
			(xy 122.420126 -231.524302) (xy 122.748814 -231.524302) (xy 122.752774 -231.475248) (xy 122.764551 -231.427464)
			(xy 122.783842 -231.382188) (xy 122.810145 -231.340592) (xy 122.84278 -231.303755) (xy 122.880901 -231.27263)
			(xy 122.923522 -231.248023) (xy 122.969538 -231.230571) (xy 123.017757 -231.220727) (xy 123.066932 -231.218746)
			(xy 123.115787 -231.224678) (xy 123.163058 -231.23837) (xy 123.20752 -231.259468) (xy 123.248023 -231.287424)
			(xy 123.283516 -231.321516) (xy 123.313081 -231.36086) (xy 123.335952 -231.404437) (xy 123.351536 -231.451118)
			(xy 123.359431 -231.499695) (xy 123.359926 -231.524302) (xy 123.688868 -231.524302) (xy 123.692828 -231.475248)
			(xy 123.704605 -231.427464) (xy 123.723896 -231.382188) (xy 123.750199 -231.340592) (xy 123.782834 -231.303755)
			(xy 123.820955 -231.27263) (xy 123.863576 -231.248023) (xy 123.909592 -231.230571) (xy 123.957811 -231.220727)
			(xy 124.006986 -231.218746) (xy 124.055841 -231.224678) (xy 124.103112 -231.23837) (xy 124.147574 -231.259468)
			(xy 124.188077 -231.287424) (xy 124.22357 -231.321516) (xy 124.253135 -231.36086) (xy 124.276006 -231.404437)
			(xy 124.29159 -231.451118) (xy 124.299485 -231.499695) (xy 124.29998 -231.524302) (xy 124.618491 -231.524302)
			(xy 124.622586 -231.473574) (xy 124.634765 -231.42416) (xy 124.654713 -231.37734) (xy 124.681914 -231.334326)
			(xy 124.715662 -231.296232) (xy 124.755084 -231.264045) (xy 124.799158 -231.238599) (xy 124.846744 -231.220552)
			(xy 124.896608 -231.210372) (xy 124.94746 -231.208323) (xy 124.997981 -231.214457) (xy 125.046865 -231.228617)
			(xy 125.092844 -231.250434) (xy 125.134728 -231.279344) (xy 125.171432 -231.314599) (xy 125.202005 -231.355285)
			(xy 125.225656 -231.400348) (xy 125.241772 -231.448622) (xy 125.249936 -231.498856) (xy 125.250448 -231.524302)
			(xy 125.558545 -231.524302) (xy 125.56264 -231.473574) (xy 125.574819 -231.42416) (xy 125.594767 -231.37734)
			(xy 125.621968 -231.334326) (xy 125.655716 -231.296232) (xy 125.695138 -231.264045) (xy 125.739212 -231.238599)
			(xy 125.786798 -231.220552) (xy 125.836662 -231.210372) (xy 125.887514 -231.208323) (xy 125.938035 -231.214457)
			(xy 125.986919 -231.228617) (xy 126.032898 -231.250434) (xy 126.074782 -231.279344) (xy 126.111486 -231.314599)
			(xy 126.142059 -231.355285) (xy 126.16571 -231.400348) (xy 126.181826 -231.448622) (xy 126.18999 -231.498856)
			(xy 126.190502 -231.524302) (xy 126.18999 -231.549748) (xy 126.181826 -231.599982) (xy 126.16571 -231.648256)
			(xy 126.142059 -231.693319) (xy 126.111486 -231.734005) (xy 126.074782 -231.76926) (xy 126.032898 -231.79817)
			(xy 125.986919 -231.819987) (xy 125.938035 -231.834147) (xy 125.887514 -231.840281) (xy 125.836662 -231.838232)
			(xy 125.786798 -231.828052) (xy 125.739212 -231.810005) (xy 125.695138 -231.784559) (xy 125.655716 -231.752372)
			(xy 125.621968 -231.714278) (xy 125.594767 -231.671264) (xy 125.574819 -231.624444) (xy 125.56264 -231.57503)
			(xy 125.558545 -231.524302) (xy 125.250448 -231.524302) (xy 125.249936 -231.549748) (xy 125.241772 -231.599982)
			(xy 125.225656 -231.648256) (xy 125.202005 -231.693319) (xy 125.171432 -231.734005) (xy 125.134728 -231.76926)
			(xy 125.092844 -231.79817) (xy 125.046865 -231.819987) (xy 124.997981 -231.834147) (xy 124.94746 -231.840281)
			(xy 124.896608 -231.838232) (xy 124.846744 -231.828052) (xy 124.799158 -231.810005) (xy 124.755084 -231.784559)
			(xy 124.715662 -231.752372) (xy 124.681914 -231.714278) (xy 124.654713 -231.671264) (xy 124.634765 -231.624444)
			(xy 124.622586 -231.57503) (xy 124.618491 -231.524302) (xy 124.29998 -231.524302) (xy 124.299485 -231.548909)
			(xy 124.29159 -231.597486) (xy 124.276006 -231.644167) (xy 124.253135 -231.687744) (xy 124.22357 -231.727088)
			(xy 124.188077 -231.76118) (xy 124.147574 -231.789136) (xy 124.103112 -231.810234) (xy 124.055841 -231.823926)
			(xy 124.006986 -231.829858) (xy 123.957811 -231.827877) (xy 123.909592 -231.818033) (xy 123.863576 -231.800581)
			(xy 123.820955 -231.775974) (xy 123.782834 -231.744849) (xy 123.750199 -231.708012) (xy 123.723896 -231.666416)
			(xy 123.704605 -231.62114) (xy 123.692828 -231.573356) (xy 123.688868 -231.524302) (xy 123.359926 -231.524302)
			(xy 123.359431 -231.548909) (xy 123.351536 -231.597486) (xy 123.335952 -231.644167) (xy 123.313081 -231.687744)
			(xy 123.283516 -231.727088) (xy 123.248023 -231.76118) (xy 123.20752 -231.789136) (xy 123.163058 -231.810234)
			(xy 123.115787 -231.823926) (xy 123.066932 -231.829858) (xy 123.017757 -231.827877) (xy 122.969538 -231.818033)
			(xy 122.923522 -231.800581) (xy 122.880901 -231.775974) (xy 122.84278 -231.744849) (xy 122.810145 -231.708012)
			(xy 122.783842 -231.666416) (xy 122.764551 -231.62114) (xy 122.752774 -231.573356) (xy 122.748814 -231.524302)
			(xy 122.420126 -231.524302) (xy 122.419631 -231.548909) (xy 122.411736 -231.597486) (xy 122.396152 -231.644167)
			(xy 122.373281 -231.687744) (xy 122.343716 -231.727088) (xy 122.308223 -231.76118) (xy 122.26772 -231.789136)
			(xy 122.223258 -231.810234) (xy 122.175987 -231.823926) (xy 122.127132 -231.829858) (xy 122.077957 -231.827877)
			(xy 122.029738 -231.818033) (xy 121.983722 -231.800581) (xy 121.941101 -231.775974) (xy 121.90298 -231.744849)
			(xy 121.870345 -231.708012) (xy 121.844042 -231.666416) (xy 121.824751 -231.62114) (xy 121.812974 -231.573356)
			(xy 121.809014 -231.524302) (xy 121.480072 -231.524302) (xy 121.479577 -231.548909) (xy 121.471682 -231.597486)
			(xy 121.456098 -231.644167) (xy 121.433227 -231.687744) (xy 121.403662 -231.727088) (xy 121.368169 -231.76118)
			(xy 121.327666 -231.789136) (xy 121.283204 -231.810234) (xy 121.235933 -231.823926) (xy 121.187078 -231.829858)
			(xy 121.137903 -231.827877) (xy 121.089684 -231.818033) (xy 121.043668 -231.800581) (xy 121.001047 -231.775974)
			(xy 120.962926 -231.744849) (xy 120.930291 -231.708012) (xy 120.903988 -231.666416) (xy 120.884697 -231.62114)
			(xy 120.87292 -231.573356) (xy 120.86896 -231.524302) (xy 120.540018 -231.524302) (xy 120.539523 -231.548909)
			(xy 120.531628 -231.597486) (xy 120.516044 -231.644167) (xy 120.493173 -231.687744) (xy 120.463608 -231.727088)
			(xy 120.428115 -231.76118) (xy 120.387612 -231.789136) (xy 120.34315 -231.810234) (xy 120.295879 -231.823926)
			(xy 120.247024 -231.829858) (xy 120.197849 -231.827877) (xy 120.14963 -231.818033) (xy 120.103614 -231.800581)
			(xy 120.060993 -231.775974) (xy 120.022872 -231.744849) (xy 119.990237 -231.708012) (xy 119.963934 -231.666416)
			(xy 119.944643 -231.62114) (xy 119.932866 -231.573356) (xy 119.928906 -231.524302) (xy 119.599964 -231.524302)
			(xy 119.599469 -231.548909) (xy 119.591574 -231.597486) (xy 119.57599 -231.644167) (xy 119.553119 -231.687744)
			(xy 119.523554 -231.727088) (xy 119.488061 -231.76118) (xy 119.447558 -231.789136) (xy 119.403096 -231.810234)
			(xy 119.355825 -231.823926) (xy 119.30697 -231.829858) (xy 119.257795 -231.827877) (xy 119.209576 -231.818033)
			(xy 119.16356 -231.800581) (xy 119.120939 -231.775974) (xy 119.082818 -231.744849) (xy 119.050183 -231.708012)
			(xy 119.02388 -231.666416) (xy 119.004589 -231.62114) (xy 118.992812 -231.573356) (xy 118.988852 -231.524302)
			(xy 118.660164 -231.524302) (xy 118.659669 -231.548909) (xy 118.651774 -231.597486) (xy 118.63619 -231.644167)
			(xy 118.613319 -231.687744) (xy 118.583754 -231.727088) (xy 118.548261 -231.76118) (xy 118.507758 -231.789136)
			(xy 118.463296 -231.810234) (xy 118.416025 -231.823926) (xy 118.36717 -231.829858) (xy 118.317995 -231.827877)
			(xy 118.269776 -231.818033) (xy 118.22376 -231.800581) (xy 118.181139 -231.775974) (xy 118.143018 -231.744849)
			(xy 118.110383 -231.708012) (xy 118.08408 -231.666416) (xy 118.064789 -231.62114) (xy 118.053012 -231.573356)
			(xy 118.049052 -231.524302) (xy 117.72011 -231.524302) (xy 117.719615 -231.548909) (xy 117.71172 -231.597486)
			(xy 117.696136 -231.644167) (xy 117.673265 -231.687744) (xy 117.6437 -231.727088) (xy 117.608207 -231.76118)
			(xy 117.567704 -231.789136) (xy 117.523242 -231.810234) (xy 117.475971 -231.823926) (xy 117.427116 -231.829858)
			(xy 117.377941 -231.827877) (xy 117.329722 -231.818033) (xy 117.283706 -231.800581) (xy 117.241085 -231.775974)
			(xy 117.202964 -231.744849) (xy 117.170329 -231.708012) (xy 117.144026 -231.666416) (xy 117.124735 -231.62114)
			(xy 117.112958 -231.573356) (xy 117.108998 -231.524302) (xy 116.780056 -231.524302) (xy 116.779561 -231.548909)
			(xy 116.771666 -231.597486) (xy 116.756082 -231.644167) (xy 116.733211 -231.687744) (xy 116.703646 -231.727088)
			(xy 116.668153 -231.76118) (xy 116.62765 -231.789136) (xy 116.583188 -231.810234) (xy 116.535917 -231.823926)
			(xy 116.487062 -231.829858) (xy 116.437887 -231.827877) (xy 116.389668 -231.818033) (xy 116.343652 -231.800581)
			(xy 116.301031 -231.775974) (xy 116.26291 -231.744849) (xy 116.230275 -231.708012) (xy 116.203972 -231.666416)
			(xy 116.184681 -231.62114) (xy 116.172904 -231.573356) (xy 116.168944 -231.524302) (xy 115.840002 -231.524302)
			(xy 115.839507 -231.548909) (xy 115.831612 -231.597486) (xy 115.816028 -231.644167) (xy 115.793157 -231.687744)
			(xy 115.763592 -231.727088) (xy 115.728099 -231.76118) (xy 115.687596 -231.789136) (xy 115.643134 -231.810234)
			(xy 115.595863 -231.823926) (xy 115.547008 -231.829858) (xy 115.497833 -231.827877) (xy 115.449614 -231.818033)
			(xy 115.403598 -231.800581) (xy 115.360977 -231.775974) (xy 115.322856 -231.744849) (xy 115.290221 -231.708012)
			(xy 115.263918 -231.666416) (xy 115.244627 -231.62114) (xy 115.23285 -231.573356) (xy 115.22889 -231.524302)
			(xy 113.56594 -231.524302) (xy 113.56594 -232.334308) (xy 113.818936 -232.334308) (xy 113.822896 -232.285254)
			(xy 113.834673 -232.23747) (xy 113.853964 -232.192194) (xy 113.880267 -232.150598) (xy 113.912902 -232.113761)
			(xy 113.951023 -232.082636) (xy 113.993644 -232.058029) (xy 114.03966 -232.040577) (xy 114.087879 -232.030733)
			(xy 114.137054 -232.028752) (xy 114.185909 -232.034684) (xy 114.23318 -232.048376) (xy 114.277642 -232.069474)
			(xy 114.318145 -232.09743) (xy 114.353638 -232.131522) (xy 114.383203 -232.170866) (xy 114.406074 -232.214443)
			(xy 114.421658 -232.261124) (xy 114.429553 -232.309701) (xy 114.430048 -232.334308) (xy 114.75899 -232.334308)
			(xy 114.76295 -232.285254) (xy 114.774727 -232.23747) (xy 114.794018 -232.192194) (xy 114.820321 -232.150598)
			(xy 114.852956 -232.113761) (xy 114.891077 -232.082636) (xy 114.933698 -232.058029) (xy 114.979714 -232.040577)
			(xy 115.027933 -232.030733) (xy 115.077108 -232.028752) (xy 115.125963 -232.034684) (xy 115.173234 -232.048376)
			(xy 115.217696 -232.069474) (xy 115.258199 -232.09743) (xy 115.293692 -232.131522) (xy 115.323257 -232.170866)
			(xy 115.346128 -232.214443) (xy 115.361712 -232.261124) (xy 115.369607 -232.309701) (xy 115.370102 -232.334308)
			(xy 115.699044 -232.334308) (xy 115.703004 -232.285254) (xy 115.714781 -232.23747) (xy 115.734072 -232.192194)
			(xy 115.760375 -232.150598) (xy 115.79301 -232.113761) (xy 115.831131 -232.082636) (xy 115.873752 -232.058029)
			(xy 115.919768 -232.040577) (xy 115.967987 -232.030733) (xy 116.017162 -232.028752) (xy 116.066017 -232.034684)
			(xy 116.113288 -232.048376) (xy 116.15775 -232.069474) (xy 116.198253 -232.09743) (xy 116.233746 -232.131522)
			(xy 116.263311 -232.170866) (xy 116.286182 -232.214443) (xy 116.301766 -232.261124) (xy 116.309661 -232.309701)
			(xy 116.310156 -232.334308) (xy 116.638844 -232.334308) (xy 116.642804 -232.285254) (xy 116.654581 -232.23747)
			(xy 116.673872 -232.192194) (xy 116.700175 -232.150598) (xy 116.73281 -232.113761) (xy 116.770931 -232.082636)
			(xy 116.813552 -232.058029) (xy 116.859568 -232.040577) (xy 116.907787 -232.030733) (xy 116.956962 -232.028752)
			(xy 117.005817 -232.034684) (xy 117.053088 -232.048376) (xy 117.09755 -232.069474) (xy 117.138053 -232.09743)
			(xy 117.173546 -232.131522) (xy 117.203111 -232.170866) (xy 117.225982 -232.214443) (xy 117.241566 -232.261124)
			(xy 117.249461 -232.309701) (xy 117.249956 -232.334308) (xy 117.578898 -232.334308) (xy 117.582858 -232.285254)
			(xy 117.594635 -232.23747) (xy 117.613926 -232.192194) (xy 117.640229 -232.150598) (xy 117.672864 -232.113761)
			(xy 117.710985 -232.082636) (xy 117.753606 -232.058029) (xy 117.799622 -232.040577) (xy 117.847841 -232.030733)
			(xy 117.897016 -232.028752) (xy 117.945871 -232.034684) (xy 117.993142 -232.048376) (xy 118.037604 -232.069474)
			(xy 118.078107 -232.09743) (xy 118.1136 -232.131522) (xy 118.143165 -232.170866) (xy 118.166036 -232.214443)
			(xy 118.18162 -232.261124) (xy 118.189515 -232.309701) (xy 118.19001 -232.334308) (xy 118.518952 -232.334308)
			(xy 118.522912 -232.285254) (xy 118.534689 -232.23747) (xy 118.55398 -232.192194) (xy 118.580283 -232.150598)
			(xy 118.612918 -232.113761) (xy 118.651039 -232.082636) (xy 118.69366 -232.058029) (xy 118.739676 -232.040577)
			(xy 118.787895 -232.030733) (xy 118.83707 -232.028752) (xy 118.885925 -232.034684) (xy 118.933196 -232.048376)
			(xy 118.977658 -232.069474) (xy 119.018161 -232.09743) (xy 119.053654 -232.131522) (xy 119.083219 -232.170866)
			(xy 119.10609 -232.214443) (xy 119.121674 -232.261124) (xy 119.129569 -232.309701) (xy 119.130064 -232.334308)
			(xy 119.459006 -232.334308) (xy 119.462966 -232.285254) (xy 119.474743 -232.23747) (xy 119.494034 -232.192194)
			(xy 119.520337 -232.150598) (xy 119.552972 -232.113761) (xy 119.591093 -232.082636) (xy 119.633714 -232.058029)
			(xy 119.67973 -232.040577) (xy 119.727949 -232.030733) (xy 119.777124 -232.028752) (xy 119.825979 -232.034684)
			(xy 119.87325 -232.048376) (xy 119.917712 -232.069474) (xy 119.958215 -232.09743) (xy 119.993708 -232.131522)
			(xy 120.023273 -232.170866) (xy 120.046144 -232.214443) (xy 120.061728 -232.261124) (xy 120.069623 -232.309701)
			(xy 120.070118 -232.334308) (xy 120.398806 -232.334308) (xy 120.402766 -232.285254) (xy 120.414543 -232.23747)
			(xy 120.433834 -232.192194) (xy 120.460137 -232.150598) (xy 120.492772 -232.113761) (xy 120.530893 -232.082636)
			(xy 120.573514 -232.058029) (xy 120.61953 -232.040577) (xy 120.667749 -232.030733) (xy 120.716924 -232.028752)
			(xy 120.765779 -232.034684) (xy 120.81305 -232.048376) (xy 120.857512 -232.069474) (xy 120.898015 -232.09743)
			(xy 120.933508 -232.131522) (xy 120.963073 -232.170866) (xy 120.985944 -232.214443) (xy 121.001528 -232.261124)
			(xy 121.009423 -232.309701) (xy 121.009918 -232.334308) (xy 121.33886 -232.334308) (xy 121.34282 -232.285254)
			(xy 121.354597 -232.23747) (xy 121.373888 -232.192194) (xy 121.400191 -232.150598) (xy 121.432826 -232.113761)
			(xy 121.470947 -232.082636) (xy 121.513568 -232.058029) (xy 121.559584 -232.040577) (xy 121.607803 -232.030733)
			(xy 121.656978 -232.028752) (xy 121.705833 -232.034684) (xy 121.753104 -232.048376) (xy 121.797566 -232.069474)
			(xy 121.838069 -232.09743) (xy 121.873562 -232.131522) (xy 121.903127 -232.170866) (xy 121.925998 -232.214443)
			(xy 121.941582 -232.261124) (xy 121.949477 -232.309701) (xy 121.949972 -232.334308) (xy 122.278914 -232.334308)
			(xy 122.282874 -232.285254) (xy 122.294651 -232.23747) (xy 122.313942 -232.192194) (xy 122.340245 -232.150598)
			(xy 122.37288 -232.113761) (xy 122.411001 -232.082636) (xy 122.453622 -232.058029) (xy 122.499638 -232.040577)
			(xy 122.547857 -232.030733) (xy 122.597032 -232.028752) (xy 122.645887 -232.034684) (xy 122.693158 -232.048376)
			(xy 122.73762 -232.069474) (xy 122.778123 -232.09743) (xy 122.813616 -232.131522) (xy 122.843181 -232.170866)
			(xy 122.866052 -232.214443) (xy 122.881636 -232.261124) (xy 122.889531 -232.309701) (xy 122.890026 -232.334308)
			(xy 123.218968 -232.334308) (xy 123.222928 -232.285254) (xy 123.234705 -232.23747) (xy 123.253996 -232.192194)
			(xy 123.280299 -232.150598) (xy 123.312934 -232.113761) (xy 123.351055 -232.082636) (xy 123.393676 -232.058029)
			(xy 123.439692 -232.040577) (xy 123.487911 -232.030733) (xy 123.537086 -232.028752) (xy 123.585941 -232.034684)
			(xy 123.633212 -232.048376) (xy 123.677674 -232.069474) (xy 123.718177 -232.09743) (xy 123.75367 -232.131522)
			(xy 123.783235 -232.170866) (xy 123.806106 -232.214443) (xy 123.82169 -232.261124) (xy 123.829585 -232.309701)
			(xy 123.83008 -232.334308) (xy 124.159022 -232.334308) (xy 124.162982 -232.285254) (xy 124.174759 -232.23747)
			(xy 124.19405 -232.192194) (xy 124.220353 -232.150598) (xy 124.252988 -232.113761) (xy 124.291109 -232.082636)
			(xy 124.33373 -232.058029) (xy 124.379746 -232.040577) (xy 124.427965 -232.030733) (xy 124.47714 -232.028752)
			(xy 124.525995 -232.034684) (xy 124.573266 -232.048376) (xy 124.617728 -232.069474) (xy 124.658231 -232.09743)
			(xy 124.693724 -232.131522) (xy 124.723289 -232.170866) (xy 124.74616 -232.214443) (xy 124.761744 -232.261124)
			(xy 124.769639 -232.309701) (xy 124.770134 -232.334308) (xy 125.098822 -232.334308) (xy 125.102782 -232.285254)
			(xy 125.114559 -232.23747) (xy 125.13385 -232.192194) (xy 125.160153 -232.150598) (xy 125.192788 -232.113761)
			(xy 125.230909 -232.082636) (xy 125.27353 -232.058029) (xy 125.319546 -232.040577) (xy 125.367765 -232.030733)
			(xy 125.41694 -232.028752) (xy 125.465795 -232.034684) (xy 125.513066 -232.048376) (xy 125.557528 -232.069474)
			(xy 125.598031 -232.09743) (xy 125.633524 -232.131522) (xy 125.663089 -232.170866) (xy 125.68596 -232.214443)
			(xy 125.701544 -232.261124) (xy 125.709439 -232.309701) (xy 125.709934 -232.334308) (xy 125.709439 -232.358915)
			(xy 125.701544 -232.407492) (xy 125.68596 -232.454173) (xy 125.663089 -232.49775) (xy 125.633524 -232.537094)
			(xy 125.598031 -232.571186) (xy 125.557528 -232.599142) (xy 125.513066 -232.62024) (xy 125.465795 -232.633932)
			(xy 125.41694 -232.639864) (xy 125.367765 -232.637883) (xy 125.319546 -232.628039) (xy 125.27353 -232.610587)
			(xy 125.230909 -232.58598) (xy 125.192788 -232.554855) (xy 125.160153 -232.518018) (xy 125.13385 -232.476422)
			(xy 125.114559 -232.431146) (xy 125.102782 -232.383362) (xy 125.098822 -232.334308) (xy 124.770134 -232.334308)
			(xy 124.769639 -232.358915) (xy 124.761744 -232.407492) (xy 124.74616 -232.454173) (xy 124.723289 -232.49775)
			(xy 124.693724 -232.537094) (xy 124.658231 -232.571186) (xy 124.617728 -232.599142) (xy 124.573266 -232.62024)
			(xy 124.525995 -232.633932) (xy 124.47714 -232.639864) (xy 124.427965 -232.637883) (xy 124.379746 -232.628039)
			(xy 124.33373 -232.610587) (xy 124.291109 -232.58598) (xy 124.252988 -232.554855) (xy 124.220353 -232.518018)
			(xy 124.19405 -232.476422) (xy 124.174759 -232.431146) (xy 124.162982 -232.383362) (xy 124.159022 -232.334308)
			(xy 123.83008 -232.334308) (xy 123.829585 -232.358915) (xy 123.82169 -232.407492) (xy 123.806106 -232.454173)
			(xy 123.783235 -232.49775) (xy 123.75367 -232.537094) (xy 123.718177 -232.571186) (xy 123.677674 -232.599142)
			(xy 123.633212 -232.62024) (xy 123.585941 -232.633932) (xy 123.537086 -232.639864) (xy 123.487911 -232.637883)
			(xy 123.439692 -232.628039) (xy 123.393676 -232.610587) (xy 123.351055 -232.58598) (xy 123.312934 -232.554855)
			(xy 123.280299 -232.518018) (xy 123.253996 -232.476422) (xy 123.234705 -232.431146) (xy 123.222928 -232.383362)
			(xy 123.218968 -232.334308) (xy 122.890026 -232.334308) (xy 122.889531 -232.358915) (xy 122.881636 -232.407492)
			(xy 122.866052 -232.454173) (xy 122.843181 -232.49775) (xy 122.813616 -232.537094) (xy 122.778123 -232.571186)
			(xy 122.73762 -232.599142) (xy 122.693158 -232.62024) (xy 122.645887 -232.633932) (xy 122.597032 -232.639864)
			(xy 122.547857 -232.637883) (xy 122.499638 -232.628039) (xy 122.453622 -232.610587) (xy 122.411001 -232.58598)
			(xy 122.37288 -232.554855) (xy 122.340245 -232.518018) (xy 122.313942 -232.476422) (xy 122.294651 -232.431146)
			(xy 122.282874 -232.383362) (xy 122.278914 -232.334308) (xy 121.949972 -232.334308) (xy 121.949477 -232.358915)
			(xy 121.941582 -232.407492) (xy 121.925998 -232.454173) (xy 121.903127 -232.49775) (xy 121.873562 -232.537094)
			(xy 121.838069 -232.571186) (xy 121.797566 -232.599142) (xy 121.753104 -232.62024) (xy 121.705833 -232.633932)
			(xy 121.656978 -232.639864) (xy 121.607803 -232.637883) (xy 121.559584 -232.628039) (xy 121.513568 -232.610587)
			(xy 121.470947 -232.58598) (xy 121.432826 -232.554855) (xy 121.400191 -232.518018) (xy 121.373888 -232.476422)
			(xy 121.354597 -232.431146) (xy 121.34282 -232.383362) (xy 121.33886 -232.334308) (xy 121.009918 -232.334308)
			(xy 121.009423 -232.358915) (xy 121.001528 -232.407492) (xy 120.985944 -232.454173) (xy 120.963073 -232.49775)
			(xy 120.933508 -232.537094) (xy 120.898015 -232.571186) (xy 120.857512 -232.599142) (xy 120.81305 -232.62024)
			(xy 120.765779 -232.633932) (xy 120.716924 -232.639864) (xy 120.667749 -232.637883) (xy 120.61953 -232.628039)
			(xy 120.573514 -232.610587) (xy 120.530893 -232.58598) (xy 120.492772 -232.554855) (xy 120.460137 -232.518018)
			(xy 120.433834 -232.476422) (xy 120.414543 -232.431146) (xy 120.402766 -232.383362) (xy 120.398806 -232.334308)
			(xy 120.070118 -232.334308) (xy 120.069623 -232.358915) (xy 120.061728 -232.407492) (xy 120.046144 -232.454173)
			(xy 120.023273 -232.49775) (xy 119.993708 -232.537094) (xy 119.958215 -232.571186) (xy 119.917712 -232.599142)
			(xy 119.87325 -232.62024) (xy 119.825979 -232.633932) (xy 119.777124 -232.639864) (xy 119.727949 -232.637883)
			(xy 119.67973 -232.628039) (xy 119.633714 -232.610587) (xy 119.591093 -232.58598) (xy 119.552972 -232.554855)
			(xy 119.520337 -232.518018) (xy 119.494034 -232.476422) (xy 119.474743 -232.431146) (xy 119.462966 -232.383362)
			(xy 119.459006 -232.334308) (xy 119.130064 -232.334308) (xy 119.129569 -232.358915) (xy 119.121674 -232.407492)
			(xy 119.10609 -232.454173) (xy 119.083219 -232.49775) (xy 119.053654 -232.537094) (xy 119.018161 -232.571186)
			(xy 118.977658 -232.599142) (xy 118.933196 -232.62024) (xy 118.885925 -232.633932) (xy 118.83707 -232.639864)
			(xy 118.787895 -232.637883) (xy 118.739676 -232.628039) (xy 118.69366 -232.610587) (xy 118.651039 -232.58598)
			(xy 118.612918 -232.554855) (xy 118.580283 -232.518018) (xy 118.55398 -232.476422) (xy 118.534689 -232.431146)
			(xy 118.522912 -232.383362) (xy 118.518952 -232.334308) (xy 118.19001 -232.334308) (xy 118.189515 -232.358915)
			(xy 118.18162 -232.407492) (xy 118.166036 -232.454173) (xy 118.143165 -232.49775) (xy 118.1136 -232.537094)
			(xy 118.078107 -232.571186) (xy 118.037604 -232.599142) (xy 117.993142 -232.62024) (xy 117.945871 -232.633932)
			(xy 117.897016 -232.639864) (xy 117.847841 -232.637883) (xy 117.799622 -232.628039) (xy 117.753606 -232.610587)
			(xy 117.710985 -232.58598) (xy 117.672864 -232.554855) (xy 117.640229 -232.518018) (xy 117.613926 -232.476422)
			(xy 117.594635 -232.431146) (xy 117.582858 -232.383362) (xy 117.578898 -232.334308) (xy 117.249956 -232.334308)
			(xy 117.249461 -232.358915) (xy 117.241566 -232.407492) (xy 117.225982 -232.454173) (xy 117.203111 -232.49775)
			(xy 117.173546 -232.537094) (xy 117.138053 -232.571186) (xy 117.09755 -232.599142) (xy 117.053088 -232.62024)
			(xy 117.005817 -232.633932) (xy 116.956962 -232.639864) (xy 116.907787 -232.637883) (xy 116.859568 -232.628039)
			(xy 116.813552 -232.610587) (xy 116.770931 -232.58598) (xy 116.73281 -232.554855) (xy 116.700175 -232.518018)
			(xy 116.673872 -232.476422) (xy 116.654581 -232.431146) (xy 116.642804 -232.383362) (xy 116.638844 -232.334308)
			(xy 116.310156 -232.334308) (xy 116.309661 -232.358915) (xy 116.301766 -232.407492) (xy 116.286182 -232.454173)
			(xy 116.263311 -232.49775) (xy 116.233746 -232.537094) (xy 116.198253 -232.571186) (xy 116.15775 -232.599142)
			(xy 116.113288 -232.62024) (xy 116.066017 -232.633932) (xy 116.017162 -232.639864) (xy 115.967987 -232.637883)
			(xy 115.919768 -232.628039) (xy 115.873752 -232.610587) (xy 115.831131 -232.58598) (xy 115.79301 -232.554855)
			(xy 115.760375 -232.518018) (xy 115.734072 -232.476422) (xy 115.714781 -232.431146) (xy 115.703004 -232.383362)
			(xy 115.699044 -232.334308) (xy 115.370102 -232.334308) (xy 115.369607 -232.358915) (xy 115.361712 -232.407492)
			(xy 115.346128 -232.454173) (xy 115.323257 -232.49775) (xy 115.293692 -232.537094) (xy 115.258199 -232.571186)
			(xy 115.217696 -232.599142) (xy 115.173234 -232.62024) (xy 115.125963 -232.633932) (xy 115.077108 -232.639864)
			(xy 115.027933 -232.637883) (xy 114.979714 -232.628039) (xy 114.933698 -232.610587) (xy 114.891077 -232.58598)
			(xy 114.852956 -232.554855) (xy 114.820321 -232.518018) (xy 114.794018 -232.476422) (xy 114.774727 -232.431146)
			(xy 114.76295 -232.383362) (xy 114.75899 -232.334308) (xy 114.430048 -232.334308) (xy 114.429553 -232.358915)
			(xy 114.421658 -232.407492) (xy 114.406074 -232.454173) (xy 114.383203 -232.49775) (xy 114.353638 -232.537094)
			(xy 114.318145 -232.571186) (xy 114.277642 -232.599142) (xy 114.23318 -232.62024) (xy 114.185909 -232.633932)
			(xy 114.137054 -232.639864) (xy 114.087879 -232.637883) (xy 114.03966 -232.628039) (xy 113.993644 -232.610587)
			(xy 113.951023 -232.58598) (xy 113.912902 -232.554855) (xy 113.880267 -232.518018) (xy 113.853964 -232.476422)
			(xy 113.834673 -232.431146) (xy 113.822896 -232.383362) (xy 113.818936 -232.334308) (xy 113.56594 -232.334308)
			(xy 113.56594 -232.73766) (xy 113.566436 -232.747472) (xy 113.573878 -232.765635) (xy 113.580418 -232.772966)
			(xy 113.629694 -232.823766) (xy 113.633187 -232.827226) (xy 113.641243 -232.83286) (xy 113.645696 -232.834942)
			(xy 113.655094 -232.839006) (xy 113.67907 -232.839499) (xy 113.726425 -232.847041) (xy 113.772019 -232.861895)
			(xy 113.81473 -232.883694) (xy 113.853507 -232.911903) (xy 113.887397 -232.945827) (xy 113.915567 -232.984633)
			(xy 113.937323 -233.027366) (xy 113.952131 -233.072975) (xy 113.959626 -233.120338) (xy 113.960148 -233.144314)
			(xy 114.288836 -233.144314) (xy 114.292796 -233.09526) (xy 114.304573 -233.047476) (xy 114.323864 -233.0022)
			(xy 114.350167 -232.960604) (xy 114.382802 -232.923767) (xy 114.420923 -232.892642) (xy 114.463544 -232.868035)
			(xy 114.50956 -232.850583) (xy 114.557779 -232.840739) (xy 114.606954 -232.838758) (xy 114.655809 -232.84469)
			(xy 114.70308 -232.858382) (xy 114.747542 -232.87948) (xy 114.788045 -232.907436) (xy 114.823538 -232.941528)
			(xy 114.853103 -232.980872) (xy 114.875974 -233.024449) (xy 114.891558 -233.07113) (xy 114.899453 -233.119707)
			(xy 114.899948 -233.144314) (xy 115.22889 -233.144314) (xy 115.23285 -233.09526) (xy 115.244627 -233.047476)
			(xy 115.263918 -233.0022) (xy 115.290221 -232.960604) (xy 115.322856 -232.923767) (xy 115.360977 -232.892642)
			(xy 115.403598 -232.868035) (xy 115.449614 -232.850583) (xy 115.497833 -232.840739) (xy 115.547008 -232.838758)
			(xy 115.595863 -232.84469) (xy 115.643134 -232.858382) (xy 115.687596 -232.87948) (xy 115.728099 -232.907436)
			(xy 115.763592 -232.941528) (xy 115.793157 -232.980872) (xy 115.816028 -233.024449) (xy 115.831612 -233.07113)
			(xy 115.839507 -233.119707) (xy 115.840002 -233.144314) (xy 116.168944 -233.144314) (xy 116.172904 -233.09526)
			(xy 116.184681 -233.047476) (xy 116.203972 -233.0022) (xy 116.230275 -232.960604) (xy 116.26291 -232.923767)
			(xy 116.301031 -232.892642) (xy 116.343652 -232.868035) (xy 116.389668 -232.850583) (xy 116.437887 -232.840739)
			(xy 116.487062 -232.838758) (xy 116.535917 -232.84469) (xy 116.583188 -232.858382) (xy 116.62765 -232.87948)
			(xy 116.668153 -232.907436) (xy 116.703646 -232.941528) (xy 116.733211 -232.980872) (xy 116.756082 -233.024449)
			(xy 116.771666 -233.07113) (xy 116.779561 -233.119707) (xy 116.780056 -233.144314) (xy 117.108998 -233.144314)
			(xy 117.112958 -233.09526) (xy 117.124735 -233.047476) (xy 117.144026 -233.0022) (xy 117.170329 -232.960604)
			(xy 117.202964 -232.923767) (xy 117.241085 -232.892642) (xy 117.283706 -232.868035) (xy 117.329722 -232.850583)
			(xy 117.377941 -232.840739) (xy 117.427116 -232.838758) (xy 117.475971 -232.84469) (xy 117.523242 -232.858382)
			(xy 117.567704 -232.87948) (xy 117.608207 -232.907436) (xy 117.6437 -232.941528) (xy 117.673265 -232.980872)
			(xy 117.696136 -233.024449) (xy 117.71172 -233.07113) (xy 117.719615 -233.119707) (xy 117.72011 -233.144314)
			(xy 118.049052 -233.144314) (xy 118.053012 -233.09526) (xy 118.064789 -233.047476) (xy 118.08408 -233.0022)
			(xy 118.110383 -232.960604) (xy 118.143018 -232.923767) (xy 118.181139 -232.892642) (xy 118.22376 -232.868035)
			(xy 118.269776 -232.850583) (xy 118.317995 -232.840739) (xy 118.36717 -232.838758) (xy 118.416025 -232.84469)
			(xy 118.463296 -232.858382) (xy 118.507758 -232.87948) (xy 118.548261 -232.907436) (xy 118.583754 -232.941528)
			(xy 118.613319 -232.980872) (xy 118.63619 -233.024449) (xy 118.651774 -233.07113) (xy 118.659669 -233.119707)
			(xy 118.660164 -233.144314) (xy 118.988852 -233.144314) (xy 118.992812 -233.09526) (xy 119.004589 -233.047476)
			(xy 119.02388 -233.0022) (xy 119.050183 -232.960604) (xy 119.082818 -232.923767) (xy 119.120939 -232.892642)
			(xy 119.16356 -232.868035) (xy 119.209576 -232.850583) (xy 119.257795 -232.840739) (xy 119.30697 -232.838758)
			(xy 119.355825 -232.84469) (xy 119.403096 -232.858382) (xy 119.447558 -232.87948) (xy 119.488061 -232.907436)
			(xy 119.523554 -232.941528) (xy 119.553119 -232.980872) (xy 119.57599 -233.024449) (xy 119.591574 -233.07113)
			(xy 119.599469 -233.119707) (xy 119.599964 -233.144314) (xy 119.928906 -233.144314) (xy 119.932866 -233.09526)
			(xy 119.944643 -233.047476) (xy 119.963934 -233.0022) (xy 119.990237 -232.960604) (xy 120.022872 -232.923767)
			(xy 120.060993 -232.892642) (xy 120.103614 -232.868035) (xy 120.14963 -232.850583) (xy 120.197849 -232.840739)
			(xy 120.247024 -232.838758) (xy 120.295879 -232.84469) (xy 120.34315 -232.858382) (xy 120.387612 -232.87948)
			(xy 120.428115 -232.907436) (xy 120.463608 -232.941528) (xy 120.493173 -232.980872) (xy 120.516044 -233.024449)
			(xy 120.531628 -233.07113) (xy 120.539523 -233.119707) (xy 120.540018 -233.144314) (xy 120.86896 -233.144314)
			(xy 120.87292 -233.09526) (xy 120.884697 -233.047476) (xy 120.903988 -233.0022) (xy 120.930291 -232.960604)
			(xy 120.962926 -232.923767) (xy 121.001047 -232.892642) (xy 121.043668 -232.868035) (xy 121.089684 -232.850583)
			(xy 121.137903 -232.840739) (xy 121.187078 -232.838758) (xy 121.235933 -232.84469) (xy 121.283204 -232.858382)
			(xy 121.327666 -232.87948) (xy 121.368169 -232.907436) (xy 121.403662 -232.941528) (xy 121.433227 -232.980872)
			(xy 121.456098 -233.024449) (xy 121.471682 -233.07113) (xy 121.479577 -233.119707) (xy 121.480072 -233.144314)
			(xy 121.809014 -233.144314) (xy 121.812974 -233.09526) (xy 121.824751 -233.047476) (xy 121.844042 -233.0022)
			(xy 121.870345 -232.960604) (xy 121.90298 -232.923767) (xy 121.941101 -232.892642) (xy 121.983722 -232.868035)
			(xy 122.029738 -232.850583) (xy 122.077957 -232.840739) (xy 122.127132 -232.838758) (xy 122.175987 -232.84469)
			(xy 122.223258 -232.858382) (xy 122.26772 -232.87948) (xy 122.308223 -232.907436) (xy 122.343716 -232.941528)
			(xy 122.373281 -232.980872) (xy 122.396152 -233.024449) (xy 122.411736 -233.07113) (xy 122.419631 -233.119707)
			(xy 122.420126 -233.144314) (xy 122.748814 -233.144314) (xy 122.752774 -233.09526) (xy 122.764551 -233.047476)
			(xy 122.783842 -233.0022) (xy 122.810145 -232.960604) (xy 122.84278 -232.923767) (xy 122.880901 -232.892642)
			(xy 122.923522 -232.868035) (xy 122.969538 -232.850583) (xy 123.017757 -232.840739) (xy 123.066932 -232.838758)
			(xy 123.115787 -232.84469) (xy 123.163058 -232.858382) (xy 123.20752 -232.87948) (xy 123.248023 -232.907436)
			(xy 123.283516 -232.941528) (xy 123.313081 -232.980872) (xy 123.335952 -233.024449) (xy 123.351536 -233.07113)
			(xy 123.359431 -233.119707) (xy 123.359926 -233.144314) (xy 123.688868 -233.144314) (xy 123.692828 -233.09526)
			(xy 123.704605 -233.047476) (xy 123.723896 -233.0022) (xy 123.750199 -232.960604) (xy 123.782834 -232.923767)
			(xy 123.820955 -232.892642) (xy 123.863576 -232.868035) (xy 123.909592 -232.850583) (xy 123.957811 -232.840739)
			(xy 124.006986 -232.838758) (xy 124.055841 -232.84469) (xy 124.103112 -232.858382) (xy 124.147574 -232.87948)
			(xy 124.188077 -232.907436) (xy 124.22357 -232.941528) (xy 124.253135 -232.980872) (xy 124.276006 -233.024449)
			(xy 124.29159 -233.07113) (xy 124.299485 -233.119707) (xy 124.29998 -233.144314) (xy 124.628922 -233.144314)
			(xy 124.632882 -233.09526) (xy 124.644659 -233.047476) (xy 124.66395 -233.0022) (xy 124.690253 -232.960604)
			(xy 124.722888 -232.923767) (xy 124.761009 -232.892642) (xy 124.80363 -232.868035) (xy 124.849646 -232.850583)
			(xy 124.897865 -232.840739) (xy 124.94704 -232.838758) (xy 124.995895 -232.84469) (xy 125.043166 -232.858382)
			(xy 125.087628 -232.87948) (xy 125.128131 -232.907436) (xy 125.163624 -232.941528) (xy 125.193189 -232.980872)
			(xy 125.21606 -233.024449) (xy 125.231644 -233.07113) (xy 125.239539 -233.119707) (xy 125.240034 -233.144314)
			(xy 125.568976 -233.144314) (xy 125.572936 -233.09526) (xy 125.584713 -233.047476) (xy 125.604004 -233.0022)
			(xy 125.630307 -232.960604) (xy 125.662942 -232.923767) (xy 125.701063 -232.892642) (xy 125.743684 -232.868035)
			(xy 125.7897 -232.850583) (xy 125.837919 -232.840739) (xy 125.887094 -232.838758) (xy 125.935949 -232.84469)
			(xy 125.98322 -232.858382) (xy 126.027682 -232.87948) (xy 126.068185 -232.907436) (xy 126.103678 -232.941528)
			(xy 126.133243 -232.980872) (xy 126.156114 -233.024449) (xy 126.171698 -233.07113) (xy 126.179593 -233.119707)
			(xy 126.180088 -233.144314) (xy 126.179593 -233.168921) (xy 126.171698 -233.217498) (xy 126.156114 -233.264179)
			(xy 126.133243 -233.307756) (xy 126.103678 -233.3471) (xy 126.068185 -233.381192) (xy 126.027682 -233.409148)
			(xy 125.98322 -233.430246) (xy 125.935949 -233.443938) (xy 125.887094 -233.44987) (xy 125.837919 -233.447889)
			(xy 125.7897 -233.438045) (xy 125.743684 -233.420593) (xy 125.701063 -233.395986) (xy 125.662942 -233.364861)
			(xy 125.630307 -233.328024) (xy 125.604004 -233.286428) (xy 125.584713 -233.241152) (xy 125.572936 -233.193368)
			(xy 125.568976 -233.144314) (xy 125.240034 -233.144314) (xy 125.239539 -233.168921) (xy 125.231644 -233.217498)
			(xy 125.21606 -233.264179) (xy 125.193189 -233.307756) (xy 125.163624 -233.3471) (xy 125.128131 -233.381192)
			(xy 125.087628 -233.409148) (xy 125.043166 -233.430246) (xy 124.995895 -233.443938) (xy 124.94704 -233.44987)
			(xy 124.897865 -233.447889) (xy 124.849646 -233.438045) (xy 124.80363 -233.420593) (xy 124.761009 -233.395986)
			(xy 124.722888 -233.364861) (xy 124.690253 -233.328024) (xy 124.66395 -233.286428) (xy 124.644659 -233.241152)
			(xy 124.632882 -233.193368) (xy 124.628922 -233.144314) (xy 124.29998 -233.144314) (xy 124.299485 -233.168921)
			(xy 124.29159 -233.217498) (xy 124.276006 -233.264179) (xy 124.253135 -233.307756) (xy 124.22357 -233.3471)
			(xy 124.188077 -233.381192) (xy 124.147574 -233.409148) (xy 124.103112 -233.430246) (xy 124.055841 -233.443938)
			(xy 124.006986 -233.44987) (xy 123.957811 -233.447889) (xy 123.909592 -233.438045) (xy 123.863576 -233.420593)
			(xy 123.820955 -233.395986) (xy 123.782834 -233.364861) (xy 123.750199 -233.328024) (xy 123.723896 -233.286428)
			(xy 123.704605 -233.241152) (xy 123.692828 -233.193368) (xy 123.688868 -233.144314) (xy 123.359926 -233.144314)
			(xy 123.359431 -233.168921) (xy 123.351536 -233.217498) (xy 123.335952 -233.264179) (xy 123.313081 -233.307756)
			(xy 123.283516 -233.3471) (xy 123.248023 -233.381192) (xy 123.20752 -233.409148) (xy 123.163058 -233.430246)
			(xy 123.115787 -233.443938) (xy 123.066932 -233.44987) (xy 123.017757 -233.447889) (xy 122.969538 -233.438045)
			(xy 122.923522 -233.420593) (xy 122.880901 -233.395986) (xy 122.84278 -233.364861) (xy 122.810145 -233.328024)
			(xy 122.783842 -233.286428) (xy 122.764551 -233.241152) (xy 122.752774 -233.193368) (xy 122.748814 -233.144314)
			(xy 122.420126 -233.144314) (xy 122.419631 -233.168921) (xy 122.411736 -233.217498) (xy 122.396152 -233.264179)
			(xy 122.373281 -233.307756) (xy 122.343716 -233.3471) (xy 122.308223 -233.381192) (xy 122.26772 -233.409148)
			(xy 122.223258 -233.430246) (xy 122.175987 -233.443938) (xy 122.127132 -233.44987) (xy 122.077957 -233.447889)
			(xy 122.029738 -233.438045) (xy 121.983722 -233.420593) (xy 121.941101 -233.395986) (xy 121.90298 -233.364861)
			(xy 121.870345 -233.328024) (xy 121.844042 -233.286428) (xy 121.824751 -233.241152) (xy 121.812974 -233.193368)
			(xy 121.809014 -233.144314) (xy 121.480072 -233.144314) (xy 121.479577 -233.168921) (xy 121.471682 -233.217498)
			(xy 121.456098 -233.264179) (xy 121.433227 -233.307756) (xy 121.403662 -233.3471) (xy 121.368169 -233.381192)
			(xy 121.327666 -233.409148) (xy 121.283204 -233.430246) (xy 121.235933 -233.443938) (xy 121.187078 -233.44987)
			(xy 121.137903 -233.447889) (xy 121.089684 -233.438045) (xy 121.043668 -233.420593) (xy 121.001047 -233.395986)
			(xy 120.962926 -233.364861) (xy 120.930291 -233.328024) (xy 120.903988 -233.286428) (xy 120.884697 -233.241152)
			(xy 120.87292 -233.193368) (xy 120.86896 -233.144314) (xy 120.540018 -233.144314) (xy 120.539523 -233.168921)
			(xy 120.531628 -233.217498) (xy 120.516044 -233.264179) (xy 120.493173 -233.307756) (xy 120.463608 -233.3471)
			(xy 120.428115 -233.381192) (xy 120.387612 -233.409148) (xy 120.34315 -233.430246) (xy 120.295879 -233.443938)
			(xy 120.247024 -233.44987) (xy 120.197849 -233.447889) (xy 120.14963 -233.438045) (xy 120.103614 -233.420593)
			(xy 120.060993 -233.395986) (xy 120.022872 -233.364861) (xy 119.990237 -233.328024) (xy 119.963934 -233.286428)
			(xy 119.944643 -233.241152) (xy 119.932866 -233.193368) (xy 119.928906 -233.144314) (xy 119.599964 -233.144314)
			(xy 119.599469 -233.168921) (xy 119.591574 -233.217498) (xy 119.57599 -233.264179) (xy 119.553119 -233.307756)
			(xy 119.523554 -233.3471) (xy 119.488061 -233.381192) (xy 119.447558 -233.409148) (xy 119.403096 -233.430246)
			(xy 119.355825 -233.443938) (xy 119.30697 -233.44987) (xy 119.257795 -233.447889) (xy 119.209576 -233.438045)
			(xy 119.16356 -233.420593) (xy 119.120939 -233.395986) (xy 119.082818 -233.364861) (xy 119.050183 -233.328024)
			(xy 119.02388 -233.286428) (xy 119.004589 -233.241152) (xy 118.992812 -233.193368) (xy 118.988852 -233.144314)
			(xy 118.660164 -233.144314) (xy 118.659669 -233.168921) (xy 118.651774 -233.217498) (xy 118.63619 -233.264179)
			(xy 118.613319 -233.307756) (xy 118.583754 -233.3471) (xy 118.548261 -233.381192) (xy 118.507758 -233.409148)
			(xy 118.463296 -233.430246) (xy 118.416025 -233.443938) (xy 118.36717 -233.44987) (xy 118.317995 -233.447889)
			(xy 118.269776 -233.438045) (xy 118.22376 -233.420593) (xy 118.181139 -233.395986) (xy 118.143018 -233.364861)
			(xy 118.110383 -233.328024) (xy 118.08408 -233.286428) (xy 118.064789 -233.241152) (xy 118.053012 -233.193368)
			(xy 118.049052 -233.144314) (xy 117.72011 -233.144314) (xy 117.719615 -233.168921) (xy 117.71172 -233.217498)
			(xy 117.696136 -233.264179) (xy 117.673265 -233.307756) (xy 117.6437 -233.3471) (xy 117.608207 -233.381192)
			(xy 117.567704 -233.409148) (xy 117.523242 -233.430246) (xy 117.475971 -233.443938) (xy 117.427116 -233.44987)
			(xy 117.377941 -233.447889) (xy 117.329722 -233.438045) (xy 117.283706 -233.420593) (xy 117.241085 -233.395986)
			(xy 117.202964 -233.364861) (xy 117.170329 -233.328024) (xy 117.144026 -233.286428) (xy 117.124735 -233.241152)
			(xy 117.112958 -233.193368) (xy 117.108998 -233.144314) (xy 116.780056 -233.144314) (xy 116.779561 -233.168921)
			(xy 116.771666 -233.217498) (xy 116.756082 -233.264179) (xy 116.733211 -233.307756) (xy 116.703646 -233.3471)
			(xy 116.668153 -233.381192) (xy 116.62765 -233.409148) (xy 116.583188 -233.430246) (xy 116.535917 -233.443938)
			(xy 116.487062 -233.44987) (xy 116.437887 -233.447889) (xy 116.389668 -233.438045) (xy 116.343652 -233.420593)
			(xy 116.301031 -233.395986) (xy 116.26291 -233.364861) (xy 116.230275 -233.328024) (xy 116.203972 -233.286428)
			(xy 116.184681 -233.241152) (xy 116.172904 -233.193368) (xy 116.168944 -233.144314) (xy 115.840002 -233.144314)
			(xy 115.839507 -233.168921) (xy 115.831612 -233.217498) (xy 115.816028 -233.264179) (xy 115.793157 -233.307756)
			(xy 115.763592 -233.3471) (xy 115.728099 -233.381192) (xy 115.687596 -233.409148) (xy 115.643134 -233.430246)
			(xy 115.595863 -233.443938) (xy 115.547008 -233.44987) (xy 115.497833 -233.447889) (xy 115.449614 -233.438045)
			(xy 115.403598 -233.420593) (xy 115.360977 -233.395986) (xy 115.322856 -233.364861) (xy 115.290221 -233.328024)
			(xy 115.263918 -233.286428) (xy 115.244627 -233.241152) (xy 115.23285 -233.193368) (xy 115.22889 -233.144314)
			(xy 114.899948 -233.144314) (xy 114.899453 -233.168921) (xy 114.891558 -233.217498) (xy 114.875974 -233.264179)
			(xy 114.853103 -233.307756) (xy 114.823538 -233.3471) (xy 114.788045 -233.381192) (xy 114.747542 -233.409148)
			(xy 114.70308 -233.430246) (xy 114.655809 -233.443938) (xy 114.606954 -233.44987) (xy 114.557779 -233.447889)
			(xy 114.50956 -233.438045) (xy 114.463544 -233.420593) (xy 114.420923 -233.395986) (xy 114.382802 -233.364861)
			(xy 114.350167 -233.328024) (xy 114.323864 -233.286428) (xy 114.304573 -233.241152) (xy 114.292796 -233.193368)
			(xy 114.288836 -233.144314) (xy 113.960148 -233.144314) (xy 113.959721 -233.167823) (xy 113.952522 -233.214287)
			(xy 113.938282 -233.259096) (xy 113.917336 -233.301191) (xy 113.890182 -233.339575) (xy 113.857461 -233.373339)
			(xy 113.819949 -233.401685) (xy 113.778532 -233.423941) (xy 113.734192 -233.439582) (xy 113.687977 -233.448236)
			(xy 113.664492 -233.449368) (xy 113.659709 -233.44967) (xy 113.650376 -233.451846) (xy 113.64595 -233.453686)
			(xy 113.636552 -233.45775) (xy 113.580418 -233.515662) (xy 113.573875 -233.522991) (xy 113.566435 -233.541155)
			(xy 113.56594 -233.550968) (xy 113.56594 -233.95432) (xy 113.818936 -233.95432) (xy 113.822896 -233.905266)
			(xy 113.834673 -233.857482) (xy 113.853964 -233.812206) (xy 113.880267 -233.77061) (xy 113.912902 -233.733773)
			(xy 113.951023 -233.702648) (xy 113.993644 -233.678041) (xy 114.03966 -233.660589) (xy 114.087879 -233.650745)
			(xy 114.137054 -233.648764) (xy 114.185909 -233.654696) (xy 114.23318 -233.668388) (xy 114.277642 -233.689486)
			(xy 114.318145 -233.717442) (xy 114.353638 -233.751534) (xy 114.383203 -233.790878) (xy 114.406074 -233.834455)
			(xy 114.421658 -233.881136) (xy 114.429553 -233.929713) (xy 114.430048 -233.95432) (xy 114.75899 -233.95432)
			(xy 114.76295 -233.905266) (xy 114.774727 -233.857482) (xy 114.794018 -233.812206) (xy 114.820321 -233.77061)
			(xy 114.852956 -233.733773) (xy 114.891077 -233.702648) (xy 114.933698 -233.678041) (xy 114.979714 -233.660589)
			(xy 115.027933 -233.650745) (xy 115.077108 -233.648764) (xy 115.125963 -233.654696) (xy 115.173234 -233.668388)
			(xy 115.217696 -233.689486) (xy 115.258199 -233.717442) (xy 115.293692 -233.751534) (xy 115.323257 -233.790878)
			(xy 115.346128 -233.834455) (xy 115.361712 -233.881136) (xy 115.369607 -233.929713) (xy 115.370102 -233.95432)
			(xy 115.699044 -233.95432) (xy 115.703004 -233.905266) (xy 115.714781 -233.857482) (xy 115.734072 -233.812206)
			(xy 115.760375 -233.77061) (xy 115.79301 -233.733773) (xy 115.831131 -233.702648) (xy 115.873752 -233.678041)
			(xy 115.919768 -233.660589) (xy 115.967987 -233.650745) (xy 116.017162 -233.648764) (xy 116.066017 -233.654696)
			(xy 116.113288 -233.668388) (xy 116.15775 -233.689486) (xy 116.198253 -233.717442) (xy 116.233746 -233.751534)
			(xy 116.263311 -233.790878) (xy 116.286182 -233.834455) (xy 116.301766 -233.881136) (xy 116.309661 -233.929713)
			(xy 116.310156 -233.95432) (xy 118.518952 -233.95432) (xy 118.522912 -233.905266) (xy 118.534689 -233.857482)
			(xy 118.55398 -233.812206) (xy 118.580283 -233.77061) (xy 118.612918 -233.733773) (xy 118.651039 -233.702648)
			(xy 118.69366 -233.678041) (xy 118.739676 -233.660589) (xy 118.787895 -233.650745) (xy 118.83707 -233.648764)
			(xy 118.885925 -233.654696) (xy 118.933196 -233.668388) (xy 118.977658 -233.689486) (xy 119.018161 -233.717442)
			(xy 119.053654 -233.751534) (xy 119.083219 -233.790878) (xy 119.10609 -233.834455) (xy 119.121674 -233.881136)
			(xy 119.129569 -233.929713) (xy 119.130064 -233.95432) (xy 121.33886 -233.95432) (xy 121.34282 -233.905266)
			(xy 121.354597 -233.857482) (xy 121.373888 -233.812206) (xy 121.400191 -233.77061) (xy 121.432826 -233.733773)
			(xy 121.470947 -233.702648) (xy 121.513568 -233.678041) (xy 121.559584 -233.660589) (xy 121.607803 -233.650745)
			(xy 121.656978 -233.648764) (xy 121.705833 -233.654696) (xy 121.753104 -233.668388) (xy 121.797566 -233.689486)
			(xy 121.838069 -233.717442) (xy 121.873562 -233.751534) (xy 121.903127 -233.790878) (xy 121.925998 -233.834455)
			(xy 121.941582 -233.881136) (xy 121.949477 -233.929713) (xy 121.949972 -233.95432) (xy 124.159022 -233.95432)
			(xy 124.162982 -233.905266) (xy 124.174759 -233.857482) (xy 124.19405 -233.812206) (xy 124.220353 -233.77061)
			(xy 124.252988 -233.733773) (xy 124.291109 -233.702648) (xy 124.33373 -233.678041) (xy 124.379746 -233.660589)
			(xy 124.427965 -233.650745) (xy 124.47714 -233.648764) (xy 124.525995 -233.654696) (xy 124.573266 -233.668388)
			(xy 124.617728 -233.689486) (xy 124.658231 -233.717442) (xy 124.693724 -233.751534) (xy 124.723289 -233.790878)
			(xy 124.74616 -233.834455) (xy 124.761744 -233.881136) (xy 124.769639 -233.929713) (xy 124.770134 -233.95432)
			(xy 124.769639 -233.978927) (xy 124.761744 -234.027504) (xy 124.74616 -234.074185) (xy 124.723289 -234.117762)
			(xy 124.693724 -234.157106) (xy 124.658231 -234.191198) (xy 124.617728 -234.219154) (xy 124.573266 -234.240252)
			(xy 124.525995 -234.253944) (xy 124.47714 -234.259876) (xy 124.427965 -234.257895) (xy 124.379746 -234.248051)
			(xy 124.33373 -234.230599) (xy 124.291109 -234.205992) (xy 124.252988 -234.174867) (xy 124.220353 -234.13803)
			(xy 124.19405 -234.096434) (xy 124.174759 -234.051158) (xy 124.162982 -234.003374) (xy 124.159022 -233.95432)
			(xy 121.949972 -233.95432) (xy 121.949477 -233.978927) (xy 121.941582 -234.027504) (xy 121.925998 -234.074185)
			(xy 121.903127 -234.117762) (xy 121.873562 -234.157106) (xy 121.838069 -234.191198) (xy 121.797566 -234.219154)
			(xy 121.753104 -234.240252) (xy 121.705833 -234.253944) (xy 121.656978 -234.259876) (xy 121.607803 -234.257895)
			(xy 121.559584 -234.248051) (xy 121.513568 -234.230599) (xy 121.470947 -234.205992) (xy 121.432826 -234.174867)
			(xy 121.400191 -234.13803) (xy 121.373888 -234.096434) (xy 121.354597 -234.051158) (xy 121.34282 -234.003374)
			(xy 121.33886 -233.95432) (xy 119.130064 -233.95432) (xy 119.129569 -233.978927) (xy 119.121674 -234.027504)
			(xy 119.10609 -234.074185) (xy 119.083219 -234.117762) (xy 119.053654 -234.157106) (xy 119.018161 -234.191198)
			(xy 118.977658 -234.219154) (xy 118.933196 -234.240252) (xy 118.885925 -234.253944) (xy 118.83707 -234.259876)
			(xy 118.787895 -234.257895) (xy 118.739676 -234.248051) (xy 118.69366 -234.230599) (xy 118.651039 -234.205992)
			(xy 118.612918 -234.174867) (xy 118.580283 -234.13803) (xy 118.55398 -234.096434) (xy 118.534689 -234.051158)
			(xy 118.522912 -234.003374) (xy 118.518952 -233.95432) (xy 116.310156 -233.95432) (xy 116.309661 -233.978927)
			(xy 116.301766 -234.027504) (xy 116.286182 -234.074185) (xy 116.263311 -234.117762) (xy 116.233746 -234.157106)
			(xy 116.198253 -234.191198) (xy 116.15775 -234.219154) (xy 116.113288 -234.240252) (xy 116.066017 -234.253944)
			(xy 116.017162 -234.259876) (xy 115.967987 -234.257895) (xy 115.919768 -234.248051) (xy 115.873752 -234.230599)
			(xy 115.831131 -234.205992) (xy 115.79301 -234.174867) (xy 115.760375 -234.13803) (xy 115.734072 -234.096434)
			(xy 115.714781 -234.051158) (xy 115.703004 -234.003374) (xy 115.699044 -233.95432) (xy 115.370102 -233.95432)
			(xy 115.369607 -233.978927) (xy 115.361712 -234.027504) (xy 115.346128 -234.074185) (xy 115.323257 -234.117762)
			(xy 115.293692 -234.157106) (xy 115.258199 -234.191198) (xy 115.217696 -234.219154) (xy 115.173234 -234.240252)
			(xy 115.125963 -234.253944) (xy 115.077108 -234.259876) (xy 115.027933 -234.257895) (xy 114.979714 -234.248051)
			(xy 114.933698 -234.230599) (xy 114.891077 -234.205992) (xy 114.852956 -234.174867) (xy 114.820321 -234.13803)
			(xy 114.794018 -234.096434) (xy 114.774727 -234.051158) (xy 114.76295 -234.003374) (xy 114.75899 -233.95432)
			(xy 114.430048 -233.95432) (xy 114.429553 -233.978927) (xy 114.421658 -234.027504) (xy 114.406074 -234.074185)
			(xy 114.383203 -234.117762) (xy 114.353638 -234.157106) (xy 114.318145 -234.191198) (xy 114.277642 -234.219154)
			(xy 114.23318 -234.240252) (xy 114.185909 -234.253944) (xy 114.137054 -234.259876) (xy 114.087879 -234.257895)
			(xy 114.03966 -234.248051) (xy 113.993644 -234.230599) (xy 113.951023 -234.205992) (xy 113.912902 -234.174867)
			(xy 113.880267 -234.13803) (xy 113.853964 -234.096434) (xy 113.834673 -234.051158) (xy 113.822896 -234.003374)
			(xy 113.818936 -233.95432) (xy 113.56594 -233.95432) (xy 113.56594 -234.764326) (xy 115.22889 -234.764326)
			(xy 115.23285 -234.715272) (xy 115.244627 -234.667488) (xy 115.263918 -234.622212) (xy 115.290221 -234.580616)
			(xy 115.322856 -234.543779) (xy 115.360977 -234.512654) (xy 115.403598 -234.488047) (xy 115.449614 -234.470595)
			(xy 115.497833 -234.460751) (xy 115.547008 -234.45877) (xy 115.595863 -234.464702) (xy 115.643134 -234.478394)
			(xy 115.687596 -234.499492) (xy 115.728099 -234.527448) (xy 115.763592 -234.56154) (xy 115.793157 -234.600884)
			(xy 115.816028 -234.644461) (xy 115.831612 -234.691142) (xy 115.839507 -234.739719) (xy 115.840002 -234.764326)
			(xy 116.168944 -234.764326) (xy 116.172904 -234.715272) (xy 116.184681 -234.667488) (xy 116.203972 -234.622212)
			(xy 116.230275 -234.580616) (xy 116.26291 -234.543779) (xy 116.301031 -234.512654) (xy 116.343652 -234.488047)
			(xy 116.389668 -234.470595) (xy 116.437887 -234.460751) (xy 116.487062 -234.45877) (xy 116.535917 -234.464702)
			(xy 116.583188 -234.478394) (xy 116.62765 -234.499492) (xy 116.668153 -234.527448) (xy 116.703646 -234.56154)
			(xy 116.733211 -234.600884) (xy 116.756082 -234.644461) (xy 116.771666 -234.691142) (xy 116.779561 -234.739719)
			(xy 116.780056 -234.764326) (xy 117.108998 -234.764326) (xy 117.112958 -234.715272) (xy 117.124735 -234.667488)
			(xy 117.144026 -234.622212) (xy 117.170329 -234.580616) (xy 117.202964 -234.543779) (xy 117.241085 -234.512654)
			(xy 117.283706 -234.488047) (xy 117.329722 -234.470595) (xy 117.377941 -234.460751) (xy 117.427116 -234.45877)
			(xy 117.475971 -234.464702) (xy 117.523242 -234.478394) (xy 117.567704 -234.499492) (xy 117.608207 -234.527448)
			(xy 117.6437 -234.56154) (xy 117.673265 -234.600884) (xy 117.696136 -234.644461) (xy 117.71172 -234.691142)
			(xy 117.719615 -234.739719) (xy 117.72011 -234.764326) (xy 118.049052 -234.764326) (xy 118.053012 -234.715272)
			(xy 118.064789 -234.667488) (xy 118.08408 -234.622212) (xy 118.110383 -234.580616) (xy 118.143018 -234.543779)
			(xy 118.181139 -234.512654) (xy 118.22376 -234.488047) (xy 118.269776 -234.470595) (xy 118.317995 -234.460751)
			(xy 118.36717 -234.45877) (xy 118.416025 -234.464702) (xy 118.463296 -234.478394) (xy 118.507758 -234.499492)
			(xy 118.548261 -234.527448) (xy 118.583754 -234.56154) (xy 118.613319 -234.600884) (xy 118.63619 -234.644461)
			(xy 118.651774 -234.691142) (xy 118.659669 -234.739719) (xy 118.660164 -234.764326) (xy 118.988852 -234.764326)
			(xy 118.992812 -234.715272) (xy 119.004589 -234.667488) (xy 119.02388 -234.622212) (xy 119.050183 -234.580616)
			(xy 119.082818 -234.543779) (xy 119.120939 -234.512654) (xy 119.16356 -234.488047) (xy 119.209576 -234.470595)
			(xy 119.257795 -234.460751) (xy 119.30697 -234.45877) (xy 119.355825 -234.464702) (xy 119.403096 -234.478394)
			(xy 119.447558 -234.499492) (xy 119.488061 -234.527448) (xy 119.523554 -234.56154) (xy 119.553119 -234.600884)
			(xy 119.57599 -234.644461) (xy 119.591574 -234.691142) (xy 119.599469 -234.739719) (xy 119.599964 -234.764326)
			(xy 119.928906 -234.764326) (xy 119.932866 -234.715272) (xy 119.944643 -234.667488) (xy 119.963934 -234.622212)
			(xy 119.990237 -234.580616) (xy 120.022872 -234.543779) (xy 120.060993 -234.512654) (xy 120.103614 -234.488047)
			(xy 120.14963 -234.470595) (xy 120.197849 -234.460751) (xy 120.247024 -234.45877) (xy 120.295879 -234.464702)
			(xy 120.34315 -234.478394) (xy 120.387612 -234.499492) (xy 120.428115 -234.527448) (xy 120.463608 -234.56154)
			(xy 120.493173 -234.600884) (xy 120.516044 -234.644461) (xy 120.531628 -234.691142) (xy 120.539523 -234.739719)
			(xy 120.540018 -234.764326) (xy 120.86896 -234.764326) (xy 120.87292 -234.715272) (xy 120.884697 -234.667488)
			(xy 120.903988 -234.622212) (xy 120.930291 -234.580616) (xy 120.962926 -234.543779) (xy 121.001047 -234.512654)
			(xy 121.043668 -234.488047) (xy 121.089684 -234.470595) (xy 121.137903 -234.460751) (xy 121.187078 -234.45877)
			(xy 121.235933 -234.464702) (xy 121.283204 -234.478394) (xy 121.327666 -234.499492) (xy 121.368169 -234.527448)
			(xy 121.403662 -234.56154) (xy 121.433227 -234.600884) (xy 121.456098 -234.644461) (xy 121.471682 -234.691142)
			(xy 121.479577 -234.739719) (xy 121.480072 -234.764326) (xy 121.809014 -234.764326) (xy 121.812974 -234.715272)
			(xy 121.824751 -234.667488) (xy 121.844042 -234.622212) (xy 121.870345 -234.580616) (xy 121.90298 -234.543779)
			(xy 121.941101 -234.512654) (xy 121.983722 -234.488047) (xy 122.029738 -234.470595) (xy 122.077957 -234.460751)
			(xy 122.127132 -234.45877) (xy 122.175987 -234.464702) (xy 122.223258 -234.478394) (xy 122.26772 -234.499492)
			(xy 122.308223 -234.527448) (xy 122.343716 -234.56154) (xy 122.373281 -234.600884) (xy 122.396152 -234.644461)
			(xy 122.411736 -234.691142) (xy 122.419631 -234.739719) (xy 122.420126 -234.764326) (xy 122.748814 -234.764326)
			(xy 122.752774 -234.715272) (xy 122.764551 -234.667488) (xy 122.783842 -234.622212) (xy 122.810145 -234.580616)
			(xy 122.84278 -234.543779) (xy 122.880901 -234.512654) (xy 122.923522 -234.488047) (xy 122.969538 -234.470595)
			(xy 123.017757 -234.460751) (xy 123.066932 -234.45877) (xy 123.115787 -234.464702) (xy 123.163058 -234.478394)
			(xy 123.20752 -234.499492) (xy 123.248023 -234.527448) (xy 123.283516 -234.56154) (xy 123.313081 -234.600884)
			(xy 123.335952 -234.644461) (xy 123.351536 -234.691142) (xy 123.359431 -234.739719) (xy 123.359926 -234.764326)
			(xy 123.688868 -234.764326) (xy 123.692828 -234.715272) (xy 123.704605 -234.667488) (xy 123.723896 -234.622212)
			(xy 123.750199 -234.580616) (xy 123.782834 -234.543779) (xy 123.820955 -234.512654) (xy 123.863576 -234.488047)
			(xy 123.909592 -234.470595) (xy 123.957811 -234.460751) (xy 124.006986 -234.45877) (xy 124.055841 -234.464702)
			(xy 124.103112 -234.478394) (xy 124.147574 -234.499492) (xy 124.188077 -234.527448) (xy 124.22357 -234.56154)
			(xy 124.253135 -234.600884) (xy 124.276006 -234.644461) (xy 124.29159 -234.691142) (xy 124.299485 -234.739719)
			(xy 124.29998 -234.764326) (xy 124.628922 -234.764326) (xy 124.632882 -234.715272) (xy 124.644659 -234.667488)
			(xy 124.66395 -234.622212) (xy 124.690253 -234.580616) (xy 124.722888 -234.543779) (xy 124.761009 -234.512654)
			(xy 124.80363 -234.488047) (xy 124.849646 -234.470595) (xy 124.897865 -234.460751) (xy 124.94704 -234.45877)
			(xy 124.995895 -234.464702) (xy 125.043166 -234.478394) (xy 125.087628 -234.499492) (xy 125.128131 -234.527448)
			(xy 125.163624 -234.56154) (xy 125.193189 -234.600884) (xy 125.21606 -234.644461) (xy 125.231644 -234.691142)
			(xy 125.239539 -234.739719) (xy 125.240034 -234.764326) (xy 125.568976 -234.764326) (xy 125.572936 -234.715272)
			(xy 125.584713 -234.667488) (xy 125.604004 -234.622212) (xy 125.630307 -234.580616) (xy 125.662942 -234.543779)
			(xy 125.701063 -234.512654) (xy 125.743684 -234.488047) (xy 125.7897 -234.470595) (xy 125.837919 -234.460751)
			(xy 125.887094 -234.45877) (xy 125.935949 -234.464702) (xy 125.98322 -234.478394) (xy 126.027682 -234.499492)
			(xy 126.068185 -234.527448) (xy 126.103678 -234.56154) (xy 126.133243 -234.600884) (xy 126.156114 -234.644461)
			(xy 126.171698 -234.691142) (xy 126.179593 -234.739719) (xy 126.180088 -234.764326) (xy 126.179593 -234.788933)
			(xy 126.171698 -234.83751) (xy 126.156114 -234.884191) (xy 126.133243 -234.927768) (xy 126.103678 -234.967112)
			(xy 126.068185 -235.001204) (xy 126.027682 -235.02916) (xy 125.98322 -235.050258) (xy 125.935949 -235.06395)
			(xy 125.887094 -235.069882) (xy 125.837919 -235.067901) (xy 125.7897 -235.058057) (xy 125.743684 -235.040605)
			(xy 125.701063 -235.015998) (xy 125.662942 -234.984873) (xy 125.630307 -234.948036) (xy 125.604004 -234.90644)
			(xy 125.584713 -234.861164) (xy 125.572936 -234.81338) (xy 125.568976 -234.764326) (xy 125.240034 -234.764326)
			(xy 125.239539 -234.788933) (xy 125.231644 -234.83751) (xy 125.21606 -234.884191) (xy 125.193189 -234.927768)
			(xy 125.163624 -234.967112) (xy 125.128131 -235.001204) (xy 125.087628 -235.02916) (xy 125.043166 -235.050258)
			(xy 124.995895 -235.06395) (xy 124.94704 -235.069882) (xy 124.897865 -235.067901) (xy 124.849646 -235.058057)
			(xy 124.80363 -235.040605) (xy 124.761009 -235.015998) (xy 124.722888 -234.984873) (xy 124.690253 -234.948036)
			(xy 124.66395 -234.90644) (xy 124.644659 -234.861164) (xy 124.632882 -234.81338) (xy 124.628922 -234.764326)
			(xy 124.29998 -234.764326) (xy 124.299485 -234.788933) (xy 124.29159 -234.83751) (xy 124.276006 -234.884191)
			(xy 124.253135 -234.927768) (xy 124.22357 -234.967112) (xy 124.188077 -235.001204) (xy 124.147574 -235.02916)
			(xy 124.103112 -235.050258) (xy 124.055841 -235.06395) (xy 124.006986 -235.069882) (xy 123.957811 -235.067901)
			(xy 123.909592 -235.058057) (xy 123.863576 -235.040605) (xy 123.820955 -235.015998) (xy 123.782834 -234.984873)
			(xy 123.750199 -234.948036) (xy 123.723896 -234.90644) (xy 123.704605 -234.861164) (xy 123.692828 -234.81338)
			(xy 123.688868 -234.764326) (xy 123.359926 -234.764326) (xy 123.359431 -234.788933) (xy 123.351536 -234.83751)
			(xy 123.335952 -234.884191) (xy 123.313081 -234.927768) (xy 123.283516 -234.967112) (xy 123.248023 -235.001204)
			(xy 123.20752 -235.02916) (xy 123.163058 -235.050258) (xy 123.115787 -235.06395) (xy 123.066932 -235.069882)
			(xy 123.017757 -235.067901) (xy 122.969538 -235.058057) (xy 122.923522 -235.040605) (xy 122.880901 -235.015998)
			(xy 122.84278 -234.984873) (xy 122.810145 -234.948036) (xy 122.783842 -234.90644) (xy 122.764551 -234.861164)
			(xy 122.752774 -234.81338) (xy 122.748814 -234.764326) (xy 122.420126 -234.764326) (xy 122.419631 -234.788933)
			(xy 122.411736 -234.83751) (xy 122.396152 -234.884191) (xy 122.373281 -234.927768) (xy 122.343716 -234.967112)
			(xy 122.308223 -235.001204) (xy 122.26772 -235.02916) (xy 122.223258 -235.050258) (xy 122.175987 -235.06395)
			(xy 122.127132 -235.069882) (xy 122.077957 -235.067901) (xy 122.029738 -235.058057) (xy 121.983722 -235.040605)
			(xy 121.941101 -235.015998) (xy 121.90298 -234.984873) (xy 121.870345 -234.948036) (xy 121.844042 -234.90644)
			(xy 121.824751 -234.861164) (xy 121.812974 -234.81338) (xy 121.809014 -234.764326) (xy 121.480072 -234.764326)
			(xy 121.479577 -234.788933) (xy 121.471682 -234.83751) (xy 121.456098 -234.884191) (xy 121.433227 -234.927768)
			(xy 121.403662 -234.967112) (xy 121.368169 -235.001204) (xy 121.327666 -235.02916) (xy 121.283204 -235.050258)
			(xy 121.235933 -235.06395) (xy 121.187078 -235.069882) (xy 121.137903 -235.067901) (xy 121.089684 -235.058057)
			(xy 121.043668 -235.040605) (xy 121.001047 -235.015998) (xy 120.962926 -234.984873) (xy 120.930291 -234.948036)
			(xy 120.903988 -234.90644) (xy 120.884697 -234.861164) (xy 120.87292 -234.81338) (xy 120.86896 -234.764326)
			(xy 120.540018 -234.764326) (xy 120.539523 -234.788933) (xy 120.531628 -234.83751) (xy 120.516044 -234.884191)
			(xy 120.493173 -234.927768) (xy 120.463608 -234.967112) (xy 120.428115 -235.001204) (xy 120.387612 -235.02916)
			(xy 120.34315 -235.050258) (xy 120.295879 -235.06395) (xy 120.247024 -235.069882) (xy 120.197849 -235.067901)
			(xy 120.14963 -235.058057) (xy 120.103614 -235.040605) (xy 120.060993 -235.015998) (xy 120.022872 -234.984873)
			(xy 119.990237 -234.948036) (xy 119.963934 -234.90644) (xy 119.944643 -234.861164) (xy 119.932866 -234.81338)
			(xy 119.928906 -234.764326) (xy 119.599964 -234.764326) (xy 119.599469 -234.788933) (xy 119.591574 -234.83751)
			(xy 119.57599 -234.884191) (xy 119.553119 -234.927768) (xy 119.523554 -234.967112) (xy 119.488061 -235.001204)
			(xy 119.447558 -235.02916) (xy 119.403096 -235.050258) (xy 119.355825 -235.06395) (xy 119.30697 -235.069882)
			(xy 119.257795 -235.067901) (xy 119.209576 -235.058057) (xy 119.16356 -235.040605) (xy 119.120939 -235.015998)
			(xy 119.082818 -234.984873) (xy 119.050183 -234.948036) (xy 119.02388 -234.90644) (xy 119.004589 -234.861164)
			(xy 118.992812 -234.81338) (xy 118.988852 -234.764326) (xy 118.660164 -234.764326) (xy 118.659669 -234.788933)
			(xy 118.651774 -234.83751) (xy 118.63619 -234.884191) (xy 118.613319 -234.927768) (xy 118.583754 -234.967112)
			(xy 118.548261 -235.001204) (xy 118.507758 -235.02916) (xy 118.463296 -235.050258) (xy 118.416025 -235.06395)
			(xy 118.36717 -235.069882) (xy 118.317995 -235.067901) (xy 118.269776 -235.058057) (xy 118.22376 -235.040605)
			(xy 118.181139 -235.015998) (xy 118.143018 -234.984873) (xy 118.110383 -234.948036) (xy 118.08408 -234.90644)
			(xy 118.064789 -234.861164) (xy 118.053012 -234.81338) (xy 118.049052 -234.764326) (xy 117.72011 -234.764326)
			(xy 117.719615 -234.788933) (xy 117.71172 -234.83751) (xy 117.696136 -234.884191) (xy 117.673265 -234.927768)
			(xy 117.6437 -234.967112) (xy 117.608207 -235.001204) (xy 117.567704 -235.02916) (xy 117.523242 -235.050258)
			(xy 117.475971 -235.06395) (xy 117.427116 -235.069882) (xy 117.377941 -235.067901) (xy 117.329722 -235.058057)
			(xy 117.283706 -235.040605) (xy 117.241085 -235.015998) (xy 117.202964 -234.984873) (xy 117.170329 -234.948036)
			(xy 117.144026 -234.90644) (xy 117.124735 -234.861164) (xy 117.112958 -234.81338) (xy 117.108998 -234.764326)
			(xy 116.780056 -234.764326) (xy 116.779561 -234.788933) (xy 116.771666 -234.83751) (xy 116.756082 -234.884191)
			(xy 116.733211 -234.927768) (xy 116.703646 -234.967112) (xy 116.668153 -235.001204) (xy 116.62765 -235.02916)
			(xy 116.583188 -235.050258) (xy 116.535917 -235.06395) (xy 116.487062 -235.069882) (xy 116.437887 -235.067901)
			(xy 116.389668 -235.058057) (xy 116.343652 -235.040605) (xy 116.301031 -235.015998) (xy 116.26291 -234.984873)
			(xy 116.230275 -234.948036) (xy 116.203972 -234.90644) (xy 116.184681 -234.861164) (xy 116.172904 -234.81338)
			(xy 116.168944 -234.764326) (xy 115.840002 -234.764326) (xy 115.839507 -234.788933) (xy 115.831612 -234.83751)
			(xy 115.816028 -234.884191) (xy 115.793157 -234.927768) (xy 115.763592 -234.967112) (xy 115.728099 -235.001204)
			(xy 115.687596 -235.02916) (xy 115.643134 -235.050258) (xy 115.595863 -235.06395) (xy 115.547008 -235.069882)
			(xy 115.497833 -235.067901) (xy 115.449614 -235.058057) (xy 115.403598 -235.040605) (xy 115.360977 -235.015998)
			(xy 115.322856 -234.984873) (xy 115.290221 -234.948036) (xy 115.263918 -234.90644) (xy 115.244627 -234.861164)
			(xy 115.23285 -234.81338) (xy 115.22889 -234.764326) (xy 113.56594 -234.764326) (xy 113.56594 -235.574332)
			(xy 113.818936 -235.574332) (xy 113.822896 -235.525278) (xy 113.834673 -235.477494) (xy 113.853964 -235.432218)
			(xy 113.880267 -235.390622) (xy 113.912902 -235.353785) (xy 113.951023 -235.32266) (xy 113.993644 -235.298053)
			(xy 114.03966 -235.280601) (xy 114.087879 -235.270757) (xy 114.137054 -235.268776) (xy 114.185909 -235.274708)
			(xy 114.23318 -235.2884) (xy 114.277642 -235.309498) (xy 114.318145 -235.337454) (xy 114.353638 -235.371546)
			(xy 114.383203 -235.41089) (xy 114.406074 -235.454467) (xy 114.421658 -235.501148) (xy 114.429553 -235.549725)
			(xy 114.430048 -235.574332) (xy 114.75899 -235.574332) (xy 114.76295 -235.525278) (xy 114.774727 -235.477494)
			(xy 114.794018 -235.432218) (xy 114.820321 -235.390622) (xy 114.852956 -235.353785) (xy 114.891077 -235.32266)
			(xy 114.933698 -235.298053) (xy 114.979714 -235.280601) (xy 115.027933 -235.270757) (xy 115.077108 -235.268776)
			(xy 115.125963 -235.274708) (xy 115.173234 -235.2884) (xy 115.217696 -235.309498) (xy 115.258199 -235.337454)
			(xy 115.293692 -235.371546) (xy 115.323257 -235.41089) (xy 115.346128 -235.454467) (xy 115.361712 -235.501148)
			(xy 115.369607 -235.549725) (xy 115.370102 -235.574332) (xy 115.699044 -235.574332) (xy 115.703004 -235.525278)
			(xy 115.714781 -235.477494) (xy 115.734072 -235.432218) (xy 115.760375 -235.390622) (xy 115.79301 -235.353785)
			(xy 115.831131 -235.32266) (xy 115.873752 -235.298053) (xy 115.919768 -235.280601) (xy 115.967987 -235.270757)
			(xy 116.017162 -235.268776) (xy 116.066017 -235.274708) (xy 116.113288 -235.2884) (xy 116.15775 -235.309498)
			(xy 116.198253 -235.337454) (xy 116.233746 -235.371546) (xy 116.263311 -235.41089) (xy 116.286182 -235.454467)
			(xy 116.301766 -235.501148) (xy 116.309661 -235.549725) (xy 116.310156 -235.574332) (xy 116.638844 -235.574332)
			(xy 116.642804 -235.525278) (xy 116.654581 -235.477494) (xy 116.673872 -235.432218) (xy 116.700175 -235.390622)
			(xy 116.73281 -235.353785) (xy 116.770931 -235.32266) (xy 116.813552 -235.298053) (xy 116.859568 -235.280601)
			(xy 116.907787 -235.270757) (xy 116.956962 -235.268776) (xy 117.005817 -235.274708) (xy 117.053088 -235.2884)
			(xy 117.09755 -235.309498) (xy 117.138053 -235.337454) (xy 117.173546 -235.371546) (xy 117.203111 -235.41089)
			(xy 117.225982 -235.454467) (xy 117.241566 -235.501148) (xy 117.249461 -235.549725) (xy 117.249956 -235.574332)
			(xy 117.578898 -235.574332) (xy 117.582858 -235.525278) (xy 117.594635 -235.477494) (xy 117.613926 -235.432218)
			(xy 117.640229 -235.390622) (xy 117.672864 -235.353785) (xy 117.710985 -235.32266) (xy 117.753606 -235.298053)
			(xy 117.799622 -235.280601) (xy 117.847841 -235.270757) (xy 117.897016 -235.268776) (xy 117.945871 -235.274708)
			(xy 117.993142 -235.2884) (xy 118.037604 -235.309498) (xy 118.078107 -235.337454) (xy 118.1136 -235.371546)
			(xy 118.143165 -235.41089) (xy 118.166036 -235.454467) (xy 118.18162 -235.501148) (xy 118.189515 -235.549725)
			(xy 118.19001 -235.574332) (xy 118.518952 -235.574332) (xy 118.522912 -235.525278) (xy 118.534689 -235.477494)
			(xy 118.55398 -235.432218) (xy 118.580283 -235.390622) (xy 118.612918 -235.353785) (xy 118.651039 -235.32266)
			(xy 118.69366 -235.298053) (xy 118.739676 -235.280601) (xy 118.787895 -235.270757) (xy 118.83707 -235.268776)
			(xy 118.885925 -235.274708) (xy 118.933196 -235.2884) (xy 118.977658 -235.309498) (xy 119.018161 -235.337454)
			(xy 119.053654 -235.371546) (xy 119.083219 -235.41089) (xy 119.10609 -235.454467) (xy 119.121674 -235.501148)
			(xy 119.129569 -235.549725) (xy 119.130064 -235.574332) (xy 119.459006 -235.574332) (xy 119.462966 -235.525278)
			(xy 119.474743 -235.477494) (xy 119.494034 -235.432218) (xy 119.520337 -235.390622) (xy 119.552972 -235.353785)
			(xy 119.591093 -235.32266) (xy 119.633714 -235.298053) (xy 119.67973 -235.280601) (xy 119.727949 -235.270757)
			(xy 119.777124 -235.268776) (xy 119.825979 -235.274708) (xy 119.87325 -235.2884) (xy 119.917712 -235.309498)
			(xy 119.958215 -235.337454) (xy 119.993708 -235.371546) (xy 120.023273 -235.41089) (xy 120.046144 -235.454467)
			(xy 120.061728 -235.501148) (xy 120.069623 -235.549725) (xy 120.070118 -235.574332) (xy 120.398806 -235.574332)
			(xy 120.402766 -235.525278) (xy 120.414543 -235.477494) (xy 120.433834 -235.432218) (xy 120.460137 -235.390622)
			(xy 120.492772 -235.353785) (xy 120.530893 -235.32266) (xy 120.573514 -235.298053) (xy 120.61953 -235.280601)
			(xy 120.667749 -235.270757) (xy 120.716924 -235.268776) (xy 120.765779 -235.274708) (xy 120.81305 -235.2884)
			(xy 120.857512 -235.309498) (xy 120.898015 -235.337454) (xy 120.933508 -235.371546) (xy 120.963073 -235.41089)
			(xy 120.985944 -235.454467) (xy 121.001528 -235.501148) (xy 121.009423 -235.549725) (xy 121.009918 -235.574332)
			(xy 121.33886 -235.574332) (xy 121.34282 -235.525278) (xy 121.354597 -235.477494) (xy 121.373888 -235.432218)
			(xy 121.400191 -235.390622) (xy 121.432826 -235.353785) (xy 121.470947 -235.32266) (xy 121.513568 -235.298053)
			(xy 121.559584 -235.280601) (xy 121.607803 -235.270757) (xy 121.656978 -235.268776) (xy 121.705833 -235.274708)
			(xy 121.753104 -235.2884) (xy 121.797566 -235.309498) (xy 121.838069 -235.337454) (xy 121.873562 -235.371546)
			(xy 121.903127 -235.41089) (xy 121.925998 -235.454467) (xy 121.941582 -235.501148) (xy 121.949477 -235.549725)
			(xy 121.949972 -235.574332) (xy 122.278914 -235.574332) (xy 122.282874 -235.525278) (xy 122.294651 -235.477494)
			(xy 122.313942 -235.432218) (xy 122.340245 -235.390622) (xy 122.37288 -235.353785) (xy 122.411001 -235.32266)
			(xy 122.453622 -235.298053) (xy 122.499638 -235.280601) (xy 122.547857 -235.270757) (xy 122.597032 -235.268776)
			(xy 122.645887 -235.274708) (xy 122.693158 -235.2884) (xy 122.73762 -235.309498) (xy 122.778123 -235.337454)
			(xy 122.813616 -235.371546) (xy 122.843181 -235.41089) (xy 122.866052 -235.454467) (xy 122.881636 -235.501148)
			(xy 122.889531 -235.549725) (xy 122.890026 -235.574332) (xy 123.218968 -235.574332) (xy 123.222928 -235.525278)
			(xy 123.234705 -235.477494) (xy 123.253996 -235.432218) (xy 123.280299 -235.390622) (xy 123.312934 -235.353785)
			(xy 123.351055 -235.32266) (xy 123.393676 -235.298053) (xy 123.439692 -235.280601) (xy 123.487911 -235.270757)
			(xy 123.537086 -235.268776) (xy 123.585941 -235.274708) (xy 123.633212 -235.2884) (xy 123.677674 -235.309498)
			(xy 123.718177 -235.337454) (xy 123.75367 -235.371546) (xy 123.783235 -235.41089) (xy 123.806106 -235.454467)
			(xy 123.82169 -235.501148) (xy 123.829585 -235.549725) (xy 123.83008 -235.574332) (xy 124.159022 -235.574332)
			(xy 124.162982 -235.525278) (xy 124.174759 -235.477494) (xy 124.19405 -235.432218) (xy 124.220353 -235.390622)
			(xy 124.252988 -235.353785) (xy 124.291109 -235.32266) (xy 124.33373 -235.298053) (xy 124.379746 -235.280601)
			(xy 124.427965 -235.270757) (xy 124.47714 -235.268776) (xy 124.525995 -235.274708) (xy 124.573266 -235.2884)
			(xy 124.617728 -235.309498) (xy 124.658231 -235.337454) (xy 124.693724 -235.371546) (xy 124.723289 -235.41089)
			(xy 124.74616 -235.454467) (xy 124.761744 -235.501148) (xy 124.769639 -235.549725) (xy 124.770134 -235.574332)
			(xy 125.098822 -235.574332) (xy 125.102782 -235.525278) (xy 125.114559 -235.477494) (xy 125.13385 -235.432218)
			(xy 125.160153 -235.390622) (xy 125.192788 -235.353785) (xy 125.230909 -235.32266) (xy 125.27353 -235.298053)
			(xy 125.319546 -235.280601) (xy 125.367765 -235.270757) (xy 125.41694 -235.268776) (xy 125.465795 -235.274708)
			(xy 125.513066 -235.2884) (xy 125.557528 -235.309498) (xy 125.598031 -235.337454) (xy 125.633524 -235.371546)
			(xy 125.663089 -235.41089) (xy 125.68596 -235.454467) (xy 125.701544 -235.501148) (xy 125.709439 -235.549725)
			(xy 125.709934 -235.574332) (xy 125.709439 -235.598939) (xy 125.701544 -235.647516) (xy 125.68596 -235.694197)
			(xy 125.663089 -235.737774) (xy 125.633524 -235.777118) (xy 125.598031 -235.81121) (xy 125.557528 -235.839166)
			(xy 125.513066 -235.860264) (xy 125.465795 -235.873956) (xy 125.41694 -235.879888) (xy 125.367765 -235.877907)
			(xy 125.319546 -235.868063) (xy 125.27353 -235.850611) (xy 125.230909 -235.826004) (xy 125.192788 -235.794879)
			(xy 125.160153 -235.758042) (xy 125.13385 -235.716446) (xy 125.114559 -235.67117) (xy 125.102782 -235.623386)
			(xy 125.098822 -235.574332) (xy 124.770134 -235.574332) (xy 124.769639 -235.598939) (xy 124.761744 -235.647516)
			(xy 124.74616 -235.694197) (xy 124.723289 -235.737774) (xy 124.693724 -235.777118) (xy 124.658231 -235.81121)
			(xy 124.617728 -235.839166) (xy 124.573266 -235.860264) (xy 124.525995 -235.873956) (xy 124.47714 -235.879888)
			(xy 124.427965 -235.877907) (xy 124.379746 -235.868063) (xy 124.33373 -235.850611) (xy 124.291109 -235.826004)
			(xy 124.252988 -235.794879) (xy 124.220353 -235.758042) (xy 124.19405 -235.716446) (xy 124.174759 -235.67117)
			(xy 124.162982 -235.623386) (xy 124.159022 -235.574332) (xy 123.83008 -235.574332) (xy 123.829585 -235.598939)
			(xy 123.82169 -235.647516) (xy 123.806106 -235.694197) (xy 123.783235 -235.737774) (xy 123.75367 -235.777118)
			(xy 123.718177 -235.81121) (xy 123.677674 -235.839166) (xy 123.633212 -235.860264) (xy 123.585941 -235.873956)
			(xy 123.537086 -235.879888) (xy 123.487911 -235.877907) (xy 123.439692 -235.868063) (xy 123.393676 -235.850611)
			(xy 123.351055 -235.826004) (xy 123.312934 -235.794879) (xy 123.280299 -235.758042) (xy 123.253996 -235.716446)
			(xy 123.234705 -235.67117) (xy 123.222928 -235.623386) (xy 123.218968 -235.574332) (xy 122.890026 -235.574332)
			(xy 122.889531 -235.598939) (xy 122.881636 -235.647516) (xy 122.866052 -235.694197) (xy 122.843181 -235.737774)
			(xy 122.813616 -235.777118) (xy 122.778123 -235.81121) (xy 122.73762 -235.839166) (xy 122.693158 -235.860264)
			(xy 122.645887 -235.873956) (xy 122.597032 -235.879888) (xy 122.547857 -235.877907) (xy 122.499638 -235.868063)
			(xy 122.453622 -235.850611) (xy 122.411001 -235.826004) (xy 122.37288 -235.794879) (xy 122.340245 -235.758042)
			(xy 122.313942 -235.716446) (xy 122.294651 -235.67117) (xy 122.282874 -235.623386) (xy 122.278914 -235.574332)
			(xy 121.949972 -235.574332) (xy 121.949477 -235.598939) (xy 121.941582 -235.647516) (xy 121.925998 -235.694197)
			(xy 121.903127 -235.737774) (xy 121.873562 -235.777118) (xy 121.838069 -235.81121) (xy 121.797566 -235.839166)
			(xy 121.753104 -235.860264) (xy 121.705833 -235.873956) (xy 121.656978 -235.879888) (xy 121.607803 -235.877907)
			(xy 121.559584 -235.868063) (xy 121.513568 -235.850611) (xy 121.470947 -235.826004) (xy 121.432826 -235.794879)
			(xy 121.400191 -235.758042) (xy 121.373888 -235.716446) (xy 121.354597 -235.67117) (xy 121.34282 -235.623386)
			(xy 121.33886 -235.574332) (xy 121.009918 -235.574332) (xy 121.009423 -235.598939) (xy 121.001528 -235.647516)
			(xy 120.985944 -235.694197) (xy 120.963073 -235.737774) (xy 120.933508 -235.777118) (xy 120.898015 -235.81121)
			(xy 120.857512 -235.839166) (xy 120.81305 -235.860264) (xy 120.765779 -235.873956) (xy 120.716924 -235.879888)
			(xy 120.667749 -235.877907) (xy 120.61953 -235.868063) (xy 120.573514 -235.850611) (xy 120.530893 -235.826004)
			(xy 120.492772 -235.794879) (xy 120.460137 -235.758042) (xy 120.433834 -235.716446) (xy 120.414543 -235.67117)
			(xy 120.402766 -235.623386) (xy 120.398806 -235.574332) (xy 120.070118 -235.574332) (xy 120.069623 -235.598939)
			(xy 120.061728 -235.647516) (xy 120.046144 -235.694197) (xy 120.023273 -235.737774) (xy 119.993708 -235.777118)
			(xy 119.958215 -235.81121) (xy 119.917712 -235.839166) (xy 119.87325 -235.860264) (xy 119.825979 -235.873956)
			(xy 119.777124 -235.879888) (xy 119.727949 -235.877907) (xy 119.67973 -235.868063) (xy 119.633714 -235.850611)
			(xy 119.591093 -235.826004) (xy 119.552972 -235.794879) (xy 119.520337 -235.758042) (xy 119.494034 -235.716446)
			(xy 119.474743 -235.67117) (xy 119.462966 -235.623386) (xy 119.459006 -235.574332) (xy 119.130064 -235.574332)
			(xy 119.129569 -235.598939) (xy 119.121674 -235.647516) (xy 119.10609 -235.694197) (xy 119.083219 -235.737774)
			(xy 119.053654 -235.777118) (xy 119.018161 -235.81121) (xy 118.977658 -235.839166) (xy 118.933196 -235.860264)
			(xy 118.885925 -235.873956) (xy 118.83707 -235.879888) (xy 118.787895 -235.877907) (xy 118.739676 -235.868063)
			(xy 118.69366 -235.850611) (xy 118.651039 -235.826004) (xy 118.612918 -235.794879) (xy 118.580283 -235.758042)
			(xy 118.55398 -235.716446) (xy 118.534689 -235.67117) (xy 118.522912 -235.623386) (xy 118.518952 -235.574332)
			(xy 118.19001 -235.574332) (xy 118.189515 -235.598939) (xy 118.18162 -235.647516) (xy 118.166036 -235.694197)
			(xy 118.143165 -235.737774) (xy 118.1136 -235.777118) (xy 118.078107 -235.81121) (xy 118.037604 -235.839166)
			(xy 117.993142 -235.860264) (xy 117.945871 -235.873956) (xy 117.897016 -235.879888) (xy 117.847841 -235.877907)
			(xy 117.799622 -235.868063) (xy 117.753606 -235.850611) (xy 117.710985 -235.826004) (xy 117.672864 -235.794879)
			(xy 117.640229 -235.758042) (xy 117.613926 -235.716446) (xy 117.594635 -235.67117) (xy 117.582858 -235.623386)
			(xy 117.578898 -235.574332) (xy 117.249956 -235.574332) (xy 117.249461 -235.598939) (xy 117.241566 -235.647516)
			(xy 117.225982 -235.694197) (xy 117.203111 -235.737774) (xy 117.173546 -235.777118) (xy 117.138053 -235.81121)
			(xy 117.09755 -235.839166) (xy 117.053088 -235.860264) (xy 117.005817 -235.873956) (xy 116.956962 -235.879888)
			(xy 116.907787 -235.877907) (xy 116.859568 -235.868063) (xy 116.813552 -235.850611) (xy 116.770931 -235.826004)
			(xy 116.73281 -235.794879) (xy 116.700175 -235.758042) (xy 116.673872 -235.716446) (xy 116.654581 -235.67117)
			(xy 116.642804 -235.623386) (xy 116.638844 -235.574332) (xy 116.310156 -235.574332) (xy 116.309661 -235.598939)
			(xy 116.301766 -235.647516) (xy 116.286182 -235.694197) (xy 116.263311 -235.737774) (xy 116.233746 -235.777118)
			(xy 116.198253 -235.81121) (xy 116.15775 -235.839166) (xy 116.113288 -235.860264) (xy 116.066017 -235.873956)
			(xy 116.017162 -235.879888) (xy 115.967987 -235.877907) (xy 115.919768 -235.868063) (xy 115.873752 -235.850611)
			(xy 115.831131 -235.826004) (xy 115.79301 -235.794879) (xy 115.760375 -235.758042) (xy 115.734072 -235.716446)
			(xy 115.714781 -235.67117) (xy 115.703004 -235.623386) (xy 115.699044 -235.574332) (xy 115.370102 -235.574332)
			(xy 115.369607 -235.598939) (xy 115.361712 -235.647516) (xy 115.346128 -235.694197) (xy 115.323257 -235.737774)
			(xy 115.293692 -235.777118) (xy 115.258199 -235.81121) (xy 115.217696 -235.839166) (xy 115.173234 -235.860264)
			(xy 115.125963 -235.873956) (xy 115.077108 -235.879888) (xy 115.027933 -235.877907) (xy 114.979714 -235.868063)
			(xy 114.933698 -235.850611) (xy 114.891077 -235.826004) (xy 114.852956 -235.794879) (xy 114.820321 -235.758042)
			(xy 114.794018 -235.716446) (xy 114.774727 -235.67117) (xy 114.76295 -235.623386) (xy 114.75899 -235.574332)
			(xy 114.430048 -235.574332) (xy 114.429553 -235.598939) (xy 114.421658 -235.647516) (xy 114.406074 -235.694197)
			(xy 114.383203 -235.737774) (xy 114.353638 -235.777118) (xy 114.318145 -235.81121) (xy 114.277642 -235.839166)
			(xy 114.23318 -235.860264) (xy 114.185909 -235.873956) (xy 114.137054 -235.879888) (xy 114.087879 -235.877907)
			(xy 114.03966 -235.868063) (xy 113.993644 -235.850611) (xy 113.951023 -235.826004) (xy 113.912902 -235.794879)
			(xy 113.880267 -235.758042) (xy 113.853964 -235.716446) (xy 113.834673 -235.67117) (xy 113.822896 -235.623386)
			(xy 113.818936 -235.574332) (xy 113.56594 -235.574332) (xy 113.56594 -235.977684) (xy 113.56644 -235.987494)
			(xy 113.573889 -236.005651) (xy 113.580418 -236.01299) (xy 113.629694 -236.06379) (xy 113.633188 -236.067248)
			(xy 113.641245 -236.07288) (xy 113.645696 -236.074966) (xy 113.655094 -236.07903) (xy 113.679069 -236.079523)
			(xy 113.726423 -236.087065) (xy 113.772015 -236.101919) (xy 113.814724 -236.123719) (xy 113.8535 -236.151928)
			(xy 113.887388 -236.185853) (xy 113.915555 -236.224659) (xy 113.937308 -236.267392) (xy 113.952112 -236.313)
			(xy 113.959604 -236.360362) (xy 113.960148 -236.384338) (xy 114.288836 -236.384338) (xy 114.292796 -236.335284)
			(xy 114.304573 -236.2875) (xy 114.323864 -236.242224) (xy 114.350167 -236.200628) (xy 114.382802 -236.163791)
			(xy 114.420923 -236.132666) (xy 114.463544 -236.108059) (xy 114.50956 -236.090607) (xy 114.557779 -236.080763)
			(xy 114.606954 -236.078782) (xy 114.655809 -236.084714) (xy 114.70308 -236.098406) (xy 114.747542 -236.119504)
			(xy 114.788045 -236.14746) (xy 114.823538 -236.181552) (xy 114.853103 -236.220896) (xy 114.875974 -236.264473)
			(xy 114.891558 -236.311154) (xy 114.899453 -236.359731) (xy 114.899948 -236.384338) (xy 115.22889 -236.384338)
			(xy 115.23285 -236.335284) (xy 115.244627 -236.2875) (xy 115.263918 -236.242224) (xy 115.290221 -236.200628)
			(xy 115.322856 -236.163791) (xy 115.360977 -236.132666) (xy 115.403598 -236.108059) (xy 115.449614 -236.090607)
			(xy 115.497833 -236.080763) (xy 115.547008 -236.078782) (xy 115.595863 -236.084714) (xy 115.643134 -236.098406)
			(xy 115.687596 -236.119504) (xy 115.728099 -236.14746) (xy 115.763592 -236.181552) (xy 115.793157 -236.220896)
			(xy 115.816028 -236.264473) (xy 115.831612 -236.311154) (xy 115.839507 -236.359731) (xy 115.840002 -236.384338)
			(xy 118.049052 -236.384338) (xy 118.053012 -236.335284) (xy 118.064789 -236.2875) (xy 118.08408 -236.242224)
			(xy 118.110383 -236.200628) (xy 118.143018 -236.163791) (xy 118.181139 -236.132666) (xy 118.22376 -236.108059)
			(xy 118.269776 -236.090607) (xy 118.317995 -236.080763) (xy 118.36717 -236.078782) (xy 118.416025 -236.084714)
			(xy 118.463296 -236.098406) (xy 118.507758 -236.119504) (xy 118.548261 -236.14746) (xy 118.583754 -236.181552)
			(xy 118.613319 -236.220896) (xy 118.63619 -236.264473) (xy 118.651774 -236.311154) (xy 118.659669 -236.359731)
			(xy 118.660164 -236.384338) (xy 120.86896 -236.384338) (xy 120.87292 -236.335284) (xy 120.884697 -236.2875)
			(xy 120.903988 -236.242224) (xy 120.930291 -236.200628) (xy 120.962926 -236.163791) (xy 121.001047 -236.132666)
			(xy 121.043668 -236.108059) (xy 121.089684 -236.090607) (xy 121.137903 -236.080763) (xy 121.187078 -236.078782)
			(xy 121.235933 -236.084714) (xy 121.283204 -236.098406) (xy 121.327666 -236.119504) (xy 121.368169 -236.14746)
			(xy 121.403662 -236.181552) (xy 121.433227 -236.220896) (xy 121.456098 -236.264473) (xy 121.471682 -236.311154)
			(xy 121.479577 -236.359731) (xy 121.480072 -236.384338) (xy 121.809014 -236.384338) (xy 121.812974 -236.335284)
			(xy 121.824751 -236.2875) (xy 121.844042 -236.242224) (xy 121.870345 -236.200628) (xy 121.90298 -236.163791)
			(xy 121.941101 -236.132666) (xy 121.983722 -236.108059) (xy 122.029738 -236.090607) (xy 122.077957 -236.080763)
			(xy 122.127132 -236.078782) (xy 122.175987 -236.084714) (xy 122.223258 -236.098406) (xy 122.26772 -236.119504)
			(xy 122.308223 -236.14746) (xy 122.343716 -236.181552) (xy 122.373281 -236.220896) (xy 122.396152 -236.264473)
			(xy 122.411736 -236.311154) (xy 122.419631 -236.359731) (xy 122.420126 -236.384338) (xy 122.748814 -236.384338)
			(xy 122.752774 -236.335284) (xy 122.764551 -236.2875) (xy 122.783842 -236.242224) (xy 122.810145 -236.200628)
			(xy 122.84278 -236.163791) (xy 122.880901 -236.132666) (xy 122.923522 -236.108059) (xy 122.969538 -236.090607)
			(xy 123.017757 -236.080763) (xy 123.066932 -236.078782) (xy 123.115787 -236.084714) (xy 123.163058 -236.098406)
			(xy 123.20752 -236.119504) (xy 123.248023 -236.14746) (xy 123.283516 -236.181552) (xy 123.313081 -236.220896)
			(xy 123.335952 -236.264473) (xy 123.351536 -236.311154) (xy 123.359431 -236.359731) (xy 123.359926 -236.384338)
			(xy 123.688868 -236.384338) (xy 123.692828 -236.335284) (xy 123.704605 -236.2875) (xy 123.723896 -236.242224)
			(xy 123.750199 -236.200628) (xy 123.782834 -236.163791) (xy 123.820955 -236.132666) (xy 123.863576 -236.108059)
			(xy 123.909592 -236.090607) (xy 123.957811 -236.080763) (xy 124.006986 -236.078782) (xy 124.055841 -236.084714)
			(xy 124.103112 -236.098406) (xy 124.147574 -236.119504) (xy 124.188077 -236.14746) (xy 124.22357 -236.181552)
			(xy 124.253135 -236.220896) (xy 124.276006 -236.264473) (xy 124.29159 -236.311154) (xy 124.299485 -236.359731)
			(xy 124.29998 -236.384338) (xy 124.628922 -236.384338) (xy 124.632882 -236.335284) (xy 124.644659 -236.2875)
			(xy 124.66395 -236.242224) (xy 124.690253 -236.200628) (xy 124.722888 -236.163791) (xy 124.761009 -236.132666)
			(xy 124.80363 -236.108059) (xy 124.849646 -236.090607) (xy 124.897865 -236.080763) (xy 124.94704 -236.078782)
			(xy 124.995895 -236.084714) (xy 125.043166 -236.098406) (xy 125.087628 -236.119504) (xy 125.128131 -236.14746)
			(xy 125.163624 -236.181552) (xy 125.193189 -236.220896) (xy 125.21606 -236.264473) (xy 125.231644 -236.311154)
			(xy 125.239539 -236.359731) (xy 125.240034 -236.384338) (xy 125.568976 -236.384338) (xy 125.572936 -236.335284)
			(xy 125.584713 -236.2875) (xy 125.604004 -236.242224) (xy 125.630307 -236.200628) (xy 125.662942 -236.163791)
			(xy 125.701063 -236.132666) (xy 125.743684 -236.108059) (xy 125.7897 -236.090607) (xy 125.837919 -236.080763)
			(xy 125.887094 -236.078782) (xy 125.935949 -236.084714) (xy 125.98322 -236.098406) (xy 126.027682 -236.119504)
			(xy 126.068185 -236.14746) (xy 126.103678 -236.181552) (xy 126.133243 -236.220896) (xy 126.156114 -236.264473)
			(xy 126.171698 -236.311154) (xy 126.179593 -236.359731) (xy 126.180088 -236.384338) (xy 126.179593 -236.408945)
			(xy 126.171698 -236.457522) (xy 126.156114 -236.504203) (xy 126.133243 -236.54778) (xy 126.103678 -236.587124)
			(xy 126.068185 -236.621216) (xy 126.027682 -236.649172) (xy 125.98322 -236.67027) (xy 125.935949 -236.683962)
			(xy 125.887094 -236.689894) (xy 125.837919 -236.687913) (xy 125.7897 -236.678069) (xy 125.743684 -236.660617)
			(xy 125.701063 -236.63601) (xy 125.662942 -236.604885) (xy 125.630307 -236.568048) (xy 125.604004 -236.526452)
			(xy 125.584713 -236.481176) (xy 125.572936 -236.433392) (xy 125.568976 -236.384338) (xy 125.240034 -236.384338)
			(xy 125.239539 -236.408945) (xy 125.231644 -236.457522) (xy 125.21606 -236.504203) (xy 125.193189 -236.54778)
			(xy 125.163624 -236.587124) (xy 125.128131 -236.621216) (xy 125.087628 -236.649172) (xy 125.043166 -236.67027)
			(xy 124.995895 -236.683962) (xy 124.94704 -236.689894) (xy 124.897865 -236.687913) (xy 124.849646 -236.678069)
			(xy 124.80363 -236.660617) (xy 124.761009 -236.63601) (xy 124.722888 -236.604885) (xy 124.690253 -236.568048)
			(xy 124.66395 -236.526452) (xy 124.644659 -236.481176) (xy 124.632882 -236.433392) (xy 124.628922 -236.384338)
			(xy 124.29998 -236.384338) (xy 124.299485 -236.408945) (xy 124.29159 -236.457522) (xy 124.276006 -236.504203)
			(xy 124.253135 -236.54778) (xy 124.22357 -236.587124) (xy 124.188077 -236.621216) (xy 124.147574 -236.649172)
			(xy 124.103112 -236.67027) (xy 124.055841 -236.683962) (xy 124.006986 -236.689894) (xy 123.957811 -236.687913)
			(xy 123.909592 -236.678069) (xy 123.863576 -236.660617) (xy 123.820955 -236.63601) (xy 123.782834 -236.604885)
			(xy 123.750199 -236.568048) (xy 123.723896 -236.526452) (xy 123.704605 -236.481176) (xy 123.692828 -236.433392)
			(xy 123.688868 -236.384338) (xy 123.359926 -236.384338) (xy 123.359431 -236.408945) (xy 123.351536 -236.457522)
			(xy 123.335952 -236.504203) (xy 123.313081 -236.54778) (xy 123.283516 -236.587124) (xy 123.248023 -236.621216)
			(xy 123.20752 -236.649172) (xy 123.163058 -236.67027) (xy 123.115787 -236.683962) (xy 123.066932 -236.689894)
			(xy 123.017757 -236.687913) (xy 122.969538 -236.678069) (xy 122.923522 -236.660617) (xy 122.880901 -236.63601)
			(xy 122.84278 -236.604885) (xy 122.810145 -236.568048) (xy 122.783842 -236.526452) (xy 122.764551 -236.481176)
			(xy 122.752774 -236.433392) (xy 122.748814 -236.384338) (xy 122.420126 -236.384338) (xy 122.419631 -236.408945)
			(xy 122.411736 -236.457522) (xy 122.396152 -236.504203) (xy 122.373281 -236.54778) (xy 122.343716 -236.587124)
			(xy 122.308223 -236.621216) (xy 122.26772 -236.649172) (xy 122.223258 -236.67027) (xy 122.175987 -236.683962)
			(xy 122.127132 -236.689894) (xy 122.077957 -236.687913) (xy 122.029738 -236.678069) (xy 121.983722 -236.660617)
			(xy 121.941101 -236.63601) (xy 121.90298 -236.604885) (xy 121.870345 -236.568048) (xy 121.844042 -236.526452)
			(xy 121.824751 -236.481176) (xy 121.812974 -236.433392) (xy 121.809014 -236.384338) (xy 121.480072 -236.384338)
			(xy 121.479577 -236.408945) (xy 121.471682 -236.457522) (xy 121.456098 -236.504203) (xy 121.433227 -236.54778)
			(xy 121.403662 -236.587124) (xy 121.368169 -236.621216) (xy 121.327666 -236.649172) (xy 121.283204 -236.67027)
			(xy 121.235933 -236.683962) (xy 121.187078 -236.689894) (xy 121.137903 -236.687913) (xy 121.089684 -236.678069)
			(xy 121.043668 -236.660617) (xy 121.001047 -236.63601) (xy 120.962926 -236.604885) (xy 120.930291 -236.568048)
			(xy 120.903988 -236.526452) (xy 120.884697 -236.481176) (xy 120.87292 -236.433392) (xy 120.86896 -236.384338)
			(xy 118.660164 -236.384338) (xy 118.659669 -236.408945) (xy 118.651774 -236.457522) (xy 118.63619 -236.504203)
			(xy 118.613319 -236.54778) (xy 118.583754 -236.587124) (xy 118.548261 -236.621216) (xy 118.507758 -236.649172)
			(xy 118.463296 -236.67027) (xy 118.416025 -236.683962) (xy 118.36717 -236.689894) (xy 118.317995 -236.687913)
			(xy 118.269776 -236.678069) (xy 118.22376 -236.660617) (xy 118.181139 -236.63601) (xy 118.143018 -236.604885)
			(xy 118.110383 -236.568048) (xy 118.08408 -236.526452) (xy 118.064789 -236.481176) (xy 118.053012 -236.433392)
			(xy 118.049052 -236.384338) (xy 115.840002 -236.384338) (xy 115.839507 -236.408945) (xy 115.831612 -236.457522)
			(xy 115.816028 -236.504203) (xy 115.793157 -236.54778) (xy 115.763592 -236.587124) (xy 115.728099 -236.621216)
			(xy 115.687596 -236.649172) (xy 115.643134 -236.67027) (xy 115.595863 -236.683962) (xy 115.547008 -236.689894)
			(xy 115.497833 -236.687913) (xy 115.449614 -236.678069) (xy 115.403598 -236.660617) (xy 115.360977 -236.63601)
			(xy 115.322856 -236.604885) (xy 115.290221 -236.568048) (xy 115.263918 -236.526452) (xy 115.244627 -236.481176)
			(xy 115.23285 -236.433392) (xy 115.22889 -236.384338) (xy 114.899948 -236.384338) (xy 114.899453 -236.408945)
			(xy 114.891558 -236.457522) (xy 114.875974 -236.504203) (xy 114.853103 -236.54778) (xy 114.823538 -236.587124)
			(xy 114.788045 -236.621216) (xy 114.747542 -236.649172) (xy 114.70308 -236.67027) (xy 114.655809 -236.683962)
			(xy 114.606954 -236.689894) (xy 114.557779 -236.687913) (xy 114.50956 -236.678069) (xy 114.463544 -236.660617)
			(xy 114.420923 -236.63601) (xy 114.382802 -236.604885) (xy 114.350167 -236.568048) (xy 114.323864 -236.526452)
			(xy 114.304573 -236.481176) (xy 114.292796 -236.433392) (xy 114.288836 -236.384338) (xy 113.960148 -236.384338)
			(xy 113.959719 -236.407846) (xy 113.952517 -236.454307) (xy 113.938275 -236.499113) (xy 113.917328 -236.541204)
			(xy 113.890173 -236.579585) (xy 113.857453 -236.613347) (xy 113.819941 -236.64169) (xy 113.778526 -236.663944)
			(xy 113.734188 -236.679583) (xy 113.687975 -236.688236) (xy 113.664492 -236.689392) (xy 113.659709 -236.689694)
			(xy 113.650376 -236.691871) (xy 113.64595 -236.69371) (xy 113.636552 -236.697774) (xy 113.580418 -236.755686)
			(xy 113.573879 -236.763017) (xy 113.566447 -236.78118) (xy 113.56594 -236.790992) (xy 113.56594 -237.060994)
			(xy 113.565529 -237.167747) (xy 113.56469 -237.194344) (xy 115.699044 -237.194344) (xy 115.703004 -237.14529)
			(xy 115.714781 -237.097506) (xy 115.734072 -237.05223) (xy 115.760375 -237.010634) (xy 115.79301 -236.973797)
			(xy 115.831131 -236.942672) (xy 115.873752 -236.918065) (xy 115.919768 -236.900613) (xy 115.967987 -236.890769)
			(xy 116.017162 -236.888788) (xy 116.066017 -236.89472) (xy 116.113288 -236.908412) (xy 116.15775 -236.92951)
			(xy 116.198253 -236.957466) (xy 116.233746 -236.991558) (xy 116.263311 -237.030902) (xy 116.286182 -237.074479)
			(xy 116.301766 -237.12116) (xy 116.309661 -237.169737) (xy 116.310156 -237.194344) (xy 116.638844 -237.194344)
			(xy 116.642804 -237.14529) (xy 116.654581 -237.097506) (xy 116.673872 -237.05223) (xy 116.700175 -237.010634)
			(xy 116.73281 -236.973797) (xy 116.770931 -236.942672) (xy 116.813552 -236.918065) (xy 116.859568 -236.900613)
			(xy 116.907787 -236.890769) (xy 116.956962 -236.888788) (xy 117.005817 -236.89472) (xy 117.053088 -236.908412)
			(xy 117.09755 -236.92951) (xy 117.138053 -236.957466) (xy 117.173546 -236.991558) (xy 117.203111 -237.030902)
			(xy 117.225982 -237.074479) (xy 117.241566 -237.12116) (xy 117.249461 -237.169737) (xy 117.249956 -237.194344)
			(xy 117.578898 -237.194344) (xy 117.582858 -237.14529) (xy 117.594635 -237.097506) (xy 117.613926 -237.05223)
			(xy 117.640229 -237.010634) (xy 117.672864 -236.973797) (xy 117.710985 -236.942672) (xy 117.753606 -236.918065)
			(xy 117.799622 -236.900613) (xy 117.847841 -236.890769) (xy 117.897016 -236.888788) (xy 117.945871 -236.89472)
			(xy 117.993142 -236.908412) (xy 118.037604 -236.92951) (xy 118.078107 -236.957466) (xy 118.1136 -236.991558)
			(xy 118.143165 -237.030902) (xy 118.166036 -237.074479) (xy 118.18162 -237.12116) (xy 118.189515 -237.169737)
			(xy 118.19001 -237.194344) (xy 118.518952 -237.194344) (xy 118.522912 -237.14529) (xy 118.534689 -237.097506)
			(xy 118.55398 -237.05223) (xy 118.580283 -237.010634) (xy 118.612918 -236.973797) (xy 118.651039 -236.942672)
			(xy 118.69366 -236.918065) (xy 118.739676 -236.900613) (xy 118.787895 -236.890769) (xy 118.83707 -236.888788)
			(xy 118.885925 -236.89472) (xy 118.933196 -236.908412) (xy 118.977658 -236.92951) (xy 119.018161 -236.957466)
			(xy 119.053654 -236.991558) (xy 119.083219 -237.030902) (xy 119.10609 -237.074479) (xy 119.121674 -237.12116)
			(xy 119.129569 -237.169737) (xy 119.130064 -237.194344) (xy 119.459006 -237.194344) (xy 119.462966 -237.14529)
			(xy 119.474743 -237.097506) (xy 119.494034 -237.05223) (xy 119.520337 -237.010634) (xy 119.552972 -236.973797)
			(xy 119.591093 -236.942672) (xy 119.633714 -236.918065) (xy 119.67973 -236.900613) (xy 119.727949 -236.890769)
			(xy 119.777124 -236.888788) (xy 119.825979 -236.89472) (xy 119.87325 -236.908412) (xy 119.917712 -236.92951)
			(xy 119.958215 -236.957466) (xy 119.993708 -236.991558) (xy 120.023273 -237.030902) (xy 120.046144 -237.074479)
			(xy 120.061728 -237.12116) (xy 120.069623 -237.169737) (xy 120.070118 -237.194344) (xy 120.398806 -237.194344)
			(xy 120.402766 -237.14529) (xy 120.414543 -237.097506) (xy 120.433834 -237.05223) (xy 120.460137 -237.010634)
			(xy 120.492772 -236.973797) (xy 120.530893 -236.942672) (xy 120.573514 -236.918065) (xy 120.61953 -236.900613)
			(xy 120.667749 -236.890769) (xy 120.716924 -236.888788) (xy 120.765779 -236.89472) (xy 120.81305 -236.908412)
			(xy 120.857512 -236.92951) (xy 120.898015 -236.957466) (xy 120.933508 -236.991558) (xy 120.963073 -237.030902)
			(xy 120.985944 -237.074479) (xy 121.001528 -237.12116) (xy 121.009423 -237.169737) (xy 121.009918 -237.194344)
			(xy 121.33886 -237.194344) (xy 121.34282 -237.14529) (xy 121.354597 -237.097506) (xy 121.373888 -237.05223)
			(xy 121.400191 -237.010634) (xy 121.432826 -236.973797) (xy 121.470947 -236.942672) (xy 121.513568 -236.918065)
			(xy 121.559584 -236.900613) (xy 121.607803 -236.890769) (xy 121.656978 -236.888788) (xy 121.705833 -236.89472)
			(xy 121.753104 -236.908412) (xy 121.797566 -236.92951) (xy 121.838069 -236.957466) (xy 121.873562 -236.991558)
			(xy 121.903127 -237.030902) (xy 121.925998 -237.074479) (xy 121.941582 -237.12116) (xy 121.949477 -237.169737)
			(xy 121.949972 -237.194344) (xy 122.278914 -237.194344) (xy 122.282874 -237.14529) (xy 122.294651 -237.097506)
			(xy 122.313942 -237.05223) (xy 122.340245 -237.010634) (xy 122.37288 -236.973797) (xy 122.411001 -236.942672)
			(xy 122.453622 -236.918065) (xy 122.499638 -236.900613) (xy 122.547857 -236.890769) (xy 122.597032 -236.888788)
			(xy 122.645887 -236.89472) (xy 122.693158 -236.908412) (xy 122.73762 -236.92951) (xy 122.778123 -236.957466)
			(xy 122.813616 -236.991558) (xy 122.843181 -237.030902) (xy 122.866052 -237.074479) (xy 122.881636 -237.12116)
			(xy 122.889531 -237.169737) (xy 122.890026 -237.194344) (xy 123.218968 -237.194344) (xy 123.222928 -237.14529)
			(xy 123.234705 -237.097506) (xy 123.253996 -237.05223) (xy 123.280299 -237.010634) (xy 123.312934 -236.973797)
			(xy 123.351055 -236.942672) (xy 123.393676 -236.918065) (xy 123.439692 -236.900613) (xy 123.487911 -236.890769)
			(xy 123.537086 -236.888788) (xy 123.585941 -236.89472) (xy 123.633212 -236.908412) (xy 123.677674 -236.92951)
			(xy 123.718177 -236.957466) (xy 123.75367 -236.991558) (xy 123.783235 -237.030902) (xy 123.806106 -237.074479)
			(xy 123.82169 -237.12116) (xy 123.829585 -237.169737) (xy 123.83008 -237.194344) (xy 124.159022 -237.194344)
			(xy 124.162982 -237.14529) (xy 124.174759 -237.097506) (xy 124.19405 -237.05223) (xy 124.220353 -237.010634)
			(xy 124.252988 -236.973797) (xy 124.291109 -236.942672) (xy 124.33373 -236.918065) (xy 124.379746 -236.900613)
			(xy 124.427965 -236.890769) (xy 124.47714 -236.888788) (xy 124.525995 -236.89472) (xy 124.573266 -236.908412)
			(xy 124.617728 -236.92951) (xy 124.658231 -236.957466) (xy 124.693724 -236.991558) (xy 124.723289 -237.030902)
			(xy 124.74616 -237.074479) (xy 124.761744 -237.12116) (xy 124.769639 -237.169737) (xy 124.770134 -237.194344)
			(xy 125.098822 -237.194344) (xy 125.102782 -237.14529) (xy 125.114559 -237.097506) (xy 125.13385 -237.05223)
			(xy 125.160153 -237.010634) (xy 125.192788 -236.973797) (xy 125.230909 -236.942672) (xy 125.27353 -236.918065)
			(xy 125.319546 -236.900613) (xy 125.367765 -236.890769) (xy 125.41694 -236.888788) (xy 125.465795 -236.89472)
			(xy 125.513066 -236.908412) (xy 125.557528 -236.92951) (xy 125.598031 -236.957466) (xy 125.633524 -236.991558)
			(xy 125.663089 -237.030902) (xy 125.68596 -237.074479) (xy 125.701544 -237.12116) (xy 125.709439 -237.169737)
			(xy 125.709934 -237.194344) (xy 125.709439 -237.218951) (xy 125.701544 -237.267528) (xy 125.68596 -237.314209)
			(xy 125.663089 -237.357786) (xy 125.633524 -237.39713) (xy 125.598031 -237.431222) (xy 125.557528 -237.459178)
			(xy 125.513066 -237.480276) (xy 125.465795 -237.493968) (xy 125.41694 -237.4999) (xy 125.367765 -237.497919)
			(xy 125.319546 -237.488075) (xy 125.27353 -237.470623) (xy 125.230909 -237.446016) (xy 125.192788 -237.414891)
			(xy 125.160153 -237.378054) (xy 125.13385 -237.336458) (xy 125.114559 -237.291182) (xy 125.102782 -237.243398)
			(xy 125.098822 -237.194344) (xy 124.770134 -237.194344) (xy 124.769639 -237.218951) (xy 124.761744 -237.267528)
			(xy 124.74616 -237.314209) (xy 124.723289 -237.357786) (xy 124.693724 -237.39713) (xy 124.658231 -237.431222)
			(xy 124.617728 -237.459178) (xy 124.573266 -237.480276) (xy 124.525995 -237.493968) (xy 124.47714 -237.4999)
			(xy 124.427965 -237.497919) (xy 124.379746 -237.488075) (xy 124.33373 -237.470623) (xy 124.291109 -237.446016)
			(xy 124.252988 -237.414891) (xy 124.220353 -237.378054) (xy 124.19405 -237.336458) (xy 124.174759 -237.291182)
			(xy 124.162982 -237.243398) (xy 124.159022 -237.194344) (xy 123.83008 -237.194344) (xy 123.829585 -237.218951)
			(xy 123.82169 -237.267528) (xy 123.806106 -237.314209) (xy 123.783235 -237.357786) (xy 123.75367 -237.39713)
			(xy 123.718177 -237.431222) (xy 123.677674 -237.459178) (xy 123.633212 -237.480276) (xy 123.585941 -237.493968)
			(xy 123.537086 -237.4999) (xy 123.487911 -237.497919) (xy 123.439692 -237.488075) (xy 123.393676 -237.470623)
			(xy 123.351055 -237.446016) (xy 123.312934 -237.414891) (xy 123.280299 -237.378054) (xy 123.253996 -237.336458)
			(xy 123.234705 -237.291182) (xy 123.222928 -237.243398) (xy 123.218968 -237.194344) (xy 122.890026 -237.194344)
			(xy 122.889531 -237.218951) (xy 122.881636 -237.267528) (xy 122.866052 -237.314209) (xy 122.843181 -237.357786)
			(xy 122.813616 -237.39713) (xy 122.778123 -237.431222) (xy 122.73762 -237.459178) (xy 122.693158 -237.480276)
			(xy 122.645887 -237.493968) (xy 122.597032 -237.4999) (xy 122.547857 -237.497919) (xy 122.499638 -237.488075)
			(xy 122.453622 -237.470623) (xy 122.411001 -237.446016) (xy 122.37288 -237.414891) (xy 122.340245 -237.378054)
			(xy 122.313942 -237.336458) (xy 122.294651 -237.291182) (xy 122.282874 -237.243398) (xy 122.278914 -237.194344)
			(xy 121.949972 -237.194344) (xy 121.949477 -237.218951) (xy 121.941582 -237.267528) (xy 121.925998 -237.314209)
			(xy 121.903127 -237.357786) (xy 121.873562 -237.39713) (xy 121.838069 -237.431222) (xy 121.797566 -237.459178)
			(xy 121.753104 -237.480276) (xy 121.705833 -237.493968) (xy 121.656978 -237.4999) (xy 121.607803 -237.497919)
			(xy 121.559584 -237.488075) (xy 121.513568 -237.470623) (xy 121.470947 -237.446016) (xy 121.432826 -237.414891)
			(xy 121.400191 -237.378054) (xy 121.373888 -237.336458) (xy 121.354597 -237.291182) (xy 121.34282 -237.243398)
			(xy 121.33886 -237.194344) (xy 121.009918 -237.194344) (xy 121.009423 -237.218951) (xy 121.001528 -237.267528)
			(xy 120.985944 -237.314209) (xy 120.963073 -237.357786) (xy 120.933508 -237.39713) (xy 120.898015 -237.431222)
			(xy 120.857512 -237.459178) (xy 120.81305 -237.480276) (xy 120.765779 -237.493968) (xy 120.716924 -237.4999)
			(xy 120.667749 -237.497919) (xy 120.61953 -237.488075) (xy 120.573514 -237.470623) (xy 120.530893 -237.446016)
			(xy 120.492772 -237.414891) (xy 120.460137 -237.378054) (xy 120.433834 -237.336458) (xy 120.414543 -237.291182)
			(xy 120.402766 -237.243398) (xy 120.398806 -237.194344) (xy 120.070118 -237.194344) (xy 120.069623 -237.218951)
			(xy 120.061728 -237.267528) (xy 120.046144 -237.314209) (xy 120.023273 -237.357786) (xy 119.993708 -237.39713)
			(xy 119.958215 -237.431222) (xy 119.917712 -237.459178) (xy 119.87325 -237.480276) (xy 119.825979 -237.493968)
			(xy 119.777124 -237.4999) (xy 119.727949 -237.497919) (xy 119.67973 -237.488075) (xy 119.633714 -237.470623)
			(xy 119.591093 -237.446016) (xy 119.552972 -237.414891) (xy 119.520337 -237.378054) (xy 119.494034 -237.336458)
			(xy 119.474743 -237.291182) (xy 119.462966 -237.243398) (xy 119.459006 -237.194344) (xy 119.130064 -237.194344)
			(xy 119.129569 -237.218951) (xy 119.121674 -237.267528) (xy 119.10609 -237.314209) (xy 119.083219 -237.357786)
			(xy 119.053654 -237.39713) (xy 119.018161 -237.431222) (xy 118.977658 -237.459178) (xy 118.933196 -237.480276)
			(xy 118.885925 -237.493968) (xy 118.83707 -237.4999) (xy 118.787895 -237.497919) (xy 118.739676 -237.488075)
			(xy 118.69366 -237.470623) (xy 118.651039 -237.446016) (xy 118.612918 -237.414891) (xy 118.580283 -237.378054)
			(xy 118.55398 -237.336458) (xy 118.534689 -237.291182) (xy 118.522912 -237.243398) (xy 118.518952 -237.194344)
			(xy 118.19001 -237.194344) (xy 118.189515 -237.218951) (xy 118.18162 -237.267528) (xy 118.166036 -237.314209)
			(xy 118.143165 -237.357786) (xy 118.1136 -237.39713) (xy 118.078107 -237.431222) (xy 118.037604 -237.459178)
			(xy 117.993142 -237.480276) (xy 117.945871 -237.493968) (xy 117.897016 -237.4999) (xy 117.847841 -237.497919)
			(xy 117.799622 -237.488075) (xy 117.753606 -237.470623) (xy 117.710985 -237.446016) (xy 117.672864 -237.414891)
			(xy 117.640229 -237.378054) (xy 117.613926 -237.336458) (xy 117.594635 -237.291182) (xy 117.582858 -237.243398)
			(xy 117.578898 -237.194344) (xy 117.249956 -237.194344) (xy 117.249461 -237.218951) (xy 117.241566 -237.267528)
			(xy 117.225982 -237.314209) (xy 117.203111 -237.357786) (xy 117.173546 -237.39713) (xy 117.138053 -237.431222)
			(xy 117.09755 -237.459178) (xy 117.053088 -237.480276) (xy 117.005817 -237.493968) (xy 116.956962 -237.4999)
			(xy 116.907787 -237.497919) (xy 116.859568 -237.488075) (xy 116.813552 -237.470623) (xy 116.770931 -237.446016)
			(xy 116.73281 -237.414891) (xy 116.700175 -237.378054) (xy 116.673872 -237.336458) (xy 116.654581 -237.291182)
			(xy 116.642804 -237.243398) (xy 116.638844 -237.194344) (xy 116.310156 -237.194344) (xy 116.309661 -237.218951)
			(xy 116.301766 -237.267528) (xy 116.286182 -237.314209) (xy 116.263311 -237.357786) (xy 116.233746 -237.39713)
			(xy 116.198253 -237.431222) (xy 116.15775 -237.459178) (xy 116.113288 -237.480276) (xy 116.066017 -237.493968)
			(xy 116.017162 -237.4999) (xy 115.967987 -237.497919) (xy 115.919768 -237.488075) (xy 115.873752 -237.470623)
			(xy 115.831131 -237.446016) (xy 115.79301 -237.414891) (xy 115.760375 -237.378054) (xy 115.734072 -237.336458)
			(xy 115.714781 -237.291182) (xy 115.703004 -237.243398) (xy 115.699044 -237.194344) (xy 113.56469 -237.194344)
			(xy 113.558799 -237.381147) (xy 113.552478 -237.487714) (xy 113.545366 -237.589314) (xy 113.545366 -237.589568)
			(xy 113.544604 -237.60049) (xy 113.54816 -237.610396) (xy 113.55004 -237.615369) (xy 113.555541 -237.624465)
			(xy 113.559082 -237.62843) (xy 113.61039 -237.68304) (xy 113.618052 -237.690524) (xy 113.637782 -237.698808)
			(xy 113.64849 -237.699042) (xy 113.65484 -237.699042) (xy 113.680089 -237.699567) (xy 113.729898 -237.707884)
			(xy 113.777658 -237.724286) (xy 113.822068 -237.748324) (xy 113.861915 -237.779344) (xy 113.896115 -237.816499)
			(xy 113.923732 -237.858775) (xy 113.944016 -237.905021) (xy 113.956411 -237.953974) (xy 113.960581 -238.0043)
			(xy 113.960577 -238.00435) (xy 114.288836 -238.00435) (xy 114.292796 -237.955296) (xy 114.304573 -237.907512)
			(xy 114.323864 -237.862236) (xy 114.350167 -237.82064) (xy 114.382802 -237.783803) (xy 114.420923 -237.752678)
			(xy 114.463544 -237.728071) (xy 114.50956 -237.710619) (xy 114.557779 -237.700775) (xy 114.606954 -237.698794)
			(xy 114.655809 -237.704726) (xy 114.70308 -237.718418) (xy 114.747542 -237.739516) (xy 114.788045 -237.767472)
			(xy 114.823538 -237.801564) (xy 114.853103 -237.840908) (xy 114.875974 -237.884485) (xy 114.891558 -237.931166)
			(xy 114.899453 -237.979743) (xy 114.899948 -238.00435) (xy 115.22889 -238.00435) (xy 115.23285 -237.955296)
			(xy 115.244627 -237.907512) (xy 115.263918 -237.862236) (xy 115.290221 -237.82064) (xy 115.322856 -237.783803)
			(xy 115.360977 -237.752678) (xy 115.403598 -237.728071) (xy 115.449614 -237.710619) (xy 115.497833 -237.700775)
			(xy 115.547008 -237.698794) (xy 115.595863 -237.704726) (xy 115.643134 -237.718418) (xy 115.687596 -237.739516)
			(xy 115.728099 -237.767472) (xy 115.763592 -237.801564) (xy 115.793157 -237.840908) (xy 115.816028 -237.884485)
			(xy 115.831612 -237.931166) (xy 115.839507 -237.979743) (xy 115.840002 -238.00435) (xy 116.168944 -238.00435)
			(xy 116.172904 -237.955296) (xy 116.184681 -237.907512) (xy 116.203972 -237.862236) (xy 116.230275 -237.82064)
			(xy 116.26291 -237.783803) (xy 116.301031 -237.752678) (xy 116.343652 -237.728071) (xy 116.389668 -237.710619)
			(xy 116.437887 -237.700775) (xy 116.487062 -237.698794) (xy 116.535917 -237.704726) (xy 116.583188 -237.718418)
			(xy 116.62765 -237.739516) (xy 116.668153 -237.767472) (xy 116.703646 -237.801564) (xy 116.733211 -237.840908)
			(xy 116.756082 -237.884485) (xy 116.771666 -237.931166) (xy 116.779561 -237.979743) (xy 116.780056 -238.00435)
			(xy 117.108998 -238.00435) (xy 117.112958 -237.955296) (xy 117.124735 -237.907512) (xy 117.144026 -237.862236)
			(xy 117.170329 -237.82064) (xy 117.202964 -237.783803) (xy 117.241085 -237.752678) (xy 117.283706 -237.728071)
			(xy 117.329722 -237.710619) (xy 117.377941 -237.700775) (xy 117.427116 -237.698794) (xy 117.475971 -237.704726)
			(xy 117.523242 -237.718418) (xy 117.567704 -237.739516) (xy 117.608207 -237.767472) (xy 117.6437 -237.801564)
			(xy 117.673265 -237.840908) (xy 117.696136 -237.884485) (xy 117.71172 -237.931166) (xy 117.719615 -237.979743)
			(xy 117.72011 -238.00435) (xy 118.049052 -238.00435) (xy 118.053012 -237.955296) (xy 118.064789 -237.907512)
			(xy 118.08408 -237.862236) (xy 118.110383 -237.82064) (xy 118.143018 -237.783803) (xy 118.181139 -237.752678)
			(xy 118.22376 -237.728071) (xy 118.269776 -237.710619) (xy 118.317995 -237.700775) (xy 118.36717 -237.698794)
			(xy 118.416025 -237.704726) (xy 118.463296 -237.718418) (xy 118.507758 -237.739516) (xy 118.548261 -237.767472)
			(xy 118.583754 -237.801564) (xy 118.613319 -237.840908) (xy 118.63619 -237.884485) (xy 118.651774 -237.931166)
			(xy 118.659669 -237.979743) (xy 118.660164 -238.00435) (xy 118.988852 -238.00435) (xy 118.992812 -237.955296)
			(xy 119.004589 -237.907512) (xy 119.02388 -237.862236) (xy 119.050183 -237.82064) (xy 119.082818 -237.783803)
			(xy 119.120939 -237.752678) (xy 119.16356 -237.728071) (xy 119.209576 -237.710619) (xy 119.257795 -237.700775)
			(xy 119.30697 -237.698794) (xy 119.355825 -237.704726) (xy 119.403096 -237.718418) (xy 119.447558 -237.739516)
			(xy 119.488061 -237.767472) (xy 119.523554 -237.801564) (xy 119.553119 -237.840908) (xy 119.57599 -237.884485)
			(xy 119.591574 -237.931166) (xy 119.599469 -237.979743) (xy 119.599964 -238.00435) (xy 119.928906 -238.00435)
			(xy 119.932866 -237.955296) (xy 119.944643 -237.907512) (xy 119.963934 -237.862236) (xy 119.990237 -237.82064)
			(xy 120.022872 -237.783803) (xy 120.060993 -237.752678) (xy 120.103614 -237.728071) (xy 120.14963 -237.710619)
			(xy 120.197849 -237.700775) (xy 120.247024 -237.698794) (xy 120.295879 -237.704726) (xy 120.34315 -237.718418)
			(xy 120.387612 -237.739516) (xy 120.428115 -237.767472) (xy 120.463608 -237.801564) (xy 120.493173 -237.840908)
			(xy 120.516044 -237.884485) (xy 120.531628 -237.931166) (xy 120.539523 -237.979743) (xy 120.540018 -238.00435)
			(xy 120.86896 -238.00435) (xy 120.87292 -237.955296) (xy 120.884697 -237.907512) (xy 120.903988 -237.862236)
			(xy 120.930291 -237.82064) (xy 120.962926 -237.783803) (xy 121.001047 -237.752678) (xy 121.043668 -237.728071)
			(xy 121.089684 -237.710619) (xy 121.137903 -237.700775) (xy 121.187078 -237.698794) (xy 121.235933 -237.704726)
			(xy 121.283204 -237.718418) (xy 121.327666 -237.739516) (xy 121.368169 -237.767472) (xy 121.403662 -237.801564)
			(xy 121.433227 -237.840908) (xy 121.456098 -237.884485) (xy 121.471682 -237.931166) (xy 121.479577 -237.979743)
			(xy 121.480072 -238.00435) (xy 121.809014 -238.00435) (xy 121.812974 -237.955296) (xy 121.824751 -237.907512)
			(xy 121.844042 -237.862236) (xy 121.870345 -237.82064) (xy 121.90298 -237.783803) (xy 121.941101 -237.752678)
			(xy 121.983722 -237.728071) (xy 122.029738 -237.710619) (xy 122.077957 -237.700775) (xy 122.127132 -237.698794)
			(xy 122.175987 -237.704726) (xy 122.223258 -237.718418) (xy 122.26772 -237.739516) (xy 122.308223 -237.767472)
			(xy 122.343716 -237.801564) (xy 122.373281 -237.840908) (xy 122.396152 -237.884485) (xy 122.411736 -237.931166)
			(xy 122.419631 -237.979743) (xy 122.420126 -238.00435) (xy 122.748814 -238.00435) (xy 122.752774 -237.955296)
			(xy 122.764551 -237.907512) (xy 122.783842 -237.862236) (xy 122.810145 -237.82064) (xy 122.84278 -237.783803)
			(xy 122.880901 -237.752678) (xy 122.923522 -237.728071) (xy 122.969538 -237.710619) (xy 123.017757 -237.700775)
			(xy 123.066932 -237.698794) (xy 123.115787 -237.704726) (xy 123.163058 -237.718418) (xy 123.20752 -237.739516)
			(xy 123.248023 -237.767472) (xy 123.283516 -237.801564) (xy 123.313081 -237.840908) (xy 123.335952 -237.884485)
			(xy 123.351536 -237.931166) (xy 123.359431 -237.979743) (xy 123.359926 -238.00435) (xy 123.688868 -238.00435)
			(xy 123.692828 -237.955296) (xy 123.704605 -237.907512) (xy 123.723896 -237.862236) (xy 123.750199 -237.82064)
			(xy 123.782834 -237.783803) (xy 123.820955 -237.752678) (xy 123.863576 -237.728071) (xy 123.909592 -237.710619)
			(xy 123.957811 -237.700775) (xy 124.006986 -237.698794) (xy 124.055841 -237.704726) (xy 124.103112 -237.718418)
			(xy 124.147574 -237.739516) (xy 124.188077 -237.767472) (xy 124.22357 -237.801564) (xy 124.253135 -237.840908)
			(xy 124.276006 -237.884485) (xy 124.29159 -237.931166) (xy 124.299485 -237.979743) (xy 124.29998 -238.00435)
			(xy 124.628922 -238.00435) (xy 124.632882 -237.955296) (xy 124.644659 -237.907512) (xy 124.66395 -237.862236)
			(xy 124.690253 -237.82064) (xy 124.722888 -237.783803) (xy 124.761009 -237.752678) (xy 124.80363 -237.728071)
			(xy 124.849646 -237.710619) (xy 124.897865 -237.700775) (xy 124.94704 -237.698794) (xy 124.995895 -237.704726)
			(xy 125.043166 -237.718418) (xy 125.087628 -237.739516) (xy 125.128131 -237.767472) (xy 125.163624 -237.801564)
			(xy 125.193189 -237.840908) (xy 125.21606 -237.884485) (xy 125.231644 -237.931166) (xy 125.239539 -237.979743)
			(xy 125.240034 -238.00435) (xy 125.568976 -238.00435) (xy 125.572936 -237.955296) (xy 125.584713 -237.907512)
			(xy 125.604004 -237.862236) (xy 125.630307 -237.82064) (xy 125.662942 -237.783803) (xy 125.701063 -237.752678)
			(xy 125.743684 -237.728071) (xy 125.7897 -237.710619) (xy 125.837919 -237.700775) (xy 125.887094 -237.698794)
			(xy 125.935949 -237.704726) (xy 125.98322 -237.718418) (xy 126.027682 -237.739516) (xy 126.068185 -237.767472)
			(xy 126.103678 -237.801564) (xy 126.133243 -237.840908) (xy 126.156114 -237.884485) (xy 126.171698 -237.931166)
			(xy 126.179593 -237.979743) (xy 126.180088 -238.00435) (xy 126.179593 -238.028957) (xy 126.171698 -238.077534)
			(xy 126.156114 -238.124215) (xy 126.133243 -238.167792) (xy 126.103678 -238.207136) (xy 126.068185 -238.241228)
			(xy 126.027682 -238.269184) (xy 125.98322 -238.290282) (xy 125.935949 -238.303974) (xy 125.887094 -238.309906)
			(xy 125.837919 -238.307925) (xy 125.7897 -238.298081) (xy 125.743684 -238.280629) (xy 125.701063 -238.256022)
			(xy 125.662942 -238.224897) (xy 125.630307 -238.18806) (xy 125.604004 -238.146464) (xy 125.584713 -238.101188)
			(xy 125.572936 -238.053404) (xy 125.568976 -238.00435) (xy 125.240034 -238.00435) (xy 125.239539 -238.028957)
			(xy 125.231644 -238.077534) (xy 125.21606 -238.124215) (xy 125.193189 -238.167792) (xy 125.163624 -238.207136)
			(xy 125.128131 -238.241228) (xy 125.087628 -238.269184) (xy 125.043166 -238.290282) (xy 124.995895 -238.303974)
			(xy 124.94704 -238.309906) (xy 124.897865 -238.307925) (xy 124.849646 -238.298081) (xy 124.80363 -238.280629)
			(xy 124.761009 -238.256022) (xy 124.722888 -238.224897) (xy 124.690253 -238.18806) (xy 124.66395 -238.146464)
			(xy 124.644659 -238.101188) (xy 124.632882 -238.053404) (xy 124.628922 -238.00435) (xy 124.29998 -238.00435)
			(xy 124.299485 -238.028957) (xy 124.29159 -238.077534) (xy 124.276006 -238.124215) (xy 124.253135 -238.167792)
			(xy 124.22357 -238.207136) (xy 124.188077 -238.241228) (xy 124.147574 -238.269184) (xy 124.103112 -238.290282)
			(xy 124.055841 -238.303974) (xy 124.006986 -238.309906) (xy 123.957811 -238.307925) (xy 123.909592 -238.298081)
			(xy 123.863576 -238.280629) (xy 123.820955 -238.256022) (xy 123.782834 -238.224897) (xy 123.750199 -238.18806)
			(xy 123.723896 -238.146464) (xy 123.704605 -238.101188) (xy 123.692828 -238.053404) (xy 123.688868 -238.00435)
			(xy 123.359926 -238.00435) (xy 123.359431 -238.028957) (xy 123.351536 -238.077534) (xy 123.335952 -238.124215)
			(xy 123.313081 -238.167792) (xy 123.283516 -238.207136) (xy 123.248023 -238.241228) (xy 123.20752 -238.269184)
			(xy 123.163058 -238.290282) (xy 123.115787 -238.303974) (xy 123.066932 -238.309906) (xy 123.017757 -238.307925)
			(xy 122.969538 -238.298081) (xy 122.923522 -238.280629) (xy 122.880901 -238.256022) (xy 122.84278 -238.224897)
			(xy 122.810145 -238.18806) (xy 122.783842 -238.146464) (xy 122.764551 -238.101188) (xy 122.752774 -238.053404)
			(xy 122.748814 -238.00435) (xy 122.420126 -238.00435) (xy 122.419631 -238.028957) (xy 122.411736 -238.077534)
			(xy 122.396152 -238.124215) (xy 122.373281 -238.167792) (xy 122.343716 -238.207136) (xy 122.308223 -238.241228)
			(xy 122.26772 -238.269184) (xy 122.223258 -238.290282) (xy 122.175987 -238.303974) (xy 122.127132 -238.309906)
			(xy 122.077957 -238.307925) (xy 122.029738 -238.298081) (xy 121.983722 -238.280629) (xy 121.941101 -238.256022)
			(xy 121.90298 -238.224897) (xy 121.870345 -238.18806) (xy 121.844042 -238.146464) (xy 121.824751 -238.101188)
			(xy 121.812974 -238.053404) (xy 121.809014 -238.00435) (xy 121.480072 -238.00435) (xy 121.479577 -238.028957)
			(xy 121.471682 -238.077534) (xy 121.456098 -238.124215) (xy 121.433227 -238.167792) (xy 121.403662 -238.207136)
			(xy 121.368169 -238.241228) (xy 121.327666 -238.269184) (xy 121.283204 -238.290282) (xy 121.235933 -238.303974)
			(xy 121.187078 -238.309906) (xy 121.137903 -238.307925) (xy 121.089684 -238.298081) (xy 121.043668 -238.280629)
			(xy 121.001047 -238.256022) (xy 120.962926 -238.224897) (xy 120.930291 -238.18806) (xy 120.903988 -238.146464)
			(xy 120.884697 -238.101188) (xy 120.87292 -238.053404) (xy 120.86896 -238.00435) (xy 120.540018 -238.00435)
			(xy 120.539523 -238.028957) (xy 120.531628 -238.077534) (xy 120.516044 -238.124215) (xy 120.493173 -238.167792)
			(xy 120.463608 -238.207136) (xy 120.428115 -238.241228) (xy 120.387612 -238.269184) (xy 120.34315 -238.290282)
			(xy 120.295879 -238.303974) (xy 120.247024 -238.309906) (xy 120.197849 -238.307925) (xy 120.14963 -238.298081)
			(xy 120.103614 -238.280629) (xy 120.060993 -238.256022) (xy 120.022872 -238.224897) (xy 119.990237 -238.18806)
			(xy 119.963934 -238.146464) (xy 119.944643 -238.101188) (xy 119.932866 -238.053404) (xy 119.928906 -238.00435)
			(xy 119.599964 -238.00435) (xy 119.599469 -238.028957) (xy 119.591574 -238.077534) (xy 119.57599 -238.124215)
			(xy 119.553119 -238.167792) (xy 119.523554 -238.207136) (xy 119.488061 -238.241228) (xy 119.447558 -238.269184)
			(xy 119.403096 -238.290282) (xy 119.355825 -238.303974) (xy 119.30697 -238.309906) (xy 119.257795 -238.307925)
			(xy 119.209576 -238.298081) (xy 119.16356 -238.280629) (xy 119.120939 -238.256022) (xy 119.082818 -238.224897)
			(xy 119.050183 -238.18806) (xy 119.02388 -238.146464) (xy 119.004589 -238.101188) (xy 118.992812 -238.053404)
			(xy 118.988852 -238.00435) (xy 118.660164 -238.00435) (xy 118.659669 -238.028957) (xy 118.651774 -238.077534)
			(xy 118.63619 -238.124215) (xy 118.613319 -238.167792) (xy 118.583754 -238.207136) (xy 118.548261 -238.241228)
			(xy 118.507758 -238.269184) (xy 118.463296 -238.290282) (xy 118.416025 -238.303974) (xy 118.36717 -238.309906)
			(xy 118.317995 -238.307925) (xy 118.269776 -238.298081) (xy 118.22376 -238.280629) (xy 118.181139 -238.256022)
			(xy 118.143018 -238.224897) (xy 118.110383 -238.18806) (xy 118.08408 -238.146464) (xy 118.064789 -238.101188)
			(xy 118.053012 -238.053404) (xy 118.049052 -238.00435) (xy 117.72011 -238.00435) (xy 117.719615 -238.028957)
			(xy 117.71172 -238.077534) (xy 117.696136 -238.124215) (xy 117.673265 -238.167792) (xy 117.6437 -238.207136)
			(xy 117.608207 -238.241228) (xy 117.567704 -238.269184) (xy 117.523242 -238.290282) (xy 117.475971 -238.303974)
			(xy 117.427116 -238.309906) (xy 117.377941 -238.307925) (xy 117.329722 -238.298081) (xy 117.283706 -238.280629)
			(xy 117.241085 -238.256022) (xy 117.202964 -238.224897) (xy 117.170329 -238.18806) (xy 117.144026 -238.146464)
			(xy 117.124735 -238.101188) (xy 117.112958 -238.053404) (xy 117.108998 -238.00435) (xy 116.780056 -238.00435)
			(xy 116.779561 -238.028957) (xy 116.771666 -238.077534) (xy 116.756082 -238.124215) (xy 116.733211 -238.167792)
			(xy 116.703646 -238.207136) (xy 116.668153 -238.241228) (xy 116.62765 -238.269184) (xy 116.583188 -238.290282)
			(xy 116.535917 -238.303974) (xy 116.487062 -238.309906) (xy 116.437887 -238.307925) (xy 116.389668 -238.298081)
			(xy 116.343652 -238.280629) (xy 116.301031 -238.256022) (xy 116.26291 -238.224897) (xy 116.230275 -238.18806)
			(xy 116.203972 -238.146464) (xy 116.184681 -238.101188) (xy 116.172904 -238.053404) (xy 116.168944 -238.00435)
			(xy 115.840002 -238.00435) (xy 115.839507 -238.028957) (xy 115.831612 -238.077534) (xy 115.816028 -238.124215)
			(xy 115.793157 -238.167792) (xy 115.763592 -238.207136) (xy 115.728099 -238.241228) (xy 115.687596 -238.269184)
			(xy 115.643134 -238.290282) (xy 115.595863 -238.303974) (xy 115.547008 -238.309906) (xy 115.497833 -238.307925)
			(xy 115.449614 -238.298081) (xy 115.403598 -238.280629) (xy 115.360977 -238.256022) (xy 115.322856 -238.224897)
			(xy 115.290221 -238.18806) (xy 115.263918 -238.146464) (xy 115.244627 -238.101188) (xy 115.23285 -238.053404)
			(xy 115.22889 -238.00435) (xy 114.899948 -238.00435) (xy 114.899453 -238.028957) (xy 114.891558 -238.077534)
			(xy 114.875974 -238.124215) (xy 114.853103 -238.167792) (xy 114.823538 -238.207136) (xy 114.788045 -238.241228)
			(xy 114.747542 -238.269184) (xy 114.70308 -238.290282) (xy 114.655809 -238.303974) (xy 114.606954 -238.309906)
			(xy 114.557779 -238.307925) (xy 114.50956 -238.298081) (xy 114.463544 -238.280629) (xy 114.420923 -238.256022)
			(xy 114.382802 -238.224897) (xy 114.350167 -238.18806) (xy 114.323864 -238.146464) (xy 114.304573 -238.101188)
			(xy 114.292796 -238.053404) (xy 114.288836 -238.00435) (xy 113.960577 -238.00435) (xy 113.956411 -238.054626)
			(xy 113.944016 -238.103579) (xy 113.923732 -238.149825) (xy 113.896115 -238.192101) (xy 113.861915 -238.229256)
			(xy 113.822068 -238.260276) (xy 113.777658 -238.284314) (xy 113.729897 -238.300716) (xy 113.680089 -238.309033)
			(xy 113.65484 -238.309658) (xy 113.631011 -238.309204) (xy 113.583931 -238.301809) (xy 113.561114 -238.294926)
			(xy 113.550954 -238.291624) (xy 113.529618 -238.29391) (xy 113.445798 -238.341916) (xy 113.433098 -238.359188)
			(xy 113.430812 -238.369856) (xy 113.402872 -238.489998) (xy 113.387632 -238.55045) (xy 113.38578 -238.559057)
			(xy 113.387394 -238.576577) (xy 113.394855 -238.592509) (xy 113.40084 -238.598964) (xy 113.417412 -238.616234)
			(xy 113.445511 -238.654978) (xy 113.467218 -238.697634) (xy 113.481999 -238.743155) (xy 113.489493 -238.790426)
			(xy 113.489994 -238.814356) (xy 113.818936 -238.814356) (xy 113.822896 -238.765302) (xy 113.834673 -238.717518)
			(xy 113.853964 -238.672242) (xy 113.880267 -238.630646) (xy 113.912902 -238.593809) (xy 113.951023 -238.562684)
			(xy 113.993644 -238.538077) (xy 114.03966 -238.520625) (xy 114.087879 -238.510781) (xy 114.137054 -238.5088)
			(xy 114.185909 -238.514732) (xy 114.23318 -238.528424) (xy 114.277642 -238.549522) (xy 114.318145 -238.577478)
			(xy 114.353638 -238.61157) (xy 114.383203 -238.650914) (xy 114.406074 -238.694491) (xy 114.421658 -238.741172)
			(xy 114.429553 -238.789749) (xy 114.430048 -238.814356) (xy 114.75899 -238.814356) (xy 114.76295 -238.765302)
			(xy 114.774727 -238.717518) (xy 114.794018 -238.672242) (xy 114.820321 -238.630646) (xy 114.852956 -238.593809)
			(xy 114.891077 -238.562684) (xy 114.933698 -238.538077) (xy 114.979714 -238.520625) (xy 115.027933 -238.510781)
			(xy 115.077108 -238.5088) (xy 115.125963 -238.514732) (xy 115.173234 -238.528424) (xy 115.217696 -238.549522)
			(xy 115.258199 -238.577478) (xy 115.293692 -238.61157) (xy 115.323257 -238.650914) (xy 115.346128 -238.694491)
			(xy 115.361712 -238.741172) (xy 115.369607 -238.789749) (xy 115.370102 -238.814356) (xy 115.699044 -238.814356)
			(xy 115.703004 -238.765302) (xy 115.714781 -238.717518) (xy 115.734072 -238.672242) (xy 115.760375 -238.630646)
			(xy 115.79301 -238.593809) (xy 115.831131 -238.562684) (xy 115.873752 -238.538077) (xy 115.919768 -238.520625)
			(xy 115.967987 -238.510781) (xy 116.017162 -238.5088) (xy 116.066017 -238.514732) (xy 116.113288 -238.528424)
			(xy 116.15775 -238.549522) (xy 116.198253 -238.577478) (xy 116.233746 -238.61157) (xy 116.263311 -238.650914)
			(xy 116.286182 -238.694491) (xy 116.301766 -238.741172) (xy 116.309661 -238.789749) (xy 116.310156 -238.814356)
			(xy 118.518952 -238.814356) (xy 118.522912 -238.765302) (xy 118.534689 -238.717518) (xy 118.55398 -238.672242)
			(xy 118.580283 -238.630646) (xy 118.612918 -238.593809) (xy 118.651039 -238.562684) (xy 118.69366 -238.538077)
			(xy 118.739676 -238.520625) (xy 118.787895 -238.510781) (xy 118.83707 -238.5088) (xy 118.885925 -238.514732)
			(xy 118.933196 -238.528424) (xy 118.977658 -238.549522) (xy 119.018161 -238.577478) (xy 119.053654 -238.61157)
			(xy 119.083219 -238.650914) (xy 119.10609 -238.694491) (xy 119.121674 -238.741172) (xy 119.129569 -238.789749)
			(xy 119.130064 -238.814356) (xy 121.33886 -238.814356) (xy 121.34282 -238.765302) (xy 121.354597 -238.717518)
			(xy 121.373888 -238.672242) (xy 121.400191 -238.630646) (xy 121.432826 -238.593809) (xy 121.470947 -238.562684)
			(xy 121.513568 -238.538077) (xy 121.559584 -238.520625) (xy 121.607803 -238.510781) (xy 121.656978 -238.5088)
			(xy 121.705833 -238.514732) (xy 121.753104 -238.528424) (xy 121.797566 -238.549522) (xy 121.838069 -238.577478)
			(xy 121.873562 -238.61157) (xy 121.903127 -238.650914) (xy 121.925998 -238.694491) (xy 121.941582 -238.741172)
			(xy 121.949477 -238.789749) (xy 121.949972 -238.814356) (xy 124.159022 -238.814356) (xy 124.162982 -238.765302)
			(xy 124.174759 -238.717518) (xy 124.19405 -238.672242) (xy 124.220353 -238.630646) (xy 124.252988 -238.593809)
			(xy 124.291109 -238.562684) (xy 124.33373 -238.538077) (xy 124.379746 -238.520625) (xy 124.427965 -238.510781)
			(xy 124.47714 -238.5088) (xy 124.525995 -238.514732) (xy 124.573266 -238.528424) (xy 124.617728 -238.549522)
			(xy 124.658231 -238.577478) (xy 124.693724 -238.61157) (xy 124.723289 -238.650914) (xy 124.74616 -238.694491)
			(xy 124.761744 -238.741172) (xy 124.769639 -238.789749) (xy 124.770134 -238.814356) (xy 124.769639 -238.838963)
			(xy 124.761744 -238.88754) (xy 124.74616 -238.934221) (xy 124.723289 -238.977798) (xy 124.693724 -239.017142)
			(xy 124.658231 -239.051234) (xy 124.617728 -239.07919) (xy 124.573266 -239.100288) (xy 124.525995 -239.11398)
			(xy 124.47714 -239.119912) (xy 124.427965 -239.117931) (xy 124.379746 -239.108087) (xy 124.33373 -239.090635)
			(xy 124.291109 -239.066028) (xy 124.252988 -239.034903) (xy 124.220353 -238.998066) (xy 124.19405 -238.95647)
			(xy 124.174759 -238.911194) (xy 124.162982 -238.86341) (xy 124.159022 -238.814356) (xy 121.949972 -238.814356)
			(xy 121.949477 -238.838963) (xy 121.941582 -238.88754) (xy 121.925998 -238.934221) (xy 121.903127 -238.977798)
			(xy 121.873562 -239.017142) (xy 121.838069 -239.051234) (xy 121.797566 -239.07919) (xy 121.753104 -239.100288)
			(xy 121.705833 -239.11398) (xy 121.656978 -239.119912) (xy 121.607803 -239.117931) (xy 121.559584 -239.108087)
			(xy 121.513568 -239.090635) (xy 121.470947 -239.066028) (xy 121.432826 -239.034903) (xy 121.400191 -238.998066)
			(xy 121.373888 -238.95647) (xy 121.354597 -238.911194) (xy 121.34282 -238.86341) (xy 121.33886 -238.814356)
			(xy 119.130064 -238.814356) (xy 119.129569 -238.838963) (xy 119.121674 -238.88754) (xy 119.10609 -238.934221)
			(xy 119.083219 -238.977798) (xy 119.053654 -239.017142) (xy 119.018161 -239.051234) (xy 118.977658 -239.07919)
			(xy 118.933196 -239.100288) (xy 118.885925 -239.11398) (xy 118.83707 -239.119912) (xy 118.787895 -239.117931)
			(xy 118.739676 -239.108087) (xy 118.69366 -239.090635) (xy 118.651039 -239.066028) (xy 118.612918 -239.034903)
			(xy 118.580283 -238.998066) (xy 118.55398 -238.95647) (xy 118.534689 -238.911194) (xy 118.522912 -238.86341)
			(xy 118.518952 -238.814356) (xy 116.310156 -238.814356) (xy 116.309661 -238.838963) (xy 116.301766 -238.88754)
			(xy 116.286182 -238.934221) (xy 116.263311 -238.977798) (xy 116.233746 -239.017142) (xy 116.198253 -239.051234)
			(xy 116.15775 -239.07919) (xy 116.113288 -239.100288) (xy 116.066017 -239.11398) (xy 116.017162 -239.119912)
			(xy 115.967987 -239.117931) (xy 115.919768 -239.108087) (xy 115.873752 -239.090635) (xy 115.831131 -239.066028)
			(xy 115.79301 -239.034903) (xy 115.760375 -238.998066) (xy 115.734072 -238.95647) (xy 115.714781 -238.911194)
			(xy 115.703004 -238.86341) (xy 115.699044 -238.814356) (xy 115.370102 -238.814356) (xy 115.369607 -238.838963)
			(xy 115.361712 -238.88754) (xy 115.346128 -238.934221) (xy 115.323257 -238.977798) (xy 115.293692 -239.017142)
			(xy 115.258199 -239.051234) (xy 115.217696 -239.07919) (xy 115.173234 -239.100288) (xy 115.125963 -239.11398)
			(xy 115.077108 -239.119912) (xy 115.027933 -239.117931) (xy 114.979714 -239.108087) (xy 114.933698 -239.090635)
			(xy 114.891077 -239.066028) (xy 114.852956 -239.034903) (xy 114.820321 -238.998066) (xy 114.794018 -238.95647)
			(xy 114.774727 -238.911194) (xy 114.76295 -238.86341) (xy 114.75899 -238.814356) (xy 114.430048 -238.814356)
			(xy 114.429553 -238.838963) (xy 114.421658 -238.88754) (xy 114.406074 -238.934221) (xy 114.383203 -238.977798)
			(xy 114.353638 -239.017142) (xy 114.318145 -239.051234) (xy 114.277642 -239.07919) (xy 114.23318 -239.100288)
			(xy 114.185909 -239.11398) (xy 114.137054 -239.119912) (xy 114.087879 -239.117931) (xy 114.03966 -239.108087)
			(xy 113.993644 -239.090635) (xy 113.951023 -239.066028) (xy 113.912902 -239.034903) (xy 113.880267 -238.998066)
			(xy 113.853964 -238.95647) (xy 113.834673 -238.911194) (xy 113.822896 -238.86341) (xy 113.818936 -238.814356)
			(xy 113.489994 -238.814356) (xy 113.489458 -238.839454) (xy 113.481196 -238.888968) (xy 113.464953 -238.936466)
			(xy 113.441166 -238.980671) (xy 113.410475 -239.020393) (xy 113.392458 -239.037876) (xy 113.385092 -239.044734)
			(xy 113.372392 -239.072674) (xy 113.370234 -239.07774) (xy 113.36793 -239.088505) (xy 113.36782 -239.09401)
			(xy 113.36782 -239.624362) (xy 115.22889 -239.624362) (xy 115.23285 -239.575308) (xy 115.244627 -239.527524)
			(xy 115.263918 -239.482248) (xy 115.290221 -239.440652) (xy 115.322856 -239.403815) (xy 115.360977 -239.37269)
			(xy 115.403598 -239.348083) (xy 115.449614 -239.330631) (xy 115.497833 -239.320787) (xy 115.547008 -239.318806)
			(xy 115.595863 -239.324738) (xy 115.643134 -239.33843) (xy 115.687596 -239.359528) (xy 115.728099 -239.387484)
			(xy 115.763592 -239.421576) (xy 115.793157 -239.46092) (xy 115.816028 -239.504497) (xy 115.831612 -239.551178)
			(xy 115.839507 -239.599755) (xy 115.840002 -239.624362) (xy 116.168944 -239.624362) (xy 116.172904 -239.575308)
			(xy 116.184681 -239.527524) (xy 116.203972 -239.482248) (xy 116.230275 -239.440652) (xy 116.26291 -239.403815)
			(xy 116.301031 -239.37269) (xy 116.343652 -239.348083) (xy 116.389668 -239.330631) (xy 116.437887 -239.320787)
			(xy 116.487062 -239.318806) (xy 116.535917 -239.324738) (xy 116.583188 -239.33843) (xy 116.62765 -239.359528)
			(xy 116.668153 -239.387484) (xy 116.703646 -239.421576) (xy 116.733211 -239.46092) (xy 116.756082 -239.504497)
			(xy 116.771666 -239.551178) (xy 116.779561 -239.599755) (xy 116.780056 -239.624362) (xy 117.108998 -239.624362)
			(xy 117.112958 -239.575308) (xy 117.124735 -239.527524) (xy 117.144026 -239.482248) (xy 117.170329 -239.440652)
			(xy 117.202964 -239.403815) (xy 117.241085 -239.37269) (xy 117.283706 -239.348083) (xy 117.329722 -239.330631)
			(xy 117.377941 -239.320787) (xy 117.427116 -239.318806) (xy 117.475971 -239.324738) (xy 117.523242 -239.33843)
			(xy 117.567704 -239.359528) (xy 117.608207 -239.387484) (xy 117.6437 -239.421576) (xy 117.673265 -239.46092)
			(xy 117.696136 -239.504497) (xy 117.71172 -239.551178) (xy 117.719615 -239.599755) (xy 117.72011 -239.624362)
			(xy 118.049052 -239.624362) (xy 118.053012 -239.575308) (xy 118.064789 -239.527524) (xy 118.08408 -239.482248)
			(xy 118.110383 -239.440652) (xy 118.143018 -239.403815) (xy 118.181139 -239.37269) (xy 118.22376 -239.348083)
			(xy 118.269776 -239.330631) (xy 118.317995 -239.320787) (xy 118.36717 -239.318806) (xy 118.416025 -239.324738)
			(xy 118.463296 -239.33843) (xy 118.507758 -239.359528) (xy 118.548261 -239.387484) (xy 118.583754 -239.421576)
			(xy 118.613319 -239.46092) (xy 118.63619 -239.504497) (xy 118.651774 -239.551178) (xy 118.659669 -239.599755)
			(xy 118.660164 -239.624362) (xy 118.988852 -239.624362) (xy 118.992812 -239.575308) (xy 119.004589 -239.527524)
			(xy 119.02388 -239.482248) (xy 119.050183 -239.440652) (xy 119.082818 -239.403815) (xy 119.120939 -239.37269)
			(xy 119.16356 -239.348083) (xy 119.209576 -239.330631) (xy 119.257795 -239.320787) (xy 119.30697 -239.318806)
			(xy 119.355825 -239.324738) (xy 119.403096 -239.33843) (xy 119.447558 -239.359528) (xy 119.488061 -239.387484)
			(xy 119.523554 -239.421576) (xy 119.553119 -239.46092) (xy 119.57599 -239.504497) (xy 119.591574 -239.551178)
			(xy 119.599469 -239.599755) (xy 119.599964 -239.624362) (xy 119.928906 -239.624362) (xy 119.932866 -239.575308)
			(xy 119.944643 -239.527524) (xy 119.963934 -239.482248) (xy 119.990237 -239.440652) (xy 120.022872 -239.403815)
			(xy 120.060993 -239.37269) (xy 120.103614 -239.348083) (xy 120.14963 -239.330631) (xy 120.197849 -239.320787)
			(xy 120.247024 -239.318806) (xy 120.295879 -239.324738) (xy 120.34315 -239.33843) (xy 120.387612 -239.359528)
			(xy 120.428115 -239.387484) (xy 120.463608 -239.421576) (xy 120.493173 -239.46092) (xy 120.516044 -239.504497)
			(xy 120.531628 -239.551178) (xy 120.539523 -239.599755) (xy 120.540018 -239.624362) (xy 120.86896 -239.624362)
			(xy 120.87292 -239.575308) (xy 120.884697 -239.527524) (xy 120.903988 -239.482248) (xy 120.930291 -239.440652)
			(xy 120.962926 -239.403815) (xy 121.001047 -239.37269) (xy 121.043668 -239.348083) (xy 121.089684 -239.330631)
			(xy 121.137903 -239.320787) (xy 121.187078 -239.318806) (xy 121.235933 -239.324738) (xy 121.283204 -239.33843)
			(xy 121.327666 -239.359528) (xy 121.368169 -239.387484) (xy 121.403662 -239.421576) (xy 121.433227 -239.46092)
			(xy 121.456098 -239.504497) (xy 121.471682 -239.551178) (xy 121.479577 -239.599755) (xy 121.480072 -239.624362)
			(xy 121.809014 -239.624362) (xy 121.812974 -239.575308) (xy 121.824751 -239.527524) (xy 121.844042 -239.482248)
			(xy 121.870345 -239.440652) (xy 121.90298 -239.403815) (xy 121.941101 -239.37269) (xy 121.983722 -239.348083)
			(xy 122.029738 -239.330631) (xy 122.077957 -239.320787) (xy 122.127132 -239.318806) (xy 122.175987 -239.324738)
			(xy 122.223258 -239.33843) (xy 122.26772 -239.359528) (xy 122.308223 -239.387484) (xy 122.343716 -239.421576)
			(xy 122.373281 -239.46092) (xy 122.396152 -239.504497) (xy 122.411736 -239.551178) (xy 122.419631 -239.599755)
			(xy 122.420126 -239.624362) (xy 122.748814 -239.624362) (xy 122.752774 -239.575308) (xy 122.764551 -239.527524)
			(xy 122.783842 -239.482248) (xy 122.810145 -239.440652) (xy 122.84278 -239.403815) (xy 122.880901 -239.37269)
			(xy 122.923522 -239.348083) (xy 122.969538 -239.330631) (xy 123.017757 -239.320787) (xy 123.066932 -239.318806)
			(xy 123.115787 -239.324738) (xy 123.163058 -239.33843) (xy 123.20752 -239.359528) (xy 123.248023 -239.387484)
			(xy 123.283516 -239.421576) (xy 123.313081 -239.46092) (xy 123.335952 -239.504497) (xy 123.351536 -239.551178)
			(xy 123.359431 -239.599755) (xy 123.359926 -239.624362) (xy 123.688868 -239.624362) (xy 123.692828 -239.575308)
			(xy 123.704605 -239.527524) (xy 123.723896 -239.482248) (xy 123.750199 -239.440652) (xy 123.782834 -239.403815)
			(xy 123.820955 -239.37269) (xy 123.863576 -239.348083) (xy 123.909592 -239.330631) (xy 123.957811 -239.320787)
			(xy 124.006986 -239.318806) (xy 124.055841 -239.324738) (xy 124.103112 -239.33843) (xy 124.147574 -239.359528)
			(xy 124.188077 -239.387484) (xy 124.22357 -239.421576) (xy 124.253135 -239.46092) (xy 124.276006 -239.504497)
			(xy 124.29159 -239.551178) (xy 124.299485 -239.599755) (xy 124.29998 -239.624362) (xy 124.628922 -239.624362)
			(xy 124.632882 -239.575308) (xy 124.644659 -239.527524) (xy 124.66395 -239.482248) (xy 124.690253 -239.440652)
			(xy 124.722888 -239.403815) (xy 124.761009 -239.37269) (xy 124.80363 -239.348083) (xy 124.849646 -239.330631)
			(xy 124.897865 -239.320787) (xy 124.94704 -239.318806) (xy 124.995895 -239.324738) (xy 125.043166 -239.33843)
			(xy 125.087628 -239.359528) (xy 125.128131 -239.387484) (xy 125.163624 -239.421576) (xy 125.193189 -239.46092)
			(xy 125.21606 -239.504497) (xy 125.231644 -239.551178) (xy 125.239539 -239.599755) (xy 125.240034 -239.624362)
			(xy 125.568976 -239.624362) (xy 125.572936 -239.575308) (xy 125.584713 -239.527524) (xy 125.604004 -239.482248)
			(xy 125.630307 -239.440652) (xy 125.662942 -239.403815) (xy 125.701063 -239.37269) (xy 125.743684 -239.348083)
			(xy 125.7897 -239.330631) (xy 125.837919 -239.320787) (xy 125.887094 -239.318806) (xy 125.935949 -239.324738)
			(xy 125.98322 -239.33843) (xy 126.027682 -239.359528) (xy 126.068185 -239.387484) (xy 126.103678 -239.421576)
			(xy 126.133243 -239.46092) (xy 126.156114 -239.504497) (xy 126.171698 -239.551178) (xy 126.179593 -239.599755)
			(xy 126.180088 -239.624362) (xy 126.179593 -239.648969) (xy 126.171698 -239.697546) (xy 126.156114 -239.744227)
			(xy 126.133243 -239.787804) (xy 126.103678 -239.827148) (xy 126.068185 -239.86124) (xy 126.027682 -239.889196)
			(xy 125.98322 -239.910294) (xy 125.935949 -239.923986) (xy 125.887094 -239.929918) (xy 125.837919 -239.927937)
			(xy 125.7897 -239.918093) (xy 125.743684 -239.900641) (xy 125.701063 -239.876034) (xy 125.662942 -239.844909)
			(xy 125.630307 -239.808072) (xy 125.604004 -239.766476) (xy 125.584713 -239.7212) (xy 125.572936 -239.673416)
			(xy 125.568976 -239.624362) (xy 125.240034 -239.624362) (xy 125.239539 -239.648969) (xy 125.231644 -239.697546)
			(xy 125.21606 -239.744227) (xy 125.193189 -239.787804) (xy 125.163624 -239.827148) (xy 125.128131 -239.86124)
			(xy 125.087628 -239.889196) (xy 125.043166 -239.910294) (xy 124.995895 -239.923986) (xy 124.94704 -239.929918)
			(xy 124.897865 -239.927937) (xy 124.849646 -239.918093) (xy 124.80363 -239.900641) (xy 124.761009 -239.876034)
			(xy 124.722888 -239.844909) (xy 124.690253 -239.808072) (xy 124.66395 -239.766476) (xy 124.644659 -239.7212)
			(xy 124.632882 -239.673416) (xy 124.628922 -239.624362) (xy 124.29998 -239.624362) (xy 124.299485 -239.648969)
			(xy 124.29159 -239.697546) (xy 124.276006 -239.744227) (xy 124.253135 -239.787804) (xy 124.22357 -239.827148)
			(xy 124.188077 -239.86124) (xy 124.147574 -239.889196) (xy 124.103112 -239.910294) (xy 124.055841 -239.923986)
			(xy 124.006986 -239.929918) (xy 123.957811 -239.927937) (xy 123.909592 -239.918093) (xy 123.863576 -239.900641)
			(xy 123.820955 -239.876034) (xy 123.782834 -239.844909) (xy 123.750199 -239.808072) (xy 123.723896 -239.766476)
			(xy 123.704605 -239.7212) (xy 123.692828 -239.673416) (xy 123.688868 -239.624362) (xy 123.359926 -239.624362)
			(xy 123.359431 -239.648969) (xy 123.351536 -239.697546) (xy 123.335952 -239.744227) (xy 123.313081 -239.787804)
			(xy 123.283516 -239.827148) (xy 123.248023 -239.86124) (xy 123.20752 -239.889196) (xy 123.163058 -239.910294)
			(xy 123.115787 -239.923986) (xy 123.066932 -239.929918) (xy 123.017757 -239.927937) (xy 122.969538 -239.918093)
			(xy 122.923522 -239.900641) (xy 122.880901 -239.876034) (xy 122.84278 -239.844909) (xy 122.810145 -239.808072)
			(xy 122.783842 -239.766476) (xy 122.764551 -239.7212) (xy 122.752774 -239.673416) (xy 122.748814 -239.624362)
			(xy 122.420126 -239.624362) (xy 122.419631 -239.648969) (xy 122.411736 -239.697546) (xy 122.396152 -239.744227)
			(xy 122.373281 -239.787804) (xy 122.343716 -239.827148) (xy 122.308223 -239.86124) (xy 122.26772 -239.889196)
			(xy 122.223258 -239.910294) (xy 122.175987 -239.923986) (xy 122.127132 -239.929918) (xy 122.077957 -239.927937)
			(xy 122.029738 -239.918093) (xy 121.983722 -239.900641) (xy 121.941101 -239.876034) (xy 121.90298 -239.844909)
			(xy 121.870345 -239.808072) (xy 121.844042 -239.766476) (xy 121.824751 -239.7212) (xy 121.812974 -239.673416)
			(xy 121.809014 -239.624362) (xy 121.480072 -239.624362) (xy 121.479577 -239.648969) (xy 121.471682 -239.697546)
			(xy 121.456098 -239.744227) (xy 121.433227 -239.787804) (xy 121.403662 -239.827148) (xy 121.368169 -239.86124)
			(xy 121.327666 -239.889196) (xy 121.283204 -239.910294) (xy 121.235933 -239.923986) (xy 121.187078 -239.929918)
			(xy 121.137903 -239.927937) (xy 121.089684 -239.918093) (xy 121.043668 -239.900641) (xy 121.001047 -239.876034)
			(xy 120.962926 -239.844909) (xy 120.930291 -239.808072) (xy 120.903988 -239.766476) (xy 120.884697 -239.7212)
			(xy 120.87292 -239.673416) (xy 120.86896 -239.624362) (xy 120.540018 -239.624362) (xy 120.539523 -239.648969)
			(xy 120.531628 -239.697546) (xy 120.516044 -239.744227) (xy 120.493173 -239.787804) (xy 120.463608 -239.827148)
			(xy 120.428115 -239.86124) (xy 120.387612 -239.889196) (xy 120.34315 -239.910294) (xy 120.295879 -239.923986)
			(xy 120.247024 -239.929918) (xy 120.197849 -239.927937) (xy 120.14963 -239.918093) (xy 120.103614 -239.900641)
			(xy 120.060993 -239.876034) (xy 120.022872 -239.844909) (xy 119.990237 -239.808072) (xy 119.963934 -239.766476)
			(xy 119.944643 -239.7212) (xy 119.932866 -239.673416) (xy 119.928906 -239.624362) (xy 119.599964 -239.624362)
			(xy 119.599469 -239.648969) (xy 119.591574 -239.697546) (xy 119.57599 -239.744227) (xy 119.553119 -239.787804)
			(xy 119.523554 -239.827148) (xy 119.488061 -239.86124) (xy 119.447558 -239.889196) (xy 119.403096 -239.910294)
			(xy 119.355825 -239.923986) (xy 119.30697 -239.929918) (xy 119.257795 -239.927937) (xy 119.209576 -239.918093)
			(xy 119.16356 -239.900641) (xy 119.120939 -239.876034) (xy 119.082818 -239.844909) (xy 119.050183 -239.808072)
			(xy 119.02388 -239.766476) (xy 119.004589 -239.7212) (xy 118.992812 -239.673416) (xy 118.988852 -239.624362)
			(xy 118.660164 -239.624362) (xy 118.659669 -239.648969) (xy 118.651774 -239.697546) (xy 118.63619 -239.744227)
			(xy 118.613319 -239.787804) (xy 118.583754 -239.827148) (xy 118.548261 -239.86124) (xy 118.507758 -239.889196)
			(xy 118.463296 -239.910294) (xy 118.416025 -239.923986) (xy 118.36717 -239.929918) (xy 118.317995 -239.927937)
			(xy 118.269776 -239.918093) (xy 118.22376 -239.900641) (xy 118.181139 -239.876034) (xy 118.143018 -239.844909)
			(xy 118.110383 -239.808072) (xy 118.08408 -239.766476) (xy 118.064789 -239.7212) (xy 118.053012 -239.673416)
			(xy 118.049052 -239.624362) (xy 117.72011 -239.624362) (xy 117.719615 -239.648969) (xy 117.71172 -239.697546)
			(xy 117.696136 -239.744227) (xy 117.673265 -239.787804) (xy 117.6437 -239.827148) (xy 117.608207 -239.86124)
			(xy 117.567704 -239.889196) (xy 117.523242 -239.910294) (xy 117.475971 -239.923986) (xy 117.427116 -239.929918)
			(xy 117.377941 -239.927937) (xy 117.329722 -239.918093) (xy 117.283706 -239.900641) (xy 117.241085 -239.876034)
			(xy 117.202964 -239.844909) (xy 117.170329 -239.808072) (xy 117.144026 -239.766476) (xy 117.124735 -239.7212)
			(xy 117.112958 -239.673416) (xy 117.108998 -239.624362) (xy 116.780056 -239.624362) (xy 116.779561 -239.648969)
			(xy 116.771666 -239.697546) (xy 116.756082 -239.744227) (xy 116.733211 -239.787804) (xy 116.703646 -239.827148)
			(xy 116.668153 -239.86124) (xy 116.62765 -239.889196) (xy 116.583188 -239.910294) (xy 116.535917 -239.923986)
			(xy 116.487062 -239.929918) (xy 116.437887 -239.927937) (xy 116.389668 -239.918093) (xy 116.343652 -239.900641)
			(xy 116.301031 -239.876034) (xy 116.26291 -239.844909) (xy 116.230275 -239.808072) (xy 116.203972 -239.766476)
			(xy 116.184681 -239.7212) (xy 116.172904 -239.673416) (xy 116.168944 -239.624362) (xy 115.840002 -239.624362)
			(xy 115.839507 -239.648969) (xy 115.831612 -239.697546) (xy 115.816028 -239.744227) (xy 115.793157 -239.787804)
			(xy 115.763592 -239.827148) (xy 115.728099 -239.86124) (xy 115.687596 -239.889196) (xy 115.643134 -239.910294)
			(xy 115.595863 -239.923986) (xy 115.547008 -239.929918) (xy 115.497833 -239.927937) (xy 115.449614 -239.918093)
			(xy 115.403598 -239.900641) (xy 115.360977 -239.876034) (xy 115.322856 -239.844909) (xy 115.290221 -239.808072)
			(xy 115.263918 -239.766476) (xy 115.244627 -239.7212) (xy 115.23285 -239.673416) (xy 115.22889 -239.624362)
			(xy 113.36782 -239.624362) (xy 113.36782 -240.154714) (xy 113.367946 -240.160217) (xy 113.370262 -240.170974)
			(xy 113.372392 -240.17605) (xy 113.385092 -240.20399) (xy 113.392458 -240.210848) (xy 113.410506 -240.228301)
			(xy 113.441207 -240.268022) (xy 113.46499 -240.312234) (xy 113.481213 -240.359743) (xy 113.489438 -240.409267)
			(xy 113.489994 -240.434368) (xy 113.818936 -240.434368) (xy 113.822896 -240.385314) (xy 113.834673 -240.33753)
			(xy 113.853964 -240.292254) (xy 113.880267 -240.250658) (xy 113.912902 -240.213821) (xy 113.951023 -240.182696)
			(xy 113.993644 -240.158089) (xy 114.03966 -240.140637) (xy 114.087879 -240.130793) (xy 114.137054 -240.128812)
			(xy 114.185909 -240.134744) (xy 114.23318 -240.148436) (xy 114.277642 -240.169534) (xy 114.318145 -240.19749)
			(xy 114.353638 -240.231582) (xy 114.383203 -240.270926) (xy 114.406074 -240.314503) (xy 114.421658 -240.361184)
			(xy 114.429553 -240.409761) (xy 114.430048 -240.434368) (xy 114.75899 -240.434368) (xy 114.76295 -240.385314)
			(xy 114.774727 -240.33753) (xy 114.794018 -240.292254) (xy 114.820321 -240.250658) (xy 114.852956 -240.213821)
			(xy 114.891077 -240.182696) (xy 114.933698 -240.158089) (xy 114.979714 -240.140637) (xy 115.027933 -240.130793)
			(xy 115.077108 -240.128812) (xy 115.125963 -240.134744) (xy 115.173234 -240.148436) (xy 115.217696 -240.169534)
			(xy 115.258199 -240.19749) (xy 115.293692 -240.231582) (xy 115.323257 -240.270926) (xy 115.346128 -240.314503)
			(xy 115.361712 -240.361184) (xy 115.369607 -240.409761) (xy 115.370102 -240.434368) (xy 115.699044 -240.434368)
			(xy 115.703004 -240.385314) (xy 115.714781 -240.33753) (xy 115.734072 -240.292254) (xy 115.760375 -240.250658)
			(xy 115.79301 -240.213821) (xy 115.831131 -240.182696) (xy 115.873752 -240.158089) (xy 115.919768 -240.140637)
			(xy 115.967987 -240.130793) (xy 116.017162 -240.128812) (xy 116.066017 -240.134744) (xy 116.113288 -240.148436)
			(xy 116.15775 -240.169534) (xy 116.198253 -240.19749) (xy 116.233746 -240.231582) (xy 116.263311 -240.270926)
			(xy 116.286182 -240.314503) (xy 116.301766 -240.361184) (xy 116.309661 -240.409761) (xy 116.310156 -240.434368)
			(xy 116.638844 -240.434368) (xy 116.642804 -240.385314) (xy 116.654581 -240.33753) (xy 116.673872 -240.292254)
			(xy 116.700175 -240.250658) (xy 116.73281 -240.213821) (xy 116.770931 -240.182696) (xy 116.813552 -240.158089)
			(xy 116.859568 -240.140637) (xy 116.907787 -240.130793) (xy 116.956962 -240.128812) (xy 117.005817 -240.134744)
			(xy 117.053088 -240.148436) (xy 117.09755 -240.169534) (xy 117.138053 -240.19749) (xy 117.173546 -240.231582)
			(xy 117.203111 -240.270926) (xy 117.225982 -240.314503) (xy 117.241566 -240.361184) (xy 117.249461 -240.409761)
			(xy 117.249956 -240.434368) (xy 117.578898 -240.434368) (xy 117.582858 -240.385314) (xy 117.594635 -240.33753)
			(xy 117.613926 -240.292254) (xy 117.640229 -240.250658) (xy 117.672864 -240.213821) (xy 117.710985 -240.182696)
			(xy 117.753606 -240.158089) (xy 117.799622 -240.140637) (xy 117.847841 -240.130793) (xy 117.897016 -240.128812)
			(xy 117.945871 -240.134744) (xy 117.993142 -240.148436) (xy 118.037604 -240.169534) (xy 118.078107 -240.19749)
			(xy 118.1136 -240.231582) (xy 118.143165 -240.270926) (xy 118.166036 -240.314503) (xy 118.18162 -240.361184)
			(xy 118.189515 -240.409761) (xy 118.19001 -240.434368) (xy 118.518952 -240.434368) (xy 118.522912 -240.385314)
			(xy 118.534689 -240.33753) (xy 118.55398 -240.292254) (xy 118.580283 -240.250658) (xy 118.612918 -240.213821)
			(xy 118.651039 -240.182696) (xy 118.69366 -240.158089) (xy 118.739676 -240.140637) (xy 118.787895 -240.130793)
			(xy 118.83707 -240.128812) (xy 118.885925 -240.134744) (xy 118.933196 -240.148436) (xy 118.977658 -240.169534)
			(xy 119.018161 -240.19749) (xy 119.053654 -240.231582) (xy 119.083219 -240.270926) (xy 119.10609 -240.314503)
			(xy 119.121674 -240.361184) (xy 119.129569 -240.409761) (xy 119.130064 -240.434368) (xy 119.459006 -240.434368)
			(xy 119.462966 -240.385314) (xy 119.474743 -240.33753) (xy 119.494034 -240.292254) (xy 119.520337 -240.250658)
			(xy 119.552972 -240.213821) (xy 119.591093 -240.182696) (xy 119.633714 -240.158089) (xy 119.67973 -240.140637)
			(xy 119.727949 -240.130793) (xy 119.777124 -240.128812) (xy 119.825979 -240.134744) (xy 119.87325 -240.148436)
			(xy 119.917712 -240.169534) (xy 119.958215 -240.19749) (xy 119.993708 -240.231582) (xy 120.023273 -240.270926)
			(xy 120.046144 -240.314503) (xy 120.061728 -240.361184) (xy 120.069623 -240.409761) (xy 120.070118 -240.434368)
			(xy 120.398806 -240.434368) (xy 120.402766 -240.385314) (xy 120.414543 -240.33753) (xy 120.433834 -240.292254)
			(xy 120.460137 -240.250658) (xy 120.492772 -240.213821) (xy 120.530893 -240.182696) (xy 120.573514 -240.158089)
			(xy 120.61953 -240.140637) (xy 120.667749 -240.130793) (xy 120.716924 -240.128812) (xy 120.765779 -240.134744)
			(xy 120.81305 -240.148436) (xy 120.857512 -240.169534) (xy 120.898015 -240.19749) (xy 120.933508 -240.231582)
			(xy 120.963073 -240.270926) (xy 120.985944 -240.314503) (xy 121.001528 -240.361184) (xy 121.009423 -240.409761)
			(xy 121.009918 -240.434368) (xy 121.33886 -240.434368) (xy 121.34282 -240.385314) (xy 121.354597 -240.33753)
			(xy 121.373888 -240.292254) (xy 121.400191 -240.250658) (xy 121.432826 -240.213821) (xy 121.470947 -240.182696)
			(xy 121.513568 -240.158089) (xy 121.559584 -240.140637) (xy 121.607803 -240.130793) (xy 121.656978 -240.128812)
			(xy 121.705833 -240.134744) (xy 121.753104 -240.148436) (xy 121.797566 -240.169534) (xy 121.838069 -240.19749)
			(xy 121.873562 -240.231582) (xy 121.903127 -240.270926) (xy 121.925998 -240.314503) (xy 121.941582 -240.361184)
			(xy 121.949477 -240.409761) (xy 121.949972 -240.434368) (xy 122.278914 -240.434368) (xy 122.282874 -240.385314)
			(xy 122.294651 -240.33753) (xy 122.313942 -240.292254) (xy 122.340245 -240.250658) (xy 122.37288 -240.213821)
			(xy 122.411001 -240.182696) (xy 122.453622 -240.158089) (xy 122.499638 -240.140637) (xy 122.547857 -240.130793)
			(xy 122.597032 -240.128812) (xy 122.645887 -240.134744) (xy 122.693158 -240.148436) (xy 122.73762 -240.169534)
			(xy 122.778123 -240.19749) (xy 122.813616 -240.231582) (xy 122.843181 -240.270926) (xy 122.866052 -240.314503)
			(xy 122.881636 -240.361184) (xy 122.889531 -240.409761) (xy 122.890026 -240.434368) (xy 123.218968 -240.434368)
			(xy 123.222928 -240.385314) (xy 123.234705 -240.33753) (xy 123.253996 -240.292254) (xy 123.280299 -240.250658)
			(xy 123.312934 -240.213821) (xy 123.351055 -240.182696) (xy 123.393676 -240.158089) (xy 123.439692 -240.140637)
			(xy 123.487911 -240.130793) (xy 123.537086 -240.128812) (xy 123.585941 -240.134744) (xy 123.633212 -240.148436)
			(xy 123.677674 -240.169534) (xy 123.718177 -240.19749) (xy 123.75367 -240.231582) (xy 123.783235 -240.270926)
			(xy 123.806106 -240.314503) (xy 123.82169 -240.361184) (xy 123.829585 -240.409761) (xy 123.83008 -240.434368)
			(xy 124.159022 -240.434368) (xy 124.162982 -240.385314) (xy 124.174759 -240.33753) (xy 124.19405 -240.292254)
			(xy 124.220353 -240.250658) (xy 124.252988 -240.213821) (xy 124.291109 -240.182696) (xy 124.33373 -240.158089)
			(xy 124.379746 -240.140637) (xy 124.427965 -240.130793) (xy 124.47714 -240.128812) (xy 124.525995 -240.134744)
			(xy 124.573266 -240.148436) (xy 124.617728 -240.169534) (xy 124.658231 -240.19749) (xy 124.693724 -240.231582)
			(xy 124.723289 -240.270926) (xy 124.74616 -240.314503) (xy 124.761744 -240.361184) (xy 124.769639 -240.409761)
			(xy 124.770134 -240.434368) (xy 125.098822 -240.434368) (xy 125.102782 -240.385314) (xy 125.114559 -240.33753)
			(xy 125.13385 -240.292254) (xy 125.160153 -240.250658) (xy 125.192788 -240.213821) (xy 125.230909 -240.182696)
			(xy 125.27353 -240.158089) (xy 125.319546 -240.140637) (xy 125.367765 -240.130793) (xy 125.41694 -240.128812)
			(xy 125.465795 -240.134744) (xy 125.513066 -240.148436) (xy 125.557528 -240.169534) (xy 125.598031 -240.19749)
			(xy 125.633524 -240.231582) (xy 125.663089 -240.270926) (xy 125.68596 -240.314503) (xy 125.701544 -240.361184)
			(xy 125.709439 -240.409761) (xy 125.709934 -240.434368) (xy 125.709439 -240.458975) (xy 125.701544 -240.507552)
			(xy 125.68596 -240.554233) (xy 125.663089 -240.59781) (xy 125.633524 -240.637154) (xy 125.598031 -240.671246)
			(xy 125.557528 -240.699202) (xy 125.513066 -240.7203) (xy 125.465795 -240.733992) (xy 125.41694 -240.739924)
			(xy 125.367765 -240.737943) (xy 125.319546 -240.728099) (xy 125.27353 -240.710647) (xy 125.230909 -240.68604)
			(xy 125.192788 -240.654915) (xy 125.160153 -240.618078) (xy 125.13385 -240.576482) (xy 125.114559 -240.531206)
			(xy 125.102782 -240.483422) (xy 125.098822 -240.434368) (xy 124.770134 -240.434368) (xy 124.769639 -240.458975)
			(xy 124.761744 -240.507552) (xy 124.74616 -240.554233) (xy 124.723289 -240.59781) (xy 124.693724 -240.637154)
			(xy 124.658231 -240.671246) (xy 124.617728 -240.699202) (xy 124.573266 -240.7203) (xy 124.525995 -240.733992)
			(xy 124.47714 -240.739924) (xy 124.427965 -240.737943) (xy 124.379746 -240.728099) (xy 124.33373 -240.710647)
			(xy 124.291109 -240.68604) (xy 124.252988 -240.654915) (xy 124.220353 -240.618078) (xy 124.19405 -240.576482)
			(xy 124.174759 -240.531206) (xy 124.162982 -240.483422) (xy 124.159022 -240.434368) (xy 123.83008 -240.434368)
			(xy 123.829585 -240.458975) (xy 123.82169 -240.507552) (xy 123.806106 -240.554233) (xy 123.783235 -240.59781)
			(xy 123.75367 -240.637154) (xy 123.718177 -240.671246) (xy 123.677674 -240.699202) (xy 123.633212 -240.7203)
			(xy 123.585941 -240.733992) (xy 123.537086 -240.739924) (xy 123.487911 -240.737943) (xy 123.439692 -240.728099)
			(xy 123.393676 -240.710647) (xy 123.351055 -240.68604) (xy 123.312934 -240.654915) (xy 123.280299 -240.618078)
			(xy 123.253996 -240.576482) (xy 123.234705 -240.531206) (xy 123.222928 -240.483422) (xy 123.218968 -240.434368)
			(xy 122.890026 -240.434368) (xy 122.889531 -240.458975) (xy 122.881636 -240.507552) (xy 122.866052 -240.554233)
			(xy 122.843181 -240.59781) (xy 122.813616 -240.637154) (xy 122.778123 -240.671246) (xy 122.73762 -240.699202)
			(xy 122.693158 -240.7203) (xy 122.645887 -240.733992) (xy 122.597032 -240.739924) (xy 122.547857 -240.737943)
			(xy 122.499638 -240.728099) (xy 122.453622 -240.710647) (xy 122.411001 -240.68604) (xy 122.37288 -240.654915)
			(xy 122.340245 -240.618078) (xy 122.313942 -240.576482) (xy 122.294651 -240.531206) (xy 122.282874 -240.483422)
			(xy 122.278914 -240.434368) (xy 121.949972 -240.434368) (xy 121.949477 -240.458975) (xy 121.941582 -240.507552)
			(xy 121.925998 -240.554233) (xy 121.903127 -240.59781) (xy 121.873562 -240.637154) (xy 121.838069 -240.671246)
			(xy 121.797566 -240.699202) (xy 121.753104 -240.7203) (xy 121.705833 -240.733992) (xy 121.656978 -240.739924)
			(xy 121.607803 -240.737943) (xy 121.559584 -240.728099) (xy 121.513568 -240.710647) (xy 121.470947 -240.68604)
			(xy 121.432826 -240.654915) (xy 121.400191 -240.618078) (xy 121.373888 -240.576482) (xy 121.354597 -240.531206)
			(xy 121.34282 -240.483422) (xy 121.33886 -240.434368) (xy 121.009918 -240.434368) (xy 121.009423 -240.458975)
			(xy 121.001528 -240.507552) (xy 120.985944 -240.554233) (xy 120.963073 -240.59781) (xy 120.933508 -240.637154)
			(xy 120.898015 -240.671246) (xy 120.857512 -240.699202) (xy 120.81305 -240.7203) (xy 120.765779 -240.733992)
			(xy 120.716924 -240.739924) (xy 120.667749 -240.737943) (xy 120.61953 -240.728099) (xy 120.573514 -240.710647)
			(xy 120.530893 -240.68604) (xy 120.492772 -240.654915) (xy 120.460137 -240.618078) (xy 120.433834 -240.576482)
			(xy 120.414543 -240.531206) (xy 120.402766 -240.483422) (xy 120.398806 -240.434368) (xy 120.070118 -240.434368)
			(xy 120.069623 -240.458975) (xy 120.061728 -240.507552) (xy 120.046144 -240.554233) (xy 120.023273 -240.59781)
			(xy 119.993708 -240.637154) (xy 119.958215 -240.671246) (xy 119.917712 -240.699202) (xy 119.87325 -240.7203)
			(xy 119.825979 -240.733992) (xy 119.777124 -240.739924) (xy 119.727949 -240.737943) (xy 119.67973 -240.728099)
			(xy 119.633714 -240.710647) (xy 119.591093 -240.68604) (xy 119.552972 -240.654915) (xy 119.520337 -240.618078)
			(xy 119.494034 -240.576482) (xy 119.474743 -240.531206) (xy 119.462966 -240.483422) (xy 119.459006 -240.434368)
			(xy 119.130064 -240.434368) (xy 119.129569 -240.458975) (xy 119.121674 -240.507552) (xy 119.10609 -240.554233)
			(xy 119.083219 -240.59781) (xy 119.053654 -240.637154) (xy 119.018161 -240.671246) (xy 118.977658 -240.699202)
			(xy 118.933196 -240.7203) (xy 118.885925 -240.733992) (xy 118.83707 -240.739924) (xy 118.787895 -240.737943)
			(xy 118.739676 -240.728099) (xy 118.69366 -240.710647) (xy 118.651039 -240.68604) (xy 118.612918 -240.654915)
			(xy 118.580283 -240.618078) (xy 118.55398 -240.576482) (xy 118.534689 -240.531206) (xy 118.522912 -240.483422)
			(xy 118.518952 -240.434368) (xy 118.19001 -240.434368) (xy 118.189515 -240.458975) (xy 118.18162 -240.507552)
			(xy 118.166036 -240.554233) (xy 118.143165 -240.59781) (xy 118.1136 -240.637154) (xy 118.078107 -240.671246)
			(xy 118.037604 -240.699202) (xy 117.993142 -240.7203) (xy 117.945871 -240.733992) (xy 117.897016 -240.739924)
			(xy 117.847841 -240.737943) (xy 117.799622 -240.728099) (xy 117.753606 -240.710647) (xy 117.710985 -240.68604)
			(xy 117.672864 -240.654915) (xy 117.640229 -240.618078) (xy 117.613926 -240.576482) (xy 117.594635 -240.531206)
			(xy 117.582858 -240.483422) (xy 117.578898 -240.434368) (xy 117.249956 -240.434368) (xy 117.249461 -240.458975)
			(xy 117.241566 -240.507552) (xy 117.225982 -240.554233) (xy 117.203111 -240.59781) (xy 117.173546 -240.637154)
			(xy 117.138053 -240.671246) (xy 117.09755 -240.699202) (xy 117.053088 -240.7203) (xy 117.005817 -240.733992)
			(xy 116.956962 -240.739924) (xy 116.907787 -240.737943) (xy 116.859568 -240.728099) (xy 116.813552 -240.710647)
			(xy 116.770931 -240.68604) (xy 116.73281 -240.654915) (xy 116.700175 -240.618078) (xy 116.673872 -240.576482)
			(xy 116.654581 -240.531206) (xy 116.642804 -240.483422) (xy 116.638844 -240.434368) (xy 116.310156 -240.434368)
			(xy 116.309661 -240.458975) (xy 116.301766 -240.507552) (xy 116.286182 -240.554233) (xy 116.263311 -240.59781)
			(xy 116.233746 -240.637154) (xy 116.198253 -240.671246) (xy 116.15775 -240.699202) (xy 116.113288 -240.7203)
			(xy 116.066017 -240.733992) (xy 116.017162 -240.739924) (xy 115.967987 -240.737943) (xy 115.919768 -240.728099)
			(xy 115.873752 -240.710647) (xy 115.831131 -240.68604) (xy 115.79301 -240.654915) (xy 115.760375 -240.618078)
			(xy 115.734072 -240.576482) (xy 115.714781 -240.531206) (xy 115.703004 -240.483422) (xy 115.699044 -240.434368)
			(xy 115.370102 -240.434368) (xy 115.369607 -240.458975) (xy 115.361712 -240.507552) (xy 115.346128 -240.554233)
			(xy 115.323257 -240.59781) (xy 115.293692 -240.637154) (xy 115.258199 -240.671246) (xy 115.217696 -240.699202)
			(xy 115.173234 -240.7203) (xy 115.125963 -240.733992) (xy 115.077108 -240.739924) (xy 115.027933 -240.737943)
			(xy 114.979714 -240.728099) (xy 114.933698 -240.710647) (xy 114.891077 -240.68604) (xy 114.852956 -240.654915)
			(xy 114.820321 -240.618078) (xy 114.794018 -240.576482) (xy 114.774727 -240.531206) (xy 114.76295 -240.483422)
			(xy 114.75899 -240.434368) (xy 114.430048 -240.434368) (xy 114.429553 -240.458975) (xy 114.421658 -240.507552)
			(xy 114.406074 -240.554233) (xy 114.383203 -240.59781) (xy 114.353638 -240.637154) (xy 114.318145 -240.671246)
			(xy 114.277642 -240.699202) (xy 114.23318 -240.7203) (xy 114.185909 -240.733992) (xy 114.137054 -240.739924)
			(xy 114.087879 -240.737943) (xy 114.03966 -240.728099) (xy 113.993644 -240.710647) (xy 113.951023 -240.68604)
			(xy 113.912902 -240.654915) (xy 113.880267 -240.618078) (xy 113.853964 -240.576482) (xy 113.834673 -240.531206)
			(xy 113.822896 -240.483422) (xy 113.818936 -240.434368) (xy 113.489994 -240.434368) (xy 113.489547 -240.457987)
			(xy 113.482263 -240.504661) (xy 113.467879 -240.549657) (xy 113.446737 -240.591901) (xy 113.419343 -240.630386)
			(xy 113.38635 -240.664194) (xy 113.348544 -240.692518) (xy 113.306828 -240.714683) (xy 113.262196 -240.730159)
			(xy 113.239042 -240.73485) (xy 113.231168 -240.736374) (xy 113.21796 -240.743232) (xy 112.716818 -241.244374)
			(xy 113.349036 -241.244374) (xy 113.352996 -241.19532) (xy 113.364773 -241.147536) (xy 113.384064 -241.10226)
			(xy 113.410367 -241.060664) (xy 113.443002 -241.023827) (xy 113.481123 -240.992702) (xy 113.523744 -240.968095)
			(xy 113.56976 -240.950643) (xy 113.617979 -240.940799) (xy 113.667154 -240.938818) (xy 113.716009 -240.94475)
			(xy 113.76328 -240.958442) (xy 113.807742 -240.97954) (xy 113.848245 -241.007496) (xy 113.883738 -241.041588)
			(xy 113.913303 -241.080932) (xy 113.936174 -241.124509) (xy 113.951758 -241.17119) (xy 113.959653 -241.219767)
			(xy 113.960148 -241.244374) (xy 114.288836 -241.244374) (xy 114.292796 -241.19532) (xy 114.304573 -241.147536)
			(xy 114.323864 -241.10226) (xy 114.350167 -241.060664) (xy 114.382802 -241.023827) (xy 114.420923 -240.992702)
			(xy 114.463544 -240.968095) (xy 114.50956 -240.950643) (xy 114.557779 -240.940799) (xy 114.606954 -240.938818)
			(xy 114.655809 -240.94475) (xy 114.70308 -240.958442) (xy 114.747542 -240.97954) (xy 114.788045 -241.007496)
			(xy 114.823538 -241.041588) (xy 114.853103 -241.080932) (xy 114.875974 -241.124509) (xy 114.891558 -241.17119)
			(xy 114.899453 -241.219767) (xy 114.899948 -241.244374) (xy 115.22889 -241.244374) (xy 115.23285 -241.19532)
			(xy 115.244627 -241.147536) (xy 115.263918 -241.10226) (xy 115.290221 -241.060664) (xy 115.322856 -241.023827)
			(xy 115.360977 -240.992702) (xy 115.403598 -240.968095) (xy 115.449614 -240.950643) (xy 115.497833 -240.940799)
			(xy 115.547008 -240.938818) (xy 115.595863 -240.94475) (xy 115.643134 -240.958442) (xy 115.687596 -240.97954)
			(xy 115.728099 -241.007496) (xy 115.763592 -241.041588) (xy 115.793157 -241.080932) (xy 115.816028 -241.124509)
			(xy 115.831612 -241.17119) (xy 115.839507 -241.219767) (xy 115.840002 -241.244374) (xy 116.168944 -241.244374)
			(xy 116.172904 -241.19532) (xy 116.184681 -241.147536) (xy 116.203972 -241.10226) (xy 116.230275 -241.060664)
			(xy 116.26291 -241.023827) (xy 116.301031 -240.992702) (xy 116.343652 -240.968095) (xy 116.389668 -240.950643)
			(xy 116.437887 -240.940799) (xy 116.487062 -240.938818) (xy 116.535917 -240.94475) (xy 116.583188 -240.958442)
			(xy 116.62765 -240.97954) (xy 116.668153 -241.007496) (xy 116.703646 -241.041588) (xy 116.733211 -241.080932)
			(xy 116.756082 -241.124509) (xy 116.771666 -241.17119) (xy 116.779561 -241.219767) (xy 116.780056 -241.244374)
			(xy 117.108998 -241.244374) (xy 117.112958 -241.19532) (xy 117.124735 -241.147536) (xy 117.144026 -241.10226)
			(xy 117.170329 -241.060664) (xy 117.202964 -241.023827) (xy 117.241085 -240.992702) (xy 117.283706 -240.968095)
			(xy 117.329722 -240.950643) (xy 117.377941 -240.940799) (xy 117.427116 -240.938818) (xy 117.475971 -240.94475)
			(xy 117.523242 -240.958442) (xy 117.567704 -240.97954) (xy 117.608207 -241.007496) (xy 117.6437 -241.041588)
			(xy 117.673265 -241.080932) (xy 117.696136 -241.124509) (xy 117.71172 -241.17119) (xy 117.719615 -241.219767)
			(xy 117.72011 -241.244374) (xy 118.049052 -241.244374) (xy 118.053012 -241.19532) (xy 118.064789 -241.147536)
			(xy 118.08408 -241.10226) (xy 118.110383 -241.060664) (xy 118.143018 -241.023827) (xy 118.181139 -240.992702)
			(xy 118.22376 -240.968095) (xy 118.269776 -240.950643) (xy 118.317995 -240.940799) (xy 118.36717 -240.938818)
			(xy 118.416025 -240.94475) (xy 118.463296 -240.958442) (xy 118.507758 -240.97954) (xy 118.548261 -241.007496)
			(xy 118.583754 -241.041588) (xy 118.613319 -241.080932) (xy 118.63619 -241.124509) (xy 118.651774 -241.17119)
			(xy 118.659669 -241.219767) (xy 118.660164 -241.244374) (xy 118.988852 -241.244374) (xy 118.992812 -241.19532)
			(xy 119.004589 -241.147536) (xy 119.02388 -241.10226) (xy 119.050183 -241.060664) (xy 119.082818 -241.023827)
			(xy 119.120939 -240.992702) (xy 119.16356 -240.968095) (xy 119.209576 -240.950643) (xy 119.257795 -240.940799)
			(xy 119.30697 -240.938818) (xy 119.355825 -240.94475) (xy 119.403096 -240.958442) (xy 119.447558 -240.97954)
			(xy 119.488061 -241.007496) (xy 119.523554 -241.041588) (xy 119.553119 -241.080932) (xy 119.57599 -241.124509)
			(xy 119.591574 -241.17119) (xy 119.599469 -241.219767) (xy 119.599964 -241.244374) (xy 119.928906 -241.244374)
			(xy 119.932866 -241.19532) (xy 119.944643 -241.147536) (xy 119.963934 -241.10226) (xy 119.990237 -241.060664)
			(xy 120.022872 -241.023827) (xy 120.060993 -240.992702) (xy 120.103614 -240.968095) (xy 120.14963 -240.950643)
			(xy 120.197849 -240.940799) (xy 120.247024 -240.938818) (xy 120.295879 -240.94475) (xy 120.34315 -240.958442)
			(xy 120.387612 -240.97954) (xy 120.428115 -241.007496) (xy 120.463608 -241.041588) (xy 120.493173 -241.080932)
			(xy 120.516044 -241.124509) (xy 120.531628 -241.17119) (xy 120.539523 -241.219767) (xy 120.540018 -241.244374)
			(xy 120.86896 -241.244374) (xy 120.87292 -241.19532) (xy 120.884697 -241.147536) (xy 120.903988 -241.10226)
			(xy 120.930291 -241.060664) (xy 120.962926 -241.023827) (xy 121.001047 -240.992702) (xy 121.043668 -240.968095)
			(xy 121.089684 -240.950643) (xy 121.137903 -240.940799) (xy 121.187078 -240.938818) (xy 121.235933 -240.94475)
			(xy 121.283204 -240.958442) (xy 121.327666 -240.97954) (xy 121.368169 -241.007496) (xy 121.403662 -241.041588)
			(xy 121.433227 -241.080932) (xy 121.456098 -241.124509) (xy 121.471682 -241.17119) (xy 121.479577 -241.219767)
			(xy 121.480072 -241.244374) (xy 121.809014 -241.244374) (xy 121.812974 -241.19532) (xy 121.824751 -241.147536)
			(xy 121.844042 -241.10226) (xy 121.870345 -241.060664) (xy 121.90298 -241.023827) (xy 121.941101 -240.992702)
			(xy 121.983722 -240.968095) (xy 122.029738 -240.950643) (xy 122.077957 -240.940799) (xy 122.127132 -240.938818)
			(xy 122.175987 -240.94475) (xy 122.223258 -240.958442) (xy 122.26772 -240.97954) (xy 122.308223 -241.007496)
			(xy 122.343716 -241.041588) (xy 122.373281 -241.080932) (xy 122.396152 -241.124509) (xy 122.411736 -241.17119)
			(xy 122.419631 -241.219767) (xy 122.420126 -241.244374) (xy 122.748814 -241.244374) (xy 122.752774 -241.19532)
			(xy 122.764551 -241.147536) (xy 122.783842 -241.10226) (xy 122.810145 -241.060664) (xy 122.84278 -241.023827)
			(xy 122.880901 -240.992702) (xy 122.923522 -240.968095) (xy 122.969538 -240.950643) (xy 123.017757 -240.940799)
			(xy 123.066932 -240.938818) (xy 123.115787 -240.94475) (xy 123.163058 -240.958442) (xy 123.20752 -240.97954)
			(xy 123.248023 -241.007496) (xy 123.283516 -241.041588) (xy 123.313081 -241.080932) (xy 123.335952 -241.124509)
			(xy 123.351536 -241.17119) (xy 123.359431 -241.219767) (xy 123.359926 -241.244374) (xy 123.688868 -241.244374)
			(xy 123.692828 -241.19532) (xy 123.704605 -241.147536) (xy 123.723896 -241.10226) (xy 123.750199 -241.060664)
			(xy 123.782834 -241.023827) (xy 123.820955 -240.992702) (xy 123.863576 -240.968095) (xy 123.909592 -240.950643)
			(xy 123.957811 -240.940799) (xy 124.006986 -240.938818) (xy 124.055841 -240.94475) (xy 124.103112 -240.958442)
			(xy 124.147574 -240.97954) (xy 124.188077 -241.007496) (xy 124.22357 -241.041588) (xy 124.253135 -241.080932)
			(xy 124.276006 -241.124509) (xy 124.29159 -241.17119) (xy 124.299485 -241.219767) (xy 124.29998 -241.244374)
			(xy 124.628922 -241.244374) (xy 124.632882 -241.19532) (xy 124.644659 -241.147536) (xy 124.66395 -241.10226)
			(xy 124.690253 -241.060664) (xy 124.722888 -241.023827) (xy 124.761009 -240.992702) (xy 124.80363 -240.968095)
			(xy 124.849646 -240.950643) (xy 124.897865 -240.940799) (xy 124.94704 -240.938818) (xy 124.995895 -240.94475)
			(xy 125.043166 -240.958442) (xy 125.087628 -240.97954) (xy 125.128131 -241.007496) (xy 125.163624 -241.041588)
			(xy 125.193189 -241.080932) (xy 125.21606 -241.124509) (xy 125.231644 -241.17119) (xy 125.239539 -241.219767)
			(xy 125.240034 -241.244374) (xy 125.568976 -241.244374) (xy 125.572936 -241.19532) (xy 125.584713 -241.147536)
			(xy 125.604004 -241.10226) (xy 125.630307 -241.060664) (xy 125.662942 -241.023827) (xy 125.701063 -240.992702)
			(xy 125.743684 -240.968095) (xy 125.7897 -240.950643) (xy 125.837919 -240.940799) (xy 125.887094 -240.938818)
			(xy 125.935949 -240.94475) (xy 125.98322 -240.958442) (xy 126.027682 -240.97954) (xy 126.068185 -241.007496)
			(xy 126.103678 -241.041588) (xy 126.133243 -241.080932) (xy 126.156114 -241.124509) (xy 126.171698 -241.17119)
			(xy 126.179593 -241.219767) (xy 126.180088 -241.244374) (xy 126.179593 -241.268981) (xy 126.171698 -241.317558)
			(xy 126.156114 -241.364239) (xy 126.133243 -241.407816) (xy 126.103678 -241.44716) (xy 126.068185 -241.481252)
			(xy 126.027682 -241.509208) (xy 125.98322 -241.530306) (xy 125.935949 -241.543998) (xy 125.887094 -241.54993)
			(xy 125.837919 -241.547949) (xy 125.7897 -241.538105) (xy 125.743684 -241.520653) (xy 125.701063 -241.496046)
			(xy 125.662942 -241.464921) (xy 125.630307 -241.428084) (xy 125.604004 -241.386488) (xy 125.584713 -241.341212)
			(xy 125.572936 -241.293428) (xy 125.568976 -241.244374) (xy 125.240034 -241.244374) (xy 125.239539 -241.268981)
			(xy 125.231644 -241.317558) (xy 125.21606 -241.364239) (xy 125.193189 -241.407816) (xy 125.163624 -241.44716)
			(xy 125.128131 -241.481252) (xy 125.087628 -241.509208) (xy 125.043166 -241.530306) (xy 124.995895 -241.543998)
			(xy 124.94704 -241.54993) (xy 124.897865 -241.547949) (xy 124.849646 -241.538105) (xy 124.80363 -241.520653)
			(xy 124.761009 -241.496046) (xy 124.722888 -241.464921) (xy 124.690253 -241.428084) (xy 124.66395 -241.386488)
			(xy 124.644659 -241.341212) (xy 124.632882 -241.293428) (xy 124.628922 -241.244374) (xy 124.29998 -241.244374)
			(xy 124.299485 -241.268981) (xy 124.29159 -241.317558) (xy 124.276006 -241.364239) (xy 124.253135 -241.407816)
			(xy 124.22357 -241.44716) (xy 124.188077 -241.481252) (xy 124.147574 -241.509208) (xy 124.103112 -241.530306)
			(xy 124.055841 -241.543998) (xy 124.006986 -241.54993) (xy 123.957811 -241.547949) (xy 123.909592 -241.538105)
			(xy 123.863576 -241.520653) (xy 123.820955 -241.496046) (xy 123.782834 -241.464921) (xy 123.750199 -241.428084)
			(xy 123.723896 -241.386488) (xy 123.704605 -241.341212) (xy 123.692828 -241.293428) (xy 123.688868 -241.244374)
			(xy 123.359926 -241.244374) (xy 123.359431 -241.268981) (xy 123.351536 -241.317558) (xy 123.335952 -241.364239)
			(xy 123.313081 -241.407816) (xy 123.283516 -241.44716) (xy 123.248023 -241.481252) (xy 123.20752 -241.509208)
			(xy 123.163058 -241.530306) (xy 123.115787 -241.543998) (xy 123.066932 -241.54993) (xy 123.017757 -241.547949)
			(xy 122.969538 -241.538105) (xy 122.923522 -241.520653) (xy 122.880901 -241.496046) (xy 122.84278 -241.464921)
			(xy 122.810145 -241.428084) (xy 122.783842 -241.386488) (xy 122.764551 -241.341212) (xy 122.752774 -241.293428)
			(xy 122.748814 -241.244374) (xy 122.420126 -241.244374) (xy 122.419631 -241.268981) (xy 122.411736 -241.317558)
			(xy 122.396152 -241.364239) (xy 122.373281 -241.407816) (xy 122.343716 -241.44716) (xy 122.308223 -241.481252)
			(xy 122.26772 -241.509208) (xy 122.223258 -241.530306) (xy 122.175987 -241.543998) (xy 122.127132 -241.54993)
			(xy 122.077957 -241.547949) (xy 122.029738 -241.538105) (xy 121.983722 -241.520653) (xy 121.941101 -241.496046)
			(xy 121.90298 -241.464921) (xy 121.870345 -241.428084) (xy 121.844042 -241.386488) (xy 121.824751 -241.341212)
			(xy 121.812974 -241.293428) (xy 121.809014 -241.244374) (xy 121.480072 -241.244374) (xy 121.479577 -241.268981)
			(xy 121.471682 -241.317558) (xy 121.456098 -241.364239) (xy 121.433227 -241.407816) (xy 121.403662 -241.44716)
			(xy 121.368169 -241.481252) (xy 121.327666 -241.509208) (xy 121.283204 -241.530306) (xy 121.235933 -241.543998)
			(xy 121.187078 -241.54993) (xy 121.137903 -241.547949) (xy 121.089684 -241.538105) (xy 121.043668 -241.520653)
			(xy 121.001047 -241.496046) (xy 120.962926 -241.464921) (xy 120.930291 -241.428084) (xy 120.903988 -241.386488)
			(xy 120.884697 -241.341212) (xy 120.87292 -241.293428) (xy 120.86896 -241.244374) (xy 120.540018 -241.244374)
			(xy 120.539523 -241.268981) (xy 120.531628 -241.317558) (xy 120.516044 -241.364239) (xy 120.493173 -241.407816)
			(xy 120.463608 -241.44716) (xy 120.428115 -241.481252) (xy 120.387612 -241.509208) (xy 120.34315 -241.530306)
			(xy 120.295879 -241.543998) (xy 120.247024 -241.54993) (xy 120.197849 -241.547949) (xy 120.14963 -241.538105)
			(xy 120.103614 -241.520653) (xy 120.060993 -241.496046) (xy 120.022872 -241.464921) (xy 119.990237 -241.428084)
			(xy 119.963934 -241.386488) (xy 119.944643 -241.341212) (xy 119.932866 -241.293428) (xy 119.928906 -241.244374)
			(xy 119.599964 -241.244374) (xy 119.599469 -241.268981) (xy 119.591574 -241.317558) (xy 119.57599 -241.364239)
			(xy 119.553119 -241.407816) (xy 119.523554 -241.44716) (xy 119.488061 -241.481252) (xy 119.447558 -241.509208)
			(xy 119.403096 -241.530306) (xy 119.355825 -241.543998) (xy 119.30697 -241.54993) (xy 119.257795 -241.547949)
			(xy 119.209576 -241.538105) (xy 119.16356 -241.520653) (xy 119.120939 -241.496046) (xy 119.082818 -241.464921)
			(xy 119.050183 -241.428084) (xy 119.02388 -241.386488) (xy 119.004589 -241.341212) (xy 118.992812 -241.293428)
			(xy 118.988852 -241.244374) (xy 118.660164 -241.244374) (xy 118.659669 -241.268981) (xy 118.651774 -241.317558)
			(xy 118.63619 -241.364239) (xy 118.613319 -241.407816) (xy 118.583754 -241.44716) (xy 118.548261 -241.481252)
			(xy 118.507758 -241.509208) (xy 118.463296 -241.530306) (xy 118.416025 -241.543998) (xy 118.36717 -241.54993)
			(xy 118.317995 -241.547949) (xy 118.269776 -241.538105) (xy 118.22376 -241.520653) (xy 118.181139 -241.496046)
			(xy 118.143018 -241.464921) (xy 118.110383 -241.428084) (xy 118.08408 -241.386488) (xy 118.064789 -241.341212)
			(xy 118.053012 -241.293428) (xy 118.049052 -241.244374) (xy 117.72011 -241.244374) (xy 117.719615 -241.268981)
			(xy 117.71172 -241.317558) (xy 117.696136 -241.364239) (xy 117.673265 -241.407816) (xy 117.6437 -241.44716)
			(xy 117.608207 -241.481252) (xy 117.567704 -241.509208) (xy 117.523242 -241.530306) (xy 117.475971 -241.543998)
			(xy 117.427116 -241.54993) (xy 117.377941 -241.547949) (xy 117.329722 -241.538105) (xy 117.283706 -241.520653)
			(xy 117.241085 -241.496046) (xy 117.202964 -241.464921) (xy 117.170329 -241.428084) (xy 117.144026 -241.386488)
			(xy 117.124735 -241.341212) (xy 117.112958 -241.293428) (xy 117.108998 -241.244374) (xy 116.780056 -241.244374)
			(xy 116.779561 -241.268981) (xy 116.771666 -241.317558) (xy 116.756082 -241.364239) (xy 116.733211 -241.407816)
			(xy 116.703646 -241.44716) (xy 116.668153 -241.481252) (xy 116.62765 -241.509208) (xy 116.583188 -241.530306)
			(xy 116.535917 -241.543998) (xy 116.487062 -241.54993) (xy 116.437887 -241.547949) (xy 116.389668 -241.538105)
			(xy 116.343652 -241.520653) (xy 116.301031 -241.496046) (xy 116.26291 -241.464921) (xy 116.230275 -241.428084)
			(xy 116.203972 -241.386488) (xy 116.184681 -241.341212) (xy 116.172904 -241.293428) (xy 116.168944 -241.244374)
			(xy 115.840002 -241.244374) (xy 115.839507 -241.268981) (xy 115.831612 -241.317558) (xy 115.816028 -241.364239)
			(xy 115.793157 -241.407816) (xy 115.763592 -241.44716) (xy 115.728099 -241.481252) (xy 115.687596 -241.509208)
			(xy 115.643134 -241.530306) (xy 115.595863 -241.543998) (xy 115.547008 -241.54993) (xy 115.497833 -241.547949)
			(xy 115.449614 -241.538105) (xy 115.403598 -241.520653) (xy 115.360977 -241.496046) (xy 115.322856 -241.464921)
			(xy 115.290221 -241.428084) (xy 115.263918 -241.386488) (xy 115.244627 -241.341212) (xy 115.23285 -241.293428)
			(xy 115.22889 -241.244374) (xy 114.899948 -241.244374) (xy 114.899453 -241.268981) (xy 114.891558 -241.317558)
			(xy 114.875974 -241.364239) (xy 114.853103 -241.407816) (xy 114.823538 -241.44716) (xy 114.788045 -241.481252)
			(xy 114.747542 -241.509208) (xy 114.70308 -241.530306) (xy 114.655809 -241.543998) (xy 114.606954 -241.54993)
			(xy 114.557779 -241.547949) (xy 114.50956 -241.538105) (xy 114.463544 -241.520653) (xy 114.420923 -241.496046)
			(xy 114.382802 -241.464921) (xy 114.350167 -241.428084) (xy 114.323864 -241.386488) (xy 114.304573 -241.341212)
			(xy 114.292796 -241.293428) (xy 114.288836 -241.244374) (xy 113.960148 -241.244374) (xy 113.959653 -241.268981)
			(xy 113.951758 -241.317558) (xy 113.936174 -241.364239) (xy 113.913303 -241.407816) (xy 113.883738 -241.44716)
			(xy 113.848245 -241.481252) (xy 113.807742 -241.509208) (xy 113.76328 -241.530306) (xy 113.716009 -241.543998)
			(xy 113.667154 -241.54993) (xy 113.617979 -241.547949) (xy 113.56976 -241.538105) (xy 113.523744 -241.520653)
			(xy 113.481123 -241.496046) (xy 113.443002 -241.464921) (xy 113.410367 -241.428084) (xy 113.384064 -241.386488)
			(xy 113.364773 -241.341212) (xy 113.352996 -241.293428) (xy 113.349036 -241.244374) (xy 112.716818 -241.244374)
			(xy 111.906812 -242.05438) (xy 112.878882 -242.05438) (xy 112.882842 -242.005326) (xy 112.894619 -241.957542)
			(xy 112.91391 -241.912266) (xy 112.940213 -241.87067) (xy 112.972848 -241.833833) (xy 113.010969 -241.802708)
			(xy 113.05359 -241.778101) (xy 113.099606 -241.760649) (xy 113.147825 -241.750805) (xy 113.197 -241.748824)
			(xy 113.245855 -241.754756) (xy 113.293126 -241.768448) (xy 113.337588 -241.789546) (xy 113.378091 -241.817502)
			(xy 113.413584 -241.851594) (xy 113.443149 -241.890938) (xy 113.46602 -241.934515) (xy 113.481604 -241.981196)
			(xy 113.489499 -242.029773) (xy 113.489994 -242.05438) (xy 113.818936 -242.05438) (xy 113.822896 -242.005326)
			(xy 113.834673 -241.957542) (xy 113.853964 -241.912266) (xy 113.880267 -241.87067) (xy 113.912902 -241.833833)
			(xy 113.951023 -241.802708) (xy 113.993644 -241.778101) (xy 114.03966 -241.760649) (xy 114.087879 -241.750805)
			(xy 114.137054 -241.748824) (xy 114.185909 -241.754756) (xy 114.23318 -241.768448) (xy 114.277642 -241.789546)
			(xy 114.318145 -241.817502) (xy 114.353638 -241.851594) (xy 114.383203 -241.890938) (xy 114.406074 -241.934515)
			(xy 114.421658 -241.981196) (xy 114.429553 -242.029773) (xy 114.430048 -242.05438) (xy 114.75899 -242.05438)
			(xy 114.76295 -242.005326) (xy 114.774727 -241.957542) (xy 114.794018 -241.912266) (xy 114.820321 -241.87067)
			(xy 114.852956 -241.833833) (xy 114.891077 -241.802708) (xy 114.933698 -241.778101) (xy 114.979714 -241.760649)
			(xy 115.027933 -241.750805) (xy 115.077108 -241.748824) (xy 115.125963 -241.754756) (xy 115.173234 -241.768448)
			(xy 115.217696 -241.789546) (xy 115.258199 -241.817502) (xy 115.293692 -241.851594) (xy 115.323257 -241.890938)
			(xy 115.346128 -241.934515) (xy 115.361712 -241.981196) (xy 115.369607 -242.029773) (xy 115.370102 -242.05438)
			(xy 115.699044 -242.05438) (xy 115.703004 -242.005326) (xy 115.714781 -241.957542) (xy 115.734072 -241.912266)
			(xy 115.760375 -241.87067) (xy 115.79301 -241.833833) (xy 115.831131 -241.802708) (xy 115.873752 -241.778101)
			(xy 115.919768 -241.760649) (xy 115.967987 -241.750805) (xy 116.017162 -241.748824) (xy 116.066017 -241.754756)
			(xy 116.113288 -241.768448) (xy 116.15775 -241.789546) (xy 116.198253 -241.817502) (xy 116.233746 -241.851594)
			(xy 116.263311 -241.890938) (xy 116.286182 -241.934515) (xy 116.301766 -241.981196) (xy 116.309661 -242.029773)
			(xy 116.310156 -242.05438) (xy 118.518952 -242.05438) (xy 118.522912 -242.005326) (xy 118.534689 -241.957542)
			(xy 118.55398 -241.912266) (xy 118.580283 -241.87067) (xy 118.612918 -241.833833) (xy 118.651039 -241.802708)
			(xy 118.69366 -241.778101) (xy 118.739676 -241.760649) (xy 118.787895 -241.750805) (xy 118.83707 -241.748824)
			(xy 118.885925 -241.754756) (xy 118.933196 -241.768448) (xy 118.977658 -241.789546) (xy 119.018161 -241.817502)
			(xy 119.053654 -241.851594) (xy 119.083219 -241.890938) (xy 119.10609 -241.934515) (xy 119.121674 -241.981196)
			(xy 119.129569 -242.029773) (xy 119.130064 -242.05438) (xy 121.33886 -242.05438) (xy 121.34282 -242.005326)
			(xy 121.354597 -241.957542) (xy 121.373888 -241.912266) (xy 121.400191 -241.87067) (xy 121.432826 -241.833833)
			(xy 121.470947 -241.802708) (xy 121.513568 -241.778101) (xy 121.559584 -241.760649) (xy 121.607803 -241.750805)
			(xy 121.656978 -241.748824) (xy 121.705833 -241.754756) (xy 121.753104 -241.768448) (xy 121.797566 -241.789546)
			(xy 121.838069 -241.817502) (xy 121.873562 -241.851594) (xy 121.903127 -241.890938) (xy 121.925998 -241.934515)
			(xy 121.941582 -241.981196) (xy 121.949477 -242.029773) (xy 121.949972 -242.05438) (xy 124.159022 -242.05438)
			(xy 124.162982 -242.005326) (xy 124.174759 -241.957542) (xy 124.19405 -241.912266) (xy 124.220353 -241.87067)
			(xy 124.252988 -241.833833) (xy 124.291109 -241.802708) (xy 124.33373 -241.778101) (xy 124.379746 -241.760649)
			(xy 124.427965 -241.750805) (xy 124.47714 -241.748824) (xy 124.525995 -241.754756) (xy 124.573266 -241.768448)
			(xy 124.617728 -241.789546) (xy 124.658231 -241.817502) (xy 124.693724 -241.851594) (xy 124.723289 -241.890938)
			(xy 124.74616 -241.934515) (xy 124.761744 -241.981196) (xy 124.769639 -242.029773) (xy 124.770134 -242.05438)
			(xy 124.769639 -242.078987) (xy 124.761744 -242.127564) (xy 124.74616 -242.174245) (xy 124.723289 -242.217822)
			(xy 124.693724 -242.257166) (xy 124.658231 -242.291258) (xy 124.617728 -242.319214) (xy 124.573266 -242.340312)
			(xy 124.525995 -242.354004) (xy 124.47714 -242.359936) (xy 124.427965 -242.357955) (xy 124.379746 -242.348111)
			(xy 124.33373 -242.330659) (xy 124.291109 -242.306052) (xy 124.252988 -242.274927) (xy 124.220353 -242.23809)
			(xy 124.19405 -242.196494) (xy 124.174759 -242.151218) (xy 124.162982 -242.103434) (xy 124.159022 -242.05438)
			(xy 121.949972 -242.05438) (xy 121.949477 -242.078987) (xy 121.941582 -242.127564) (xy 121.925998 -242.174245)
			(xy 121.903127 -242.217822) (xy 121.873562 -242.257166) (xy 121.838069 -242.291258) (xy 121.797566 -242.319214)
			(xy 121.753104 -242.340312) (xy 121.705833 -242.354004) (xy 121.656978 -242.359936) (xy 121.607803 -242.357955)
			(xy 121.559584 -242.348111) (xy 121.513568 -242.330659) (xy 121.470947 -242.306052) (xy 121.432826 -242.274927)
			(xy 121.400191 -242.23809) (xy 121.373888 -242.196494) (xy 121.354597 -242.151218) (xy 121.34282 -242.103434)
			(xy 121.33886 -242.05438) (xy 119.130064 -242.05438) (xy 119.129569 -242.078987) (xy 119.121674 -242.127564)
			(xy 119.10609 -242.174245) (xy 119.083219 -242.217822) (xy 119.053654 -242.257166) (xy 119.018161 -242.291258)
			(xy 118.977658 -242.319214) (xy 118.933196 -242.340312) (xy 118.885925 -242.354004) (xy 118.83707 -242.359936)
			(xy 118.787895 -242.357955) (xy 118.739676 -242.348111) (xy 118.69366 -242.330659) (xy 118.651039 -242.306052)
			(xy 118.612918 -242.274927) (xy 118.580283 -242.23809) (xy 118.55398 -242.196494) (xy 118.534689 -242.151218)
			(xy 118.522912 -242.103434) (xy 118.518952 -242.05438) (xy 116.310156 -242.05438) (xy 116.309661 -242.078987)
			(xy 116.301766 -242.127564) (xy 116.286182 -242.174245) (xy 116.263311 -242.217822) (xy 116.233746 -242.257166)
			(xy 116.198253 -242.291258) (xy 116.15775 -242.319214) (xy 116.113288 -242.340312) (xy 116.066017 -242.354004)
			(xy 116.017162 -242.359936) (xy 115.967987 -242.357955) (xy 115.919768 -242.348111) (xy 115.873752 -242.330659)
			(xy 115.831131 -242.306052) (xy 115.79301 -242.274927) (xy 115.760375 -242.23809) (xy 115.734072 -242.196494)
			(xy 115.714781 -242.151218) (xy 115.703004 -242.103434) (xy 115.699044 -242.05438) (xy 115.370102 -242.05438)
			(xy 115.369607 -242.078987) (xy 115.361712 -242.127564) (xy 115.346128 -242.174245) (xy 115.323257 -242.217822)
			(xy 115.293692 -242.257166) (xy 115.258199 -242.291258) (xy 115.217696 -242.319214) (xy 115.173234 -242.340312)
			(xy 115.125963 -242.354004) (xy 115.077108 -242.359936) (xy 115.027933 -242.357955) (xy 114.979714 -242.348111)
			(xy 114.933698 -242.330659) (xy 114.891077 -242.306052) (xy 114.852956 -242.274927) (xy 114.820321 -242.23809)
			(xy 114.794018 -242.196494) (xy 114.774727 -242.151218) (xy 114.76295 -242.103434) (xy 114.75899 -242.05438)
			(xy 114.430048 -242.05438) (xy 114.429553 -242.078987) (xy 114.421658 -242.127564) (xy 114.406074 -242.174245)
			(xy 114.383203 -242.217822) (xy 114.353638 -242.257166) (xy 114.318145 -242.291258) (xy 114.277642 -242.319214)
			(xy 114.23318 -242.340312) (xy 114.185909 -242.354004) (xy 114.137054 -242.359936) (xy 114.087879 -242.357955)
			(xy 114.03966 -242.348111) (xy 113.993644 -242.330659) (xy 113.951023 -242.306052) (xy 113.912902 -242.274927)
			(xy 113.880267 -242.23809) (xy 113.853964 -242.196494) (xy 113.834673 -242.151218) (xy 113.822896 -242.103434)
			(xy 113.818936 -242.05438) (xy 113.489994 -242.05438) (xy 113.489499 -242.078987) (xy 113.481604 -242.127564)
			(xy 113.46602 -242.174245) (xy 113.443149 -242.217822) (xy 113.413584 -242.257166) (xy 113.378091 -242.291258)
			(xy 113.337588 -242.319214) (xy 113.293126 -242.340312) (xy 113.245855 -242.354004) (xy 113.197 -242.359936)
			(xy 113.147825 -242.357955) (xy 113.099606 -242.348111) (xy 113.05359 -242.330659) (xy 113.010969 -242.306052)
			(xy 112.972848 -242.274927) (xy 112.940213 -242.23809) (xy 112.91391 -242.196494) (xy 112.894619 -242.151218)
			(xy 112.882842 -242.103434) (xy 112.878882 -242.05438) (xy 111.906812 -242.05438) (xy 111.294418 -242.666774)
			(xy 111.287016 -242.67361) (xy 111.268418 -242.681319) (xy 111.25835 -242.68176) (xy 109.891068 -242.68176)
			(xy 109.883514 -242.682042) (xy 109.869059 -242.686436) (xy 109.86262 -242.690396) (xy 109.830752 -242.71145)
			(xy 109.763601 -242.747854) (xy 109.69317 -242.777418) (xy 109.620154 -242.799849) (xy 109.545273 -242.814927)
			(xy 109.469266 -242.822501) (xy 109.431074 -242.822984) (xy 109.133132 -242.822984) (xy 109.097944 -242.822624)
			(xy 109.027856 -242.816266) (xy 108.993178 -242.810284) (xy 108.974128 -242.806474) (xy 108.971588 -242.805966)
			(xy 108.961174 -242.80495) (xy 108.950506 -242.805966) (xy 108.947966 -242.806474) (xy 108.928916 -242.810284)
			(xy 108.894239 -242.816271) (xy 108.824151 -242.822636) (xy 108.788962 -242.822984) (xy 108.49102 -242.822984)
			(xy 108.476082 -242.822922) (xy 108.446229 -242.821777) (xy 108.43133 -242.820698) (xy 108.426505 -242.820476)
			(xy 108.416917 -242.821631) (xy 108.41228 -242.822984) (xy 108.403898 -242.825524) (xy 108.355271 -242.864386)
			(xy 115.22889 -242.864386) (xy 115.23285 -242.815332) (xy 115.244627 -242.767548) (xy 115.263918 -242.722272)
			(xy 115.290221 -242.680676) (xy 115.322856 -242.643839) (xy 115.360977 -242.612714) (xy 115.403598 -242.588107)
			(xy 115.449614 -242.570655) (xy 115.497833 -242.560811) (xy 115.547008 -242.55883) (xy 115.595863 -242.564762)
			(xy 115.643134 -242.578454) (xy 115.687596 -242.599552) (xy 115.728099 -242.627508) (xy 115.763592 -242.6616)
			(xy 115.793157 -242.700944) (xy 115.816028 -242.744521) (xy 115.831612 -242.791202) (xy 115.839507 -242.839779)
			(xy 115.840002 -242.864386) (xy 116.168944 -242.864386) (xy 116.172904 -242.815332) (xy 116.184681 -242.767548)
			(xy 116.203972 -242.722272) (xy 116.230275 -242.680676) (xy 116.26291 -242.643839) (xy 116.301031 -242.612714)
			(xy 116.343652 -242.588107) (xy 116.389668 -242.570655) (xy 116.437887 -242.560811) (xy 116.487062 -242.55883)
			(xy 116.535917 -242.564762) (xy 116.583188 -242.578454) (xy 116.62765 -242.599552) (xy 116.668153 -242.627508)
			(xy 116.703646 -242.6616) (xy 116.733211 -242.700944) (xy 116.756082 -242.744521) (xy 116.771666 -242.791202)
			(xy 116.779561 -242.839779) (xy 116.780056 -242.864386) (xy 117.108998 -242.864386) (xy 117.112958 -242.815332)
			(xy 117.124735 -242.767548) (xy 117.144026 -242.722272) (xy 117.170329 -242.680676) (xy 117.202964 -242.643839)
			(xy 117.241085 -242.612714) (xy 117.283706 -242.588107) (xy 117.329722 -242.570655) (xy 117.377941 -242.560811)
			(xy 117.427116 -242.55883) (xy 117.475971 -242.564762) (xy 117.523242 -242.578454) (xy 117.567704 -242.599552)
			(xy 117.608207 -242.627508) (xy 117.6437 -242.6616) (xy 117.673265 -242.700944) (xy 117.696136 -242.744521)
			(xy 117.71172 -242.791202) (xy 117.719615 -242.839779) (xy 117.72011 -242.864386) (xy 118.049052 -242.864386)
			(xy 118.053012 -242.815332) (xy 118.064789 -242.767548) (xy 118.08408 -242.722272) (xy 118.110383 -242.680676)
			(xy 118.143018 -242.643839) (xy 118.181139 -242.612714) (xy 118.22376 -242.588107) (xy 118.269776 -242.570655)
			(xy 118.317995 -242.560811) (xy 118.36717 -242.55883) (xy 118.416025 -242.564762) (xy 118.463296 -242.578454)
			(xy 118.507758 -242.599552) (xy 118.548261 -242.627508) (xy 118.583754 -242.6616) (xy 118.613319 -242.700944)
			(xy 118.63619 -242.744521) (xy 118.651774 -242.791202) (xy 118.659669 -242.839779) (xy 118.660164 -242.864386)
			(xy 118.988852 -242.864386) (xy 118.992812 -242.815332) (xy 119.004589 -242.767548) (xy 119.02388 -242.722272)
			(xy 119.050183 -242.680676) (xy 119.082818 -242.643839) (xy 119.120939 -242.612714) (xy 119.16356 -242.588107)
			(xy 119.209576 -242.570655) (xy 119.257795 -242.560811) (xy 119.30697 -242.55883) (xy 119.355825 -242.564762)
			(xy 119.403096 -242.578454) (xy 119.447558 -242.599552) (xy 119.488061 -242.627508) (xy 119.523554 -242.6616)
			(xy 119.553119 -242.700944) (xy 119.57599 -242.744521) (xy 119.591574 -242.791202) (xy 119.599469 -242.839779)
			(xy 119.599964 -242.864386) (xy 119.928906 -242.864386) (xy 119.932866 -242.815332) (xy 119.944643 -242.767548)
			(xy 119.963934 -242.722272) (xy 119.990237 -242.680676) (xy 120.022872 -242.643839) (xy 120.060993 -242.612714)
			(xy 120.103614 -242.588107) (xy 120.14963 -242.570655) (xy 120.197849 -242.560811) (xy 120.247024 -242.55883)
			(xy 120.295879 -242.564762) (xy 120.34315 -242.578454) (xy 120.387612 -242.599552) (xy 120.428115 -242.627508)
			(xy 120.463608 -242.6616) (xy 120.493173 -242.700944) (xy 120.516044 -242.744521) (xy 120.531628 -242.791202)
			(xy 120.539523 -242.839779) (xy 120.540018 -242.864386) (xy 120.86896 -242.864386) (xy 120.87292 -242.815332)
			(xy 120.884697 -242.767548) (xy 120.903988 -242.722272) (xy 120.930291 -242.680676) (xy 120.962926 -242.643839)
			(xy 121.001047 -242.612714) (xy 121.043668 -242.588107) (xy 121.089684 -242.570655) (xy 121.137903 -242.560811)
			(xy 121.187078 -242.55883) (xy 121.235933 -242.564762) (xy 121.283204 -242.578454) (xy 121.327666 -242.599552)
			(xy 121.368169 -242.627508) (xy 121.403662 -242.6616) (xy 121.433227 -242.700944) (xy 121.456098 -242.744521)
			(xy 121.471682 -242.791202) (xy 121.479577 -242.839779) (xy 121.480072 -242.864386) (xy 121.809014 -242.864386)
			(xy 121.812974 -242.815332) (xy 121.824751 -242.767548) (xy 121.844042 -242.722272) (xy 121.870345 -242.680676)
			(xy 121.90298 -242.643839) (xy 121.941101 -242.612714) (xy 121.983722 -242.588107) (xy 122.029738 -242.570655)
			(xy 122.077957 -242.560811) (xy 122.127132 -242.55883) (xy 122.175987 -242.564762) (xy 122.223258 -242.578454)
			(xy 122.26772 -242.599552) (xy 122.308223 -242.627508) (xy 122.343716 -242.6616) (xy 122.373281 -242.700944)
			(xy 122.396152 -242.744521) (xy 122.411736 -242.791202) (xy 122.419631 -242.839779) (xy 122.420126 -242.864386)
			(xy 122.748814 -242.864386) (xy 122.752774 -242.815332) (xy 122.764551 -242.767548) (xy 122.783842 -242.722272)
			(xy 122.810145 -242.680676) (xy 122.84278 -242.643839) (xy 122.880901 -242.612714) (xy 122.923522 -242.588107)
			(xy 122.969538 -242.570655) (xy 123.017757 -242.560811) (xy 123.066932 -242.55883) (xy 123.115787 -242.564762)
			(xy 123.163058 -242.578454) (xy 123.20752 -242.599552) (xy 123.248023 -242.627508) (xy 123.283516 -242.6616)
			(xy 123.313081 -242.700944) (xy 123.335952 -242.744521) (xy 123.351536 -242.791202) (xy 123.359431 -242.839779)
			(xy 123.359926 -242.864386) (xy 123.688868 -242.864386) (xy 123.692828 -242.815332) (xy 123.704605 -242.767548)
			(xy 123.723896 -242.722272) (xy 123.750199 -242.680676) (xy 123.782834 -242.643839) (xy 123.820955 -242.612714)
			(xy 123.863576 -242.588107) (xy 123.909592 -242.570655) (xy 123.957811 -242.560811) (xy 124.006986 -242.55883)
			(xy 124.055841 -242.564762) (xy 124.103112 -242.578454) (xy 124.147574 -242.599552) (xy 124.188077 -242.627508)
			(xy 124.22357 -242.6616) (xy 124.253135 -242.700944) (xy 124.276006 -242.744521) (xy 124.29159 -242.791202)
			(xy 124.299485 -242.839779) (xy 124.29998 -242.864386) (xy 124.628922 -242.864386) (xy 124.632882 -242.815332)
			(xy 124.644659 -242.767548) (xy 124.66395 -242.722272) (xy 124.690253 -242.680676) (xy 124.722888 -242.643839)
			(xy 124.761009 -242.612714) (xy 124.80363 -242.588107) (xy 124.849646 -242.570655) (xy 124.897865 -242.560811)
			(xy 124.94704 -242.55883) (xy 124.995895 -242.564762) (xy 125.043166 -242.578454) (xy 125.087628 -242.599552)
			(xy 125.128131 -242.627508) (xy 125.163624 -242.6616) (xy 125.193189 -242.700944) (xy 125.21606 -242.744521)
			(xy 125.231644 -242.791202) (xy 125.239539 -242.839779) (xy 125.240034 -242.864386) (xy 125.568976 -242.864386)
			(xy 125.572936 -242.815332) (xy 125.584713 -242.767548) (xy 125.604004 -242.722272) (xy 125.630307 -242.680676)
			(xy 125.662942 -242.643839) (xy 125.701063 -242.612714) (xy 125.743684 -242.588107) (xy 125.7897 -242.570655)
			(xy 125.837919 -242.560811) (xy 125.887094 -242.55883) (xy 125.935949 -242.564762) (xy 125.98322 -242.578454)
			(xy 126.027682 -242.599552) (xy 126.068185 -242.627508) (xy 126.103678 -242.6616) (xy 126.133243 -242.700944)
			(xy 126.156114 -242.744521) (xy 126.171698 -242.791202) (xy 126.179593 -242.839779) (xy 126.180088 -242.864386)
			(xy 126.179593 -242.888993) (xy 126.171698 -242.93757) (xy 126.156114 -242.984251) (xy 126.133243 -243.027828)
			(xy 126.103678 -243.067172) (xy 126.068185 -243.101264) (xy 126.027682 -243.12922) (xy 125.98322 -243.150318)
			(xy 125.935949 -243.16401) (xy 125.887094 -243.169942) (xy 125.837919 -243.167961) (xy 125.7897 -243.158117)
			(xy 125.743684 -243.140665) (xy 125.701063 -243.116058) (xy 125.662942 -243.084933) (xy 125.630307 -243.048096)
			(xy 125.604004 -243.0065) (xy 125.584713 -242.961224) (xy 125.572936 -242.91344) (xy 125.568976 -242.864386)
			(xy 125.240034 -242.864386) (xy 125.239539 -242.888993) (xy 125.231644 -242.93757) (xy 125.21606 -242.984251)
			(xy 125.193189 -243.027828) (xy 125.163624 -243.067172) (xy 125.128131 -243.101264) (xy 125.087628 -243.12922)
			(xy 125.043166 -243.150318) (xy 124.995895 -243.16401) (xy 124.94704 -243.169942) (xy 124.897865 -243.167961)
			(xy 124.849646 -243.158117) (xy 124.80363 -243.140665) (xy 124.761009 -243.116058) (xy 124.722888 -243.084933)
			(xy 124.690253 -243.048096) (xy 124.66395 -243.0065) (xy 124.644659 -242.961224) (xy 124.632882 -242.91344)
			(xy 124.628922 -242.864386) (xy 124.29998 -242.864386) (xy 124.299485 -242.888993) (xy 124.29159 -242.93757)
			(xy 124.276006 -242.984251) (xy 124.253135 -243.027828) (xy 124.22357 -243.067172) (xy 124.188077 -243.101264)
			(xy 124.147574 -243.12922) (xy 124.103112 -243.150318) (xy 124.055841 -243.16401) (xy 124.006986 -243.169942)
			(xy 123.957811 -243.167961) (xy 123.909592 -243.158117) (xy 123.863576 -243.140665) (xy 123.820955 -243.116058)
			(xy 123.782834 -243.084933) (xy 123.750199 -243.048096) (xy 123.723896 -243.0065) (xy 123.704605 -242.961224)
			(xy 123.692828 -242.91344) (xy 123.688868 -242.864386) (xy 123.359926 -242.864386) (xy 123.359431 -242.888993)
			(xy 123.351536 -242.93757) (xy 123.335952 -242.984251) (xy 123.313081 -243.027828) (xy 123.283516 -243.067172)
			(xy 123.248023 -243.101264) (xy 123.20752 -243.12922) (xy 123.163058 -243.150318) (xy 123.115787 -243.16401)
			(xy 123.066932 -243.169942) (xy 123.017757 -243.167961) (xy 122.969538 -243.158117) (xy 122.923522 -243.140665)
			(xy 122.880901 -243.116058) (xy 122.84278 -243.084933) (xy 122.810145 -243.048096) (xy 122.783842 -243.0065)
			(xy 122.764551 -242.961224) (xy 122.752774 -242.91344) (xy 122.748814 -242.864386) (xy 122.420126 -242.864386)
			(xy 122.419631 -242.888993) (xy 122.411736 -242.93757) (xy 122.396152 -242.984251) (xy 122.373281 -243.027828)
			(xy 122.343716 -243.067172) (xy 122.308223 -243.101264) (xy 122.26772 -243.12922) (xy 122.223258 -243.150318)
			(xy 122.175987 -243.16401) (xy 122.127132 -243.169942) (xy 122.077957 -243.167961) (xy 122.029738 -243.158117)
			(xy 121.983722 -243.140665) (xy 121.941101 -243.116058) (xy 121.90298 -243.084933) (xy 121.870345 -243.048096)
			(xy 121.844042 -243.0065) (xy 121.824751 -242.961224) (xy 121.812974 -242.91344) (xy 121.809014 -242.864386)
			(xy 121.480072 -242.864386) (xy 121.479577 -242.888993) (xy 121.471682 -242.93757) (xy 121.456098 -242.984251)
			(xy 121.433227 -243.027828) (xy 121.403662 -243.067172) (xy 121.368169 -243.101264) (xy 121.327666 -243.12922)
			(xy 121.283204 -243.150318) (xy 121.235933 -243.16401) (xy 121.187078 -243.169942) (xy 121.137903 -243.167961)
			(xy 121.089684 -243.158117) (xy 121.043668 -243.140665) (xy 121.001047 -243.116058) (xy 120.962926 -243.084933)
			(xy 120.930291 -243.048096) (xy 120.903988 -243.0065) (xy 120.884697 -242.961224) (xy 120.87292 -242.91344)
			(xy 120.86896 -242.864386) (xy 120.540018 -242.864386) (xy 120.539523 -242.888993) (xy 120.531628 -242.93757)
			(xy 120.516044 -242.984251) (xy 120.493173 -243.027828) (xy 120.463608 -243.067172) (xy 120.428115 -243.101264)
			(xy 120.387612 -243.12922) (xy 120.34315 -243.150318) (xy 120.295879 -243.16401) (xy 120.247024 -243.169942)
			(xy 120.197849 -243.167961) (xy 120.14963 -243.158117) (xy 120.103614 -243.140665) (xy 120.060993 -243.116058)
			(xy 120.022872 -243.084933) (xy 119.990237 -243.048096) (xy 119.963934 -243.0065) (xy 119.944643 -242.961224)
			(xy 119.932866 -242.91344) (xy 119.928906 -242.864386) (xy 119.599964 -242.864386) (xy 119.599469 -242.888993)
			(xy 119.591574 -242.93757) (xy 119.57599 -242.984251) (xy 119.553119 -243.027828) (xy 119.523554 -243.067172)
			(xy 119.488061 -243.101264) (xy 119.447558 -243.12922) (xy 119.403096 -243.150318) (xy 119.355825 -243.16401)
			(xy 119.30697 -243.169942) (xy 119.257795 -243.167961) (xy 119.209576 -243.158117) (xy 119.16356 -243.140665)
			(xy 119.120939 -243.116058) (xy 119.082818 -243.084933) (xy 119.050183 -243.048096) (xy 119.02388 -243.0065)
			(xy 119.004589 -242.961224) (xy 118.992812 -242.91344) (xy 118.988852 -242.864386) (xy 118.660164 -242.864386)
			(xy 118.659669 -242.888993) (xy 118.651774 -242.93757) (xy 118.63619 -242.984251) (xy 118.613319 -243.027828)
			(xy 118.583754 -243.067172) (xy 118.548261 -243.101264) (xy 118.507758 -243.12922) (xy 118.463296 -243.150318)
			(xy 118.416025 -243.16401) (xy 118.36717 -243.169942) (xy 118.317995 -243.167961) (xy 118.269776 -243.158117)
			(xy 118.22376 -243.140665) (xy 118.181139 -243.116058) (xy 118.143018 -243.084933) (xy 118.110383 -243.048096)
			(xy 118.08408 -243.0065) (xy 118.064789 -242.961224) (xy 118.053012 -242.91344) (xy 118.049052 -242.864386)
			(xy 117.72011 -242.864386) (xy 117.719615 -242.888993) (xy 117.71172 -242.93757) (xy 117.696136 -242.984251)
			(xy 117.673265 -243.027828) (xy 117.6437 -243.067172) (xy 117.608207 -243.101264) (xy 117.567704 -243.12922)
			(xy 117.523242 -243.150318) (xy 117.475971 -243.16401) (xy 117.427116 -243.169942) (xy 117.377941 -243.167961)
			(xy 117.329722 -243.158117) (xy 117.283706 -243.140665) (xy 117.241085 -243.116058) (xy 117.202964 -243.084933)
			(xy 117.170329 -243.048096) (xy 117.144026 -243.0065) (xy 117.124735 -242.961224) (xy 117.112958 -242.91344)
			(xy 117.108998 -242.864386) (xy 116.780056 -242.864386) (xy 116.779561 -242.888993) (xy 116.771666 -242.93757)
			(xy 116.756082 -242.984251) (xy 116.733211 -243.027828) (xy 116.703646 -243.067172) (xy 116.668153 -243.101264)
			(xy 116.62765 -243.12922) (xy 116.583188 -243.150318) (xy 116.535917 -243.16401) (xy 116.487062 -243.169942)
			(xy 116.437887 -243.167961) (xy 116.389668 -243.158117) (xy 116.343652 -243.140665) (xy 116.301031 -243.116058)
			(xy 116.26291 -243.084933) (xy 116.230275 -243.048096) (xy 116.203972 -243.0065) (xy 116.184681 -242.961224)
			(xy 116.172904 -242.91344) (xy 116.168944 -242.864386) (xy 115.840002 -242.864386) (xy 115.839507 -242.888993)
			(xy 115.831612 -242.93757) (xy 115.816028 -242.984251) (xy 115.793157 -243.027828) (xy 115.763592 -243.067172)
			(xy 115.728099 -243.101264) (xy 115.687596 -243.12922) (xy 115.643134 -243.150318) (xy 115.595863 -243.16401)
			(xy 115.547008 -243.169942) (xy 115.497833 -243.167961) (xy 115.449614 -243.158117) (xy 115.403598 -243.140665)
			(xy 115.360977 -243.116058) (xy 115.322856 -243.084933) (xy 115.290221 -243.048096) (xy 115.263918 -243.0065)
			(xy 115.244627 -242.961224) (xy 115.23285 -242.91344) (xy 115.22889 -242.864386) (xy 108.355271 -242.864386)
			(xy 108.341922 -242.875054) (xy 108.334547 -242.881527) (xy 108.325 -242.89865) (xy 108.32338 -242.908328)
			(xy 108.31949 -242.932022) (xy 108.305242 -242.977872) (xy 108.283992 -243.020927) (xy 108.256263 -243.060124)
			(xy 108.22274 -243.094497) (xy 108.184249 -243.123197) (xy 108.141739 -243.145518) (xy 108.096259 -243.160908)
			(xy 108.04893 -243.168988) (xy 108.02493 -243.169694) (xy 108.018326 -243.169694) (xy 107.989523 -243.168786)
			(xy 107.933013 -243.157533) (xy 107.906058 -243.147342) (xy 107.891834 -243.1415) (xy 107.861862 -243.147596)
			(xy 107.724702 -243.284756) (xy 107.721908 -243.289074) (xy 107.717336 -243.295932) (xy 107.717082 -243.296186)
			(xy 107.716574 -243.296694) (xy 107.711624 -243.304866) (xy 107.707589 -243.323526) (xy 107.7087 -243.333016)
			(xy 107.719622 -243.401342) (xy 107.721512 -243.410796) (xy 107.731303 -243.427385) (xy 107.738672 -243.4336)
			(xy 107.756654 -243.448156) (xy 107.788435 -243.481775) (xy 107.81478 -243.519804) (xy 107.835085 -243.561372)
			(xy 107.848887 -243.605528) (xy 107.855868 -243.651261) (xy 107.856274 -243.674392) (xy 107.856274 -243.6744)
			(xy 108.185132 -243.6744) (xy 108.189304 -243.624054) (xy 108.201706 -243.575081) (xy 108.222 -243.528817)
			(xy 108.249632 -243.486525) (xy 108.283849 -243.449358) (xy 108.323717 -243.418331) (xy 108.368148 -243.394288)
			(xy 108.41593 -243.377887) (xy 108.465761 -243.369575) (xy 108.49102 -243.369084) (xy 109.431074 -243.369084)
			(xy 109.456332 -243.369591) (xy 109.506161 -243.377902) (xy 109.553942 -243.394301) (xy 109.598371 -243.418342)
			(xy 109.638238 -243.449368) (xy 109.672453 -243.486533) (xy 109.700085 -243.528823) (xy 109.720378 -243.575085)
			(xy 109.73278 -243.624056) (xy 109.736951 -243.674392) (xy 110.065324 -243.674392) (xy 110.069284 -243.625338)
			(xy 110.081061 -243.577554) (xy 110.100352 -243.532278) (xy 110.126655 -243.490682) (xy 110.15929 -243.453845)
			(xy 110.197411 -243.42272) (xy 110.240032 -243.398113) (xy 110.286048 -243.380661) (xy 110.334267 -243.370817)
			(xy 110.383442 -243.368836) (xy 110.432297 -243.374768) (xy 110.479568 -243.38846) (xy 110.52403 -243.409558)
			(xy 110.564533 -243.437514) (xy 110.600026 -243.471606) (xy 110.629591 -243.51095) (xy 110.652462 -243.554527)
			(xy 110.668046 -243.601208) (xy 110.675941 -243.649785) (xy 110.676436 -243.674392) (xy 112.878882 -243.674392)
			(xy 112.882842 -243.625338) (xy 112.894619 -243.577554) (xy 112.91391 -243.532278) (xy 112.940213 -243.490682)
			(xy 112.972848 -243.453845) (xy 113.010969 -243.42272) (xy 113.05359 -243.398113) (xy 113.099606 -243.380661)
			(xy 113.147825 -243.370817) (xy 113.197 -243.368836) (xy 113.245855 -243.374768) (xy 113.293126 -243.38846)
			(xy 113.337588 -243.409558) (xy 113.378091 -243.437514) (xy 113.413584 -243.471606) (xy 113.443149 -243.51095)
			(xy 113.46602 -243.554527) (xy 113.481604 -243.601208) (xy 113.489499 -243.649785) (xy 113.489994 -243.674392)
			(xy 113.818936 -243.674392) (xy 113.822896 -243.625338) (xy 113.834673 -243.577554) (xy 113.853964 -243.532278)
			(xy 113.880267 -243.490682) (xy 113.912902 -243.453845) (xy 113.951023 -243.42272) (xy 113.993644 -243.398113)
			(xy 114.03966 -243.380661) (xy 114.087879 -243.370817) (xy 114.137054 -243.368836) (xy 114.185909 -243.374768)
			(xy 114.23318 -243.38846) (xy 114.277642 -243.409558) (xy 114.318145 -243.437514) (xy 114.353638 -243.471606)
			(xy 114.383203 -243.51095) (xy 114.406074 -243.554527) (xy 114.421658 -243.601208) (xy 114.429553 -243.649785)
			(xy 114.430048 -243.674392) (xy 114.75899 -243.674392) (xy 114.76295 -243.625338) (xy 114.774727 -243.577554)
			(xy 114.794018 -243.532278) (xy 114.820321 -243.490682) (xy 114.852956 -243.453845) (xy 114.891077 -243.42272)
			(xy 114.933698 -243.398113) (xy 114.979714 -243.380661) (xy 115.027933 -243.370817) (xy 115.077108 -243.368836)
			(xy 115.125963 -243.374768) (xy 115.173234 -243.38846) (xy 115.217696 -243.409558) (xy 115.258199 -243.437514)
			(xy 115.293692 -243.471606) (xy 115.323257 -243.51095) (xy 115.346128 -243.554527) (xy 115.361712 -243.601208)
			(xy 115.369607 -243.649785) (xy 115.370102 -243.674392) (xy 115.699044 -243.674392) (xy 115.703004 -243.625338)
			(xy 115.714781 -243.577554) (xy 115.734072 -243.532278) (xy 115.760375 -243.490682) (xy 115.79301 -243.453845)
			(xy 115.831131 -243.42272) (xy 115.873752 -243.398113) (xy 115.919768 -243.380661) (xy 115.967987 -243.370817)
			(xy 116.017162 -243.368836) (xy 116.066017 -243.374768) (xy 116.113288 -243.38846) (xy 116.15775 -243.409558)
			(xy 116.198253 -243.437514) (xy 116.233746 -243.471606) (xy 116.263311 -243.51095) (xy 116.286182 -243.554527)
			(xy 116.301766 -243.601208) (xy 116.309661 -243.649785) (xy 116.310156 -243.674392) (xy 116.638844 -243.674392)
			(xy 116.642804 -243.625338) (xy 116.654581 -243.577554) (xy 116.673872 -243.532278) (xy 116.700175 -243.490682)
			(xy 116.73281 -243.453845) (xy 116.770931 -243.42272) (xy 116.813552 -243.398113) (xy 116.859568 -243.380661)
			(xy 116.907787 -243.370817) (xy 116.956962 -243.368836) (xy 117.005817 -243.374768) (xy 117.053088 -243.38846)
			(xy 117.09755 -243.409558) (xy 117.138053 -243.437514) (xy 117.173546 -243.471606) (xy 117.203111 -243.51095)
			(xy 117.225982 -243.554527) (xy 117.241566 -243.601208) (xy 117.249461 -243.649785) (xy 117.249956 -243.674392)
			(xy 117.578898 -243.674392) (xy 117.582858 -243.625338) (xy 117.594635 -243.577554) (xy 117.613926 -243.532278)
			(xy 117.640229 -243.490682) (xy 117.672864 -243.453845) (xy 117.710985 -243.42272) (xy 117.753606 -243.398113)
			(xy 117.799622 -243.380661) (xy 117.847841 -243.370817) (xy 117.897016 -243.368836) (xy 117.945871 -243.374768)
			(xy 117.993142 -243.38846) (xy 118.037604 -243.409558) (xy 118.078107 -243.437514) (xy 118.1136 -243.471606)
			(xy 118.143165 -243.51095) (xy 118.166036 -243.554527) (xy 118.18162 -243.601208) (xy 118.189515 -243.649785)
			(xy 118.19001 -243.674392) (xy 118.518952 -243.674392) (xy 118.522912 -243.625338) (xy 118.534689 -243.577554)
			(xy 118.55398 -243.532278) (xy 118.580283 -243.490682) (xy 118.612918 -243.453845) (xy 118.651039 -243.42272)
			(xy 118.69366 -243.398113) (xy 118.739676 -243.380661) (xy 118.787895 -243.370817) (xy 118.83707 -243.368836)
			(xy 118.885925 -243.374768) (xy 118.933196 -243.38846) (xy 118.977658 -243.409558) (xy 119.018161 -243.437514)
			(xy 119.053654 -243.471606) (xy 119.083219 -243.51095) (xy 119.10609 -243.554527) (xy 119.121674 -243.601208)
			(xy 119.129569 -243.649785) (xy 119.130064 -243.674392) (xy 119.459006 -243.674392) (xy 119.462966 -243.625338)
			(xy 119.474743 -243.577554) (xy 119.494034 -243.532278) (xy 119.520337 -243.490682) (xy 119.552972 -243.453845)
			(xy 119.591093 -243.42272) (xy 119.633714 -243.398113) (xy 119.67973 -243.380661) (xy 119.727949 -243.370817)
			(xy 119.777124 -243.368836) (xy 119.825979 -243.374768) (xy 119.87325 -243.38846) (xy 119.917712 -243.409558)
			(xy 119.958215 -243.437514) (xy 119.993708 -243.471606) (xy 120.023273 -243.51095) (xy 120.046144 -243.554527)
			(xy 120.061728 -243.601208) (xy 120.069623 -243.649785) (xy 120.070118 -243.674392) (xy 120.398806 -243.674392)
			(xy 120.402766 -243.625338) (xy 120.414543 -243.577554) (xy 120.433834 -243.532278) (xy 120.460137 -243.490682)
			(xy 120.492772 -243.453845) (xy 120.530893 -243.42272) (xy 120.573514 -243.398113) (xy 120.61953 -243.380661)
			(xy 120.667749 -243.370817) (xy 120.716924 -243.368836) (xy 120.765779 -243.374768) (xy 120.81305 -243.38846)
			(xy 120.857512 -243.409558) (xy 120.898015 -243.437514) (xy 120.933508 -243.471606) (xy 120.963073 -243.51095)
			(xy 120.985944 -243.554527) (xy 121.001528 -243.601208) (xy 121.009423 -243.649785) (xy 121.009918 -243.674392)
			(xy 121.33886 -243.674392) (xy 121.34282 -243.625338) (xy 121.354597 -243.577554) (xy 121.373888 -243.532278)
			(xy 121.400191 -243.490682) (xy 121.432826 -243.453845) (xy 121.470947 -243.42272) (xy 121.513568 -243.398113)
			(xy 121.559584 -243.380661) (xy 121.607803 -243.370817) (xy 121.656978 -243.368836) (xy 121.705833 -243.374768)
			(xy 121.753104 -243.38846) (xy 121.797566 -243.409558) (xy 121.838069 -243.437514) (xy 121.873562 -243.471606)
			(xy 121.903127 -243.51095) (xy 121.925998 -243.554527) (xy 121.941582 -243.601208) (xy 121.949477 -243.649785)
			(xy 121.949972 -243.674392) (xy 122.278914 -243.674392) (xy 122.282874 -243.625338) (xy 122.294651 -243.577554)
			(xy 122.313942 -243.532278) (xy 122.340245 -243.490682) (xy 122.37288 -243.453845) (xy 122.411001 -243.42272)
			(xy 122.453622 -243.398113) (xy 122.499638 -243.380661) (xy 122.547857 -243.370817) (xy 122.597032 -243.368836)
			(xy 122.645887 -243.374768) (xy 122.693158 -243.38846) (xy 122.73762 -243.409558) (xy 122.778123 -243.437514)
			(xy 122.813616 -243.471606) (xy 122.843181 -243.51095) (xy 122.866052 -243.554527) (xy 122.881636 -243.601208)
			(xy 122.889531 -243.649785) (xy 122.890026 -243.674392) (xy 123.218968 -243.674392) (xy 123.222928 -243.625338)
			(xy 123.234705 -243.577554) (xy 123.253996 -243.532278) (xy 123.280299 -243.490682) (xy 123.312934 -243.453845)
			(xy 123.351055 -243.42272) (xy 123.393676 -243.398113) (xy 123.439692 -243.380661) (xy 123.487911 -243.370817)
			(xy 123.537086 -243.368836) (xy 123.585941 -243.374768) (xy 123.633212 -243.38846) (xy 123.677674 -243.409558)
			(xy 123.718177 -243.437514) (xy 123.75367 -243.471606) (xy 123.783235 -243.51095) (xy 123.806106 -243.554527)
			(xy 123.82169 -243.601208) (xy 123.829585 -243.649785) (xy 123.83008 -243.674392) (xy 124.159022 -243.674392)
			(xy 124.162982 -243.625338) (xy 124.174759 -243.577554) (xy 124.19405 -243.532278) (xy 124.220353 -243.490682)
			(xy 124.252988 -243.453845) (xy 124.291109 -243.42272) (xy 124.33373 -243.398113) (xy 124.379746 -243.380661)
			(xy 124.427965 -243.370817) (xy 124.47714 -243.368836) (xy 124.525995 -243.374768) (xy 124.573266 -243.38846)
			(xy 124.617728 -243.409558) (xy 124.658231 -243.437514) (xy 124.693724 -243.471606) (xy 124.723289 -243.51095)
			(xy 124.74616 -243.554527) (xy 124.761744 -243.601208) (xy 124.769639 -243.649785) (xy 124.770134 -243.674392)
			(xy 125.098822 -243.674392) (xy 125.102782 -243.625338) (xy 125.114559 -243.577554) (xy 125.13385 -243.532278)
			(xy 125.160153 -243.490682) (xy 125.192788 -243.453845) (xy 125.230909 -243.42272) (xy 125.27353 -243.398113)
			(xy 125.319546 -243.380661) (xy 125.367765 -243.370817) (xy 125.41694 -243.368836) (xy 125.465795 -243.374768)
			(xy 125.513066 -243.38846) (xy 125.557528 -243.409558) (xy 125.598031 -243.437514) (xy 125.633524 -243.471606)
			(xy 125.663089 -243.51095) (xy 125.68596 -243.554527) (xy 125.701544 -243.601208) (xy 125.709439 -243.649785)
			(xy 125.709934 -243.674392) (xy 125.709439 -243.698999) (xy 125.701544 -243.747576) (xy 125.68596 -243.794257)
			(xy 125.663089 -243.837834) (xy 125.633524 -243.877178) (xy 125.598031 -243.91127) (xy 125.557528 -243.939226)
			(xy 125.513066 -243.960324) (xy 125.465795 -243.974016) (xy 125.41694 -243.979948) (xy 125.367765 -243.977967)
			(xy 125.319546 -243.968123) (xy 125.27353 -243.950671) (xy 125.230909 -243.926064) (xy 125.192788 -243.894939)
			(xy 125.160153 -243.858102) (xy 125.13385 -243.816506) (xy 125.114559 -243.77123) (xy 125.102782 -243.723446)
			(xy 125.098822 -243.674392) (xy 124.770134 -243.674392) (xy 124.769639 -243.698999) (xy 124.761744 -243.747576)
			(xy 124.74616 -243.794257) (xy 124.723289 -243.837834) (xy 124.693724 -243.877178) (xy 124.658231 -243.91127)
			(xy 124.617728 -243.939226) (xy 124.573266 -243.960324) (xy 124.525995 -243.974016) (xy 124.47714 -243.979948)
			(xy 124.427965 -243.977967) (xy 124.379746 -243.968123) (xy 124.33373 -243.950671) (xy 124.291109 -243.926064)
			(xy 124.252988 -243.894939) (xy 124.220353 -243.858102) (xy 124.19405 -243.816506) (xy 124.174759 -243.77123)
			(xy 124.162982 -243.723446) (xy 124.159022 -243.674392) (xy 123.83008 -243.674392) (xy 123.829585 -243.698999)
			(xy 123.82169 -243.747576) (xy 123.806106 -243.794257) (xy 123.783235 -243.837834) (xy 123.75367 -243.877178)
			(xy 123.718177 -243.91127) (xy 123.677674 -243.939226) (xy 123.633212 -243.960324) (xy 123.585941 -243.974016)
			(xy 123.537086 -243.979948) (xy 123.487911 -243.977967) (xy 123.439692 -243.968123) (xy 123.393676 -243.950671)
			(xy 123.351055 -243.926064) (xy 123.312934 -243.894939) (xy 123.280299 -243.858102) (xy 123.253996 -243.816506)
			(xy 123.234705 -243.77123) (xy 123.222928 -243.723446) (xy 123.218968 -243.674392) (xy 122.890026 -243.674392)
			(xy 122.889531 -243.698999) (xy 122.881636 -243.747576) (xy 122.866052 -243.794257) (xy 122.843181 -243.837834)
			(xy 122.813616 -243.877178) (xy 122.778123 -243.91127) (xy 122.73762 -243.939226) (xy 122.693158 -243.960324)
			(xy 122.645887 -243.974016) (xy 122.597032 -243.979948) (xy 122.547857 -243.977967) (xy 122.499638 -243.968123)
			(xy 122.453622 -243.950671) (xy 122.411001 -243.926064) (xy 122.37288 -243.894939) (xy 122.340245 -243.858102)
			(xy 122.313942 -243.816506) (xy 122.294651 -243.77123) (xy 122.282874 -243.723446) (xy 122.278914 -243.674392)
			(xy 121.949972 -243.674392) (xy 121.949477 -243.698999) (xy 121.941582 -243.747576) (xy 121.925998 -243.794257)
			(xy 121.903127 -243.837834) (xy 121.873562 -243.877178) (xy 121.838069 -243.91127) (xy 121.797566 -243.939226)
			(xy 121.753104 -243.960324) (xy 121.705833 -243.974016) (xy 121.656978 -243.979948) (xy 121.607803 -243.977967)
			(xy 121.559584 -243.968123) (xy 121.513568 -243.950671) (xy 121.470947 -243.926064) (xy 121.432826 -243.894939)
			(xy 121.400191 -243.858102) (xy 121.373888 -243.816506) (xy 121.354597 -243.77123) (xy 121.34282 -243.723446)
			(xy 121.33886 -243.674392) (xy 121.009918 -243.674392) (xy 121.009423 -243.698999) (xy 121.001528 -243.747576)
			(xy 120.985944 -243.794257) (xy 120.963073 -243.837834) (xy 120.933508 -243.877178) (xy 120.898015 -243.91127)
			(xy 120.857512 -243.939226) (xy 120.81305 -243.960324) (xy 120.765779 -243.974016) (xy 120.716924 -243.979948)
			(xy 120.667749 -243.977967) (xy 120.61953 -243.968123) (xy 120.573514 -243.950671) (xy 120.530893 -243.926064)
			(xy 120.492772 -243.894939) (xy 120.460137 -243.858102) (xy 120.433834 -243.816506) (xy 120.414543 -243.77123)
			(xy 120.402766 -243.723446) (xy 120.398806 -243.674392) (xy 120.070118 -243.674392) (xy 120.069623 -243.698999)
			(xy 120.061728 -243.747576) (xy 120.046144 -243.794257) (xy 120.023273 -243.837834) (xy 119.993708 -243.877178)
			(xy 119.958215 -243.91127) (xy 119.917712 -243.939226) (xy 119.87325 -243.960324) (xy 119.825979 -243.974016)
			(xy 119.777124 -243.979948) (xy 119.727949 -243.977967) (xy 119.67973 -243.968123) (xy 119.633714 -243.950671)
			(xy 119.591093 -243.926064) (xy 119.552972 -243.894939) (xy 119.520337 -243.858102) (xy 119.494034 -243.816506)
			(xy 119.474743 -243.77123) (xy 119.462966 -243.723446) (xy 119.459006 -243.674392) (xy 119.130064 -243.674392)
			(xy 119.129569 -243.698999) (xy 119.121674 -243.747576) (xy 119.10609 -243.794257) (xy 119.083219 -243.837834)
			(xy 119.053654 -243.877178) (xy 119.018161 -243.91127) (xy 118.977658 -243.939226) (xy 118.933196 -243.960324)
			(xy 118.885925 -243.974016) (xy 118.83707 -243.979948) (xy 118.787895 -243.977967) (xy 118.739676 -243.968123)
			(xy 118.69366 -243.950671) (xy 118.651039 -243.926064) (xy 118.612918 -243.894939) (xy 118.580283 -243.858102)
			(xy 118.55398 -243.816506) (xy 118.534689 -243.77123) (xy 118.522912 -243.723446) (xy 118.518952 -243.674392)
			(xy 118.19001 -243.674392) (xy 118.189515 -243.698999) (xy 118.18162 -243.747576) (xy 118.166036 -243.794257)
			(xy 118.143165 -243.837834) (xy 118.1136 -243.877178) (xy 118.078107 -243.91127) (xy 118.037604 -243.939226)
			(xy 117.993142 -243.960324) (xy 117.945871 -243.974016) (xy 117.897016 -243.979948) (xy 117.847841 -243.977967)
			(xy 117.799622 -243.968123) (xy 117.753606 -243.950671) (xy 117.710985 -243.926064) (xy 117.672864 -243.894939)
			(xy 117.640229 -243.858102) (xy 117.613926 -243.816506) (xy 117.594635 -243.77123) (xy 117.582858 -243.723446)
			(xy 117.578898 -243.674392) (xy 117.249956 -243.674392) (xy 117.249461 -243.698999) (xy 117.241566 -243.747576)
			(xy 117.225982 -243.794257) (xy 117.203111 -243.837834) (xy 117.173546 -243.877178) (xy 117.138053 -243.91127)
			(xy 117.09755 -243.939226) (xy 117.053088 -243.960324) (xy 117.005817 -243.974016) (xy 116.956962 -243.979948)
			(xy 116.907787 -243.977967) (xy 116.859568 -243.968123) (xy 116.813552 -243.950671) (xy 116.770931 -243.926064)
			(xy 116.73281 -243.894939) (xy 116.700175 -243.858102) (xy 116.673872 -243.816506) (xy 116.654581 -243.77123)
			(xy 116.642804 -243.723446) (xy 116.638844 -243.674392) (xy 116.310156 -243.674392) (xy 116.309661 -243.698999)
			(xy 116.301766 -243.747576) (xy 116.286182 -243.794257) (xy 116.263311 -243.837834) (xy 116.233746 -243.877178)
			(xy 116.198253 -243.91127) (xy 116.15775 -243.939226) (xy 116.113288 -243.960324) (xy 116.066017 -243.974016)
			(xy 116.017162 -243.979948) (xy 115.967987 -243.977967) (xy 115.919768 -243.968123) (xy 115.873752 -243.950671)
			(xy 115.831131 -243.926064) (xy 115.79301 -243.894939) (xy 115.760375 -243.858102) (xy 115.734072 -243.816506)
			(xy 115.714781 -243.77123) (xy 115.703004 -243.723446) (xy 115.699044 -243.674392) (xy 115.370102 -243.674392)
			(xy 115.369607 -243.698999) (xy 115.361712 -243.747576) (xy 115.346128 -243.794257) (xy 115.323257 -243.837834)
			(xy 115.293692 -243.877178) (xy 115.258199 -243.91127) (xy 115.217696 -243.939226) (xy 115.173234 -243.960324)
			(xy 115.125963 -243.974016) (xy 115.077108 -243.979948) (xy 115.027933 -243.977967) (xy 114.979714 -243.968123)
			(xy 114.933698 -243.950671) (xy 114.891077 -243.926064) (xy 114.852956 -243.894939) (xy 114.820321 -243.858102)
			(xy 114.794018 -243.816506) (xy 114.774727 -243.77123) (xy 114.76295 -243.723446) (xy 114.75899 -243.674392)
			(xy 114.430048 -243.674392) (xy 114.429553 -243.698999) (xy 114.421658 -243.747576) (xy 114.406074 -243.794257)
			(xy 114.383203 -243.837834) (xy 114.353638 -243.877178) (xy 114.318145 -243.91127) (xy 114.277642 -243.939226)
			(xy 114.23318 -243.960324) (xy 114.185909 -243.974016) (xy 114.137054 -243.979948) (xy 114.087879 -243.977967)
			(xy 114.03966 -243.968123) (xy 113.993644 -243.950671) (xy 113.951023 -243.926064) (xy 113.912902 -243.894939)
			(xy 113.880267 -243.858102) (xy 113.853964 -243.816506) (xy 113.834673 -243.77123) (xy 113.822896 -243.723446)
			(xy 113.818936 -243.674392) (xy 113.489994 -243.674392) (xy 113.489499 -243.698999) (xy 113.481604 -243.747576)
			(xy 113.46602 -243.794257) (xy 113.443149 -243.837834) (xy 113.413584 -243.877178) (xy 113.378091 -243.91127)
			(xy 113.337588 -243.939226) (xy 113.293126 -243.960324) (xy 113.245855 -243.974016) (xy 113.197 -243.979948)
			(xy 113.147825 -243.977967) (xy 113.099606 -243.968123) (xy 113.05359 -243.950671) (xy 113.010969 -243.926064)
			(xy 112.972848 -243.894939) (xy 112.940213 -243.858102) (xy 112.91391 -243.816506) (xy 112.894619 -243.77123)
			(xy 112.882842 -243.723446) (xy 112.878882 -243.674392) (xy 110.676436 -243.674392) (xy 110.675941 -243.698999)
			(xy 110.668046 -243.747576) (xy 110.652462 -243.794257) (xy 110.629591 -243.837834) (xy 110.600026 -243.877178)
			(xy 110.564533 -243.91127) (xy 110.52403 -243.939226) (xy 110.479568 -243.960324) (xy 110.432297 -243.974016)
			(xy 110.383442 -243.979948) (xy 110.334267 -243.977967) (xy 110.286048 -243.968123) (xy 110.240032 -243.950671)
			(xy 110.197411 -243.926064) (xy 110.15929 -243.894939) (xy 110.126655 -243.858102) (xy 110.100352 -243.816506)
			(xy 110.081061 -243.77123) (xy 110.069284 -243.723446) (xy 110.065324 -243.674392) (xy 109.736951 -243.674392)
			(xy 109.736952 -243.6744) (xy 109.73278 -243.724744) (xy 109.720378 -243.773715) (xy 109.700085 -243.819977)
			(xy 109.672453 -243.862267) (xy 109.638238 -243.899432) (xy 109.598371 -243.930458) (xy 109.553942 -243.954499)
			(xy 109.506161 -243.970898) (xy 109.456332 -243.979209) (xy 109.431074 -243.9797) (xy 108.49102 -243.9797)
			(xy 108.465761 -243.979225) (xy 108.41593 -243.970913) (xy 108.368148 -243.954512) (xy 108.323717 -243.930469)
			(xy 108.283849 -243.899442) (xy 108.249632 -243.862275) (xy 108.222 -243.819983) (xy 108.201706 -243.773719)
			(xy 108.189304 -243.724746) (xy 108.185132 -243.6744) (xy 107.856274 -243.6744) (xy 107.855828 -243.698385)
			(xy 107.848322 -243.745779) (xy 107.833494 -243.791416) (xy 107.811709 -243.83417) (xy 107.783503 -243.87299)
			(xy 107.749571 -243.90692) (xy 107.710748 -243.935122) (xy 107.667992 -243.956904) (xy 107.622354 -243.971729)
			(xy 107.574959 -243.97923) (xy 107.550966 -243.9797) (xy 107.538203 -243.979562) (xy 107.512769 -243.977399)
			(xy 107.500166 -243.975382) (xy 107.500166 -243.975636) (xy 107.477779 -243.97144) (xy 107.434488 -243.957287)
			(xy 107.393782 -243.936854) (xy 107.356567 -243.910598) (xy 107.323668 -243.879099) (xy 107.309412 -243.861336)
			(xy 107.302554 -243.8527) (xy 107.28325 -243.84254) (xy 107.196382 -243.837206) (xy 107.18561 -243.837044)
			(xy 107.165489 -243.844687) (xy 107.15752 -243.851938) (xy 107.096052 -243.913406) (xy 107.088651 -243.920244)
			(xy 107.070053 -243.92796) (xy 107.059984 -243.928392) (xy 106.801412 -243.928392) (xy 106.78795 -243.93017)
			(xy 106.769916 -243.93525) (xy 106.764328 -243.938552) (xy 106.740896 -243.951485) (xy 106.690624 -243.969837)
			(xy 106.637924 -243.979155) (xy 106.584408 -243.979155) (xy 106.531708 -243.969837) (xy 106.481436 -243.951485)
			(xy 106.458004 -243.938552) (xy 106.452416 -243.93525) (xy 106.434382 -243.93017) (xy 106.42092 -243.928392)
			(xy 106.14025 -243.928392) (xy 106.101629 -243.928046) (xy 106.024591 -243.92244) (xy 105.948163 -243.911254)
			(xy 105.91038 -243.903246) (xy 105.903268 -243.901722) (xy 105.889806 -243.902484) (xy 105.86339 -243.911628)
			(xy 105.856786 -243.916708) (xy 105.836673 -243.931508) (xy 105.792633 -243.95504) (xy 105.745347 -243.971082)
			(xy 105.696079 -243.979204) (xy 105.671112 -243.9797) (xy 105.663746 -243.9797) (xy 105.64013 -243.978696)
			(xy 105.593616 -243.970304) (xy 105.548951 -243.954843) (xy 105.507202 -243.932683) (xy 105.469368 -243.904353)
			(xy 105.436351 -243.870531) (xy 105.408942 -243.832024) (xy 105.387796 -243.789753) (xy 105.373416 -243.744728)
			(xy 105.366148 -243.698025) (xy 105.365804 -243.674392) (xy 105.365901 -243.663687) (xy 105.367424 -243.64233)
			(xy 105.368852 -243.63172) (xy 105.37063 -243.618512) (xy 105.357168 -243.583714) (xy 105.350818 -243.576856)
			(xy 105.332806 -243.556545) (xy 105.298625 -243.514361) (xy 105.282492 -243.492528) (xy 105.282238 -243.492274)
			(xy 105.281984 -243.49202) (xy 105.274422 -243.482833) (xy 105.253224 -243.47209) (xy 105.241344 -243.471446)
			(xy 105.160826 -243.471446) (xy 105.148951 -243.472126) (xy 105.127748 -243.482841) (xy 105.120186 -243.49202)
			(xy 105.119932 -243.492274) (xy 105.119678 -243.492528) (xy 105.103552 -243.514367) (xy 105.069372 -243.556552)
			(xy 105.051352 -243.576856) (xy 105.045002 -243.583714) (xy 105.03154 -243.618512) (xy 105.033064 -243.629434)
			(xy 105.034613 -243.640609) (xy 105.036268 -243.663111) (xy 105.036366 -243.674392) (xy 105.035918 -243.698015)
			(xy 105.028629 -243.744697) (xy 105.01424 -243.789699) (xy 104.993093 -243.831949) (xy 104.965693 -243.870439)
			(xy 104.932693 -243.904252) (xy 104.894881 -243.93258) (xy 104.853158 -243.954749) (xy 104.808519 -243.970229)
			(xy 104.762029 -243.978651) (xy 104.738424 -243.9797) (xy 104.732328 -243.9797) (xy 104.731058 -243.9797)
			(xy 104.706093 -243.979199) (xy 104.656829 -243.971064) (xy 104.609547 -243.95502) (xy 104.565507 -243.931493)
			(xy 104.545384 -243.916708) (xy 104.53878 -243.911628) (xy 104.512364 -243.902484) (xy 104.498902 -243.901722)
			(xy 104.49179 -243.903246) (xy 104.454006 -243.911249) (xy 104.377578 -243.922422) (xy 104.30054 -243.928032)
			(xy 104.26192 -243.928392) (xy 103.98125 -243.928392) (xy 103.967788 -243.93017) (xy 103.949754 -243.93525)
			(xy 103.944166 -243.938552) (xy 103.920734 -243.951485) (xy 103.870462 -243.969837) (xy 103.817762 -243.979155)
			(xy 103.764246 -243.979155) (xy 103.711546 -243.969837) (xy 103.661274 -243.951485) (xy 103.637842 -243.938552)
			(xy 103.632254 -243.93525) (xy 103.61422 -243.93017) (xy 103.600758 -243.928392) (xy 103.320596 -243.928392)
			(xy 103.282017 -243.928039) (xy 103.205064 -243.922427) (xy 103.128721 -243.911248) (xy 103.09098 -243.903246)
			(xy 103.090218 -243.903246) (xy 103.083289 -243.901985) (xy 103.06924 -243.902882) (xy 103.062532 -243.905024)
			(xy 103.04272 -243.912136) (xy 103.03637 -243.916962) (xy 103.01627 -243.931707) (xy 102.972277 -243.955145)
			(xy 102.925059 -243.971122) (xy 102.875874 -243.979214) (xy 102.85095 -243.9797) (xy 102.84333 -243.9797)
			(xy 102.819734 -243.978673) (xy 102.773263 -243.970242) (xy 102.728646 -243.954753) (xy 102.686947 -243.932575)
			(xy 102.649163 -243.904238) (xy 102.616195 -243.870419) (xy 102.58883 -243.831925) (xy 102.567723 -243.789675)
			(xy 102.553376 -243.744678) (xy 102.546132 -243.698007) (xy 102.545642 -243.674392) (xy 102.545751 -243.663238)
			(xy 102.547407 -243.64099) (xy 102.548944 -243.629942) (xy 102.550468 -243.618258) (xy 102.537006 -243.58346)
			(xy 102.530656 -243.576602) (xy 102.51258 -243.55636) (xy 102.478272 -243.514304) (xy 102.462076 -243.492528)
			(xy 102.462076 -243.492274) (xy 102.461822 -243.49202) (xy 102.454256 -243.482844) (xy 102.433058 -243.472126)
			(xy 102.421182 -243.471446) (xy 102.340918 -243.471446) (xy 102.329044 -243.472127) (xy 102.307844 -243.482845)
			(xy 102.300278 -243.49202) (xy 102.300024 -243.492274) (xy 102.300024 -243.492528) (xy 102.283826 -243.514302)
			(xy 102.249519 -243.556359) (xy 102.231444 -243.576602) (xy 102.225094 -243.58346) (xy 102.211632 -243.618258)
			(xy 102.213156 -243.629942) (xy 102.214689 -243.640991) (xy 102.216344 -243.663238) (xy 102.216458 -243.674392)
			(xy 102.215989 -243.69837) (xy 102.208491 -243.745735) (xy 102.19368 -243.791345) (xy 102.171918 -243.834078)
			(xy 102.143741 -243.872882) (xy 102.109844 -243.906804) (xy 102.071059 -243.935007) (xy 102.028341 -243.956798)
			(xy 101.982741 -243.971642) (xy 101.935381 -243.979172) (xy 101.911404 -243.9797) (xy 101.910896 -243.9797)
			(xy 101.885962 -243.979187) (xy 101.836762 -243.971041) (xy 101.789543 -243.955) (xy 101.745562 -243.93149)
			(xy 101.725476 -243.916708) (xy 101.718872 -243.911882) (xy 101.699568 -243.905024) (xy 101.692861 -243.90287)
			(xy 101.678808 -243.901961) (xy 101.671882 -243.903246) (xy 101.67112 -243.903246) (xy 101.633378 -243.911242)
			(xy 101.557034 -243.922412) (xy 101.480082 -243.928029) (xy 101.441504 -243.928392) (xy 101.161342 -243.928392)
			(xy 101.14788 -243.93017) (xy 101.129846 -243.93525) (xy 101.124258 -243.938552) (xy 101.100826 -243.951485)
			(xy 101.050554 -243.969837) (xy 100.997854 -243.979155) (xy 100.944338 -243.979155) (xy 100.891638 -243.969837)
			(xy 100.841366 -243.951485) (xy 100.817934 -243.938552) (xy 100.812346 -243.93525) (xy 100.794312 -243.93017)
			(xy 100.78085 -243.928392) (xy 100.50018 -243.928392) (xy 100.461559 -243.928047) (xy 100.38452 -243.922443)
			(xy 100.308092 -243.911259) (xy 100.27031 -243.903246) (xy 100.263198 -243.901722) (xy 100.249736 -243.902484)
			(xy 100.22332 -243.911628) (xy 100.216716 -243.916708) (xy 100.196604 -243.93151) (xy 100.152564 -243.955047)
			(xy 100.105278 -243.971093) (xy 100.056009 -243.979219) (xy 100.031042 -243.9797) (xy 100.023676 -243.9797)
			(xy 100.000064 -243.978691) (xy 99.953558 -243.97029) (xy 99.908902 -243.954823) (xy 99.867163 -243.93266)
			(xy 99.829338 -243.904329) (xy 99.79633 -243.870508) (xy 99.768928 -243.832004) (xy 99.747787 -243.789738)
			(xy 99.733412 -243.744718) (xy 99.726146 -243.698021) (xy 99.725734 -243.674392) (xy 99.725831 -243.663687)
			(xy 99.727354 -243.64233) (xy 99.728782 -243.63172) (xy 99.73056 -243.618512) (xy 99.717098 -243.583714)
			(xy 99.710748 -243.576856) (xy 99.692735 -243.556546) (xy 99.658554 -243.514362) (xy 99.642422 -243.492528)
			(xy 99.642168 -243.492274) (xy 99.641914 -243.49202) (xy 99.634347 -243.482845) (xy 99.613149 -243.472131)
			(xy 99.601274 -243.471446) (xy 99.520756 -243.471446) (xy 99.508889 -243.47214) (xy 99.48771 -243.482873)
			(xy 99.480116 -243.49202) (xy 99.479862 -243.492274) (xy 99.479608 -243.492528) (xy 99.463482 -243.514367)
			(xy 99.429303 -243.556553) (xy 99.411282 -243.576856) (xy 99.404932 -243.583714) (xy 99.39147 -243.618512)
			(xy 99.392994 -243.629434) (xy 99.394543 -243.640609) (xy 99.396197 -243.663111) (xy 99.396296 -243.674392)
			(xy 99.395848 -243.698016) (xy 99.388559 -243.744699) (xy 99.37417 -243.789703) (xy 99.353024 -243.831955)
			(xy 99.325625 -243.870448) (xy 99.292626 -243.904263) (xy 99.254814 -243.932595) (xy 99.21309 -243.954767)
			(xy 99.168451 -243.970251) (xy 99.12196 -243.978678) (xy 99.098354 -243.9797) (xy 99.092258 -243.9797)
			(xy 99.090988 -243.9797) (xy 99.066022 -243.979201) (xy 99.016756 -243.971071) (xy 98.969471 -243.95503)
			(xy 98.925427 -243.931506) (xy 98.905314 -243.916708) (xy 98.89871 -243.911628) (xy 98.872294 -243.902484)
			(xy 98.858832 -243.901722) (xy 98.85172 -243.903246) (xy 98.813936 -243.91125) (xy 98.737508 -243.922426)
			(xy 98.660471 -243.928037) (xy 98.62185 -243.928392) (xy 98.34118 -243.928392) (xy 98.327718 -243.93017)
			(xy 98.309684 -243.93525) (xy 98.304096 -243.938552) (xy 98.280664 -243.951485) (xy 98.230392 -243.969837)
			(xy 98.177692 -243.979155) (xy 98.124176 -243.979155) (xy 98.071476 -243.969837) (xy 98.021204 -243.951485)
			(xy 97.997772 -243.938552) (xy 97.992184 -243.93525) (xy 97.97415 -243.93017) (xy 97.960688 -243.928392)
			(xy 97.680272 -243.928392) (xy 97.641651 -243.928047) (xy 97.564612 -243.922443) (xy 97.488185 -243.911258)
			(xy 97.450402 -243.903246) (xy 97.44329 -243.901722) (xy 97.429828 -243.902484) (xy 97.403412 -243.911628)
			(xy 97.396808 -243.916708) (xy 97.376696 -243.93151) (xy 97.332656 -243.955045) (xy 97.28537 -243.97109)
			(xy 97.236101 -243.979215) (xy 97.211134 -243.9797) (xy 97.203768 -243.9797) (xy 97.180156 -243.97869)
			(xy 97.133651 -243.970289) (xy 97.088996 -243.954821) (xy 97.047258 -243.932657) (xy 97.009434 -243.904326)
			(xy 96.976427 -243.870505) (xy 96.949027 -243.832002) (xy 96.927886 -243.789736) (xy 96.913512 -243.744717)
			(xy 96.906246 -243.698021) (xy 96.905826 -243.674392) (xy 96.905923 -243.663687) (xy 96.907446 -243.64233)
			(xy 96.908874 -243.63172) (xy 96.910652 -243.618512) (xy 96.89719 -243.583714) (xy 96.89084 -243.576856)
			(xy 96.87942 -243.564093) (xy 96.857316 -243.537927) (xy 96.846644 -243.524532) (xy 96.844612 -243.522246)
			(xy 96.84258 -243.520214) (xy 96.835168 -243.51353) (xy 96.816735 -243.505933) (xy 96.796797 -243.505933)
			(xy 96.778364 -243.51353) (xy 96.770952 -243.520214) (xy 96.740726 -243.55044) (xy 96.734013 -243.557678)
			(xy 96.726423 -243.575883) (xy 96.725994 -243.585746) (xy 96.725994 -244.111018) (xy 96.726299 -244.120377)
			(xy 96.732942 -244.137872) (xy 96.738948 -244.145054) (xy 96.758506 -244.166644) (xy 96.76638 -244.170962)
			(xy 96.787716 -244.182392) (xy 96.79559 -244.183916) (xy 96.820103 -244.188878) (xy 96.867195 -244.205715)
			(xy 96.910914 -244.229999) (xy 96.950093 -244.261082) (xy 96.983683 -244.298133) (xy 97.010789 -244.340161)
			(xy 97.030684 -244.386044) (xy 97.042838 -244.434556) (xy 97.046926 -244.4844) (xy 97.374883 -244.4844)
			(xy 97.379059 -244.434011) (xy 97.391472 -244.384997) (xy 97.411784 -244.338695) (xy 97.43944 -244.296368)
			(xy 97.473686 -244.259171) (xy 97.513588 -244.228118) (xy 97.558057 -244.204057) (xy 97.605881 -244.187644)
			(xy 97.655753 -244.179326) (xy 97.681034 -244.178836) (xy 98.621088 -244.178836) (xy 98.646367 -244.179332)
			(xy 98.696236 -244.187652) (xy 98.744056 -244.204067) (xy 98.788521 -244.228129) (xy 98.82842 -244.259181)
			(xy 98.862663 -244.296378) (xy 98.890316 -244.338703) (xy 98.910626 -244.385003) (xy 98.923037 -244.434014)
			(xy 98.927213 -244.484398) (xy 99.255338 -244.484398) (xy 99.259298 -244.435344) (xy 99.271075 -244.38756)
			(xy 99.290366 -244.342284) (xy 99.316669 -244.300688) (xy 99.349304 -244.263851) (xy 99.387425 -244.232726)
			(xy 99.430046 -244.208119) (xy 99.476062 -244.190667) (xy 99.524281 -244.180823) (xy 99.573456 -244.178842)
			(xy 99.622311 -244.184774) (xy 99.669582 -244.198466) (xy 99.714044 -244.219564) (xy 99.754547 -244.24752)
			(xy 99.79004 -244.281612) (xy 99.819605 -244.320956) (xy 99.842476 -244.364533) (xy 99.85806 -244.411214)
			(xy 99.865955 -244.459791) (xy 99.86645 -244.484398) (xy 99.86645 -244.4844) (xy 100.194783 -244.4844)
			(xy 100.198959 -244.434011) (xy 100.211373 -244.384996) (xy 100.231685 -244.338693) (xy 100.259342 -244.296365)
			(xy 100.293589 -244.259168) (xy 100.333492 -244.228115) (xy 100.377963 -244.204054) (xy 100.425787 -244.187642)
			(xy 100.475661 -244.179326) (xy 100.500942 -244.178836) (xy 101.440996 -244.178836) (xy 101.466275 -244.179333)
			(xy 101.516143 -244.187654) (xy 101.563961 -244.204069) (xy 101.608426 -244.228131) (xy 101.648323 -244.259184)
			(xy 101.682565 -244.29638) (xy 101.710217 -244.338705) (xy 101.730526 -244.385005) (xy 101.742937 -244.434015)
			(xy 101.747113 -244.484398) (xy 102.075246 -244.484398) (xy 102.079206 -244.435344) (xy 102.090983 -244.38756)
			(xy 102.110274 -244.342284) (xy 102.136577 -244.300688) (xy 102.169212 -244.263851) (xy 102.207333 -244.232726)
			(xy 102.249954 -244.208119) (xy 102.29597 -244.190667) (xy 102.344189 -244.180823) (xy 102.393364 -244.178842)
			(xy 102.442219 -244.184774) (xy 102.48949 -244.198466) (xy 102.533952 -244.219564) (xy 102.574455 -244.24752)
			(xy 102.609948 -244.281612) (xy 102.639513 -244.320956) (xy 102.662384 -244.364533) (xy 102.677968 -244.411214)
			(xy 102.685863 -244.459791) (xy 102.686358 -244.484398) (xy 102.686358 -244.4844) (xy 103.014983 -244.4844)
			(xy 103.019159 -244.434014) (xy 103.03157 -244.385003) (xy 103.051879 -244.338704) (xy 103.079532 -244.296378)
			(xy 103.113774 -244.259181) (xy 103.153672 -244.228128) (xy 103.198137 -244.204065) (xy 103.245956 -244.18765)
			(xy 103.295825 -244.179329) (xy 103.321104 -244.178836) (xy 104.261158 -244.178836) (xy 104.286439 -244.17933)
			(xy 104.336312 -244.187646) (xy 104.384136 -244.204058) (xy 104.428605 -244.228118) (xy 104.468508 -244.259171)
			(xy 104.502755 -244.296368) (xy 104.530412 -244.338695) (xy 104.550724 -244.384997) (xy 104.563137 -244.434011)
			(xy 104.567313 -244.484398) (xy 104.895154 -244.484398) (xy 104.899114 -244.435344) (xy 104.910891 -244.38756)
			(xy 104.930182 -244.342284) (xy 104.956485 -244.300688) (xy 104.98912 -244.263851) (xy 105.027241 -244.232726)
			(xy 105.069862 -244.208119) (xy 105.115878 -244.190667) (xy 105.164097 -244.180823) (xy 105.213272 -244.178842)
			(xy 105.262127 -244.184774) (xy 105.309398 -244.198466) (xy 105.35386 -244.219564) (xy 105.394363 -244.24752)
			(xy 105.429856 -244.281612) (xy 105.459421 -244.320956) (xy 105.482292 -244.364533) (xy 105.497876 -244.411214)
			(xy 105.505771 -244.459791) (xy 105.506266 -244.484398) (xy 105.506266 -244.4844) (xy 105.834883 -244.4844)
			(xy 105.839059 -244.434014) (xy 105.851471 -244.385002) (xy 105.87178 -244.338701) (xy 105.899434 -244.296375)
			(xy 105.933678 -244.259178) (xy 105.973577 -244.228125) (xy 106.018043 -244.204063) (xy 106.065863 -244.187648)
			(xy 106.115732 -244.179328) (xy 106.141012 -244.178836) (xy 107.081066 -244.178836) (xy 107.106346 -244.17933)
			(xy 107.156218 -244.187647) (xy 107.204041 -244.20406) (xy 107.24851 -244.228121) (xy 107.288411 -244.259174)
			(xy 107.322657 -244.29637) (xy 107.350313 -244.338697) (xy 107.370624 -244.384999) (xy 107.383037 -244.434012)
			(xy 107.387213 -244.484398) (xy 107.715316 -244.484398) (xy 107.719276 -244.435344) (xy 107.731053 -244.38756)
			(xy 107.750344 -244.342284) (xy 107.776647 -244.300688) (xy 107.809282 -244.263851) (xy 107.847403 -244.232726)
			(xy 107.890024 -244.208119) (xy 107.93604 -244.190667) (xy 107.984259 -244.180823) (xy 108.033434 -244.178842)
			(xy 108.082289 -244.184774) (xy 108.12956 -244.198466) (xy 108.174022 -244.219564) (xy 108.214525 -244.24752)
			(xy 108.250018 -244.281612) (xy 108.279583 -244.320956) (xy 108.302454 -244.364533) (xy 108.318038 -244.411214)
			(xy 108.325933 -244.459791) (xy 108.326428 -244.484398) (xy 108.65537 -244.484398) (xy 108.65933 -244.435344)
			(xy 108.671107 -244.38756) (xy 108.690398 -244.342284) (xy 108.716701 -244.300688) (xy 108.749336 -244.263851)
			(xy 108.787457 -244.232726) (xy 108.830078 -244.208119) (xy 108.876094 -244.190667) (xy 108.924313 -244.180823)
			(xy 108.973488 -244.178842) (xy 109.022343 -244.184774) (xy 109.069614 -244.198466) (xy 109.114076 -244.219564)
			(xy 109.154579 -244.24752) (xy 109.190072 -244.281612) (xy 109.219637 -244.320956) (xy 109.242508 -244.364533)
			(xy 109.258092 -244.411214) (xy 109.265987 -244.459791) (xy 109.266482 -244.484398) (xy 109.59517 -244.484398)
			(xy 109.59913 -244.435344) (xy 109.610907 -244.38756) (xy 109.630198 -244.342284) (xy 109.656501 -244.300688)
			(xy 109.689136 -244.263851) (xy 109.727257 -244.232726) (xy 109.769878 -244.208119) (xy 109.815894 -244.190667)
			(xy 109.864113 -244.180823) (xy 109.913288 -244.178842) (xy 109.962143 -244.184774) (xy 110.009414 -244.198466)
			(xy 110.053876 -244.219564) (xy 110.094379 -244.24752) (xy 110.129872 -244.281612) (xy 110.159437 -244.320956)
			(xy 110.182308 -244.364533) (xy 110.197892 -244.411214) (xy 110.205787 -244.459791) (xy 110.206282 -244.484398)
			(xy 113.349036 -244.484398) (xy 113.352996 -244.435344) (xy 113.364773 -244.38756) (xy 113.384064 -244.342284)
			(xy 113.410367 -244.300688) (xy 113.443002 -244.263851) (xy 113.481123 -244.232726) (xy 113.523744 -244.208119)
			(xy 113.56976 -244.190667) (xy 113.617979 -244.180823) (xy 113.667154 -244.178842) (xy 113.716009 -244.184774)
			(xy 113.76328 -244.198466) (xy 113.807742 -244.219564) (xy 113.848245 -244.24752) (xy 113.883738 -244.281612)
			(xy 113.913303 -244.320956) (xy 113.936174 -244.364533) (xy 113.951758 -244.411214) (xy 113.959653 -244.459791)
			(xy 113.960148 -244.484398) (xy 114.288836 -244.484398) (xy 114.292796 -244.435344) (xy 114.304573 -244.38756)
			(xy 114.323864 -244.342284) (xy 114.350167 -244.300688) (xy 114.382802 -244.263851) (xy 114.420923 -244.232726)
			(xy 114.463544 -244.208119) (xy 114.50956 -244.190667) (xy 114.557779 -244.180823) (xy 114.606954 -244.178842)
			(xy 114.655809 -244.184774) (xy 114.70308 -244.198466) (xy 114.747542 -244.219564) (xy 114.788045 -244.24752)
			(xy 114.823538 -244.281612) (xy 114.853103 -244.320956) (xy 114.875974 -244.364533) (xy 114.891558 -244.411214)
			(xy 114.899453 -244.459791) (xy 114.899948 -244.484398) (xy 115.22889 -244.484398) (xy 115.23285 -244.435344)
			(xy 115.244627 -244.38756) (xy 115.263918 -244.342284) (xy 115.290221 -244.300688) (xy 115.322856 -244.263851)
			(xy 115.360977 -244.232726) (xy 115.403598 -244.208119) (xy 115.449614 -244.190667) (xy 115.497833 -244.180823)
			(xy 115.547008 -244.178842) (xy 115.595863 -244.184774) (xy 115.643134 -244.198466) (xy 115.687596 -244.219564)
			(xy 115.728099 -244.24752) (xy 115.763592 -244.281612) (xy 115.793157 -244.320956) (xy 115.816028 -244.364533)
			(xy 115.831612 -244.411214) (xy 115.839507 -244.459791) (xy 115.840002 -244.484398) (xy 116.168944 -244.484398)
			(xy 116.172904 -244.435344) (xy 116.184681 -244.38756) (xy 116.203972 -244.342284) (xy 116.230275 -244.300688)
			(xy 116.26291 -244.263851) (xy 116.301031 -244.232726) (xy 116.343652 -244.208119) (xy 116.389668 -244.190667)
			(xy 116.437887 -244.180823) (xy 116.487062 -244.178842) (xy 116.535917 -244.184774) (xy 116.583188 -244.198466)
			(xy 116.62765 -244.219564) (xy 116.668153 -244.24752) (xy 116.703646 -244.281612) (xy 116.733211 -244.320956)
			(xy 116.756082 -244.364533) (xy 116.771666 -244.411214) (xy 116.779561 -244.459791) (xy 116.780056 -244.484398)
			(xy 117.108998 -244.484398) (xy 117.112958 -244.435344) (xy 117.124735 -244.38756) (xy 117.144026 -244.342284)
			(xy 117.170329 -244.300688) (xy 117.202964 -244.263851) (xy 117.241085 -244.232726) (xy 117.283706 -244.208119)
			(xy 117.329722 -244.190667) (xy 117.377941 -244.180823) (xy 117.427116 -244.178842) (xy 117.475971 -244.184774)
			(xy 117.523242 -244.198466) (xy 117.567704 -244.219564) (xy 117.608207 -244.24752) (xy 117.6437 -244.281612)
			(xy 117.673265 -244.320956) (xy 117.696136 -244.364533) (xy 117.71172 -244.411214) (xy 117.719615 -244.459791)
			(xy 117.72011 -244.484398) (xy 118.049052 -244.484398) (xy 118.053012 -244.435344) (xy 118.064789 -244.38756)
			(xy 118.08408 -244.342284) (xy 118.110383 -244.300688) (xy 118.143018 -244.263851) (xy 118.181139 -244.232726)
			(xy 118.22376 -244.208119) (xy 118.269776 -244.190667) (xy 118.317995 -244.180823) (xy 118.36717 -244.178842)
			(xy 118.416025 -244.184774) (xy 118.463296 -244.198466) (xy 118.507758 -244.219564) (xy 118.548261 -244.24752)
			(xy 118.583754 -244.281612) (xy 118.613319 -244.320956) (xy 118.63619 -244.364533) (xy 118.651774 -244.411214)
			(xy 118.659669 -244.459791) (xy 118.660164 -244.484398) (xy 118.988852 -244.484398) (xy 118.992812 -244.435344)
			(xy 119.004589 -244.38756) (xy 119.02388 -244.342284) (xy 119.050183 -244.300688) (xy 119.082818 -244.263851)
			(xy 119.120939 -244.232726) (xy 119.16356 -244.208119) (xy 119.209576 -244.190667) (xy 119.257795 -244.180823)
			(xy 119.30697 -244.178842) (xy 119.355825 -244.184774) (xy 119.403096 -244.198466) (xy 119.447558 -244.219564)
			(xy 119.488061 -244.24752) (xy 119.523554 -244.281612) (xy 119.553119 -244.320956) (xy 119.57599 -244.364533)
			(xy 119.591574 -244.411214) (xy 119.599469 -244.459791) (xy 119.599964 -244.484398) (xy 119.928906 -244.484398)
			(xy 119.932866 -244.435344) (xy 119.944643 -244.38756) (xy 119.963934 -244.342284) (xy 119.990237 -244.300688)
			(xy 120.022872 -244.263851) (xy 120.060993 -244.232726) (xy 120.103614 -244.208119) (xy 120.14963 -244.190667)
			(xy 120.197849 -244.180823) (xy 120.247024 -244.178842) (xy 120.295879 -244.184774) (xy 120.34315 -244.198466)
			(xy 120.387612 -244.219564) (xy 120.428115 -244.24752) (xy 120.463608 -244.281612) (xy 120.493173 -244.320956)
			(xy 120.516044 -244.364533) (xy 120.531628 -244.411214) (xy 120.539523 -244.459791) (xy 120.540018 -244.484398)
			(xy 120.86896 -244.484398) (xy 120.87292 -244.435344) (xy 120.884697 -244.38756) (xy 120.903988 -244.342284)
			(xy 120.930291 -244.300688) (xy 120.962926 -244.263851) (xy 121.001047 -244.232726) (xy 121.043668 -244.208119)
			(xy 121.089684 -244.190667) (xy 121.137903 -244.180823) (xy 121.187078 -244.178842) (xy 121.235933 -244.184774)
			(xy 121.283204 -244.198466) (xy 121.327666 -244.219564) (xy 121.368169 -244.24752) (xy 121.403662 -244.281612)
			(xy 121.433227 -244.320956) (xy 121.456098 -244.364533) (xy 121.471682 -244.411214) (xy 121.479577 -244.459791)
			(xy 121.480072 -244.484398) (xy 121.809014 -244.484398) (xy 121.812974 -244.435344) (xy 121.824751 -244.38756)
			(xy 121.844042 -244.342284) (xy 121.870345 -244.300688) (xy 121.90298 -244.263851) (xy 121.941101 -244.232726)
			(xy 121.983722 -244.208119) (xy 122.029738 -244.190667) (xy 122.077957 -244.180823) (xy 122.127132 -244.178842)
			(xy 122.175987 -244.184774) (xy 122.223258 -244.198466) (xy 122.26772 -244.219564) (xy 122.308223 -244.24752)
			(xy 122.343716 -244.281612) (xy 122.373281 -244.320956) (xy 122.396152 -244.364533) (xy 122.411736 -244.411214)
			(xy 122.419631 -244.459791) (xy 122.420126 -244.484398) (xy 122.748814 -244.484398) (xy 122.752774 -244.435344)
			(xy 122.764551 -244.38756) (xy 122.783842 -244.342284) (xy 122.810145 -244.300688) (xy 122.84278 -244.263851)
			(xy 122.880901 -244.232726) (xy 122.923522 -244.208119) (xy 122.969538 -244.190667) (xy 123.017757 -244.180823)
			(xy 123.066932 -244.178842) (xy 123.115787 -244.184774) (xy 123.163058 -244.198466) (xy 123.20752 -244.219564)
			(xy 123.248023 -244.24752) (xy 123.283516 -244.281612) (xy 123.313081 -244.320956) (xy 123.335952 -244.364533)
			(xy 123.351536 -244.411214) (xy 123.359431 -244.459791) (xy 123.359926 -244.484398) (xy 123.688868 -244.484398)
			(xy 123.692828 -244.435344) (xy 123.704605 -244.38756) (xy 123.723896 -244.342284) (xy 123.750199 -244.300688)
			(xy 123.782834 -244.263851) (xy 123.820955 -244.232726) (xy 123.863576 -244.208119) (xy 123.909592 -244.190667)
			(xy 123.957811 -244.180823) (xy 124.006986 -244.178842) (xy 124.055841 -244.184774) (xy 124.103112 -244.198466)
			(xy 124.147574 -244.219564) (xy 124.188077 -244.24752) (xy 124.22357 -244.281612) (xy 124.253135 -244.320956)
			(xy 124.276006 -244.364533) (xy 124.29159 -244.411214) (xy 124.299485 -244.459791) (xy 124.29998 -244.484398)
			(xy 124.628922 -244.484398) (xy 124.632882 -244.435344) (xy 124.644659 -244.38756) (xy 124.66395 -244.342284)
			(xy 124.690253 -244.300688) (xy 124.722888 -244.263851) (xy 124.761009 -244.232726) (xy 124.80363 -244.208119)
			(xy 124.849646 -244.190667) (xy 124.897865 -244.180823) (xy 124.94704 -244.178842) (xy 124.995895 -244.184774)
			(xy 125.043166 -244.198466) (xy 125.087628 -244.219564) (xy 125.128131 -244.24752) (xy 125.163624 -244.281612)
			(xy 125.193189 -244.320956) (xy 125.21606 -244.364533) (xy 125.231644 -244.411214) (xy 125.239539 -244.459791)
			(xy 125.240034 -244.484398) (xy 125.568976 -244.484398) (xy 125.572936 -244.435344) (xy 125.584713 -244.38756)
			(xy 125.604004 -244.342284) (xy 125.630307 -244.300688) (xy 125.662942 -244.263851) (xy 125.701063 -244.232726)
			(xy 125.743684 -244.208119) (xy 125.7897 -244.190667) (xy 125.837919 -244.180823) (xy 125.887094 -244.178842)
			(xy 125.935949 -244.184774) (xy 125.98322 -244.198466) (xy 126.027682 -244.219564) (xy 126.068185 -244.24752)
			(xy 126.103678 -244.281612) (xy 126.133243 -244.320956) (xy 126.156114 -244.364533) (xy 126.171698 -244.411214)
			(xy 126.179593 -244.459791) (xy 126.180088 -244.484398) (xy 126.179593 -244.509005) (xy 126.171698 -244.557582)
			(xy 126.156114 -244.604263) (xy 126.133243 -244.64784) (xy 126.103678 -244.687184) (xy 126.068185 -244.721276)
			(xy 126.027682 -244.749232) (xy 125.98322 -244.77033) (xy 125.935949 -244.784022) (xy 125.887094 -244.789954)
			(xy 125.837919 -244.787973) (xy 125.7897 -244.778129) (xy 125.743684 -244.760677) (xy 125.701063 -244.73607)
			(xy 125.662942 -244.704945) (xy 125.630307 -244.668108) (xy 125.604004 -244.626512) (xy 125.584713 -244.581236)
			(xy 125.572936 -244.533452) (xy 125.568976 -244.484398) (xy 125.240034 -244.484398) (xy 125.239539 -244.509005)
			(xy 125.231644 -244.557582) (xy 125.21606 -244.604263) (xy 125.193189 -244.64784) (xy 125.163624 -244.687184)
			(xy 125.128131 -244.721276) (xy 125.087628 -244.749232) (xy 125.043166 -244.77033) (xy 124.995895 -244.784022)
			(xy 124.94704 -244.789954) (xy 124.897865 -244.787973) (xy 124.849646 -244.778129) (xy 124.80363 -244.760677)
			(xy 124.761009 -244.73607) (xy 124.722888 -244.704945) (xy 124.690253 -244.668108) (xy 124.66395 -244.626512)
			(xy 124.644659 -244.581236) (xy 124.632882 -244.533452) (xy 124.628922 -244.484398) (xy 124.29998 -244.484398)
			(xy 124.299485 -244.509005) (xy 124.29159 -244.557582) (xy 124.276006 -244.604263) (xy 124.253135 -244.64784)
			(xy 124.22357 -244.687184) (xy 124.188077 -244.721276) (xy 124.147574 -244.749232) (xy 124.103112 -244.77033)
			(xy 124.055841 -244.784022) (xy 124.006986 -244.789954) (xy 123.957811 -244.787973) (xy 123.909592 -244.778129)
			(xy 123.863576 -244.760677) (xy 123.820955 -244.73607) (xy 123.782834 -244.704945) (xy 123.750199 -244.668108)
			(xy 123.723896 -244.626512) (xy 123.704605 -244.581236) (xy 123.692828 -244.533452) (xy 123.688868 -244.484398)
			(xy 123.359926 -244.484398) (xy 123.359431 -244.509005) (xy 123.351536 -244.557582) (xy 123.335952 -244.604263)
			(xy 123.313081 -244.64784) (xy 123.283516 -244.687184) (xy 123.248023 -244.721276) (xy 123.20752 -244.749232)
			(xy 123.163058 -244.77033) (xy 123.115787 -244.784022) (xy 123.066932 -244.789954) (xy 123.017757 -244.787973)
			(xy 122.969538 -244.778129) (xy 122.923522 -244.760677) (xy 122.880901 -244.73607) (xy 122.84278 -244.704945)
			(xy 122.810145 -244.668108) (xy 122.783842 -244.626512) (xy 122.764551 -244.581236) (xy 122.752774 -244.533452)
			(xy 122.748814 -244.484398) (xy 122.420126 -244.484398) (xy 122.419631 -244.509005) (xy 122.411736 -244.557582)
			(xy 122.396152 -244.604263) (xy 122.373281 -244.64784) (xy 122.343716 -244.687184) (xy 122.308223 -244.721276)
			(xy 122.26772 -244.749232) (xy 122.223258 -244.77033) (xy 122.175987 -244.784022) (xy 122.127132 -244.789954)
			(xy 122.077957 -244.787973) (xy 122.029738 -244.778129) (xy 121.983722 -244.760677) (xy 121.941101 -244.73607)
			(xy 121.90298 -244.704945) (xy 121.870345 -244.668108) (xy 121.844042 -244.626512) (xy 121.824751 -244.581236)
			(xy 121.812974 -244.533452) (xy 121.809014 -244.484398) (xy 121.480072 -244.484398) (xy 121.479577 -244.509005)
			(xy 121.471682 -244.557582) (xy 121.456098 -244.604263) (xy 121.433227 -244.64784) (xy 121.403662 -244.687184)
			(xy 121.368169 -244.721276) (xy 121.327666 -244.749232) (xy 121.283204 -244.77033) (xy 121.235933 -244.784022)
			(xy 121.187078 -244.789954) (xy 121.137903 -244.787973) (xy 121.089684 -244.778129) (xy 121.043668 -244.760677)
			(xy 121.001047 -244.73607) (xy 120.962926 -244.704945) (xy 120.930291 -244.668108) (xy 120.903988 -244.626512)
			(xy 120.884697 -244.581236) (xy 120.87292 -244.533452) (xy 120.86896 -244.484398) (xy 120.540018 -244.484398)
			(xy 120.539523 -244.509005) (xy 120.531628 -244.557582) (xy 120.516044 -244.604263) (xy 120.493173 -244.64784)
			(xy 120.463608 -244.687184) (xy 120.428115 -244.721276) (xy 120.387612 -244.749232) (xy 120.34315 -244.77033)
			(xy 120.295879 -244.784022) (xy 120.247024 -244.789954) (xy 120.197849 -244.787973) (xy 120.14963 -244.778129)
			(xy 120.103614 -244.760677) (xy 120.060993 -244.73607) (xy 120.022872 -244.704945) (xy 119.990237 -244.668108)
			(xy 119.963934 -244.626512) (xy 119.944643 -244.581236) (xy 119.932866 -244.533452) (xy 119.928906 -244.484398)
			(xy 119.599964 -244.484398) (xy 119.599469 -244.509005) (xy 119.591574 -244.557582) (xy 119.57599 -244.604263)
			(xy 119.553119 -244.64784) (xy 119.523554 -244.687184) (xy 119.488061 -244.721276) (xy 119.447558 -244.749232)
			(xy 119.403096 -244.77033) (xy 119.355825 -244.784022) (xy 119.30697 -244.789954) (xy 119.257795 -244.787973)
			(xy 119.209576 -244.778129) (xy 119.16356 -244.760677) (xy 119.120939 -244.73607) (xy 119.082818 -244.704945)
			(xy 119.050183 -244.668108) (xy 119.02388 -244.626512) (xy 119.004589 -244.581236) (xy 118.992812 -244.533452)
			(xy 118.988852 -244.484398) (xy 118.660164 -244.484398) (xy 118.659669 -244.509005) (xy 118.651774 -244.557582)
			(xy 118.63619 -244.604263) (xy 118.613319 -244.64784) (xy 118.583754 -244.687184) (xy 118.548261 -244.721276)
			(xy 118.507758 -244.749232) (xy 118.463296 -244.77033) (xy 118.416025 -244.784022) (xy 118.36717 -244.789954)
			(xy 118.317995 -244.787973) (xy 118.269776 -244.778129) (xy 118.22376 -244.760677) (xy 118.181139 -244.73607)
			(xy 118.143018 -244.704945) (xy 118.110383 -244.668108) (xy 118.08408 -244.626512) (xy 118.064789 -244.581236)
			(xy 118.053012 -244.533452) (xy 118.049052 -244.484398) (xy 117.72011 -244.484398) (xy 117.719615 -244.509005)
			(xy 117.71172 -244.557582) (xy 117.696136 -244.604263) (xy 117.673265 -244.64784) (xy 117.6437 -244.687184)
			(xy 117.608207 -244.721276) (xy 117.567704 -244.749232) (xy 117.523242 -244.77033) (xy 117.475971 -244.784022)
			(xy 117.427116 -244.789954) (xy 117.377941 -244.787973) (xy 117.329722 -244.778129) (xy 117.283706 -244.760677)
			(xy 117.241085 -244.73607) (xy 117.202964 -244.704945) (xy 117.170329 -244.668108) (xy 117.144026 -244.626512)
			(xy 117.124735 -244.581236) (xy 117.112958 -244.533452) (xy 117.108998 -244.484398) (xy 116.780056 -244.484398)
			(xy 116.779561 -244.509005) (xy 116.771666 -244.557582) (xy 116.756082 -244.604263) (xy 116.733211 -244.64784)
			(xy 116.703646 -244.687184) (xy 116.668153 -244.721276) (xy 116.62765 -244.749232) (xy 116.583188 -244.77033)
			(xy 116.535917 -244.784022) (xy 116.487062 -244.789954) (xy 116.437887 -244.787973) (xy 116.389668 -244.778129)
			(xy 116.343652 -244.760677) (xy 116.301031 -244.73607) (xy 116.26291 -244.704945) (xy 116.230275 -244.668108)
			(xy 116.203972 -244.626512) (xy 116.184681 -244.581236) (xy 116.172904 -244.533452) (xy 116.168944 -244.484398)
			(xy 115.840002 -244.484398) (xy 115.839507 -244.509005) (xy 115.831612 -244.557582) (xy 115.816028 -244.604263)
			(xy 115.793157 -244.64784) (xy 115.763592 -244.687184) (xy 115.728099 -244.721276) (xy 115.687596 -244.749232)
			(xy 115.643134 -244.77033) (xy 115.595863 -244.784022) (xy 115.547008 -244.789954) (xy 115.497833 -244.787973)
			(xy 115.449614 -244.778129) (xy 115.403598 -244.760677) (xy 115.360977 -244.73607) (xy 115.322856 -244.704945)
			(xy 115.290221 -244.668108) (xy 115.263918 -244.626512) (xy 115.244627 -244.581236) (xy 115.23285 -244.533452)
			(xy 115.22889 -244.484398) (xy 114.899948 -244.484398) (xy 114.899453 -244.509005) (xy 114.891558 -244.557582)
			(xy 114.875974 -244.604263) (xy 114.853103 -244.64784) (xy 114.823538 -244.687184) (xy 114.788045 -244.721276)
			(xy 114.747542 -244.749232) (xy 114.70308 -244.77033) (xy 114.655809 -244.784022) (xy 114.606954 -244.789954)
			(xy 114.557779 -244.787973) (xy 114.50956 -244.778129) (xy 114.463544 -244.760677) (xy 114.420923 -244.73607)
			(xy 114.382802 -244.704945) (xy 114.350167 -244.668108) (xy 114.323864 -244.626512) (xy 114.304573 -244.581236)
			(xy 114.292796 -244.533452) (xy 114.288836 -244.484398) (xy 113.960148 -244.484398) (xy 113.959653 -244.509005)
			(xy 113.951758 -244.557582) (xy 113.936174 -244.604263) (xy 113.913303 -244.64784) (xy 113.883738 -244.687184)
			(xy 113.848245 -244.721276) (xy 113.807742 -244.749232) (xy 113.76328 -244.77033) (xy 113.716009 -244.784022)
			(xy 113.667154 -244.789954) (xy 113.617979 -244.787973) (xy 113.56976 -244.778129) (xy 113.523744 -244.760677)
			(xy 113.481123 -244.73607) (xy 113.443002 -244.704945) (xy 113.410367 -244.668108) (xy 113.384064 -244.626512)
			(xy 113.364773 -244.581236) (xy 113.352996 -244.533452) (xy 113.349036 -244.484398) (xy 110.206282 -244.484398)
			(xy 110.205787 -244.509005) (xy 110.197892 -244.557582) (xy 110.182308 -244.604263) (xy 110.159437 -244.64784)
			(xy 110.129872 -244.687184) (xy 110.094379 -244.721276) (xy 110.053876 -244.749232) (xy 110.009414 -244.77033)
			(xy 109.962143 -244.784022) (xy 109.913288 -244.789954) (xy 109.864113 -244.787973) (xy 109.815894 -244.778129)
			(xy 109.769878 -244.760677) (xy 109.727257 -244.73607) (xy 109.689136 -244.704945) (xy 109.656501 -244.668108)
			(xy 109.630198 -244.626512) (xy 109.610907 -244.581236) (xy 109.59913 -244.533452) (xy 109.59517 -244.484398)
			(xy 109.266482 -244.484398) (xy 109.265987 -244.509005) (xy 109.258092 -244.557582) (xy 109.242508 -244.604263)
			(xy 109.219637 -244.64784) (xy 109.190072 -244.687184) (xy 109.154579 -244.721276) (xy 109.114076 -244.749232)
			(xy 109.069614 -244.77033) (xy 109.022343 -244.784022) (xy 108.973488 -244.789954) (xy 108.924313 -244.787973)
			(xy 108.876094 -244.778129) (xy 108.830078 -244.760677) (xy 108.787457 -244.73607) (xy 108.749336 -244.704945)
			(xy 108.716701 -244.668108) (xy 108.690398 -244.626512) (xy 108.671107 -244.581236) (xy 108.65933 -244.533452)
			(xy 108.65537 -244.484398) (xy 108.326428 -244.484398) (xy 108.325933 -244.509005) (xy 108.318038 -244.557582)
			(xy 108.302454 -244.604263) (xy 108.279583 -244.64784) (xy 108.250018 -244.687184) (xy 108.214525 -244.721276)
			(xy 108.174022 -244.749232) (xy 108.12956 -244.77033) (xy 108.082289 -244.784022) (xy 108.033434 -244.789954)
			(xy 107.984259 -244.787973) (xy 107.93604 -244.778129) (xy 107.890024 -244.760677) (xy 107.847403 -244.73607)
			(xy 107.809282 -244.704945) (xy 107.776647 -244.668108) (xy 107.750344 -244.626512) (xy 107.731053 -244.581236)
			(xy 107.719276 -244.533452) (xy 107.715316 -244.484398) (xy 107.387213 -244.484398) (xy 107.387213 -244.4844)
			(xy 107.383037 -244.534788) (xy 107.370624 -244.583801) (xy 107.350313 -244.630103) (xy 107.322657 -244.67243)
			(xy 107.288411 -244.709626) (xy 107.24851 -244.740679) (xy 107.204041 -244.76474) (xy 107.156218 -244.781153)
			(xy 107.106346 -244.78947) (xy 107.081066 -244.78996) (xy 106.141012 -244.78996) (xy 106.115732 -244.789472)
			(xy 106.065863 -244.781152) (xy 106.018043 -244.764737) (xy 105.973577 -244.740675) (xy 105.933678 -244.709622)
			(xy 105.899434 -244.672425) (xy 105.87178 -244.630099) (xy 105.851471 -244.583798) (xy 105.839059 -244.534786)
			(xy 105.834883 -244.4844) (xy 105.506266 -244.4844) (xy 105.505771 -244.509005) (xy 105.497876 -244.557582)
			(xy 105.482292 -244.604263) (xy 105.459421 -244.64784) (xy 105.429856 -244.687184) (xy 105.394363 -244.721276)
			(xy 105.35386 -244.749232) (xy 105.309398 -244.77033) (xy 105.262127 -244.784022) (xy 105.213272 -244.789954)
			(xy 105.164097 -244.787973) (xy 105.115878 -244.778129) (xy 105.069862 -244.760677) (xy 105.027241 -244.73607)
			(xy 104.98912 -244.704945) (xy 104.956485 -244.668108) (xy 104.930182 -244.626512) (xy 104.910891 -244.581236)
			(xy 104.899114 -244.533452) (xy 104.895154 -244.484398) (xy 104.567313 -244.484398) (xy 104.567313 -244.4844)
			(xy 104.563137 -244.534789) (xy 104.550724 -244.583803) (xy 104.530412 -244.630105) (xy 104.502755 -244.672432)
			(xy 104.468508 -244.709629) (xy 104.428605 -244.740682) (xy 104.384136 -244.764742) (xy 104.336312 -244.781154)
			(xy 104.286439 -244.78947) (xy 104.261158 -244.78996) (xy 103.321104 -244.78996) (xy 103.295825 -244.789471)
			(xy 103.245956 -244.78115) (xy 103.198137 -244.764735) (xy 103.153672 -244.740672) (xy 103.113774 -244.709619)
			(xy 103.079532 -244.672422) (xy 103.051879 -244.630096) (xy 103.03157 -244.583797) (xy 103.019159 -244.534786)
			(xy 103.014983 -244.4844) (xy 102.686358 -244.4844) (xy 102.685863 -244.509005) (xy 102.677968 -244.557582)
			(xy 102.662384 -244.604263) (xy 102.639513 -244.64784) (xy 102.609948 -244.687184) (xy 102.574455 -244.721276)
			(xy 102.533952 -244.749232) (xy 102.48949 -244.77033) (xy 102.442219 -244.784022) (xy 102.393364 -244.789954)
			(xy 102.344189 -244.787973) (xy 102.29597 -244.778129) (xy 102.249954 -244.760677) (xy 102.207333 -244.73607)
			(xy 102.169212 -244.704945) (xy 102.136577 -244.668108) (xy 102.110274 -244.626512) (xy 102.090983 -244.581236)
			(xy 102.079206 -244.533452) (xy 102.075246 -244.484398) (xy 101.747113 -244.484398) (xy 101.747113 -244.4844)
			(xy 101.742937 -244.534785) (xy 101.730526 -244.583795) (xy 101.710217 -244.630095) (xy 101.682565 -244.67242)
			(xy 101.648323 -244.709616) (xy 101.608426 -244.740669) (xy 101.563961 -244.764731) (xy 101.516143 -244.781146)
			(xy 101.466275 -244.789467) (xy 101.440996 -244.78996) (xy 100.500942 -244.78996) (xy 100.475661 -244.789474)
			(xy 100.425787 -244.781158) (xy 100.377963 -244.764746) (xy 100.333492 -244.740685) (xy 100.293589 -244.709632)
			(xy 100.259342 -244.672435) (xy 100.231685 -244.630107) (xy 100.211373 -244.583804) (xy 100.198959 -244.534789)
			(xy 100.194783 -244.4844) (xy 99.86645 -244.4844) (xy 99.865955 -244.509005) (xy 99.85806 -244.557582)
			(xy 99.842476 -244.604263) (xy 99.819605 -244.64784) (xy 99.79004 -244.687184) (xy 99.754547 -244.721276)
			(xy 99.714044 -244.749232) (xy 99.669582 -244.77033) (xy 99.622311 -244.784022) (xy 99.573456 -244.789954)
			(xy 99.524281 -244.787973) (xy 99.476062 -244.778129) (xy 99.430046 -244.760677) (xy 99.387425 -244.73607)
			(xy 99.349304 -244.704945) (xy 99.316669 -244.668108) (xy 99.290366 -244.626512) (xy 99.271075 -244.581236)
			(xy 99.259298 -244.533452) (xy 99.255338 -244.484398) (xy 98.927213 -244.484398) (xy 98.927213 -244.4844)
			(xy 98.923037 -244.534786) (xy 98.910626 -244.583797) (xy 98.890316 -244.630097) (xy 98.862663 -244.672422)
			(xy 98.82842 -244.709619) (xy 98.788521 -244.740671) (xy 98.744056 -244.764733) (xy 98.696236 -244.781148)
			(xy 98.646367 -244.789468) (xy 98.621088 -244.78996) (xy 97.681034 -244.78996) (xy 97.655753 -244.789474)
			(xy 97.605881 -244.781156) (xy 97.558057 -244.764743) (xy 97.513588 -244.740682) (xy 97.473686 -244.709629)
			(xy 97.43944 -244.672432) (xy 97.411784 -244.630105) (xy 97.391472 -244.583803) (xy 97.379059 -244.534789)
			(xy 97.374883 -244.4844) (xy 97.046926 -244.4844) (xy 97.042838 -244.534243) (xy 97.030684 -244.582755)
			(xy 97.010789 -244.628638) (xy 96.983684 -244.670667) (xy 96.950093 -244.707718) (xy 96.910915 -244.738801)
			(xy 96.867196 -244.763085) (xy 96.820104 -244.779922) (xy 96.79559 -244.78488) (xy 96.787716 -244.786404)
			(xy 96.76638 -244.797834) (xy 96.758506 -244.802152) (xy 96.738948 -244.823742) (xy 96.733052 -244.830991)
			(xy 96.726418 -244.848443) (xy 96.725994 -244.857778) (xy 96.725994 -245.294404) (xy 98.785184 -245.294404)
			(xy 98.789144 -245.24535) (xy 98.800921 -245.197566) (xy 98.820212 -245.15229) (xy 98.846515 -245.110694)
			(xy 98.87915 -245.073857) (xy 98.917271 -245.042732) (xy 98.959892 -245.018125) (xy 99.005908 -245.000673)
			(xy 99.054127 -244.990829) (xy 99.103302 -244.988848) (xy 99.152157 -244.99478) (xy 99.199428 -245.008472)
			(xy 99.24389 -245.02957) (xy 99.284393 -245.057526) (xy 99.319886 -245.091618) (xy 99.349451 -245.130962)
			(xy 99.372322 -245.174539) (xy 99.387906 -245.22122) (xy 99.395801 -245.269797) (xy 99.396296 -245.294404)
			(xy 101.605346 -245.294404) (xy 101.609306 -245.24535) (xy 101.621083 -245.197566) (xy 101.640374 -245.15229)
			(xy 101.666677 -245.110694) (xy 101.699312 -245.073857) (xy 101.737433 -245.042732) (xy 101.780054 -245.018125)
			(xy 101.82607 -245.000673) (xy 101.874289 -244.990829) (xy 101.923464 -244.988848) (xy 101.972319 -244.99478)
			(xy 102.01959 -245.008472) (xy 102.064052 -245.02957) (xy 102.104555 -245.057526) (xy 102.140048 -245.091618)
			(xy 102.169613 -245.130962) (xy 102.192484 -245.174539) (xy 102.208068 -245.22122) (xy 102.215963 -245.269797)
			(xy 102.216458 -245.294404) (xy 104.425254 -245.294404) (xy 104.429214 -245.24535) (xy 104.440991 -245.197566)
			(xy 104.460282 -245.15229) (xy 104.486585 -245.110694) (xy 104.51922 -245.073857) (xy 104.557341 -245.042732)
			(xy 104.599962 -245.018125) (xy 104.645978 -245.000673) (xy 104.694197 -244.990829) (xy 104.743372 -244.988848)
			(xy 104.792227 -244.99478) (xy 104.839498 -245.008472) (xy 104.88396 -245.02957) (xy 104.924463 -245.057526)
			(xy 104.959956 -245.091618) (xy 104.989521 -245.130962) (xy 105.012392 -245.174539) (xy 105.027976 -245.22122)
			(xy 105.035871 -245.269797) (xy 105.036366 -245.294404) (xy 107.245162 -245.294404) (xy 107.249122 -245.24535)
			(xy 107.260899 -245.197566) (xy 107.28019 -245.15229) (xy 107.306493 -245.110694) (xy 107.339128 -245.073857)
			(xy 107.377249 -245.042732) (xy 107.41987 -245.018125) (xy 107.465886 -245.000673) (xy 107.514105 -244.990829)
			(xy 107.56328 -244.988848) (xy 107.612135 -244.99478) (xy 107.659406 -245.008472) (xy 107.703868 -245.02957)
			(xy 107.744371 -245.057526) (xy 107.779864 -245.091618) (xy 107.809429 -245.130962) (xy 107.8323 -245.174539)
			(xy 107.847884 -245.22122) (xy 107.855779 -245.269797) (xy 107.856274 -245.2944) (xy 108.185144 -245.2944)
			(xy 108.189316 -245.244056) (xy 108.201717 -245.195085) (xy 108.222011 -245.148823) (xy 108.249642 -245.106533)
			(xy 108.283857 -245.069367) (xy 108.323723 -245.038341) (xy 108.368153 -245.014299) (xy 108.415933 -244.997899)
			(xy 108.465762 -244.989587) (xy 108.49102 -244.989096) (xy 109.431074 -244.989096) (xy 109.456333 -244.989579)
			(xy 109.506164 -244.99789) (xy 109.553947 -245.01429) (xy 109.598378 -245.038332) (xy 109.638246 -245.069359)
			(xy 109.672463 -245.106526) (xy 109.700095 -245.148818) (xy 109.72039 -245.195081) (xy 109.732792 -245.244054)
			(xy 109.736964 -245.2944) (xy 109.736964 -245.294404) (xy 110.065324 -245.294404) (xy 110.069284 -245.24535)
			(xy 110.081061 -245.197566) (xy 110.100352 -245.15229) (xy 110.126655 -245.110694) (xy 110.15929 -245.073857)
			(xy 110.197411 -245.042732) (xy 110.240032 -245.018125) (xy 110.286048 -245.000673) (xy 110.334267 -244.990829)
			(xy 110.383442 -244.988848) (xy 110.432297 -244.99478) (xy 110.479568 -245.008472) (xy 110.52403 -245.02957)
			(xy 110.564533 -245.057526) (xy 110.600026 -245.091618) (xy 110.629591 -245.130962) (xy 110.652462 -245.174539)
			(xy 110.668046 -245.22122) (xy 110.675941 -245.269797) (xy 110.676436 -245.294404) (xy 110.675941 -245.319011)
			(xy 110.668046 -245.367588) (xy 110.652462 -245.414269) (xy 110.629591 -245.457846) (xy 110.600026 -245.49719)
			(xy 110.564533 -245.531282) (xy 110.534206 -245.552214) (xy 111.456473 -245.552214) (xy 111.460503 -245.499716)
			(xy 111.4725 -245.448448) (xy 111.492183 -245.399613) (xy 111.519089 -245.354354) (xy 111.552589 -245.313733)
			(xy 111.591897 -245.278702) (xy 111.636092 -245.250082) (xy 111.684137 -245.228543) (xy 111.734908 -245.214591)
			(xy 111.787213 -245.208553) (xy 111.839827 -245.21057) (xy 111.891517 -245.220594) (xy 111.94107 -245.238392)
			(xy 111.987326 -245.263545) (xy 112.027809 -245.294404) (xy 112.878882 -245.294404) (xy 112.882842 -245.24535)
			(xy 112.894619 -245.197566) (xy 112.91391 -245.15229) (xy 112.940213 -245.110694) (xy 112.972848 -245.073857)
			(xy 113.010969 -245.042732) (xy 113.05359 -245.018125) (xy 113.099606 -245.000673) (xy 113.147825 -244.990829)
			(xy 113.197 -244.988848) (xy 113.245855 -244.99478) (xy 113.293126 -245.008472) (xy 113.337588 -245.02957)
			(xy 113.378091 -245.057526) (xy 113.413584 -245.091618) (xy 113.443149 -245.130962) (xy 113.46602 -245.174539)
			(xy 113.481604 -245.22122) (xy 113.489499 -245.269797) (xy 113.489994 -245.294404) (xy 113.818936 -245.294404)
			(xy 113.822896 -245.24535) (xy 113.834673 -245.197566) (xy 113.853964 -245.15229) (xy 113.880267 -245.110694)
			(xy 113.912902 -245.073857) (xy 113.951023 -245.042732) (xy 113.993644 -245.018125) (xy 114.03966 -245.000673)
			(xy 114.087879 -244.990829) (xy 114.137054 -244.988848) (xy 114.185909 -244.99478) (xy 114.23318 -245.008472)
			(xy 114.277642 -245.02957) (xy 114.318145 -245.057526) (xy 114.353638 -245.091618) (xy 114.383203 -245.130962)
			(xy 114.406074 -245.174539) (xy 114.421658 -245.22122) (xy 114.429553 -245.269797) (xy 114.430048 -245.294404)
			(xy 114.75899 -245.294404) (xy 114.76295 -245.24535) (xy 114.774727 -245.197566) (xy 114.794018 -245.15229)
			(xy 114.820321 -245.110694) (xy 114.852956 -245.073857) (xy 114.891077 -245.042732) (xy 114.933698 -245.018125)
			(xy 114.979714 -245.000673) (xy 115.027933 -244.990829) (xy 115.077108 -244.988848) (xy 115.125963 -244.99478)
			(xy 115.173234 -245.008472) (xy 115.217696 -245.02957) (xy 115.258199 -245.057526) (xy 115.293692 -245.091618)
			(xy 115.323257 -245.130962) (xy 115.346128 -245.174539) (xy 115.361712 -245.22122) (xy 115.369607 -245.269797)
			(xy 115.370102 -245.294404) (xy 115.699044 -245.294404) (xy 115.703004 -245.24535) (xy 115.714781 -245.197566)
			(xy 115.734072 -245.15229) (xy 115.760375 -245.110694) (xy 115.79301 -245.073857) (xy 115.831131 -245.042732)
			(xy 115.873752 -245.018125) (xy 115.919768 -245.000673) (xy 115.967987 -244.990829) (xy 116.017162 -244.988848)
			(xy 116.066017 -244.99478) (xy 116.113288 -245.008472) (xy 116.15775 -245.02957) (xy 116.198253 -245.057526)
			(xy 116.233746 -245.091618) (xy 116.263311 -245.130962) (xy 116.286182 -245.174539) (xy 116.301766 -245.22122)
			(xy 116.309661 -245.269797) (xy 116.310156 -245.294404) (xy 118.518952 -245.294404) (xy 118.522912 -245.24535)
			(xy 118.534689 -245.197566) (xy 118.55398 -245.15229) (xy 118.580283 -245.110694) (xy 118.612918 -245.073857)
			(xy 118.651039 -245.042732) (xy 118.69366 -245.018125) (xy 118.739676 -245.000673) (xy 118.787895 -244.990829)
			(xy 118.83707 -244.988848) (xy 118.885925 -244.99478) (xy 118.933196 -245.008472) (xy 118.977658 -245.02957)
			(xy 119.018161 -245.057526) (xy 119.053654 -245.091618) (xy 119.083219 -245.130962) (xy 119.10609 -245.174539)
			(xy 119.121674 -245.22122) (xy 119.129569 -245.269797) (xy 119.130064 -245.294404) (xy 121.33886 -245.294404)
			(xy 121.34282 -245.24535) (xy 121.354597 -245.197566) (xy 121.373888 -245.15229) (xy 121.400191 -245.110694)
			(xy 121.432826 -245.073857) (xy 121.470947 -245.042732) (xy 121.513568 -245.018125) (xy 121.559584 -245.000673)
			(xy 121.607803 -244.990829) (xy 121.656978 -244.988848) (xy 121.705833 -244.99478) (xy 121.753104 -245.008472)
			(xy 121.797566 -245.02957) (xy 121.838069 -245.057526) (xy 121.873562 -245.091618) (xy 121.903127 -245.130962)
			(xy 121.925998 -245.174539) (xy 121.941582 -245.22122) (xy 121.949477 -245.269797) (xy 121.949972 -245.294404)
			(xy 124.159022 -245.294404) (xy 124.162982 -245.24535) (xy 124.174759 -245.197566) (xy 124.19405 -245.15229)
			(xy 124.220353 -245.110694) (xy 124.252988 -245.073857) (xy 124.291109 -245.042732) (xy 124.33373 -245.018125)
			(xy 124.379746 -245.000673) (xy 124.427965 -244.990829) (xy 124.47714 -244.988848) (xy 124.525995 -244.99478)
			(xy 124.573266 -245.008472) (xy 124.617728 -245.02957) (xy 124.658231 -245.057526) (xy 124.693724 -245.091618)
			(xy 124.723289 -245.130962) (xy 124.74616 -245.174539) (xy 124.761744 -245.22122) (xy 124.769639 -245.269797)
			(xy 124.770134 -245.294404) (xy 124.769639 -245.319011) (xy 124.761744 -245.367588) (xy 124.74616 -245.414269)
			(xy 124.723289 -245.457846) (xy 124.693724 -245.49719) (xy 124.658231 -245.531282) (xy 124.617728 -245.559238)
			(xy 124.573266 -245.580336) (xy 124.525995 -245.594028) (xy 124.47714 -245.59996) (xy 124.427965 -245.597979)
			(xy 124.379746 -245.588135) (xy 124.33373 -245.570683) (xy 124.291109 -245.546076) (xy 124.252988 -245.514951)
			(xy 124.220353 -245.478114) (xy 124.19405 -245.436518) (xy 124.174759 -245.391242) (xy 124.162982 -245.343458)
			(xy 124.159022 -245.294404) (xy 121.949972 -245.294404) (xy 121.949477 -245.319011) (xy 121.941582 -245.367588)
			(xy 121.925998 -245.414269) (xy 121.903127 -245.457846) (xy 121.873562 -245.49719) (xy 121.838069 -245.531282)
			(xy 121.797566 -245.559238) (xy 121.753104 -245.580336) (xy 121.705833 -245.594028) (xy 121.656978 -245.59996)
			(xy 121.607803 -245.597979) (xy 121.559584 -245.588135) (xy 121.513568 -245.570683) (xy 121.470947 -245.546076)
			(xy 121.432826 -245.514951) (xy 121.400191 -245.478114) (xy 121.373888 -245.436518) (xy 121.354597 -245.391242)
			(xy 121.34282 -245.343458) (xy 121.33886 -245.294404) (xy 119.130064 -245.294404) (xy 119.129569 -245.319011)
			(xy 119.121674 -245.367588) (xy 119.10609 -245.414269) (xy 119.083219 -245.457846) (xy 119.053654 -245.49719)
			(xy 119.018161 -245.531282) (xy 118.977658 -245.559238) (xy 118.933196 -245.580336) (xy 118.885925 -245.594028)
			(xy 118.83707 -245.59996) (xy 118.787895 -245.597979) (xy 118.739676 -245.588135) (xy 118.69366 -245.570683)
			(xy 118.651039 -245.546076) (xy 118.612918 -245.514951) (xy 118.580283 -245.478114) (xy 118.55398 -245.436518)
			(xy 118.534689 -245.391242) (xy 118.522912 -245.343458) (xy 118.518952 -245.294404) (xy 116.310156 -245.294404)
			(xy 116.309661 -245.319011) (xy 116.301766 -245.367588) (xy 116.286182 -245.414269) (xy 116.263311 -245.457846)
			(xy 116.233746 -245.49719) (xy 116.198253 -245.531282) (xy 116.15775 -245.559238) (xy 116.113288 -245.580336)
			(xy 116.066017 -245.594028) (xy 116.017162 -245.59996) (xy 115.967987 -245.597979) (xy 115.919768 -245.588135)
			(xy 115.873752 -245.570683) (xy 115.831131 -245.546076) (xy 115.79301 -245.514951) (xy 115.760375 -245.478114)
			(xy 115.734072 -245.436518) (xy 115.714781 -245.391242) (xy 115.703004 -245.343458) (xy 115.699044 -245.294404)
			(xy 115.370102 -245.294404) (xy 115.369607 -245.319011) (xy 115.361712 -245.367588) (xy 115.346128 -245.414269)
			(xy 115.323257 -245.457846) (xy 115.293692 -245.49719) (xy 115.258199 -245.531282) (xy 115.217696 -245.559238)
			(xy 115.173234 -245.580336) (xy 115.125963 -245.594028) (xy 115.077108 -245.59996) (xy 115.027933 -245.597979)
			(xy 114.979714 -245.588135) (xy 114.933698 -245.570683) (xy 114.891077 -245.546076) (xy 114.852956 -245.514951)
			(xy 114.820321 -245.478114) (xy 114.794018 -245.436518) (xy 114.774727 -245.391242) (xy 114.76295 -245.343458)
			(xy 114.75899 -245.294404) (xy 114.430048 -245.294404) (xy 114.429553 -245.319011) (xy 114.421658 -245.367588)
			(xy 114.406074 -245.414269) (xy 114.383203 -245.457846) (xy 114.353638 -245.49719) (xy 114.318145 -245.531282)
			(xy 114.277642 -245.559238) (xy 114.23318 -245.580336) (xy 114.185909 -245.594028) (xy 114.137054 -245.59996)
			(xy 114.087879 -245.597979) (xy 114.03966 -245.588135) (xy 113.993644 -245.570683) (xy 113.951023 -245.546076)
			(xy 113.912902 -245.514951) (xy 113.880267 -245.478114) (xy 113.853964 -245.436518) (xy 113.834673 -245.391242)
			(xy 113.822896 -245.343458) (xy 113.818936 -245.294404) (xy 113.489994 -245.294404) (xy 113.489499 -245.319011)
			(xy 113.481604 -245.367588) (xy 113.46602 -245.414269) (xy 113.443149 -245.457846) (xy 113.413584 -245.49719)
			(xy 113.378091 -245.531282) (xy 113.337588 -245.559238) (xy 113.293126 -245.580336) (xy 113.245855 -245.594028)
			(xy 113.197 -245.59996) (xy 113.147825 -245.597979) (xy 113.099606 -245.588135) (xy 113.05359 -245.570683)
			(xy 113.010969 -245.546076) (xy 112.972848 -245.514951) (xy 112.940213 -245.478114) (xy 112.91391 -245.436518)
			(xy 112.894619 -245.391242) (xy 112.882842 -245.343458) (xy 112.878882 -245.294404) (xy 112.027809 -245.294404)
			(xy 112.0292 -245.295464) (xy 112.065712 -245.333402) (xy 112.096004 -245.376468) (xy 112.119367 -245.423653)
			(xy 112.135253 -245.473852) (xy 112.14329 -245.525888) (xy 112.143794 -245.552214) (xy 112.14329 -245.57854)
			(xy 112.135253 -245.630576) (xy 112.119367 -245.680775) (xy 112.096004 -245.72796) (xy 112.065712 -245.771026)
			(xy 112.0292 -245.808964) (xy 111.987326 -245.840883) (xy 111.94107 -245.866036) (xy 111.891517 -245.883834)
			(xy 111.839827 -245.893858) (xy 111.787213 -245.895875) (xy 111.734908 -245.889837) (xy 111.684137 -245.875885)
			(xy 111.636092 -245.854346) (xy 111.591897 -245.825726) (xy 111.552589 -245.790695) (xy 111.519089 -245.750074)
			(xy 111.492183 -245.704815) (xy 111.4725 -245.65598) (xy 111.460503 -245.604712) (xy 111.456473 -245.552214)
			(xy 110.534206 -245.552214) (xy 110.52403 -245.559238) (xy 110.479568 -245.580336) (xy 110.432297 -245.594028)
			(xy 110.383442 -245.59996) (xy 110.334267 -245.597979) (xy 110.286048 -245.588135) (xy 110.240032 -245.570683)
			(xy 110.197411 -245.546076) (xy 110.15929 -245.514951) (xy 110.126655 -245.478114) (xy 110.100352 -245.436518)
			(xy 110.081061 -245.391242) (xy 110.069284 -245.343458) (xy 110.065324 -245.294404) (xy 109.736964 -245.294404)
			(xy 109.732792 -245.344746) (xy 109.72039 -245.393719) (xy 109.700095 -245.439982) (xy 109.672463 -245.482274)
			(xy 109.638246 -245.519441) (xy 109.598378 -245.550468) (xy 109.553947 -245.57451) (xy 109.506164 -245.59091)
			(xy 109.456333 -245.599221) (xy 109.431074 -245.599712) (xy 108.49102 -245.599712) (xy 108.465762 -245.599213)
			(xy 108.415933 -245.590901) (xy 108.368153 -245.574501) (xy 108.323723 -245.550459) (xy 108.283857 -245.519433)
			(xy 108.249642 -245.482267) (xy 108.222011 -245.439977) (xy 108.201717 -245.393715) (xy 108.189316 -245.344744)
			(xy 108.185144 -245.2944) (xy 107.856274 -245.2944) (xy 107.856274 -245.294404) (xy 107.855779 -245.319011)
			(xy 107.847884 -245.367588) (xy 107.8323 -245.414269) (xy 107.809429 -245.457846) (xy 107.779864 -245.49719)
			(xy 107.744371 -245.531282) (xy 107.703868 -245.559238) (xy 107.659406 -245.580336) (xy 107.612135 -245.594028)
			(xy 107.56328 -245.59996) (xy 107.514105 -245.597979) (xy 107.465886 -245.588135) (xy 107.41987 -245.570683)
			(xy 107.377249 -245.546076) (xy 107.339128 -245.514951) (xy 107.306493 -245.478114) (xy 107.28019 -245.436518)
			(xy 107.260899 -245.391242) (xy 107.249122 -245.343458) (xy 107.245162 -245.294404) (xy 105.036366 -245.294404)
			(xy 105.035871 -245.319011) (xy 105.027976 -245.367588) (xy 105.012392 -245.414269) (xy 104.989521 -245.457846)
			(xy 104.959956 -245.49719) (xy 104.924463 -245.531282) (xy 104.88396 -245.559238) (xy 104.839498 -245.580336)
			(xy 104.792227 -245.594028) (xy 104.743372 -245.59996) (xy 104.694197 -245.597979) (xy 104.645978 -245.588135)
			(xy 104.599962 -245.570683) (xy 104.557341 -245.546076) (xy 104.51922 -245.514951) (xy 104.486585 -245.478114)
			(xy 104.460282 -245.436518) (xy 104.440991 -245.391242) (xy 104.429214 -245.343458) (xy 104.425254 -245.294404)
			(xy 102.216458 -245.294404) (xy 102.215963 -245.319011) (xy 102.208068 -245.367588) (xy 102.192484 -245.414269)
			(xy 102.169613 -245.457846) (xy 102.140048 -245.49719) (xy 102.104555 -245.531282) (xy 102.064052 -245.559238)
			(xy 102.01959 -245.580336) (xy 101.972319 -245.594028) (xy 101.923464 -245.59996) (xy 101.874289 -245.597979)
			(xy 101.82607 -245.588135) (xy 101.780054 -245.570683) (xy 101.737433 -245.546076) (xy 101.699312 -245.514951)
			(xy 101.666677 -245.478114) (xy 101.640374 -245.436518) (xy 101.621083 -245.391242) (xy 101.609306 -245.343458)
			(xy 101.605346 -245.294404) (xy 99.396296 -245.294404) (xy 99.395801 -245.319011) (xy 99.387906 -245.367588)
			(xy 99.372322 -245.414269) (xy 99.349451 -245.457846) (xy 99.319886 -245.49719) (xy 99.284393 -245.531282)
			(xy 99.24389 -245.559238) (xy 99.199428 -245.580336) (xy 99.152157 -245.594028) (xy 99.103302 -245.59996)
			(xy 99.054127 -245.597979) (xy 99.005908 -245.588135) (xy 98.959892 -245.570683) (xy 98.917271 -245.546076)
			(xy 98.87915 -245.514951) (xy 98.846515 -245.478114) (xy 98.820212 -245.436518) (xy 98.800921 -245.391242)
			(xy 98.789144 -245.343458) (xy 98.785184 -245.294404) (xy 96.725994 -245.294404) (xy 96.725994 -245.73103)
			(xy 96.726301 -245.740388) (xy 96.732947 -245.75788) (xy 96.738948 -245.765066) (xy 96.758506 -245.786656)
			(xy 96.76638 -245.790974) (xy 96.787716 -245.802404) (xy 96.79559 -245.803928) (xy 96.820102 -245.80889)
			(xy 96.867192 -245.825726) (xy 96.910909 -245.85001) (xy 96.950086 -245.881092) (xy 96.983675 -245.918142)
			(xy 97.010779 -245.960169) (xy 97.030674 -246.00605) (xy 97.042827 -246.05456) (xy 97.046914 -246.1044)
			(xy 97.374895 -246.1044) (xy 97.379071 -246.054013) (xy 97.391483 -246.005001) (xy 97.411794 -245.958701)
			(xy 97.439449 -245.916375) (xy 97.473694 -245.879179) (xy 97.513595 -245.848128) (xy 97.558062 -245.824068)
			(xy 97.605884 -245.807655) (xy 97.655754 -245.799338) (xy 97.681034 -245.798848) (xy 98.621088 -245.798848)
			(xy 98.646368 -245.79932) (xy 98.696239 -245.80764) (xy 98.744061 -245.824056) (xy 98.788528 -245.848119)
			(xy 98.828428 -245.879173) (xy 98.862672 -245.91637) (xy 98.890327 -245.958698) (xy 98.910637 -246.004999)
			(xy 98.923049 -246.054012) (xy 98.927225 -246.1044) (xy 98.927224 -246.10441) (xy 99.255338 -246.10441)
			(xy 99.259298 -246.055356) (xy 99.271075 -246.007572) (xy 99.290366 -245.962296) (xy 99.316669 -245.9207)
			(xy 99.349304 -245.883863) (xy 99.387425 -245.852738) (xy 99.430046 -245.828131) (xy 99.476062 -245.810679)
			(xy 99.524281 -245.800835) (xy 99.573456 -245.798854) (xy 99.622311 -245.804786) (xy 99.669582 -245.818478)
			(xy 99.714044 -245.839576) (xy 99.754547 -245.867532) (xy 99.79004 -245.901624) (xy 99.819605 -245.940968)
			(xy 99.842476 -245.984545) (xy 99.85806 -246.031226) (xy 99.865955 -246.079803) (xy 99.86645 -246.1044)
			(xy 100.194795 -246.1044) (xy 100.198971 -246.054012) (xy 100.211384 -246.005) (xy 100.231695 -245.958699)
			(xy 100.259351 -245.916373) (xy 100.293597 -245.879177) (xy 100.333499 -245.848125) (xy 100.377968 -245.824065)
			(xy 100.42579 -245.807654) (xy 100.475662 -245.799338) (xy 100.500942 -245.798848) (xy 101.440996 -245.798848)
			(xy 101.466276 -245.799321) (xy 101.516146 -245.807642) (xy 101.563966 -245.824058) (xy 101.608432 -245.848121)
			(xy 101.648331 -245.879175) (xy 101.682574 -245.916373) (xy 101.710228 -245.9587) (xy 101.730538 -246.005001)
			(xy 101.742949 -246.054013) (xy 101.747125 -246.1044) (xy 101.747124 -246.10441) (xy 102.075246 -246.10441)
			(xy 102.079206 -246.055356) (xy 102.090983 -246.007572) (xy 102.110274 -245.962296) (xy 102.136577 -245.9207)
			(xy 102.169212 -245.883863) (xy 102.207333 -245.852738) (xy 102.249954 -245.828131) (xy 102.29597 -245.810679)
			(xy 102.344189 -245.800835) (xy 102.393364 -245.798854) (xy 102.442219 -245.804786) (xy 102.48949 -245.818478)
			(xy 102.533952 -245.839576) (xy 102.574455 -245.867532) (xy 102.609948 -245.901624) (xy 102.639513 -245.940968)
			(xy 102.662384 -245.984545) (xy 102.677968 -246.031226) (xy 102.685863 -246.079803) (xy 102.686358 -246.1044)
			(xy 103.014995 -246.1044) (xy 103.01917 -246.054016) (xy 103.031581 -246.005007) (xy 103.05189 -245.958709)
			(xy 103.079542 -245.916385) (xy 103.113783 -245.87919) (xy 103.153679 -245.848138) (xy 103.198142 -245.824076)
			(xy 103.245959 -245.807661) (xy 103.295826 -245.799341) (xy 103.321104 -245.798848) (xy 104.261158 -245.798848)
			(xy 104.28644 -245.799318) (xy 104.336315 -245.807634) (xy 104.38414 -245.824047) (xy 104.428612 -245.848108)
			(xy 104.468516 -245.879162) (xy 104.502764 -245.91636) (xy 104.530422 -245.958689) (xy 104.550735 -246.004993)
			(xy 104.563149 -246.054009) (xy 104.567325 -246.1044) (xy 104.567324 -246.10441) (xy 104.895154 -246.10441)
			(xy 104.899114 -246.055356) (xy 104.910891 -246.007572) (xy 104.930182 -245.962296) (xy 104.956485 -245.9207)
			(xy 104.98912 -245.883863) (xy 105.027241 -245.852738) (xy 105.069862 -245.828131) (xy 105.115878 -245.810679)
			(xy 105.164097 -245.800835) (xy 105.213272 -245.798854) (xy 105.262127 -245.804786) (xy 105.309398 -245.818478)
			(xy 105.35386 -245.839576) (xy 105.394363 -245.867532) (xy 105.429856 -245.901624) (xy 105.459421 -245.940968)
			(xy 105.482292 -245.984545) (xy 105.497876 -246.031226) (xy 105.505771 -246.079803) (xy 105.506266 -246.1044)
			(xy 105.834895 -246.1044) (xy 105.839071 -246.054016) (xy 105.851482 -246.005006) (xy 105.871791 -245.958707)
			(xy 105.899444 -245.916383) (xy 105.933686 -245.879187) (xy 105.973583 -245.848135) (xy 106.018047 -245.824074)
			(xy 106.065866 -245.80766) (xy 106.115733 -245.79934) (xy 106.141012 -245.798848) (xy 107.081066 -245.798848)
			(xy 107.106347 -245.799318) (xy 107.156221 -245.807636) (xy 107.204046 -245.824049) (xy 107.248516 -245.848111)
			(xy 107.288419 -245.879165) (xy 107.322666 -245.916363) (xy 107.350323 -245.958691) (xy 107.370636 -246.004995)
			(xy 107.383049 -246.05401) (xy 107.387225 -246.1044) (xy 107.387224 -246.10441) (xy 107.715316 -246.10441)
			(xy 107.719276 -246.055356) (xy 107.731053 -246.007572) (xy 107.750344 -245.962296) (xy 107.776647 -245.9207)
			(xy 107.809282 -245.883863) (xy 107.847403 -245.852738) (xy 107.890024 -245.828131) (xy 107.93604 -245.810679)
			(xy 107.984259 -245.800835) (xy 108.033434 -245.798854) (xy 108.082289 -245.804786) (xy 108.12956 -245.818478)
			(xy 108.174022 -245.839576) (xy 108.214525 -245.867532) (xy 108.250018 -245.901624) (xy 108.279583 -245.940968)
			(xy 108.302454 -245.984545) (xy 108.318038 -246.031226) (xy 108.325933 -246.079803) (xy 108.326428 -246.10441)
			(xy 115.22889 -246.10441) (xy 115.23285 -246.055356) (xy 115.244627 -246.007572) (xy 115.263918 -245.962296)
			(xy 115.290221 -245.9207) (xy 115.322856 -245.883863) (xy 115.360977 -245.852738) (xy 115.403598 -245.828131)
			(xy 115.449614 -245.810679) (xy 115.497833 -245.800835) (xy 115.547008 -245.798854) (xy 115.595863 -245.804786)
			(xy 115.643134 -245.818478) (xy 115.687596 -245.839576) (xy 115.728099 -245.867532) (xy 115.763592 -245.901624)
			(xy 115.793157 -245.940968) (xy 115.816028 -245.984545) (xy 115.831612 -246.031226) (xy 115.839507 -246.079803)
			(xy 115.840002 -246.10441) (xy 116.168944 -246.10441) (xy 116.172904 -246.055356) (xy 116.184681 -246.007572)
			(xy 116.203972 -245.962296) (xy 116.230275 -245.9207) (xy 116.26291 -245.883863) (xy 116.301031 -245.852738)
			(xy 116.343652 -245.828131) (xy 116.389668 -245.810679) (xy 116.437887 -245.800835) (xy 116.487062 -245.798854)
			(xy 116.535917 -245.804786) (xy 116.583188 -245.818478) (xy 116.62765 -245.839576) (xy 116.668153 -245.867532)
			(xy 116.703646 -245.901624) (xy 116.733211 -245.940968) (xy 116.756082 -245.984545) (xy 116.771666 -246.031226)
			(xy 116.779561 -246.079803) (xy 116.780056 -246.10441) (xy 117.108998 -246.10441) (xy 117.112958 -246.055356)
			(xy 117.124735 -246.007572) (xy 117.144026 -245.962296) (xy 117.170329 -245.9207) (xy 117.202964 -245.883863)
			(xy 117.241085 -245.852738) (xy 117.283706 -245.828131) (xy 117.329722 -245.810679) (xy 117.377941 -245.800835)
			(xy 117.427116 -245.798854) (xy 117.475971 -245.804786) (xy 117.523242 -245.818478) (xy 117.567704 -245.839576)
			(xy 117.608207 -245.867532) (xy 117.6437 -245.901624) (xy 117.673265 -245.940968) (xy 117.696136 -245.984545)
			(xy 117.71172 -246.031226) (xy 117.719615 -246.079803) (xy 117.72011 -246.10441) (xy 118.049052 -246.10441)
			(xy 118.053012 -246.055356) (xy 118.064789 -246.007572) (xy 118.08408 -245.962296) (xy 118.110383 -245.9207)
			(xy 118.143018 -245.883863) (xy 118.181139 -245.852738) (xy 118.22376 -245.828131) (xy 118.269776 -245.810679)
			(xy 118.317995 -245.800835) (xy 118.36717 -245.798854) (xy 118.416025 -245.804786) (xy 118.463296 -245.818478)
			(xy 118.507758 -245.839576) (xy 118.548261 -245.867532) (xy 118.583754 -245.901624) (xy 118.613319 -245.940968)
			(xy 118.63619 -245.984545) (xy 118.651774 -246.031226) (xy 118.659669 -246.079803) (xy 118.660164 -246.10441)
			(xy 118.988852 -246.10441) (xy 118.992812 -246.055356) (xy 119.004589 -246.007572) (xy 119.02388 -245.962296)
			(xy 119.050183 -245.9207) (xy 119.082818 -245.883863) (xy 119.120939 -245.852738) (xy 119.16356 -245.828131)
			(xy 119.209576 -245.810679) (xy 119.257795 -245.800835) (xy 119.30697 -245.798854) (xy 119.355825 -245.804786)
			(xy 119.403096 -245.818478) (xy 119.447558 -245.839576) (xy 119.488061 -245.867532) (xy 119.523554 -245.901624)
			(xy 119.553119 -245.940968) (xy 119.57599 -245.984545) (xy 119.591574 -246.031226) (xy 119.599469 -246.079803)
			(xy 119.599964 -246.10441) (xy 119.928906 -246.10441) (xy 119.932866 -246.055356) (xy 119.944643 -246.007572)
			(xy 119.963934 -245.962296) (xy 119.990237 -245.9207) (xy 120.022872 -245.883863) (xy 120.060993 -245.852738)
			(xy 120.103614 -245.828131) (xy 120.14963 -245.810679) (xy 120.197849 -245.800835) (xy 120.247024 -245.798854)
			(xy 120.295879 -245.804786) (xy 120.34315 -245.818478) (xy 120.387612 -245.839576) (xy 120.428115 -245.867532)
			(xy 120.463608 -245.901624) (xy 120.493173 -245.940968) (xy 120.516044 -245.984545) (xy 120.531628 -246.031226)
			(xy 120.539523 -246.079803) (xy 120.540018 -246.10441) (xy 120.86896 -246.10441) (xy 120.87292 -246.055356)
			(xy 120.884697 -246.007572) (xy 120.903988 -245.962296) (xy 120.930291 -245.9207) (xy 120.962926 -245.883863)
			(xy 121.001047 -245.852738) (xy 121.043668 -245.828131) (xy 121.089684 -245.810679) (xy 121.137903 -245.800835)
			(xy 121.187078 -245.798854) (xy 121.235933 -245.804786) (xy 121.283204 -245.818478) (xy 121.327666 -245.839576)
			(xy 121.368169 -245.867532) (xy 121.403662 -245.901624) (xy 121.433227 -245.940968) (xy 121.456098 -245.984545)
			(xy 121.471682 -246.031226) (xy 121.479577 -246.079803) (xy 121.480072 -246.10441) (xy 121.809014 -246.10441)
			(xy 121.812974 -246.055356) (xy 121.824751 -246.007572) (xy 121.844042 -245.962296) (xy 121.870345 -245.9207)
			(xy 121.90298 -245.883863) (xy 121.941101 -245.852738) (xy 121.983722 -245.828131) (xy 122.029738 -245.810679)
			(xy 122.077957 -245.800835) (xy 122.127132 -245.798854) (xy 122.175987 -245.804786) (xy 122.223258 -245.818478)
			(xy 122.26772 -245.839576) (xy 122.308223 -245.867532) (xy 122.343716 -245.901624) (xy 122.373281 -245.940968)
			(xy 122.396152 -245.984545) (xy 122.411736 -246.031226) (xy 122.419631 -246.079803) (xy 122.420126 -246.10441)
			(xy 122.748814 -246.10441) (xy 122.752774 -246.055356) (xy 122.764551 -246.007572) (xy 122.783842 -245.962296)
			(xy 122.810145 -245.9207) (xy 122.84278 -245.883863) (xy 122.880901 -245.852738) (xy 122.923522 -245.828131)
			(xy 122.969538 -245.810679) (xy 123.017757 -245.800835) (xy 123.066932 -245.798854) (xy 123.115787 -245.804786)
			(xy 123.163058 -245.818478) (xy 123.20752 -245.839576) (xy 123.248023 -245.867532) (xy 123.283516 -245.901624)
			(xy 123.313081 -245.940968) (xy 123.335952 -245.984545) (xy 123.351536 -246.031226) (xy 123.359431 -246.079803)
			(xy 123.359926 -246.10441) (xy 123.688868 -246.10441) (xy 123.692828 -246.055356) (xy 123.704605 -246.007572)
			(xy 123.723896 -245.962296) (xy 123.750199 -245.9207) (xy 123.782834 -245.883863) (xy 123.820955 -245.852738)
			(xy 123.863576 -245.828131) (xy 123.909592 -245.810679) (xy 123.957811 -245.800835) (xy 124.006986 -245.798854)
			(xy 124.055841 -245.804786) (xy 124.103112 -245.818478) (xy 124.147574 -245.839576) (xy 124.188077 -245.867532)
			(xy 124.22357 -245.901624) (xy 124.253135 -245.940968) (xy 124.276006 -245.984545) (xy 124.29159 -246.031226)
			(xy 124.299485 -246.079803) (xy 124.29998 -246.10441) (xy 124.628922 -246.10441) (xy 124.632882 -246.055356)
			(xy 124.644659 -246.007572) (xy 124.66395 -245.962296) (xy 124.690253 -245.9207) (xy 124.722888 -245.883863)
			(xy 124.761009 -245.852738) (xy 124.80363 -245.828131) (xy 124.849646 -245.810679) (xy 124.897865 -245.800835)
			(xy 124.94704 -245.798854) (xy 124.995895 -245.804786) (xy 125.043166 -245.818478) (xy 125.087628 -245.839576)
			(xy 125.128131 -245.867532) (xy 125.163624 -245.901624) (xy 125.193189 -245.940968) (xy 125.21606 -245.984545)
			(xy 125.231644 -246.031226) (xy 125.239539 -246.079803) (xy 125.240034 -246.10441) (xy 125.568976 -246.10441)
			(xy 125.572936 -246.055356) (xy 125.584713 -246.007572) (xy 125.604004 -245.962296) (xy 125.630307 -245.9207)
			(xy 125.662942 -245.883863) (xy 125.701063 -245.852738) (xy 125.743684 -245.828131) (xy 125.7897 -245.810679)
			(xy 125.837919 -245.800835) (xy 125.887094 -245.798854) (xy 125.935949 -245.804786) (xy 125.98322 -245.818478)
			(xy 126.027682 -245.839576) (xy 126.068185 -245.867532) (xy 126.103678 -245.901624) (xy 126.133243 -245.940968)
			(xy 126.156114 -245.984545) (xy 126.171698 -246.031226) (xy 126.179593 -246.079803) (xy 126.180088 -246.10441)
			(xy 126.179593 -246.129017) (xy 126.171698 -246.177594) (xy 126.156114 -246.224275) (xy 126.133243 -246.267852)
			(xy 126.103678 -246.307196) (xy 126.068185 -246.341288) (xy 126.027682 -246.369244) (xy 125.98322 -246.390342)
			(xy 125.935949 -246.404034) (xy 125.887094 -246.409966) (xy 125.837919 -246.407985) (xy 125.7897 -246.398141)
			(xy 125.743684 -246.380689) (xy 125.701063 -246.356082) (xy 125.662942 -246.324957) (xy 125.630307 -246.28812)
			(xy 125.604004 -246.246524) (xy 125.584713 -246.201248) (xy 125.572936 -246.153464) (xy 125.568976 -246.10441)
			(xy 125.240034 -246.10441) (xy 125.239539 -246.129017) (xy 125.231644 -246.177594) (xy 125.21606 -246.224275)
			(xy 125.193189 -246.267852) (xy 125.163624 -246.307196) (xy 125.128131 -246.341288) (xy 125.087628 -246.369244)
			(xy 125.043166 -246.390342) (xy 124.995895 -246.404034) (xy 124.94704 -246.409966) (xy 124.897865 -246.407985)
			(xy 124.849646 -246.398141) (xy 124.80363 -246.380689) (xy 124.761009 -246.356082) (xy 124.722888 -246.324957)
			(xy 124.690253 -246.28812) (xy 124.66395 -246.246524) (xy 124.644659 -246.201248) (xy 124.632882 -246.153464)
			(xy 124.628922 -246.10441) (xy 124.29998 -246.10441) (xy 124.299485 -246.129017) (xy 124.29159 -246.177594)
			(xy 124.276006 -246.224275) (xy 124.253135 -246.267852) (xy 124.22357 -246.307196) (xy 124.188077 -246.341288)
			(xy 124.147574 -246.369244) (xy 124.103112 -246.390342) (xy 124.055841 -246.404034) (xy 124.006986 -246.409966)
			(xy 123.957811 -246.407985) (xy 123.909592 -246.398141) (xy 123.863576 -246.380689) (xy 123.820955 -246.356082)
			(xy 123.782834 -246.324957) (xy 123.750199 -246.28812) (xy 123.723896 -246.246524) (xy 123.704605 -246.201248)
			(xy 123.692828 -246.153464) (xy 123.688868 -246.10441) (xy 123.359926 -246.10441) (xy 123.359431 -246.129017)
			(xy 123.351536 -246.177594) (xy 123.335952 -246.224275) (xy 123.313081 -246.267852) (xy 123.283516 -246.307196)
			(xy 123.248023 -246.341288) (xy 123.20752 -246.369244) (xy 123.163058 -246.390342) (xy 123.115787 -246.404034)
			(xy 123.066932 -246.409966) (xy 123.017757 -246.407985) (xy 122.969538 -246.398141) (xy 122.923522 -246.380689)
			(xy 122.880901 -246.356082) (xy 122.84278 -246.324957) (xy 122.810145 -246.28812) (xy 122.783842 -246.246524)
			(xy 122.764551 -246.201248) (xy 122.752774 -246.153464) (xy 122.748814 -246.10441) (xy 122.420126 -246.10441)
			(xy 122.419631 -246.129017) (xy 122.411736 -246.177594) (xy 122.396152 -246.224275) (xy 122.373281 -246.267852)
			(xy 122.343716 -246.307196) (xy 122.308223 -246.341288) (xy 122.26772 -246.369244) (xy 122.223258 -246.390342)
			(xy 122.175987 -246.404034) (xy 122.127132 -246.409966) (xy 122.077957 -246.407985) (xy 122.029738 -246.398141)
			(xy 121.983722 -246.380689) (xy 121.941101 -246.356082) (xy 121.90298 -246.324957) (xy 121.870345 -246.28812)
			(xy 121.844042 -246.246524) (xy 121.824751 -246.201248) (xy 121.812974 -246.153464) (xy 121.809014 -246.10441)
			(xy 121.480072 -246.10441) (xy 121.479577 -246.129017) (xy 121.471682 -246.177594) (xy 121.456098 -246.224275)
			(xy 121.433227 -246.267852) (xy 121.403662 -246.307196) (xy 121.368169 -246.341288) (xy 121.327666 -246.369244)
			(xy 121.283204 -246.390342) (xy 121.235933 -246.404034) (xy 121.187078 -246.409966) (xy 121.137903 -246.407985)
			(xy 121.089684 -246.398141) (xy 121.043668 -246.380689) (xy 121.001047 -246.356082) (xy 120.962926 -246.324957)
			(xy 120.930291 -246.28812) (xy 120.903988 -246.246524) (xy 120.884697 -246.201248) (xy 120.87292 -246.153464)
			(xy 120.86896 -246.10441) (xy 120.540018 -246.10441) (xy 120.539523 -246.129017) (xy 120.531628 -246.177594)
			(xy 120.516044 -246.224275) (xy 120.493173 -246.267852) (xy 120.463608 -246.307196) (xy 120.428115 -246.341288)
			(xy 120.387612 -246.369244) (xy 120.34315 -246.390342) (xy 120.295879 -246.404034) (xy 120.247024 -246.409966)
			(xy 120.197849 -246.407985) (xy 120.14963 -246.398141) (xy 120.103614 -246.380689) (xy 120.060993 -246.356082)
			(xy 120.022872 -246.324957) (xy 119.990237 -246.28812) (xy 119.963934 -246.246524) (xy 119.944643 -246.201248)
			(xy 119.932866 -246.153464) (xy 119.928906 -246.10441) (xy 119.599964 -246.10441) (xy 119.599469 -246.129017)
			(xy 119.591574 -246.177594) (xy 119.57599 -246.224275) (xy 119.553119 -246.267852) (xy 119.523554 -246.307196)
			(xy 119.488061 -246.341288) (xy 119.447558 -246.369244) (xy 119.403096 -246.390342) (xy 119.355825 -246.404034)
			(xy 119.30697 -246.409966) (xy 119.257795 -246.407985) (xy 119.209576 -246.398141) (xy 119.16356 -246.380689)
			(xy 119.120939 -246.356082) (xy 119.082818 -246.324957) (xy 119.050183 -246.28812) (xy 119.02388 -246.246524)
			(xy 119.004589 -246.201248) (xy 118.992812 -246.153464) (xy 118.988852 -246.10441) (xy 118.660164 -246.10441)
			(xy 118.659669 -246.129017) (xy 118.651774 -246.177594) (xy 118.63619 -246.224275) (xy 118.613319 -246.267852)
			(xy 118.583754 -246.307196) (xy 118.548261 -246.341288) (xy 118.507758 -246.369244) (xy 118.463296 -246.390342)
			(xy 118.416025 -246.404034) (xy 118.36717 -246.409966) (xy 118.317995 -246.407985) (xy 118.269776 -246.398141)
			(xy 118.22376 -246.380689) (xy 118.181139 -246.356082) (xy 118.143018 -246.324957) (xy 118.110383 -246.28812)
			(xy 118.08408 -246.246524) (xy 118.064789 -246.201248) (xy 118.053012 -246.153464) (xy 118.049052 -246.10441)
			(xy 117.72011 -246.10441) (xy 117.719615 -246.129017) (xy 117.71172 -246.177594) (xy 117.696136 -246.224275)
			(xy 117.673265 -246.267852) (xy 117.6437 -246.307196) (xy 117.608207 -246.341288) (xy 117.567704 -246.369244)
			(xy 117.523242 -246.390342) (xy 117.475971 -246.404034) (xy 117.427116 -246.409966) (xy 117.377941 -246.407985)
			(xy 117.329722 -246.398141) (xy 117.283706 -246.380689) (xy 117.241085 -246.356082) (xy 117.202964 -246.324957)
			(xy 117.170329 -246.28812) (xy 117.144026 -246.246524) (xy 117.124735 -246.201248) (xy 117.112958 -246.153464)
			(xy 117.108998 -246.10441) (xy 116.780056 -246.10441) (xy 116.779561 -246.129017) (xy 116.771666 -246.177594)
			(xy 116.756082 -246.224275) (xy 116.733211 -246.267852) (xy 116.703646 -246.307196) (xy 116.668153 -246.341288)
			(xy 116.62765 -246.369244) (xy 116.583188 -246.390342) (xy 116.535917 -246.404034) (xy 116.487062 -246.409966)
			(xy 116.437887 -246.407985) (xy 116.389668 -246.398141) (xy 116.343652 -246.380689) (xy 116.301031 -246.356082)
			(xy 116.26291 -246.324957) (xy 116.230275 -246.28812) (xy 116.203972 -246.246524) (xy 116.184681 -246.201248)
			(xy 116.172904 -246.153464) (xy 116.168944 -246.10441) (xy 115.840002 -246.10441) (xy 115.839507 -246.129017)
			(xy 115.831612 -246.177594) (xy 115.816028 -246.224275) (xy 115.793157 -246.267852) (xy 115.763592 -246.307196)
			(xy 115.728099 -246.341288) (xy 115.687596 -246.369244) (xy 115.643134 -246.390342) (xy 115.595863 -246.404034)
			(xy 115.547008 -246.409966) (xy 115.497833 -246.407985) (xy 115.449614 -246.398141) (xy 115.403598 -246.380689)
			(xy 115.360977 -246.356082) (xy 115.322856 -246.324957) (xy 115.290221 -246.28812) (xy 115.263918 -246.246524)
			(xy 115.244627 -246.201248) (xy 115.23285 -246.153464) (xy 115.22889 -246.10441) (xy 108.326428 -246.10441)
			(xy 108.325933 -246.129017) (xy 108.318038 -246.177594) (xy 108.302454 -246.224275) (xy 108.279583 -246.267852)
			(xy 108.250018 -246.307196) (xy 108.214525 -246.341288) (xy 108.174022 -246.369244) (xy 108.12956 -246.390342)
			(xy 108.082289 -246.404034) (xy 108.033434 -246.409966) (xy 107.984259 -246.407985) (xy 107.93604 -246.398141)
			(xy 107.890024 -246.380689) (xy 107.847403 -246.356082) (xy 107.809282 -246.324957) (xy 107.776647 -246.28812)
			(xy 107.750344 -246.246524) (xy 107.731053 -246.201248) (xy 107.719276 -246.153464) (xy 107.715316 -246.10441)
			(xy 107.387224 -246.10441) (xy 107.383049 -246.15479) (xy 107.370636 -246.203805) (xy 107.350323 -246.250109)
			(xy 107.322666 -246.292437) (xy 107.288419 -246.329635) (xy 107.248516 -246.360689) (xy 107.204046 -246.384751)
			(xy 107.156221 -246.401164) (xy 107.106347 -246.409482) (xy 107.081066 -246.409972) (xy 106.141012 -246.409972)
			(xy 106.115733 -246.40946) (xy 106.065866 -246.40114) (xy 106.018047 -246.384726) (xy 105.973583 -246.360665)
			(xy 105.933686 -246.329613) (xy 105.899444 -246.292417) (xy 105.871791 -246.250093) (xy 105.851482 -246.203794)
			(xy 105.839071 -246.154784) (xy 105.834895 -246.1044) (xy 105.506266 -246.1044) (xy 105.506266 -246.10441)
			(xy 105.505771 -246.129017) (xy 105.497876 -246.177594) (xy 105.482292 -246.224275) (xy 105.459421 -246.267852)
			(xy 105.429856 -246.307196) (xy 105.394363 -246.341288) (xy 105.35386 -246.369244) (xy 105.309398 -246.390342)
			(xy 105.262127 -246.404034) (xy 105.213272 -246.409966) (xy 105.164097 -246.407985) (xy 105.115878 -246.398141)
			(xy 105.069862 -246.380689) (xy 105.027241 -246.356082) (xy 104.98912 -246.324957) (xy 104.956485 -246.28812)
			(xy 104.930182 -246.246524) (xy 104.910891 -246.201248) (xy 104.899114 -246.153464) (xy 104.895154 -246.10441)
			(xy 104.567324 -246.10441) (xy 104.563149 -246.154791) (xy 104.550735 -246.203807) (xy 104.530422 -246.250111)
			(xy 104.502764 -246.29244) (xy 104.468516 -246.329638) (xy 104.428612 -246.360692) (xy 104.38414 -246.384753)
			(xy 104.336315 -246.401166) (xy 104.28644 -246.409482) (xy 104.261158 -246.409972) (xy 103.321104 -246.409972)
			(xy 103.295826 -246.409459) (xy 103.245959 -246.401139) (xy 103.198142 -246.384724) (xy 103.153679 -246.360662)
			(xy 103.113783 -246.32961) (xy 103.079542 -246.292415) (xy 103.05189 -246.250091) (xy 103.031581 -246.203793)
			(xy 103.01917 -246.154784) (xy 103.014995 -246.1044) (xy 102.686358 -246.1044) (xy 102.686358 -246.10441)
			(xy 102.685863 -246.129017) (xy 102.677968 -246.177594) (xy 102.662384 -246.224275) (xy 102.639513 -246.267852)
			(xy 102.609948 -246.307196) (xy 102.574455 -246.341288) (xy 102.533952 -246.369244) (xy 102.48949 -246.390342)
			(xy 102.442219 -246.404034) (xy 102.393364 -246.409966) (xy 102.344189 -246.407985) (xy 102.29597 -246.398141)
			(xy 102.249954 -246.380689) (xy 102.207333 -246.356082) (xy 102.169212 -246.324957) (xy 102.136577 -246.28812)
			(xy 102.110274 -246.246524) (xy 102.090983 -246.201248) (xy 102.079206 -246.153464) (xy 102.075246 -246.10441)
			(xy 101.747124 -246.10441) (xy 101.742949 -246.154787) (xy 101.730538 -246.203799) (xy 101.710228 -246.2501)
			(xy 101.682574 -246.292427) (xy 101.648331 -246.329625) (xy 101.608432 -246.360679) (xy 101.563966 -246.384742)
			(xy 101.516146 -246.401158) (xy 101.466276 -246.409479) (xy 101.440996 -246.409972) (xy 100.500942 -246.409972)
			(xy 100.475662 -246.409462) (xy 100.42579 -246.401146) (xy 100.377968 -246.384735) (xy 100.333499 -246.360675)
			(xy 100.293597 -246.329623) (xy 100.259351 -246.292427) (xy 100.231695 -246.250101) (xy 100.211384 -246.2038)
			(xy 100.198971 -246.154788) (xy 100.194795 -246.1044) (xy 99.86645 -246.1044) (xy 99.86645 -246.10441)
			(xy 99.865955 -246.129017) (xy 99.85806 -246.177594) (xy 99.842476 -246.224275) (xy 99.819605 -246.267852)
			(xy 99.79004 -246.307196) (xy 99.754547 -246.341288) (xy 99.714044 -246.369244) (xy 99.669582 -246.390342)
			(xy 99.622311 -246.404034) (xy 99.573456 -246.409966) (xy 99.524281 -246.407985) (xy 99.476062 -246.398141)
			(xy 99.430046 -246.380689) (xy 99.387425 -246.356082) (xy 99.349304 -246.324957) (xy 99.316669 -246.28812)
			(xy 99.290366 -246.246524) (xy 99.271075 -246.201248) (xy 99.259298 -246.153464) (xy 99.255338 -246.10441)
			(xy 98.927224 -246.10441) (xy 98.923049 -246.154788) (xy 98.910637 -246.203801) (xy 98.890327 -246.250102)
			(xy 98.862672 -246.29243) (xy 98.828428 -246.329627) (xy 98.788528 -246.360681) (xy 98.744061 -246.384744)
			(xy 98.696239 -246.40116) (xy 98.646368 -246.40948) (xy 98.621088 -246.409972) (xy 97.681034 -246.409972)
			(xy 97.655754 -246.409462) (xy 97.605884 -246.401145) (xy 97.558062 -246.384732) (xy 97.513595 -246.360672)
			(xy 97.473694 -246.329621) (xy 97.439449 -246.292425) (xy 97.411794 -246.250099) (xy 97.391483 -246.203799)
			(xy 97.379071 -246.154787) (xy 97.374895 -246.1044) (xy 97.046914 -246.1044) (xy 97.046914 -246.104402)
			(xy 97.042826 -246.154243) (xy 97.030673 -246.202753) (xy 97.010778 -246.248634) (xy 96.983673 -246.290661)
			(xy 96.950084 -246.327711) (xy 96.910906 -246.358792) (xy 96.867189 -246.383075) (xy 96.820099 -246.399911)
			(xy 96.79559 -246.404892) (xy 96.787716 -246.406416) (xy 96.76638 -246.417846) (xy 96.758506 -246.422164)
			(xy 96.738948 -246.443754) (xy 96.733054 -246.451004) (xy 96.726423 -246.468456) (xy 96.725994 -246.47779)
			(xy 96.725994 -246.914416) (xy 96.90533 -246.914416) (xy 96.90929 -246.865362) (xy 96.921067 -246.817578)
			(xy 96.940358 -246.772302) (xy 96.966661 -246.730706) (xy 96.999296 -246.693869) (xy 97.037417 -246.662744)
			(xy 97.080038 -246.638137) (xy 97.126054 -246.620685) (xy 97.174273 -246.610841) (xy 97.223448 -246.60886)
			(xy 97.272303 -246.614792) (xy 97.319574 -246.628484) (xy 97.364036 -246.649582) (xy 97.404539 -246.677538)
			(xy 97.440032 -246.71163) (xy 97.469597 -246.750974) (xy 97.492468 -246.794551) (xy 97.508052 -246.841232)
			(xy 97.515947 -246.889809) (xy 97.516442 -246.914416) (xy 97.84513 -246.914416) (xy 97.84909 -246.865362)
			(xy 97.860867 -246.817578) (xy 97.880158 -246.772302) (xy 97.906461 -246.730706) (xy 97.939096 -246.693869)
			(xy 97.977217 -246.662744) (xy 98.019838 -246.638137) (xy 98.065854 -246.620685) (xy 98.114073 -246.610841)
			(xy 98.163248 -246.60886) (xy 98.212103 -246.614792) (xy 98.259374 -246.628484) (xy 98.303836 -246.649582)
			(xy 98.344339 -246.677538) (xy 98.379832 -246.71163) (xy 98.409397 -246.750974) (xy 98.432268 -246.794551)
			(xy 98.447852 -246.841232) (xy 98.455747 -246.889809) (xy 98.456242 -246.914416) (xy 98.785184 -246.914416)
			(xy 98.789144 -246.865362) (xy 98.800921 -246.817578) (xy 98.820212 -246.772302) (xy 98.846515 -246.730706)
			(xy 98.87915 -246.693869) (xy 98.917271 -246.662744) (xy 98.959892 -246.638137) (xy 99.005908 -246.620685)
			(xy 99.054127 -246.610841) (xy 99.103302 -246.60886) (xy 99.152157 -246.614792) (xy 99.199428 -246.628484)
			(xy 99.24389 -246.649582) (xy 99.284393 -246.677538) (xy 99.319886 -246.71163) (xy 99.349451 -246.750974)
			(xy 99.372322 -246.794551) (xy 99.387906 -246.841232) (xy 99.395801 -246.889809) (xy 99.396296 -246.914416)
			(xy 99.725238 -246.914416) (xy 99.729198 -246.865362) (xy 99.740975 -246.817578) (xy 99.760266 -246.772302)
			(xy 99.786569 -246.730706) (xy 99.819204 -246.693869) (xy 99.857325 -246.662744) (xy 99.899946 -246.638137)
			(xy 99.945962 -246.620685) (xy 99.994181 -246.610841) (xy 100.043356 -246.60886) (xy 100.092211 -246.614792)
			(xy 100.139482 -246.628484) (xy 100.183944 -246.649582) (xy 100.224447 -246.677538) (xy 100.25994 -246.71163)
			(xy 100.289505 -246.750974) (xy 100.312376 -246.794551) (xy 100.32796 -246.841232) (xy 100.335855 -246.889809)
			(xy 100.33635 -246.914416) (xy 100.665292 -246.914416) (xy 100.669252 -246.865362) (xy 100.681029 -246.817578)
			(xy 100.70032 -246.772302) (xy 100.726623 -246.730706) (xy 100.759258 -246.693869) (xy 100.797379 -246.662744)
			(xy 100.84 -246.638137) (xy 100.886016 -246.620685) (xy 100.934235 -246.610841) (xy 100.98341 -246.60886)
			(xy 101.032265 -246.614792) (xy 101.079536 -246.628484) (xy 101.123998 -246.649582) (xy 101.164501 -246.677538)
			(xy 101.199994 -246.71163) (xy 101.229559 -246.750974) (xy 101.25243 -246.794551) (xy 101.268014 -246.841232)
			(xy 101.275909 -246.889809) (xy 101.276404 -246.914416) (xy 101.605346 -246.914416) (xy 101.609306 -246.865362)
			(xy 101.621083 -246.817578) (xy 101.640374 -246.772302) (xy 101.666677 -246.730706) (xy 101.699312 -246.693869)
			(xy 101.737433 -246.662744) (xy 101.780054 -246.638137) (xy 101.82607 -246.620685) (xy 101.874289 -246.610841)
			(xy 101.923464 -246.60886) (xy 101.972319 -246.614792) (xy 102.01959 -246.628484) (xy 102.064052 -246.649582)
			(xy 102.104555 -246.677538) (xy 102.140048 -246.71163) (xy 102.169613 -246.750974) (xy 102.192484 -246.794551)
			(xy 102.208068 -246.841232) (xy 102.215963 -246.889809) (xy 102.216458 -246.914416) (xy 102.545146 -246.914416)
			(xy 102.549106 -246.865362) (xy 102.560883 -246.817578) (xy 102.580174 -246.772302) (xy 102.606477 -246.730706)
			(xy 102.639112 -246.693869) (xy 102.677233 -246.662744) (xy 102.719854 -246.638137) (xy 102.76587 -246.620685)
			(xy 102.814089 -246.610841) (xy 102.863264 -246.60886) (xy 102.912119 -246.614792) (xy 102.95939 -246.628484)
			(xy 103.003852 -246.649582) (xy 103.044355 -246.677538) (xy 103.079848 -246.71163) (xy 103.109413 -246.750974)
			(xy 103.132284 -246.794551) (xy 103.147868 -246.841232) (xy 103.155763 -246.889809) (xy 103.156258 -246.914416)
			(xy 103.4852 -246.914416) (xy 103.48916 -246.865362) (xy 103.500937 -246.817578) (xy 103.520228 -246.772302)
			(xy 103.546531 -246.730706) (xy 103.579166 -246.693869) (xy 103.617287 -246.662744) (xy 103.659908 -246.638137)
			(xy 103.705924 -246.620685) (xy 103.754143 -246.610841) (xy 103.803318 -246.60886) (xy 103.852173 -246.614792)
			(xy 103.899444 -246.628484) (xy 103.943906 -246.649582) (xy 103.984409 -246.677538) (xy 104.019902 -246.71163)
			(xy 104.049467 -246.750974) (xy 104.072338 -246.794551) (xy 104.087922 -246.841232) (xy 104.095817 -246.889809)
			(xy 104.096312 -246.914416) (xy 104.425254 -246.914416) (xy 104.429214 -246.865362) (xy 104.440991 -246.817578)
			(xy 104.460282 -246.772302) (xy 104.486585 -246.730706) (xy 104.51922 -246.693869) (xy 104.557341 -246.662744)
			(xy 104.599962 -246.638137) (xy 104.645978 -246.620685) (xy 104.694197 -246.610841) (xy 104.743372 -246.60886)
			(xy 104.792227 -246.614792) (xy 104.839498 -246.628484) (xy 104.88396 -246.649582) (xy 104.924463 -246.677538)
			(xy 104.959956 -246.71163) (xy 104.989521 -246.750974) (xy 105.012392 -246.794551) (xy 105.027976 -246.841232)
			(xy 105.035871 -246.889809) (xy 105.036366 -246.914416) (xy 105.365308 -246.914416) (xy 105.369268 -246.865362)
			(xy 105.381045 -246.817578) (xy 105.400336 -246.772302) (xy 105.426639 -246.730706) (xy 105.459274 -246.693869)
			(xy 105.497395 -246.662744) (xy 105.540016 -246.638137) (xy 105.586032 -246.620685) (xy 105.634251 -246.610841)
			(xy 105.683426 -246.60886) (xy 105.732281 -246.614792) (xy 105.779552 -246.628484) (xy 105.824014 -246.649582)
			(xy 105.864517 -246.677538) (xy 105.90001 -246.71163) (xy 105.929575 -246.750974) (xy 105.952446 -246.794551)
			(xy 105.96803 -246.841232) (xy 105.975925 -246.889809) (xy 105.97642 -246.914416) (xy 106.305362 -246.914416)
			(xy 106.309322 -246.865362) (xy 106.321099 -246.817578) (xy 106.34039 -246.772302) (xy 106.366693 -246.730706)
			(xy 106.399328 -246.693869) (xy 106.437449 -246.662744) (xy 106.48007 -246.638137) (xy 106.526086 -246.620685)
			(xy 106.574305 -246.610841) (xy 106.62348 -246.60886) (xy 106.672335 -246.614792) (xy 106.719606 -246.628484)
			(xy 106.764068 -246.649582) (xy 106.804571 -246.677538) (xy 106.840064 -246.71163) (xy 106.869629 -246.750974)
			(xy 106.8925 -246.794551) (xy 106.908084 -246.841232) (xy 106.915979 -246.889809) (xy 106.916474 -246.914416)
			(xy 107.245162 -246.914416) (xy 107.249122 -246.865362) (xy 107.260899 -246.817578) (xy 107.28019 -246.772302)
			(xy 107.306493 -246.730706) (xy 107.339128 -246.693869) (xy 107.377249 -246.662744) (xy 107.41987 -246.638137)
			(xy 107.465886 -246.620685) (xy 107.514105 -246.610841) (xy 107.56328 -246.60886) (xy 107.612135 -246.614792)
			(xy 107.659406 -246.628484) (xy 107.703868 -246.649582) (xy 107.744371 -246.677538) (xy 107.779864 -246.71163)
			(xy 107.809429 -246.750974) (xy 107.8323 -246.794551) (xy 107.847884 -246.841232) (xy 107.855779 -246.889809)
			(xy 107.856274 -246.9144) (xy 108.185156 -246.9144) (xy 108.189328 -246.864058) (xy 108.201729 -246.815089)
			(xy 108.222021 -246.768829) (xy 108.249651 -246.72654) (xy 108.283865 -246.689376) (xy 108.32373 -246.658351)
			(xy 108.368157 -246.63431) (xy 108.415936 -246.617911) (xy 108.465763 -246.609599) (xy 108.49102 -246.609108)
			(xy 109.431074 -246.609108) (xy 109.456334 -246.609567) (xy 109.506167 -246.617878) (xy 109.553951 -246.634279)
			(xy 109.598385 -246.658322) (xy 109.638254 -246.68935) (xy 109.672472 -246.726518) (xy 109.700106 -246.768812)
			(xy 109.720401 -246.815077) (xy 109.732804 -246.864052) (xy 109.736976 -246.9144) (xy 109.736975 -246.914416)
			(xy 110.065324 -246.914416) (xy 110.069284 -246.865362) (xy 110.081061 -246.817578) (xy 110.100352 -246.772302)
			(xy 110.126655 -246.730706) (xy 110.15929 -246.693869) (xy 110.197411 -246.662744) (xy 110.240032 -246.638137)
			(xy 110.286048 -246.620685) (xy 110.334267 -246.610841) (xy 110.383442 -246.60886) (xy 110.432297 -246.614792)
			(xy 110.479568 -246.628484) (xy 110.52403 -246.649582) (xy 110.564533 -246.677538) (xy 110.600026 -246.71163)
			(xy 110.629591 -246.750974) (xy 110.652462 -246.794551) (xy 110.668046 -246.841232) (xy 110.675941 -246.889809)
			(xy 110.676436 -246.914416) (xy 112.878882 -246.914416) (xy 112.882842 -246.865362) (xy 112.894619 -246.817578)
			(xy 112.91391 -246.772302) (xy 112.940213 -246.730706) (xy 112.972848 -246.693869) (xy 113.010969 -246.662744)
			(xy 113.05359 -246.638137) (xy 113.099606 -246.620685) (xy 113.147825 -246.610841) (xy 113.197 -246.60886)
			(xy 113.245855 -246.614792) (xy 113.293126 -246.628484) (xy 113.337588 -246.649582) (xy 113.378091 -246.677538)
			(xy 113.413584 -246.71163) (xy 113.443149 -246.750974) (xy 113.46602 -246.794551) (xy 113.481604 -246.841232)
			(xy 113.489499 -246.889809) (xy 113.489994 -246.914416) (xy 113.818936 -246.914416) (xy 113.822896 -246.865362)
			(xy 113.834673 -246.817578) (xy 113.853964 -246.772302) (xy 113.880267 -246.730706) (xy 113.912902 -246.693869)
			(xy 113.951023 -246.662744) (xy 113.993644 -246.638137) (xy 114.03966 -246.620685) (xy 114.087879 -246.610841)
			(xy 114.137054 -246.60886) (xy 114.185909 -246.614792) (xy 114.23318 -246.628484) (xy 114.277642 -246.649582)
			(xy 114.318145 -246.677538) (xy 114.353638 -246.71163) (xy 114.383203 -246.750974) (xy 114.406074 -246.794551)
			(xy 114.421658 -246.841232) (xy 114.429553 -246.889809) (xy 114.430048 -246.914416) (xy 114.75899 -246.914416)
			(xy 114.76295 -246.865362) (xy 114.774727 -246.817578) (xy 114.794018 -246.772302) (xy 114.820321 -246.730706)
			(xy 114.852956 -246.693869) (xy 114.891077 -246.662744) (xy 114.933698 -246.638137) (xy 114.979714 -246.620685)
			(xy 115.027933 -246.610841) (xy 115.077108 -246.60886) (xy 115.125963 -246.614792) (xy 115.173234 -246.628484)
			(xy 115.217696 -246.649582) (xy 115.258199 -246.677538) (xy 115.293692 -246.71163) (xy 115.323257 -246.750974)
			(xy 115.346128 -246.794551) (xy 115.361712 -246.841232) (xy 115.369607 -246.889809) (xy 115.370102 -246.914416)
			(xy 115.699044 -246.914416) (xy 115.703004 -246.865362) (xy 115.714781 -246.817578) (xy 115.734072 -246.772302)
			(xy 115.760375 -246.730706) (xy 115.79301 -246.693869) (xy 115.831131 -246.662744) (xy 115.873752 -246.638137)
			(xy 115.919768 -246.620685) (xy 115.967987 -246.610841) (xy 116.017162 -246.60886) (xy 116.066017 -246.614792)
			(xy 116.113288 -246.628484) (xy 116.15775 -246.649582) (xy 116.198253 -246.677538) (xy 116.233746 -246.71163)
			(xy 116.263311 -246.750974) (xy 116.286182 -246.794551) (xy 116.301766 -246.841232) (xy 116.309661 -246.889809)
			(xy 116.310156 -246.914416) (xy 116.638844 -246.914416) (xy 116.642804 -246.865362) (xy 116.654581 -246.817578)
			(xy 116.673872 -246.772302) (xy 116.700175 -246.730706) (xy 116.73281 -246.693869) (xy 116.770931 -246.662744)
			(xy 116.813552 -246.638137) (xy 116.859568 -246.620685) (xy 116.907787 -246.610841) (xy 116.956962 -246.60886)
			(xy 117.005817 -246.614792) (xy 117.053088 -246.628484) (xy 117.09755 -246.649582) (xy 117.138053 -246.677538)
			(xy 117.173546 -246.71163) (xy 117.203111 -246.750974) (xy 117.225982 -246.794551) (xy 117.241566 -246.841232)
			(xy 117.249461 -246.889809) (xy 117.249956 -246.914416) (xy 117.578898 -246.914416) (xy 117.582858 -246.865362)
			(xy 117.594635 -246.817578) (xy 117.613926 -246.772302) (xy 117.640229 -246.730706) (xy 117.672864 -246.693869)
			(xy 117.710985 -246.662744) (xy 117.753606 -246.638137) (xy 117.799622 -246.620685) (xy 117.847841 -246.610841)
			(xy 117.897016 -246.60886) (xy 117.945871 -246.614792) (xy 117.993142 -246.628484) (xy 118.037604 -246.649582)
			(xy 118.078107 -246.677538) (xy 118.1136 -246.71163) (xy 118.143165 -246.750974) (xy 118.166036 -246.794551)
			(xy 118.18162 -246.841232) (xy 118.189515 -246.889809) (xy 118.19001 -246.914416) (xy 118.518952 -246.914416)
			(xy 118.522912 -246.865362) (xy 118.534689 -246.817578) (xy 118.55398 -246.772302) (xy 118.580283 -246.730706)
			(xy 118.612918 -246.693869) (xy 118.651039 -246.662744) (xy 118.69366 -246.638137) (xy 118.739676 -246.620685)
			(xy 118.787895 -246.610841) (xy 118.83707 -246.60886) (xy 118.885925 -246.614792) (xy 118.933196 -246.628484)
			(xy 118.977658 -246.649582) (xy 119.018161 -246.677538) (xy 119.053654 -246.71163) (xy 119.083219 -246.750974)
			(xy 119.10609 -246.794551) (xy 119.121674 -246.841232) (xy 119.129569 -246.889809) (xy 119.130064 -246.914416)
			(xy 119.459006 -246.914416) (xy 119.462966 -246.865362) (xy 119.474743 -246.817578) (xy 119.494034 -246.772302)
			(xy 119.520337 -246.730706) (xy 119.552972 -246.693869) (xy 119.591093 -246.662744) (xy 119.633714 -246.638137)
			(xy 119.67973 -246.620685) (xy 119.727949 -246.610841) (xy 119.777124 -246.60886) (xy 119.825979 -246.614792)
			(xy 119.87325 -246.628484) (xy 119.917712 -246.649582) (xy 119.958215 -246.677538) (xy 119.993708 -246.71163)
			(xy 120.023273 -246.750974) (xy 120.046144 -246.794551) (xy 120.061728 -246.841232) (xy 120.069623 -246.889809)
			(xy 120.070118 -246.914416) (xy 120.398806 -246.914416) (xy 120.402766 -246.865362) (xy 120.414543 -246.817578)
			(xy 120.433834 -246.772302) (xy 120.460137 -246.730706) (xy 120.492772 -246.693869) (xy 120.530893 -246.662744)
			(xy 120.573514 -246.638137) (xy 120.61953 -246.620685) (xy 120.667749 -246.610841) (xy 120.716924 -246.60886)
			(xy 120.765779 -246.614792) (xy 120.81305 -246.628484) (xy 120.857512 -246.649582) (xy 120.898015 -246.677538)
			(xy 120.933508 -246.71163) (xy 120.963073 -246.750974) (xy 120.985944 -246.794551) (xy 121.001528 -246.841232)
			(xy 121.009423 -246.889809) (xy 121.009918 -246.914416) (xy 121.33886 -246.914416) (xy 121.34282 -246.865362)
			(xy 121.354597 -246.817578) (xy 121.373888 -246.772302) (xy 121.400191 -246.730706) (xy 121.432826 -246.693869)
			(xy 121.470947 -246.662744) (xy 121.513568 -246.638137) (xy 121.559584 -246.620685) (xy 121.607803 -246.610841)
			(xy 121.656978 -246.60886) (xy 121.705833 -246.614792) (xy 121.753104 -246.628484) (xy 121.797566 -246.649582)
			(xy 121.838069 -246.677538) (xy 121.873562 -246.71163) (xy 121.903127 -246.750974) (xy 121.925998 -246.794551)
			(xy 121.941582 -246.841232) (xy 121.949477 -246.889809) (xy 121.949972 -246.914416) (xy 122.278914 -246.914416)
			(xy 122.282874 -246.865362) (xy 122.294651 -246.817578) (xy 122.313942 -246.772302) (xy 122.340245 -246.730706)
			(xy 122.37288 -246.693869) (xy 122.411001 -246.662744) (xy 122.453622 -246.638137) (xy 122.499638 -246.620685)
			(xy 122.547857 -246.610841) (xy 122.597032 -246.60886) (xy 122.645887 -246.614792) (xy 122.693158 -246.628484)
			(xy 122.73762 -246.649582) (xy 122.778123 -246.677538) (xy 122.813616 -246.71163) (xy 122.843181 -246.750974)
			(xy 122.866052 -246.794551) (xy 122.881636 -246.841232) (xy 122.889531 -246.889809) (xy 122.890026 -246.914416)
			(xy 123.218968 -246.914416) (xy 123.222928 -246.865362) (xy 123.234705 -246.817578) (xy 123.253996 -246.772302)
			(xy 123.280299 -246.730706) (xy 123.312934 -246.693869) (xy 123.351055 -246.662744) (xy 123.393676 -246.638137)
			(xy 123.439692 -246.620685) (xy 123.487911 -246.610841) (xy 123.537086 -246.60886) (xy 123.585941 -246.614792)
			(xy 123.633212 -246.628484) (xy 123.677674 -246.649582) (xy 123.718177 -246.677538) (xy 123.75367 -246.71163)
			(xy 123.783235 -246.750974) (xy 123.806106 -246.794551) (xy 123.82169 -246.841232) (xy 123.829585 -246.889809)
			(xy 123.83008 -246.914416) (xy 124.159022 -246.914416) (xy 124.162982 -246.865362) (xy 124.174759 -246.817578)
			(xy 124.19405 -246.772302) (xy 124.220353 -246.730706) (xy 124.252988 -246.693869) (xy 124.291109 -246.662744)
			(xy 124.33373 -246.638137) (xy 124.379746 -246.620685) (xy 124.427965 -246.610841) (xy 124.47714 -246.60886)
			(xy 124.525995 -246.614792) (xy 124.573266 -246.628484) (xy 124.617728 -246.649582) (xy 124.658231 -246.677538)
			(xy 124.693724 -246.71163) (xy 124.723289 -246.750974) (xy 124.74616 -246.794551) (xy 124.761744 -246.841232)
			(xy 124.769639 -246.889809) (xy 124.770134 -246.914416) (xy 125.098822 -246.914416) (xy 125.102782 -246.865362)
			(xy 125.114559 -246.817578) (xy 125.13385 -246.772302) (xy 125.160153 -246.730706) (xy 125.192788 -246.693869)
			(xy 125.230909 -246.662744) (xy 125.27353 -246.638137) (xy 125.319546 -246.620685) (xy 125.367765 -246.610841)
			(xy 125.41694 -246.60886) (xy 125.465795 -246.614792) (xy 125.513066 -246.628484) (xy 125.557528 -246.649582)
			(xy 125.598031 -246.677538) (xy 125.633524 -246.71163) (xy 125.663089 -246.750974) (xy 125.68596 -246.794551)
			(xy 125.701544 -246.841232) (xy 125.709439 -246.889809) (xy 125.709934 -246.914416) (xy 125.709439 -246.939023)
			(xy 125.701544 -246.9876) (xy 125.68596 -247.034281) (xy 125.663089 -247.077858) (xy 125.633524 -247.117202)
			(xy 125.598031 -247.151294) (xy 125.557528 -247.17925) (xy 125.513066 -247.200348) (xy 125.465795 -247.21404)
			(xy 125.41694 -247.219972) (xy 125.367765 -247.217991) (xy 125.319546 -247.208147) (xy 125.27353 -247.190695)
			(xy 125.230909 -247.166088) (xy 125.192788 -247.134963) (xy 125.160153 -247.098126) (xy 125.13385 -247.05653)
			(xy 125.114559 -247.011254) (xy 125.102782 -246.96347) (xy 125.098822 -246.914416) (xy 124.770134 -246.914416)
			(xy 124.769639 -246.939023) (xy 124.761744 -246.9876) (xy 124.74616 -247.034281) (xy 124.723289 -247.077858)
			(xy 124.693724 -247.117202) (xy 124.658231 -247.151294) (xy 124.617728 -247.17925) (xy 124.573266 -247.200348)
			(xy 124.525995 -247.21404) (xy 124.47714 -247.219972) (xy 124.427965 -247.217991) (xy 124.379746 -247.208147)
			(xy 124.33373 -247.190695) (xy 124.291109 -247.166088) (xy 124.252988 -247.134963) (xy 124.220353 -247.098126)
			(xy 124.19405 -247.05653) (xy 124.174759 -247.011254) (xy 124.162982 -246.96347) (xy 124.159022 -246.914416)
			(xy 123.83008 -246.914416) (xy 123.829585 -246.939023) (xy 123.82169 -246.9876) (xy 123.806106 -247.034281)
			(xy 123.783235 -247.077858) (xy 123.75367 -247.117202) (xy 123.718177 -247.151294) (xy 123.677674 -247.17925)
			(xy 123.633212 -247.200348) (xy 123.585941 -247.21404) (xy 123.537086 -247.219972) (xy 123.487911 -247.217991)
			(xy 123.439692 -247.208147) (xy 123.393676 -247.190695) (xy 123.351055 -247.166088) (xy 123.312934 -247.134963)
			(xy 123.280299 -247.098126) (xy 123.253996 -247.05653) (xy 123.234705 -247.011254) (xy 123.222928 -246.96347)
			(xy 123.218968 -246.914416) (xy 122.890026 -246.914416) (xy 122.889531 -246.939023) (xy 122.881636 -246.9876)
			(xy 122.866052 -247.034281) (xy 122.843181 -247.077858) (xy 122.813616 -247.117202) (xy 122.778123 -247.151294)
			(xy 122.73762 -247.17925) (xy 122.693158 -247.200348) (xy 122.645887 -247.21404) (xy 122.597032 -247.219972)
			(xy 122.547857 -247.217991) (xy 122.499638 -247.208147) (xy 122.453622 -247.190695) (xy 122.411001 -247.166088)
			(xy 122.37288 -247.134963) (xy 122.340245 -247.098126) (xy 122.313942 -247.05653) (xy 122.294651 -247.011254)
			(xy 122.282874 -246.96347) (xy 122.278914 -246.914416) (xy 121.949972 -246.914416) (xy 121.949477 -246.939023)
			(xy 121.941582 -246.9876) (xy 121.925998 -247.034281) (xy 121.903127 -247.077858) (xy 121.873562 -247.117202)
			(xy 121.838069 -247.151294) (xy 121.797566 -247.17925) (xy 121.753104 -247.200348) (xy 121.705833 -247.21404)
			(xy 121.656978 -247.219972) (xy 121.607803 -247.217991) (xy 121.559584 -247.208147) (xy 121.513568 -247.190695)
			(xy 121.470947 -247.166088) (xy 121.432826 -247.134963) (xy 121.400191 -247.098126) (xy 121.373888 -247.05653)
			(xy 121.354597 -247.011254) (xy 121.34282 -246.96347) (xy 121.33886 -246.914416) (xy 121.009918 -246.914416)
			(xy 121.009423 -246.939023) (xy 121.001528 -246.9876) (xy 120.985944 -247.034281) (xy 120.963073 -247.077858)
			(xy 120.933508 -247.117202) (xy 120.898015 -247.151294) (xy 120.857512 -247.17925) (xy 120.81305 -247.200348)
			(xy 120.765779 -247.21404) (xy 120.716924 -247.219972) (xy 120.667749 -247.217991) (xy 120.61953 -247.208147)
			(xy 120.573514 -247.190695) (xy 120.530893 -247.166088) (xy 120.492772 -247.134963) (xy 120.460137 -247.098126)
			(xy 120.433834 -247.05653) (xy 120.414543 -247.011254) (xy 120.402766 -246.96347) (xy 120.398806 -246.914416)
			(xy 120.070118 -246.914416) (xy 120.069623 -246.939023) (xy 120.061728 -246.9876) (xy 120.046144 -247.034281)
			(xy 120.023273 -247.077858) (xy 119.993708 -247.117202) (xy 119.958215 -247.151294) (xy 119.917712 -247.17925)
			(xy 119.87325 -247.200348) (xy 119.825979 -247.21404) (xy 119.777124 -247.219972) (xy 119.727949 -247.217991)
			(xy 119.67973 -247.208147) (xy 119.633714 -247.190695) (xy 119.591093 -247.166088) (xy 119.552972 -247.134963)
			(xy 119.520337 -247.098126) (xy 119.494034 -247.05653) (xy 119.474743 -247.011254) (xy 119.462966 -246.96347)
			(xy 119.459006 -246.914416) (xy 119.130064 -246.914416) (xy 119.129569 -246.939023) (xy 119.121674 -246.9876)
			(xy 119.10609 -247.034281) (xy 119.083219 -247.077858) (xy 119.053654 -247.117202) (xy 119.018161 -247.151294)
			(xy 118.977658 -247.17925) (xy 118.933196 -247.200348) (xy 118.885925 -247.21404) (xy 118.83707 -247.219972)
			(xy 118.787895 -247.217991) (xy 118.739676 -247.208147) (xy 118.69366 -247.190695) (xy 118.651039 -247.166088)
			(xy 118.612918 -247.134963) (xy 118.580283 -247.098126) (xy 118.55398 -247.05653) (xy 118.534689 -247.011254)
			(xy 118.522912 -246.96347) (xy 118.518952 -246.914416) (xy 118.19001 -246.914416) (xy 118.189515 -246.939023)
			(xy 118.18162 -246.9876) (xy 118.166036 -247.034281) (xy 118.143165 -247.077858) (xy 118.1136 -247.117202)
			(xy 118.078107 -247.151294) (xy 118.037604 -247.17925) (xy 117.993142 -247.200348) (xy 117.945871 -247.21404)
			(xy 117.897016 -247.219972) (xy 117.847841 -247.217991) (xy 117.799622 -247.208147) (xy 117.753606 -247.190695)
			(xy 117.710985 -247.166088) (xy 117.672864 -247.134963) (xy 117.640229 -247.098126) (xy 117.613926 -247.05653)
			(xy 117.594635 -247.011254) (xy 117.582858 -246.96347) (xy 117.578898 -246.914416) (xy 117.249956 -246.914416)
			(xy 117.249461 -246.939023) (xy 117.241566 -246.9876) (xy 117.225982 -247.034281) (xy 117.203111 -247.077858)
			(xy 117.173546 -247.117202) (xy 117.138053 -247.151294) (xy 117.09755 -247.17925) (xy 117.053088 -247.200348)
			(xy 117.005817 -247.21404) (xy 116.956962 -247.219972) (xy 116.907787 -247.217991) (xy 116.859568 -247.208147)
			(xy 116.813552 -247.190695) (xy 116.770931 -247.166088) (xy 116.73281 -247.134963) (xy 116.700175 -247.098126)
			(xy 116.673872 -247.05653) (xy 116.654581 -247.011254) (xy 116.642804 -246.96347) (xy 116.638844 -246.914416)
			(xy 116.310156 -246.914416) (xy 116.309661 -246.939023) (xy 116.301766 -246.9876) (xy 116.286182 -247.034281)
			(xy 116.263311 -247.077858) (xy 116.233746 -247.117202) (xy 116.198253 -247.151294) (xy 116.15775 -247.17925)
			(xy 116.113288 -247.200348) (xy 116.066017 -247.21404) (xy 116.017162 -247.219972) (xy 115.967987 -247.217991)
			(xy 115.919768 -247.208147) (xy 115.873752 -247.190695) (xy 115.831131 -247.166088) (xy 115.79301 -247.134963)
			(xy 115.760375 -247.098126) (xy 115.734072 -247.05653) (xy 115.714781 -247.011254) (xy 115.703004 -246.96347)
			(xy 115.699044 -246.914416) (xy 115.370102 -246.914416) (xy 115.369607 -246.939023) (xy 115.361712 -246.9876)
			(xy 115.346128 -247.034281) (xy 115.323257 -247.077858) (xy 115.293692 -247.117202) (xy 115.258199 -247.151294)
			(xy 115.217696 -247.17925) (xy 115.173234 -247.200348) (xy 115.125963 -247.21404) (xy 115.077108 -247.219972)
			(xy 115.027933 -247.217991) (xy 114.979714 -247.208147) (xy 114.933698 -247.190695) (xy 114.891077 -247.166088)
			(xy 114.852956 -247.134963) (xy 114.820321 -247.098126) (xy 114.794018 -247.05653) (xy 114.774727 -247.011254)
			(xy 114.76295 -246.96347) (xy 114.75899 -246.914416) (xy 114.430048 -246.914416) (xy 114.429553 -246.939023)
			(xy 114.421658 -246.9876) (xy 114.406074 -247.034281) (xy 114.383203 -247.077858) (xy 114.353638 -247.117202)
			(xy 114.318145 -247.151294) (xy 114.277642 -247.17925) (xy 114.23318 -247.200348) (xy 114.185909 -247.21404)
			(xy 114.137054 -247.219972) (xy 114.087879 -247.217991) (xy 114.03966 -247.208147) (xy 113.993644 -247.190695)
			(xy 113.951023 -247.166088) (xy 113.912902 -247.134963) (xy 113.880267 -247.098126) (xy 113.853964 -247.05653)
			(xy 113.834673 -247.011254) (xy 113.822896 -246.96347) (xy 113.818936 -246.914416) (xy 113.489994 -246.914416)
			(xy 113.489499 -246.939023) (xy 113.481604 -246.9876) (xy 113.46602 -247.034281) (xy 113.443149 -247.077858)
			(xy 113.413584 -247.117202) (xy 113.378091 -247.151294) (xy 113.337588 -247.17925) (xy 113.293126 -247.200348)
			(xy 113.245855 -247.21404) (xy 113.197 -247.219972) (xy 113.147825 -247.217991) (xy 113.099606 -247.208147)
			(xy 113.05359 -247.190695) (xy 113.010969 -247.166088) (xy 112.972848 -247.134963) (xy 112.940213 -247.098126)
			(xy 112.91391 -247.05653) (xy 112.894619 -247.011254) (xy 112.882842 -246.96347) (xy 112.878882 -246.914416)
			(xy 110.676436 -246.914416) (xy 110.675941 -246.939023) (xy 110.668046 -246.9876) (xy 110.652462 -247.034281)
			(xy 110.629591 -247.077858) (xy 110.600026 -247.117202) (xy 110.564533 -247.151294) (xy 110.52403 -247.17925)
			(xy 110.479568 -247.200348) (xy 110.432297 -247.21404) (xy 110.383442 -247.219972) (xy 110.334267 -247.217991)
			(xy 110.286048 -247.208147) (xy 110.240032 -247.190695) (xy 110.197411 -247.166088) (xy 110.15929 -247.134963)
			(xy 110.126655 -247.098126) (xy 110.100352 -247.05653) (xy 110.081061 -247.011254) (xy 110.069284 -246.96347)
			(xy 110.065324 -246.914416) (xy 109.736975 -246.914416) (xy 109.732804 -246.964748) (xy 109.720401 -247.013723)
			(xy 109.700106 -247.059988) (xy 109.672472 -247.102282) (xy 109.638254 -247.13945) (xy 109.598385 -247.170478)
			(xy 109.553951 -247.194521) (xy 109.506167 -247.210922) (xy 109.456334 -247.219233) (xy 109.431074 -247.219724)
			(xy 108.49102 -247.219724) (xy 108.465763 -247.219201) (xy 108.415936 -247.210889) (xy 108.368157 -247.19449)
			(xy 108.32373 -247.170449) (xy 108.283865 -247.139424) (xy 108.249651 -247.10226) (xy 108.222021 -247.059971)
			(xy 108.201729 -247.013711) (xy 108.189328 -246.964742) (xy 108.185156 -246.9144) (xy 107.856274 -246.9144)
			(xy 107.856274 -246.914416) (xy 107.855779 -246.939023) (xy 107.847884 -246.9876) (xy 107.8323 -247.034281)
			(xy 107.809429 -247.077858) (xy 107.779864 -247.117202) (xy 107.744371 -247.151294) (xy 107.703868 -247.17925)
			(xy 107.659406 -247.200348) (xy 107.612135 -247.21404) (xy 107.56328 -247.219972) (xy 107.514105 -247.217991)
			(xy 107.465886 -247.208147) (xy 107.41987 -247.190695) (xy 107.377249 -247.166088) (xy 107.339128 -247.134963)
			(xy 107.306493 -247.098126) (xy 107.28019 -247.05653) (xy 107.260899 -247.011254) (xy 107.249122 -246.96347)
			(xy 107.245162 -246.914416) (xy 106.916474 -246.914416) (xy 106.915979 -246.939023) (xy 106.908084 -246.9876)
			(xy 106.8925 -247.034281) (xy 106.869629 -247.077858) (xy 106.840064 -247.117202) (xy 106.804571 -247.151294)
			(xy 106.764068 -247.17925) (xy 106.719606 -247.200348) (xy 106.672335 -247.21404) (xy 106.62348 -247.219972)
			(xy 106.574305 -247.217991) (xy 106.526086 -247.208147) (xy 106.48007 -247.190695) (xy 106.437449 -247.166088)
			(xy 106.399328 -247.134963) (xy 106.366693 -247.098126) (xy 106.34039 -247.05653) (xy 106.321099 -247.011254)
			(xy 106.309322 -246.96347) (xy 106.305362 -246.914416) (xy 105.97642 -246.914416) (xy 105.975925 -246.939023)
			(xy 105.96803 -246.9876) (xy 105.952446 -247.034281) (xy 105.929575 -247.077858) (xy 105.90001 -247.117202)
			(xy 105.864517 -247.151294) (xy 105.824014 -247.17925) (xy 105.779552 -247.200348) (xy 105.732281 -247.21404)
			(xy 105.683426 -247.219972) (xy 105.634251 -247.217991) (xy 105.586032 -247.208147) (xy 105.540016 -247.190695)
			(xy 105.497395 -247.166088) (xy 105.459274 -247.134963) (xy 105.426639 -247.098126) (xy 105.400336 -247.05653)
			(xy 105.381045 -247.011254) (xy 105.369268 -246.96347) (xy 105.365308 -246.914416) (xy 105.036366 -246.914416)
			(xy 105.035871 -246.939023) (xy 105.027976 -246.9876) (xy 105.012392 -247.034281) (xy 104.989521 -247.077858)
			(xy 104.959956 -247.117202) (xy 104.924463 -247.151294) (xy 104.88396 -247.17925) (xy 104.839498 -247.200348)
			(xy 104.792227 -247.21404) (xy 104.743372 -247.219972) (xy 104.694197 -247.217991) (xy 104.645978 -247.208147)
			(xy 104.599962 -247.190695) (xy 104.557341 -247.166088) (xy 104.51922 -247.134963) (xy 104.486585 -247.098126)
			(xy 104.460282 -247.05653) (xy 104.440991 -247.011254) (xy 104.429214 -246.96347) (xy 104.425254 -246.914416)
			(xy 104.096312 -246.914416) (xy 104.095817 -246.939023) (xy 104.087922 -246.9876) (xy 104.072338 -247.034281)
			(xy 104.049467 -247.077858) (xy 104.019902 -247.117202) (xy 103.984409 -247.151294) (xy 103.943906 -247.17925)
			(xy 103.899444 -247.200348) (xy 103.852173 -247.21404) (xy 103.803318 -247.219972) (xy 103.754143 -247.217991)
			(xy 103.705924 -247.208147) (xy 103.659908 -247.190695) (xy 103.617287 -247.166088) (xy 103.579166 -247.134963)
			(xy 103.546531 -247.098126) (xy 103.520228 -247.05653) (xy 103.500937 -247.011254) (xy 103.48916 -246.96347)
			(xy 103.4852 -246.914416) (xy 103.156258 -246.914416) (xy 103.155763 -246.939023) (xy 103.147868 -246.9876)
			(xy 103.132284 -247.034281) (xy 103.109413 -247.077858) (xy 103.079848 -247.117202) (xy 103.044355 -247.151294)
			(xy 103.003852 -247.17925) (xy 102.95939 -247.200348) (xy 102.912119 -247.21404) (xy 102.863264 -247.219972)
			(xy 102.814089 -247.217991) (xy 102.76587 -247.208147) (xy 102.719854 -247.190695) (xy 102.677233 -247.166088)
			(xy 102.639112 -247.134963) (xy 102.606477 -247.098126) (xy 102.580174 -247.05653) (xy 102.560883 -247.011254)
			(xy 102.549106 -246.96347) (xy 102.545146 -246.914416) (xy 102.216458 -246.914416) (xy 102.215963 -246.939023)
			(xy 102.208068 -246.9876) (xy 102.192484 -247.034281) (xy 102.169613 -247.077858) (xy 102.140048 -247.117202)
			(xy 102.104555 -247.151294) (xy 102.064052 -247.17925) (xy 102.01959 -247.200348) (xy 101.972319 -247.21404)
			(xy 101.923464 -247.219972) (xy 101.874289 -247.217991) (xy 101.82607 -247.208147) (xy 101.780054 -247.190695)
			(xy 101.737433 -247.166088) (xy 101.699312 -247.134963) (xy 101.666677 -247.098126) (xy 101.640374 -247.05653)
			(xy 101.621083 -247.011254) (xy 101.609306 -246.96347) (xy 101.605346 -246.914416) (xy 101.276404 -246.914416)
			(xy 101.275909 -246.939023) (xy 101.268014 -246.9876) (xy 101.25243 -247.034281) (xy 101.229559 -247.077858)
			(xy 101.199994 -247.117202) (xy 101.164501 -247.151294) (xy 101.123998 -247.17925) (xy 101.079536 -247.200348)
			(xy 101.032265 -247.21404) (xy 100.98341 -247.219972) (xy 100.934235 -247.217991) (xy 100.886016 -247.208147)
			(xy 100.84 -247.190695) (xy 100.797379 -247.166088) (xy 100.759258 -247.134963) (xy 100.726623 -247.098126)
			(xy 100.70032 -247.05653) (xy 100.681029 -247.011254) (xy 100.669252 -246.96347) (xy 100.665292 -246.914416)
			(xy 100.33635 -246.914416) (xy 100.335855 -246.939023) (xy 100.32796 -246.9876) (xy 100.312376 -247.034281)
			(xy 100.289505 -247.077858) (xy 100.25994 -247.117202) (xy 100.224447 -247.151294) (xy 100.183944 -247.17925)
			(xy 100.139482 -247.200348) (xy 100.092211 -247.21404) (xy 100.043356 -247.219972) (xy 99.994181 -247.217991)
			(xy 99.945962 -247.208147) (xy 99.899946 -247.190695) (xy 99.857325 -247.166088) (xy 99.819204 -247.134963)
			(xy 99.786569 -247.098126) (xy 99.760266 -247.05653) (xy 99.740975 -247.011254) (xy 99.729198 -246.96347)
			(xy 99.725238 -246.914416) (xy 99.396296 -246.914416) (xy 99.395801 -246.939023) (xy 99.387906 -246.9876)
			(xy 99.372322 -247.034281) (xy 99.349451 -247.077858) (xy 99.319886 -247.117202) (xy 99.284393 -247.151294)
			(xy 99.24389 -247.17925) (xy 99.199428 -247.200348) (xy 99.152157 -247.21404) (xy 99.103302 -247.219972)
			(xy 99.054127 -247.217991) (xy 99.005908 -247.208147) (xy 98.959892 -247.190695) (xy 98.917271 -247.166088)
			(xy 98.87915 -247.134963) (xy 98.846515 -247.098126) (xy 98.820212 -247.05653) (xy 98.800921 -247.011254)
			(xy 98.789144 -246.96347) (xy 98.785184 -246.914416) (xy 98.456242 -246.914416) (xy 98.455747 -246.939023)
			(xy 98.447852 -246.9876) (xy 98.432268 -247.034281) (xy 98.409397 -247.077858) (xy 98.379832 -247.117202)
			(xy 98.344339 -247.151294) (xy 98.303836 -247.17925) (xy 98.259374 -247.200348) (xy 98.212103 -247.21404)
			(xy 98.163248 -247.219972) (xy 98.114073 -247.217991) (xy 98.065854 -247.208147) (xy 98.019838 -247.190695)
			(xy 97.977217 -247.166088) (xy 97.939096 -247.134963) (xy 97.906461 -247.098126) (xy 97.880158 -247.05653)
			(xy 97.860867 -247.011254) (xy 97.84909 -246.96347) (xy 97.84513 -246.914416) (xy 97.516442 -246.914416)
			(xy 97.515947 -246.939023) (xy 97.508052 -246.9876) (xy 97.492468 -247.034281) (xy 97.469597 -247.077858)
			(xy 97.440032 -247.117202) (xy 97.404539 -247.151294) (xy 97.364036 -247.17925) (xy 97.319574 -247.200348)
			(xy 97.272303 -247.21404) (xy 97.223448 -247.219972) (xy 97.174273 -247.217991) (xy 97.126054 -247.208147)
			(xy 97.080038 -247.190695) (xy 97.037417 -247.166088) (xy 96.999296 -247.134963) (xy 96.966661 -247.098126)
			(xy 96.940358 -247.05653) (xy 96.921067 -247.011254) (xy 96.90929 -246.96347) (xy 96.90533 -246.914416)
			(xy 96.725994 -246.914416) (xy 96.725994 -247.351042) (xy 96.726303 -247.360399) (xy 96.732952 -247.377888)
			(xy 96.738948 -247.385078) (xy 96.758506 -247.406668) (xy 96.76638 -247.410986) (xy 96.787716 -247.422416)
			(xy 96.79559 -247.42394) (xy 96.820101 -247.428902) (xy 96.867189 -247.445738) (xy 96.910905 -247.470021)
			(xy 96.95008 -247.501102) (xy 96.983667 -247.53815) (xy 97.01077 -247.580176) (xy 97.030663 -247.626056)
			(xy 97.042816 -247.674564) (xy 97.046902 -247.7244) (xy 97.374907 -247.7244) (xy 97.379083 -247.674015)
			(xy 97.391495 -247.625005) (xy 97.411805 -247.578707) (xy 97.439459 -247.536383) (xy 97.473702 -247.499188)
			(xy 97.513601 -247.468138) (xy 97.558067 -247.444079) (xy 97.605887 -247.427667) (xy 97.655755 -247.41935)
			(xy 97.681034 -247.41886) (xy 98.621088 -247.41886) (xy 98.646369 -247.419308) (xy 98.696242 -247.427629)
			(xy 98.744066 -247.444045) (xy 98.788534 -247.468109) (xy 98.828436 -247.499164) (xy 98.862682 -247.536363)
			(xy 98.890337 -247.578692) (xy 98.910648 -247.624995) (xy 98.923061 -247.67401) (xy 98.927237 -247.7244)
			(xy 98.927235 -247.724422) (xy 99.255338 -247.724422) (xy 99.259298 -247.675368) (xy 99.271075 -247.627584)
			(xy 99.290366 -247.582308) (xy 99.316669 -247.540712) (xy 99.349304 -247.503875) (xy 99.387425 -247.47275)
			(xy 99.430046 -247.448143) (xy 99.476062 -247.430691) (xy 99.524281 -247.420847) (xy 99.573456 -247.418866)
			(xy 99.622311 -247.424798) (xy 99.669582 -247.43849) (xy 99.714044 -247.459588) (xy 99.754547 -247.487544)
			(xy 99.79004 -247.521636) (xy 99.819605 -247.56098) (xy 99.842476 -247.604557) (xy 99.85806 -247.651238)
			(xy 99.865955 -247.699815) (xy 99.86645 -247.7244) (xy 100.194807 -247.7244) (xy 100.198983 -247.674014)
			(xy 100.211395 -247.625004) (xy 100.231706 -247.578704) (xy 100.259361 -247.53638) (xy 100.293605 -247.499185)
			(xy 100.333506 -247.468135) (xy 100.377972 -247.444076) (xy 100.425793 -247.427665) (xy 100.475663 -247.41935)
			(xy 100.500942 -247.41886) (xy 101.440996 -247.41886) (xy 101.466277 -247.419309) (xy 101.516149 -247.42763)
			(xy 101.563971 -247.444047) (xy 101.608439 -247.468111) (xy 101.648339 -247.499167) (xy 101.682584 -247.536366)
			(xy 101.710238 -247.578694) (xy 101.730549 -247.624997) (xy 101.742961 -247.674011) (xy 101.747137 -247.7244)
			(xy 101.747135 -247.724422) (xy 102.075246 -247.724422) (xy 102.079206 -247.675368) (xy 102.090983 -247.627584)
			(xy 102.110274 -247.582308) (xy 102.136577 -247.540712) (xy 102.169212 -247.503875) (xy 102.207333 -247.47275)
			(xy 102.249954 -247.448143) (xy 102.29597 -247.430691) (xy 102.344189 -247.420847) (xy 102.393364 -247.418866)
			(xy 102.442219 -247.424798) (xy 102.48949 -247.43849) (xy 102.533952 -247.459588) (xy 102.574455 -247.487544)
			(xy 102.609948 -247.521636) (xy 102.639513 -247.56098) (xy 102.662384 -247.604557) (xy 102.677968 -247.651238)
			(xy 102.685863 -247.699815) (xy 102.686358 -247.7244) (xy 103.015007 -247.7244) (xy 103.019182 -247.674018)
			(xy 103.031593 -247.625011) (xy 103.0519 -247.578715) (xy 103.079551 -247.536393) (xy 103.113791 -247.499199)
			(xy 103.153685 -247.468148) (xy 103.198147 -247.444087) (xy 103.245962 -247.427673) (xy 103.295827 -247.419353)
			(xy 103.321104 -247.41886) (xy 104.261158 -247.41886) (xy 104.286441 -247.419306) (xy 104.336318 -247.427622)
			(xy 104.384145 -247.444036) (xy 104.428619 -247.468098) (xy 104.468524 -247.499153) (xy 104.502774 -247.536353)
			(xy 104.530433 -247.578683) (xy 104.550746 -247.624989) (xy 104.56316 -247.674007) (xy 104.567337 -247.7244)
			(xy 104.567335 -247.724422) (xy 104.895154 -247.724422) (xy 104.899114 -247.675368) (xy 104.910891 -247.627584)
			(xy 104.930182 -247.582308) (xy 104.956485 -247.540712) (xy 104.98912 -247.503875) (xy 105.027241 -247.47275)
			(xy 105.069862 -247.448143) (xy 105.115878 -247.430691) (xy 105.164097 -247.420847) (xy 105.213272 -247.418866)
			(xy 105.262127 -247.424798) (xy 105.309398 -247.43849) (xy 105.35386 -247.459588) (xy 105.394363 -247.487544)
			(xy 105.429856 -247.521636) (xy 105.459421 -247.56098) (xy 105.482292 -247.604557) (xy 105.497876 -247.651238)
			(xy 105.505771 -247.699815) (xy 105.506266 -247.7244) (xy 105.834907 -247.7244) (xy 105.839082 -247.674018)
			(xy 105.851493 -247.62501) (xy 105.871801 -247.578713) (xy 105.899453 -247.53639) (xy 105.933694 -247.499196)
			(xy 105.97359 -247.468145) (xy 106.018052 -247.444085) (xy 106.065869 -247.427671) (xy 106.115734 -247.419352)
			(xy 106.141012 -247.41886) (xy 107.081066 -247.41886) (xy 107.106348 -247.419306) (xy 107.156224 -247.427624)
			(xy 107.204051 -247.444038) (xy 107.248523 -247.468101) (xy 107.288427 -247.499156) (xy 107.322676 -247.536356)
			(xy 107.350334 -247.578686) (xy 107.370647 -247.624991) (xy 107.383061 -247.674008) (xy 107.387237 -247.7244)
			(xy 107.387235 -247.724422) (xy 107.715316 -247.724422) (xy 107.719276 -247.675368) (xy 107.731053 -247.627584)
			(xy 107.750344 -247.582308) (xy 107.776647 -247.540712) (xy 107.809282 -247.503875) (xy 107.847403 -247.47275)
			(xy 107.890024 -247.448143) (xy 107.93604 -247.430691) (xy 107.984259 -247.420847) (xy 108.033434 -247.418866)
			(xy 108.082289 -247.424798) (xy 108.12956 -247.43849) (xy 108.174022 -247.459588) (xy 108.214525 -247.487544)
			(xy 108.250018 -247.521636) (xy 108.279583 -247.56098) (xy 108.302454 -247.604557) (xy 108.318038 -247.651238)
			(xy 108.325933 -247.699815) (xy 108.326428 -247.724422) (xy 108.65537 -247.724422) (xy 108.65933 -247.675368)
			(xy 108.671107 -247.627584) (xy 108.690398 -247.582308) (xy 108.716701 -247.540712) (xy 108.749336 -247.503875)
			(xy 108.787457 -247.47275) (xy 108.830078 -247.448143) (xy 108.876094 -247.430691) (xy 108.924313 -247.420847)
			(xy 108.973488 -247.418866) (xy 109.022343 -247.424798) (xy 109.069614 -247.43849) (xy 109.114076 -247.459588)
			(xy 109.154579 -247.487544) (xy 109.190072 -247.521636) (xy 109.219637 -247.56098) (xy 109.242508 -247.604557)
			(xy 109.258092 -247.651238) (xy 109.265987 -247.699815) (xy 109.266482 -247.724422) (xy 109.59517 -247.724422)
			(xy 109.59913 -247.675368) (xy 109.610907 -247.627584) (xy 109.630198 -247.582308) (xy 109.656501 -247.540712)
			(xy 109.689136 -247.503875) (xy 109.727257 -247.47275) (xy 109.769878 -247.448143) (xy 109.815894 -247.430691)
			(xy 109.864113 -247.420847) (xy 109.913288 -247.418866) (xy 109.962143 -247.424798) (xy 110.009414 -247.43849)
			(xy 110.048873 -247.457214) (xy 111.456473 -247.457214) (xy 111.460503 -247.404716) (xy 111.4725 -247.353448)
			(xy 111.492183 -247.304613) (xy 111.519089 -247.259354) (xy 111.552589 -247.218733) (xy 111.591897 -247.183702)
			(xy 111.636092 -247.155082) (xy 111.684137 -247.133543) (xy 111.734908 -247.119591) (xy 111.787213 -247.113553)
			(xy 111.839827 -247.11557) (xy 111.891517 -247.125594) (xy 111.94107 -247.143392) (xy 111.987326 -247.168545)
			(xy 112.0292 -247.200464) (xy 112.065712 -247.238402) (xy 112.096004 -247.281468) (xy 112.119367 -247.328653)
			(xy 112.135253 -247.378852) (xy 112.14329 -247.430888) (xy 112.143794 -247.457214) (xy 112.14329 -247.48354)
			(xy 112.135253 -247.535576) (xy 112.119367 -247.585775) (xy 112.096004 -247.63296) (xy 112.065712 -247.676026)
			(xy 112.0292 -247.713964) (xy 112.01548 -247.724422) (xy 113.349036 -247.724422) (xy 113.352996 -247.675368)
			(xy 113.364773 -247.627584) (xy 113.384064 -247.582308) (xy 113.410367 -247.540712) (xy 113.443002 -247.503875)
			(xy 113.481123 -247.47275) (xy 113.523744 -247.448143) (xy 113.56976 -247.430691) (xy 113.617979 -247.420847)
			(xy 113.667154 -247.418866) (xy 113.716009 -247.424798) (xy 113.76328 -247.43849) (xy 113.807742 -247.459588)
			(xy 113.848245 -247.487544) (xy 113.883738 -247.521636) (xy 113.913303 -247.56098) (xy 113.936174 -247.604557)
			(xy 113.951758 -247.651238) (xy 113.959653 -247.699815) (xy 113.960148 -247.724422) (xy 114.288836 -247.724422)
			(xy 114.292796 -247.675368) (xy 114.304573 -247.627584) (xy 114.323864 -247.582308) (xy 114.350167 -247.540712)
			(xy 114.382802 -247.503875) (xy 114.420923 -247.47275) (xy 114.463544 -247.448143) (xy 114.50956 -247.430691)
			(xy 114.557779 -247.420847) (xy 114.606954 -247.418866) (xy 114.655809 -247.424798) (xy 114.70308 -247.43849)
			(xy 114.747542 -247.459588) (xy 114.788045 -247.487544) (xy 114.823538 -247.521636) (xy 114.853103 -247.56098)
			(xy 114.875974 -247.604557) (xy 114.891558 -247.651238) (xy 114.899453 -247.699815) (xy 114.899948 -247.724422)
			(xy 115.22889 -247.724422) (xy 115.23285 -247.675368) (xy 115.244627 -247.627584) (xy 115.263918 -247.582308)
			(xy 115.290221 -247.540712) (xy 115.322856 -247.503875) (xy 115.360977 -247.47275) (xy 115.403598 -247.448143)
			(xy 115.449614 -247.430691) (xy 115.497833 -247.420847) (xy 115.547008 -247.418866) (xy 115.595863 -247.424798)
			(xy 115.643134 -247.43849) (xy 115.687596 -247.459588) (xy 115.728099 -247.487544) (xy 115.763592 -247.521636)
			(xy 115.793157 -247.56098) (xy 115.816028 -247.604557) (xy 115.831612 -247.651238) (xy 115.839507 -247.699815)
			(xy 115.840002 -247.724422) (xy 116.168944 -247.724422) (xy 116.172904 -247.675368) (xy 116.184681 -247.627584)
			(xy 116.203972 -247.582308) (xy 116.230275 -247.540712) (xy 116.26291 -247.503875) (xy 116.301031 -247.47275)
			(xy 116.343652 -247.448143) (xy 116.389668 -247.430691) (xy 116.437887 -247.420847) (xy 116.487062 -247.418866)
			(xy 116.535917 -247.424798) (xy 116.583188 -247.43849) (xy 116.62765 -247.459588) (xy 116.668153 -247.487544)
			(xy 116.703646 -247.521636) (xy 116.733211 -247.56098) (xy 116.756082 -247.604557) (xy 116.771666 -247.651238)
			(xy 116.779561 -247.699815) (xy 116.780056 -247.724422) (xy 117.108998 -247.724422) (xy 117.112958 -247.675368)
			(xy 117.124735 -247.627584) (xy 117.144026 -247.582308) (xy 117.170329 -247.540712) (xy 117.202964 -247.503875)
			(xy 117.241085 -247.47275) (xy 117.283706 -247.448143) (xy 117.329722 -247.430691) (xy 117.377941 -247.420847)
			(xy 117.427116 -247.418866) (xy 117.475971 -247.424798) (xy 117.523242 -247.43849) (xy 117.567704 -247.459588)
			(xy 117.608207 -247.487544) (xy 117.6437 -247.521636) (xy 117.673265 -247.56098) (xy 117.696136 -247.604557)
			(xy 117.71172 -247.651238) (xy 117.719615 -247.699815) (xy 117.72011 -247.724422) (xy 118.049052 -247.724422)
			(xy 118.053012 -247.675368) (xy 118.064789 -247.627584) (xy 118.08408 -247.582308) (xy 118.110383 -247.540712)
			(xy 118.143018 -247.503875) (xy 118.181139 -247.47275) (xy 118.22376 -247.448143) (xy 118.269776 -247.430691)
			(xy 118.317995 -247.420847) (xy 118.36717 -247.418866) (xy 118.416025 -247.424798) (xy 118.463296 -247.43849)
			(xy 118.507758 -247.459588) (xy 118.548261 -247.487544) (xy 118.583754 -247.521636) (xy 118.613319 -247.56098)
			(xy 118.63619 -247.604557) (xy 118.651774 -247.651238) (xy 118.659669 -247.699815) (xy 118.660164 -247.724422)
			(xy 118.988852 -247.724422) (xy 118.992812 -247.675368) (xy 119.004589 -247.627584) (xy 119.02388 -247.582308)
			(xy 119.050183 -247.540712) (xy 119.082818 -247.503875) (xy 119.120939 -247.47275) (xy 119.16356 -247.448143)
			(xy 119.209576 -247.430691) (xy 119.257795 -247.420847) (xy 119.30697 -247.418866) (xy 119.355825 -247.424798)
			(xy 119.403096 -247.43849) (xy 119.447558 -247.459588) (xy 119.488061 -247.487544) (xy 119.523554 -247.521636)
			(xy 119.553119 -247.56098) (xy 119.57599 -247.604557) (xy 119.591574 -247.651238) (xy 119.599469 -247.699815)
			(xy 119.599964 -247.724422) (xy 119.928906 -247.724422) (xy 119.932866 -247.675368) (xy 119.944643 -247.627584)
			(xy 119.963934 -247.582308) (xy 119.990237 -247.540712) (xy 120.022872 -247.503875) (xy 120.060993 -247.47275)
			(xy 120.103614 -247.448143) (xy 120.14963 -247.430691) (xy 120.197849 -247.420847) (xy 120.247024 -247.418866)
			(xy 120.295879 -247.424798) (xy 120.34315 -247.43849) (xy 120.387612 -247.459588) (xy 120.428115 -247.487544)
			(xy 120.463608 -247.521636) (xy 120.493173 -247.56098) (xy 120.516044 -247.604557) (xy 120.531628 -247.651238)
			(xy 120.539523 -247.699815) (xy 120.540018 -247.724422) (xy 120.86896 -247.724422) (xy 120.87292 -247.675368)
			(xy 120.884697 -247.627584) (xy 120.903988 -247.582308) (xy 120.930291 -247.540712) (xy 120.962926 -247.503875)
			(xy 121.001047 -247.47275) (xy 121.043668 -247.448143) (xy 121.089684 -247.430691) (xy 121.137903 -247.420847)
			(xy 121.187078 -247.418866) (xy 121.235933 -247.424798) (xy 121.283204 -247.43849) (xy 121.327666 -247.459588)
			(xy 121.368169 -247.487544) (xy 121.403662 -247.521636) (xy 121.433227 -247.56098) (xy 121.456098 -247.604557)
			(xy 121.471682 -247.651238) (xy 121.479577 -247.699815) (xy 121.480072 -247.724422) (xy 121.809014 -247.724422)
			(xy 121.812974 -247.675368) (xy 121.824751 -247.627584) (xy 121.844042 -247.582308) (xy 121.870345 -247.540712)
			(xy 121.90298 -247.503875) (xy 121.941101 -247.47275) (xy 121.983722 -247.448143) (xy 122.029738 -247.430691)
			(xy 122.077957 -247.420847) (xy 122.127132 -247.418866) (xy 122.175987 -247.424798) (xy 122.223258 -247.43849)
			(xy 122.26772 -247.459588) (xy 122.308223 -247.487544) (xy 122.343716 -247.521636) (xy 122.373281 -247.56098)
			(xy 122.396152 -247.604557) (xy 122.411736 -247.651238) (xy 122.419631 -247.699815) (xy 122.420126 -247.724422)
			(xy 122.748814 -247.724422) (xy 122.752774 -247.675368) (xy 122.764551 -247.627584) (xy 122.783842 -247.582308)
			(xy 122.810145 -247.540712) (xy 122.84278 -247.503875) (xy 122.880901 -247.47275) (xy 122.923522 -247.448143)
			(xy 122.969538 -247.430691) (xy 123.017757 -247.420847) (xy 123.066932 -247.418866) (xy 123.115787 -247.424798)
			(xy 123.163058 -247.43849) (xy 123.20752 -247.459588) (xy 123.248023 -247.487544) (xy 123.283516 -247.521636)
			(xy 123.313081 -247.56098) (xy 123.335952 -247.604557) (xy 123.351536 -247.651238) (xy 123.359431 -247.699815)
			(xy 123.359926 -247.724422) (xy 123.688868 -247.724422) (xy 123.692828 -247.675368) (xy 123.704605 -247.627584)
			(xy 123.723896 -247.582308) (xy 123.750199 -247.540712) (xy 123.782834 -247.503875) (xy 123.820955 -247.47275)
			(xy 123.863576 -247.448143) (xy 123.909592 -247.430691) (xy 123.957811 -247.420847) (xy 124.006986 -247.418866)
			(xy 124.055841 -247.424798) (xy 124.103112 -247.43849) (xy 124.147574 -247.459588) (xy 124.188077 -247.487544)
			(xy 124.22357 -247.521636) (xy 124.253135 -247.56098) (xy 124.276006 -247.604557) (xy 124.29159 -247.651238)
			(xy 124.299485 -247.699815) (xy 124.29998 -247.724422) (xy 124.628922 -247.724422) (xy 124.632882 -247.675368)
			(xy 124.644659 -247.627584) (xy 124.66395 -247.582308) (xy 124.690253 -247.540712) (xy 124.722888 -247.503875)
			(xy 124.761009 -247.47275) (xy 124.80363 -247.448143) (xy 124.849646 -247.430691) (xy 124.897865 -247.420847)
			(xy 124.94704 -247.418866) (xy 124.995895 -247.424798) (xy 125.043166 -247.43849) (xy 125.087628 -247.459588)
			(xy 125.128131 -247.487544) (xy 125.163624 -247.521636) (xy 125.193189 -247.56098) (xy 125.21606 -247.604557)
			(xy 125.231644 -247.651238) (xy 125.239539 -247.699815) (xy 125.240034 -247.724422) (xy 125.568976 -247.724422)
			(xy 125.572936 -247.675368) (xy 125.584713 -247.627584) (xy 125.604004 -247.582308) (xy 125.630307 -247.540712)
			(xy 125.662942 -247.503875) (xy 125.701063 -247.47275) (xy 125.743684 -247.448143) (xy 125.7897 -247.430691)
			(xy 125.837919 -247.420847) (xy 125.887094 -247.418866) (xy 125.935949 -247.424798) (xy 125.98322 -247.43849)
			(xy 126.027682 -247.459588) (xy 126.068185 -247.487544) (xy 126.103678 -247.521636) (xy 126.133243 -247.56098)
			(xy 126.156114 -247.604557) (xy 126.171698 -247.651238) (xy 126.179593 -247.699815) (xy 126.180088 -247.724422)
			(xy 126.179593 -247.749029) (xy 126.171698 -247.797606) (xy 126.156114 -247.844287) (xy 126.133243 -247.887864)
			(xy 126.103678 -247.927208) (xy 126.068185 -247.9613) (xy 126.027682 -247.989256) (xy 125.98322 -248.010354)
			(xy 125.935949 -248.024046) (xy 125.887094 -248.029978) (xy 125.837919 -248.027997) (xy 125.7897 -248.018153)
			(xy 125.743684 -248.000701) (xy 125.701063 -247.976094) (xy 125.662942 -247.944969) (xy 125.630307 -247.908132)
			(xy 125.604004 -247.866536) (xy 125.584713 -247.82126) (xy 125.572936 -247.773476) (xy 125.568976 -247.724422)
			(xy 125.240034 -247.724422) (xy 125.239539 -247.749029) (xy 125.231644 -247.797606) (xy 125.21606 -247.844287)
			(xy 125.193189 -247.887864) (xy 125.163624 -247.927208) (xy 125.128131 -247.9613) (xy 125.087628 -247.989256)
			(xy 125.043166 -248.010354) (xy 124.995895 -248.024046) (xy 124.94704 -248.029978) (xy 124.897865 -248.027997)
			(xy 124.849646 -248.018153) (xy 124.80363 -248.000701) (xy 124.761009 -247.976094) (xy 124.722888 -247.944969)
			(xy 124.690253 -247.908132) (xy 124.66395 -247.866536) (xy 124.644659 -247.82126) (xy 124.632882 -247.773476)
			(xy 124.628922 -247.724422) (xy 124.29998 -247.724422) (xy 124.299485 -247.749029) (xy 124.29159 -247.797606)
			(xy 124.276006 -247.844287) (xy 124.253135 -247.887864) (xy 124.22357 -247.927208) (xy 124.188077 -247.9613)
			(xy 124.147574 -247.989256) (xy 124.103112 -248.010354) (xy 124.055841 -248.024046) (xy 124.006986 -248.029978)
			(xy 123.957811 -248.027997) (xy 123.909592 -248.018153) (xy 123.863576 -248.000701) (xy 123.820955 -247.976094)
			(xy 123.782834 -247.944969) (xy 123.750199 -247.908132) (xy 123.723896 -247.866536) (xy 123.704605 -247.82126)
			(xy 123.692828 -247.773476) (xy 123.688868 -247.724422) (xy 123.359926 -247.724422) (xy 123.359431 -247.749029)
			(xy 123.351536 -247.797606) (xy 123.335952 -247.844287) (xy 123.313081 -247.887864) (xy 123.283516 -247.927208)
			(xy 123.248023 -247.9613) (xy 123.20752 -247.989256) (xy 123.163058 -248.010354) (xy 123.115787 -248.024046)
			(xy 123.066932 -248.029978) (xy 123.017757 -248.027997) (xy 122.969538 -248.018153) (xy 122.923522 -248.000701)
			(xy 122.880901 -247.976094) (xy 122.84278 -247.944969) (xy 122.810145 -247.908132) (xy 122.783842 -247.866536)
			(xy 122.764551 -247.82126) (xy 122.752774 -247.773476) (xy 122.748814 -247.724422) (xy 122.420126 -247.724422)
			(xy 122.419631 -247.749029) (xy 122.411736 -247.797606) (xy 122.396152 -247.844287) (xy 122.373281 -247.887864)
			(xy 122.343716 -247.927208) (xy 122.308223 -247.9613) (xy 122.26772 -247.989256) (xy 122.223258 -248.010354)
			(xy 122.175987 -248.024046) (xy 122.127132 -248.029978) (xy 122.077957 -248.027997) (xy 122.029738 -248.018153)
			(xy 121.983722 -248.000701) (xy 121.941101 -247.976094) (xy 121.90298 -247.944969) (xy 121.870345 -247.908132)
			(xy 121.844042 -247.866536) (xy 121.824751 -247.82126) (xy 121.812974 -247.773476) (xy 121.809014 -247.724422)
			(xy 121.480072 -247.724422) (xy 121.479577 -247.749029) (xy 121.471682 -247.797606) (xy 121.456098 -247.844287)
			(xy 121.433227 -247.887864) (xy 121.403662 -247.927208) (xy 121.368169 -247.9613) (xy 121.327666 -247.989256)
			(xy 121.283204 -248.010354) (xy 121.235933 -248.024046) (xy 121.187078 -248.029978) (xy 121.137903 -248.027997)
			(xy 121.089684 -248.018153) (xy 121.043668 -248.000701) (xy 121.001047 -247.976094) (xy 120.962926 -247.944969)
			(xy 120.930291 -247.908132) (xy 120.903988 -247.866536) (xy 120.884697 -247.82126) (xy 120.87292 -247.773476)
			(xy 120.86896 -247.724422) (xy 120.540018 -247.724422) (xy 120.539523 -247.749029) (xy 120.531628 -247.797606)
			(xy 120.516044 -247.844287) (xy 120.493173 -247.887864) (xy 120.463608 -247.927208) (xy 120.428115 -247.9613)
			(xy 120.387612 -247.989256) (xy 120.34315 -248.010354) (xy 120.295879 -248.024046) (xy 120.247024 -248.029978)
			(xy 120.197849 -248.027997) (xy 120.14963 -248.018153) (xy 120.103614 -248.000701) (xy 120.060993 -247.976094)
			(xy 120.022872 -247.944969) (xy 119.990237 -247.908132) (xy 119.963934 -247.866536) (xy 119.944643 -247.82126)
			(xy 119.932866 -247.773476) (xy 119.928906 -247.724422) (xy 119.599964 -247.724422) (xy 119.599469 -247.749029)
			(xy 119.591574 -247.797606) (xy 119.57599 -247.844287) (xy 119.553119 -247.887864) (xy 119.523554 -247.927208)
			(xy 119.488061 -247.9613) (xy 119.447558 -247.989256) (xy 119.403096 -248.010354) (xy 119.355825 -248.024046)
			(xy 119.30697 -248.029978) (xy 119.257795 -248.027997) (xy 119.209576 -248.018153) (xy 119.16356 -248.000701)
			(xy 119.120939 -247.976094) (xy 119.082818 -247.944969) (xy 119.050183 -247.908132) (xy 119.02388 -247.866536)
			(xy 119.004589 -247.82126) (xy 118.992812 -247.773476) (xy 118.988852 -247.724422) (xy 118.660164 -247.724422)
			(xy 118.659669 -247.749029) (xy 118.651774 -247.797606) (xy 118.63619 -247.844287) (xy 118.613319 -247.887864)
			(xy 118.583754 -247.927208) (xy 118.548261 -247.9613) (xy 118.507758 -247.989256) (xy 118.463296 -248.010354)
			(xy 118.416025 -248.024046) (xy 118.36717 -248.029978) (xy 118.317995 -248.027997) (xy 118.269776 -248.018153)
			(xy 118.22376 -248.000701) (xy 118.181139 -247.976094) (xy 118.143018 -247.944969) (xy 118.110383 -247.908132)
			(xy 118.08408 -247.866536) (xy 118.064789 -247.82126) (xy 118.053012 -247.773476) (xy 118.049052 -247.724422)
			(xy 117.72011 -247.724422) (xy 117.719615 -247.749029) (xy 117.71172 -247.797606) (xy 117.696136 -247.844287)
			(xy 117.673265 -247.887864) (xy 117.6437 -247.927208) (xy 117.608207 -247.9613) (xy 117.567704 -247.989256)
			(xy 117.523242 -248.010354) (xy 117.475971 -248.024046) (xy 117.427116 -248.029978) (xy 117.377941 -248.027997)
			(xy 117.329722 -248.018153) (xy 117.283706 -248.000701) (xy 117.241085 -247.976094) (xy 117.202964 -247.944969)
			(xy 117.170329 -247.908132) (xy 117.144026 -247.866536) (xy 117.124735 -247.82126) (xy 117.112958 -247.773476)
			(xy 117.108998 -247.724422) (xy 116.780056 -247.724422) (xy 116.779561 -247.749029) (xy 116.771666 -247.797606)
			(xy 116.756082 -247.844287) (xy 116.733211 -247.887864) (xy 116.703646 -247.927208) (xy 116.668153 -247.9613)
			(xy 116.62765 -247.989256) (xy 116.583188 -248.010354) (xy 116.535917 -248.024046) (xy 116.487062 -248.029978)
			(xy 116.437887 -248.027997) (xy 116.389668 -248.018153) (xy 116.343652 -248.000701) (xy 116.301031 -247.976094)
			(xy 116.26291 -247.944969) (xy 116.230275 -247.908132) (xy 116.203972 -247.866536) (xy 116.184681 -247.82126)
			(xy 116.172904 -247.773476) (xy 116.168944 -247.724422) (xy 115.840002 -247.724422) (xy 115.839507 -247.749029)
			(xy 115.831612 -247.797606) (xy 115.816028 -247.844287) (xy 115.793157 -247.887864) (xy 115.763592 -247.927208)
			(xy 115.728099 -247.9613) (xy 115.687596 -247.989256) (xy 115.643134 -248.010354) (xy 115.595863 -248.024046)
			(xy 115.547008 -248.029978) (xy 115.497833 -248.027997) (xy 115.449614 -248.018153) (xy 115.403598 -248.000701)
			(xy 115.360977 -247.976094) (xy 115.322856 -247.944969) (xy 115.290221 -247.908132) (xy 115.263918 -247.866536)
			(xy 115.244627 -247.82126) (xy 115.23285 -247.773476) (xy 115.22889 -247.724422) (xy 114.899948 -247.724422)
			(xy 114.899453 -247.749029) (xy 114.891558 -247.797606) (xy 114.875974 -247.844287) (xy 114.853103 -247.887864)
			(xy 114.823538 -247.927208) (xy 114.788045 -247.9613) (xy 114.747542 -247.989256) (xy 114.70308 -248.010354)
			(xy 114.655809 -248.024046) (xy 114.606954 -248.029978) (xy 114.557779 -248.027997) (xy 114.50956 -248.018153)
			(xy 114.463544 -248.000701) (xy 114.420923 -247.976094) (xy 114.382802 -247.944969) (xy 114.350167 -247.908132)
			(xy 114.323864 -247.866536) (xy 114.304573 -247.82126) (xy 114.292796 -247.773476) (xy 114.288836 -247.724422)
			(xy 113.960148 -247.724422) (xy 113.959653 -247.749029) (xy 113.951758 -247.797606) (xy 113.936174 -247.844287)
			(xy 113.913303 -247.887864) (xy 113.883738 -247.927208) (xy 113.848245 -247.9613) (xy 113.807742 -247.989256)
			(xy 113.76328 -248.010354) (xy 113.716009 -248.024046) (xy 113.667154 -248.029978) (xy 113.617979 -248.027997)
			(xy 113.56976 -248.018153) (xy 113.523744 -248.000701) (xy 113.481123 -247.976094) (xy 113.443002 -247.944969)
			(xy 113.410367 -247.908132) (xy 113.384064 -247.866536) (xy 113.364773 -247.82126) (xy 113.352996 -247.773476)
			(xy 113.349036 -247.724422) (xy 112.01548 -247.724422) (xy 111.987326 -247.745883) (xy 111.94107 -247.771036)
			(xy 111.891517 -247.788834) (xy 111.839827 -247.798858) (xy 111.787213 -247.800875) (xy 111.734908 -247.794837)
			(xy 111.684137 -247.780885) (xy 111.636092 -247.759346) (xy 111.591897 -247.730726) (xy 111.552589 -247.695695)
			(xy 111.519089 -247.655074) (xy 111.492183 -247.609815) (xy 111.4725 -247.56098) (xy 111.460503 -247.509712)
			(xy 111.456473 -247.457214) (xy 110.048873 -247.457214) (xy 110.053876 -247.459588) (xy 110.094379 -247.487544)
			(xy 110.129872 -247.521636) (xy 110.159437 -247.56098) (xy 110.182308 -247.604557) (xy 110.197892 -247.651238)
			(xy 110.205787 -247.699815) (xy 110.206282 -247.724422) (xy 110.205787 -247.749029) (xy 110.197892 -247.797606)
			(xy 110.182308 -247.844287) (xy 110.159437 -247.887864) (xy 110.129872 -247.927208) (xy 110.094379 -247.9613)
			(xy 110.053876 -247.989256) (xy 110.009414 -248.010354) (xy 109.962143 -248.024046) (xy 109.913288 -248.029978)
			(xy 109.864113 -248.027997) (xy 109.815894 -248.018153) (xy 109.769878 -248.000701) (xy 109.727257 -247.976094)
			(xy 109.689136 -247.944969) (xy 109.656501 -247.908132) (xy 109.630198 -247.866536) (xy 109.610907 -247.82126)
			(xy 109.59913 -247.773476) (xy 109.59517 -247.724422) (xy 109.266482 -247.724422) (xy 109.265987 -247.749029)
			(xy 109.258092 -247.797606) (xy 109.242508 -247.844287) (xy 109.219637 -247.887864) (xy 109.190072 -247.927208)
			(xy 109.154579 -247.9613) (xy 109.114076 -247.989256) (xy 109.069614 -248.010354) (xy 109.022343 -248.024046)
			(xy 108.973488 -248.029978) (xy 108.924313 -248.027997) (xy 108.876094 -248.018153) (xy 108.830078 -248.000701)
			(xy 108.787457 -247.976094) (xy 108.749336 -247.944969) (xy 108.716701 -247.908132) (xy 108.690398 -247.866536)
			(xy 108.671107 -247.82126) (xy 108.65933 -247.773476) (xy 108.65537 -247.724422) (xy 108.326428 -247.724422)
			(xy 108.325933 -247.749029) (xy 108.318038 -247.797606) (xy 108.302454 -247.844287) (xy 108.279583 -247.887864)
			(xy 108.250018 -247.927208) (xy 108.214525 -247.9613) (xy 108.174022 -247.989256) (xy 108.12956 -248.010354)
			(xy 108.082289 -248.024046) (xy 108.033434 -248.029978) (xy 107.984259 -248.027997) (xy 107.93604 -248.018153)
			(xy 107.890024 -248.000701) (xy 107.847403 -247.976094) (xy 107.809282 -247.944969) (xy 107.776647 -247.908132)
			(xy 107.750344 -247.866536) (xy 107.731053 -247.82126) (xy 107.719276 -247.773476) (xy 107.715316 -247.724422)
			(xy 107.387235 -247.724422) (xy 107.383061 -247.774792) (xy 107.370647 -247.823809) (xy 107.350334 -247.870114)
			(xy 107.322676 -247.912444) (xy 107.288427 -247.949644) (xy 107.248523 -247.980699) (xy 107.204051 -248.004762)
			(xy 107.156224 -248.021176) (xy 107.106348 -248.029494) (xy 107.081066 -248.029984) (xy 106.141012 -248.029984)
			(xy 106.115734 -248.029448) (xy 106.065869 -248.021129) (xy 106.018052 -248.004715) (xy 105.97359 -247.980655)
			(xy 105.933694 -247.949604) (xy 105.899453 -247.91241) (xy 105.871801 -247.870087) (xy 105.851493 -247.82379)
			(xy 105.839082 -247.774782) (xy 105.834907 -247.7244) (xy 105.506266 -247.7244) (xy 105.506266 -247.724422)
			(xy 105.505771 -247.749029) (xy 105.497876 -247.797606) (xy 105.482292 -247.844287) (xy 105.459421 -247.887864)
			(xy 105.429856 -247.927208) (xy 105.394363 -247.9613) (xy 105.35386 -247.989256) (xy 105.309398 -248.010354)
			(xy 105.262127 -248.024046) (xy 105.213272 -248.029978) (xy 105.164097 -248.027997) (xy 105.115878 -248.018153)
			(xy 105.069862 -248.000701) (xy 105.027241 -247.976094) (xy 104.98912 -247.944969) (xy 104.956485 -247.908132)
			(xy 104.930182 -247.866536) (xy 104.910891 -247.82126) (xy 104.899114 -247.773476) (xy 104.895154 -247.724422)
			(xy 104.567335 -247.724422) (xy 104.56316 -247.774793) (xy 104.550746 -247.823811) (xy 104.530433 -247.870117)
			(xy 104.502774 -247.912447) (xy 104.468524 -247.949647) (xy 104.428619 -247.980702) (xy 104.384145 -248.004764)
			(xy 104.336318 -248.021178) (xy 104.286441 -248.029494) (xy 104.261158 -248.029984) (xy 103.321104 -248.029984)
			(xy 103.295827 -248.029447) (xy 103.245962 -248.021127) (xy 103.198147 -248.004713) (xy 103.153685 -247.980652)
			(xy 103.113791 -247.949601) (xy 103.079551 -247.912407) (xy 103.0519 -247.870085) (xy 103.031593 -247.823789)
			(xy 103.019182 -247.774782) (xy 103.015007 -247.7244) (xy 102.686358 -247.7244) (xy 102.686358 -247.724422)
			(xy 102.685863 -247.749029) (xy 102.677968 -247.797606) (xy 102.662384 -247.844287) (xy 102.639513 -247.887864)
			(xy 102.609948 -247.927208) (xy 102.574455 -247.9613) (xy 102.533952 -247.989256) (xy 102.48949 -248.010354)
			(xy 102.442219 -248.024046) (xy 102.393364 -248.029978) (xy 102.344189 -248.027997) (xy 102.29597 -248.018153)
			(xy 102.249954 -248.000701) (xy 102.207333 -247.976094) (xy 102.169212 -247.944969) (xy 102.136577 -247.908132)
			(xy 102.110274 -247.866536) (xy 102.090983 -247.82126) (xy 102.079206 -247.773476) (xy 102.075246 -247.724422)
			(xy 101.747135 -247.724422) (xy 101.742961 -247.774789) (xy 101.730549 -247.823803) (xy 101.710238 -247.870106)
			(xy 101.682584 -247.912434) (xy 101.648339 -247.949633) (xy 101.608439 -247.980689) (xy 101.563971 -248.004753)
			(xy 101.516149 -248.02117) (xy 101.466277 -248.029491) (xy 101.440996 -248.029984) (xy 100.500942 -248.029984)
			(xy 100.475663 -248.02945) (xy 100.425793 -248.021135) (xy 100.377972 -248.004724) (xy 100.333506 -247.980665)
			(xy 100.293605 -247.949615) (xy 100.259361 -247.91242) (xy 100.231706 -247.870096) (xy 100.211395 -247.823796)
			(xy 100.198983 -247.774786) (xy 100.194807 -247.7244) (xy 99.86645 -247.7244) (xy 99.86645 -247.724422)
			(xy 99.865955 -247.749029) (xy 99.85806 -247.797606) (xy 99.842476 -247.844287) (xy 99.819605 -247.887864)
			(xy 99.79004 -247.927208) (xy 99.754547 -247.9613) (xy 99.714044 -247.989256) (xy 99.669582 -248.010354)
			(xy 99.622311 -248.024046) (xy 99.573456 -248.029978) (xy 99.524281 -248.027997) (xy 99.476062 -248.018153)
			(xy 99.430046 -248.000701) (xy 99.387425 -247.976094) (xy 99.349304 -247.944969) (xy 99.316669 -247.908132)
			(xy 99.290366 -247.866536) (xy 99.271075 -247.82126) (xy 99.259298 -247.773476) (xy 99.255338 -247.724422)
			(xy 98.927235 -247.724422) (xy 98.923061 -247.77479) (xy 98.910648 -247.823805) (xy 98.890337 -247.870108)
			(xy 98.862682 -247.912437) (xy 98.828436 -247.949636) (xy 98.788534 -247.980691) (xy 98.744066 -248.004755)
			(xy 98.696242 -248.021171) (xy 98.646369 -248.029492) (xy 98.621088 -248.029984) (xy 97.681034 -248.029984)
			(xy 97.655755 -248.02945) (xy 97.605887 -248.021133) (xy 97.558067 -248.004721) (xy 97.513601 -247.980662)
			(xy 97.473702 -247.949612) (xy 97.439459 -247.912417) (xy 97.411805 -247.870093) (xy 97.391495 -247.823795)
			(xy 97.379083 -247.774785) (xy 97.374907 -247.7244) (xy 97.046902 -247.7244) (xy 97.046902 -247.724404)
			(xy 97.042814 -247.774244) (xy 97.030661 -247.822751) (xy 97.010766 -247.868631) (xy 96.983662 -247.910656)
			(xy 96.950074 -247.947703) (xy 96.910898 -247.978783) (xy 96.867182 -248.003065) (xy 96.820094 -248.0199)
			(xy 96.79559 -248.024904) (xy 96.787716 -248.026428) (xy 96.76638 -248.037858) (xy 96.758506 -248.042176)
			(xy 96.738948 -248.063766) (xy 96.733056 -248.071016) (xy 96.726429 -248.088468) (xy 96.725994 -248.097802)
			(xy 96.725994 -248.61647) (xy 96.726463 -248.626343) (xy 96.733919 -248.644629) (xy 96.740472 -248.65203)
			(xy 96.740726 -248.652284) (xy 96.975168 -248.886726) (xy 96.975676 -248.887234) (xy 96.983058 -248.893815)
			(xy 97.001357 -248.90126) (xy 97.011236 -248.901712) (xy 98.78568 -248.901712) (xy 98.792183 -248.901547)
			(xy 98.804785 -248.898333) (xy 98.810572 -248.895362) (xy 98.810572 -248.895108) (xy 98.817457 -248.890894)
			(xy 98.828329 -248.878975) (xy 98.831908 -248.87174) (xy 98.875342 -248.775982) (xy 98.871024 -248.746772)
			(xy 98.861118 -248.735342) (xy 98.843534 -248.714282) (xy 98.815395 -248.667191) (xy 98.796116 -248.615832)
			(xy 98.786317 -248.561857) (xy 98.78568 -248.534428) (xy 98.786202 -248.509173) (xy 98.794515 -248.459351)
			(xy 98.810916 -248.411577) (xy 98.834957 -248.367154) (xy 98.865981 -248.327294) (xy 98.903143 -248.293084)
			(xy 98.945429 -248.265458) (xy 98.991685 -248.245168) (xy 99.04065 -248.232768) (xy 99.090988 -248.228597)
			(xy 99.141326 -248.232768) (xy 99.190291 -248.245168) (xy 99.236547 -248.265458) (xy 99.278833 -248.293084)
			(xy 99.315995 -248.327294) (xy 99.347019 -248.367154) (xy 99.37106 -248.411577) (xy 99.387461 -248.459351)
			(xy 99.395774 -248.509173) (xy 99.396296 -248.534428) (xy 101.605346 -248.534428) (xy 101.609306 -248.485374)
			(xy 101.621083 -248.43759) (xy 101.640374 -248.392314) (xy 101.666677 -248.350718) (xy 101.699312 -248.313881)
			(xy 101.737433 -248.282756) (xy 101.780054 -248.258149) (xy 101.82607 -248.240697) (xy 101.874289 -248.230853)
			(xy 101.923464 -248.228872) (xy 101.972319 -248.234804) (xy 102.01959 -248.248496) (xy 102.064052 -248.269594)
			(xy 102.104555 -248.29755) (xy 102.140048 -248.331642) (xy 102.169613 -248.370986) (xy 102.192484 -248.414563)
			(xy 102.208068 -248.461244) (xy 102.215963 -248.509821) (xy 102.216458 -248.534428) (xy 104.425254 -248.534428)
			(xy 104.429214 -248.485374) (xy 104.440991 -248.43759) (xy 104.460282 -248.392314) (xy 104.486585 -248.350718)
			(xy 104.51922 -248.313881) (xy 104.557341 -248.282756) (xy 104.599962 -248.258149) (xy 104.645978 -248.240697)
			(xy 104.694197 -248.230853) (xy 104.743372 -248.228872) (xy 104.792227 -248.234804) (xy 104.839498 -248.248496)
			(xy 104.88396 -248.269594) (xy 104.924463 -248.29755) (xy 104.959956 -248.331642) (xy 104.989521 -248.370986)
			(xy 105.012392 -248.414563) (xy 105.027976 -248.461244) (xy 105.035871 -248.509821) (xy 105.036366 -248.534428)
			(xy 107.245162 -248.534428) (xy 107.249122 -248.485374) (xy 107.260899 -248.43759) (xy 107.28019 -248.392314)
			(xy 107.306493 -248.350718) (xy 107.339128 -248.313881) (xy 107.377249 -248.282756) (xy 107.41987 -248.258149)
			(xy 107.465886 -248.240697) (xy 107.514105 -248.230853) (xy 107.56328 -248.228872) (xy 107.612135 -248.234804)
			(xy 107.659406 -248.248496) (xy 107.703868 -248.269594) (xy 107.744371 -248.29755) (xy 107.779864 -248.331642)
			(xy 107.809429 -248.370986) (xy 107.8323 -248.414563) (xy 107.847884 -248.461244) (xy 107.855779 -248.509821)
			(xy 107.856273 -248.5344) (xy 108.185168 -248.5344) (xy 108.189339 -248.48406) (xy 108.20174 -248.435093)
			(xy 108.222032 -248.388834) (xy 108.249661 -248.346547) (xy 108.283873 -248.309385) (xy 108.323736 -248.278361)
			(xy 108.368162 -248.254321) (xy 108.415939 -248.237922) (xy 108.465764 -248.229611) (xy 108.49102 -248.22912)
			(xy 109.431074 -248.22912) (xy 109.456335 -248.229555) (xy 109.50617 -248.237867) (xy 109.553956 -248.254268)
			(xy 109.598391 -248.278312) (xy 109.638262 -248.309342) (xy 109.672482 -248.346511) (xy 109.700117 -248.388806)
			(xy 109.720412 -248.435073) (xy 109.732816 -248.48405) (xy 109.736988 -248.5344) (xy 109.736986 -248.534428)
			(xy 110.065324 -248.534428) (xy 110.069284 -248.485374) (xy 110.081061 -248.43759) (xy 110.100352 -248.392314)
			(xy 110.126655 -248.350718) (xy 110.15929 -248.313881) (xy 110.197411 -248.282756) (xy 110.240032 -248.258149)
			(xy 110.286048 -248.240697) (xy 110.334267 -248.230853) (xy 110.383442 -248.228872) (xy 110.432297 -248.234804)
			(xy 110.479568 -248.248496) (xy 110.52403 -248.269594) (xy 110.564533 -248.29755) (xy 110.600026 -248.331642)
			(xy 110.629591 -248.370986) (xy 110.652462 -248.414563) (xy 110.668046 -248.461244) (xy 110.675941 -248.509821)
			(xy 110.676436 -248.534428) (xy 112.878882 -248.534428) (xy 112.882842 -248.485374) (xy 112.894619 -248.43759)
			(xy 112.91391 -248.392314) (xy 112.940213 -248.350718) (xy 112.972848 -248.313881) (xy 113.010969 -248.282756)
			(xy 113.05359 -248.258149) (xy 113.099606 -248.240697) (xy 113.147825 -248.230853) (xy 113.197 -248.228872)
			(xy 113.245855 -248.234804) (xy 113.293126 -248.248496) (xy 113.337588 -248.269594) (xy 113.378091 -248.29755)
			(xy 113.413584 -248.331642) (xy 113.443149 -248.370986) (xy 113.46602 -248.414563) (xy 113.481604 -248.461244)
			(xy 113.489499 -248.509821) (xy 113.489994 -248.534428) (xy 113.818936 -248.534428) (xy 113.822896 -248.485374)
			(xy 113.834673 -248.43759) (xy 113.853964 -248.392314) (xy 113.880267 -248.350718) (xy 113.912902 -248.313881)
			(xy 113.951023 -248.282756) (xy 113.993644 -248.258149) (xy 114.03966 -248.240697) (xy 114.087879 -248.230853)
			(xy 114.137054 -248.228872) (xy 114.185909 -248.234804) (xy 114.23318 -248.248496) (xy 114.277642 -248.269594)
			(xy 114.318145 -248.29755) (xy 114.353638 -248.331642) (xy 114.383203 -248.370986) (xy 114.406074 -248.414563)
			(xy 114.421658 -248.461244) (xy 114.429553 -248.509821) (xy 114.430048 -248.534428) (xy 114.75899 -248.534428)
			(xy 114.76295 -248.485374) (xy 114.774727 -248.43759) (xy 114.794018 -248.392314) (xy 114.820321 -248.350718)
			(xy 114.852956 -248.313881) (xy 114.891077 -248.282756) (xy 114.933698 -248.258149) (xy 114.979714 -248.240697)
			(xy 115.027933 -248.230853) (xy 115.077108 -248.228872) (xy 115.125963 -248.234804) (xy 115.173234 -248.248496)
			(xy 115.217696 -248.269594) (xy 115.258199 -248.29755) (xy 115.293692 -248.331642) (xy 115.323257 -248.370986)
			(xy 115.346128 -248.414563) (xy 115.361712 -248.461244) (xy 115.369607 -248.509821) (xy 115.370102 -248.534428)
			(xy 115.699044 -248.534428) (xy 115.703004 -248.485374) (xy 115.714781 -248.43759) (xy 115.734072 -248.392314)
			(xy 115.760375 -248.350718) (xy 115.79301 -248.313881) (xy 115.831131 -248.282756) (xy 115.873752 -248.258149)
			(xy 115.919768 -248.240697) (xy 115.967987 -248.230853) (xy 116.017162 -248.228872) (xy 116.066017 -248.234804)
			(xy 116.113288 -248.248496) (xy 116.15775 -248.269594) (xy 116.198253 -248.29755) (xy 116.233746 -248.331642)
			(xy 116.263311 -248.370986) (xy 116.286182 -248.414563) (xy 116.301766 -248.461244) (xy 116.309661 -248.509821)
			(xy 116.310156 -248.534428) (xy 118.518952 -248.534428) (xy 118.522912 -248.485374) (xy 118.534689 -248.43759)
			(xy 118.55398 -248.392314) (xy 118.580283 -248.350718) (xy 118.612918 -248.313881) (xy 118.651039 -248.282756)
			(xy 118.69366 -248.258149) (xy 118.739676 -248.240697) (xy 118.787895 -248.230853) (xy 118.83707 -248.228872)
			(xy 118.885925 -248.234804) (xy 118.933196 -248.248496) (xy 118.977658 -248.269594) (xy 119.018161 -248.29755)
			(xy 119.053654 -248.331642) (xy 119.083219 -248.370986) (xy 119.10609 -248.414563) (xy 119.121674 -248.461244)
			(xy 119.129569 -248.509821) (xy 119.130064 -248.534428) (xy 121.33886 -248.534428) (xy 121.34282 -248.485374)
			(xy 121.354597 -248.43759) (xy 121.373888 -248.392314) (xy 121.400191 -248.350718) (xy 121.432826 -248.313881)
			(xy 121.470947 -248.282756) (xy 121.513568 -248.258149) (xy 121.559584 -248.240697) (xy 121.607803 -248.230853)
			(xy 121.656978 -248.228872) (xy 121.705833 -248.234804) (xy 121.753104 -248.248496) (xy 121.797566 -248.269594)
			(xy 121.838069 -248.29755) (xy 121.873562 -248.331642) (xy 121.903127 -248.370986) (xy 121.925998 -248.414563)
			(xy 121.941582 -248.461244) (xy 121.949477 -248.509821) (xy 121.949972 -248.534428) (xy 124.159022 -248.534428)
			(xy 124.162982 -248.485374) (xy 124.174759 -248.43759) (xy 124.19405 -248.392314) (xy 124.220353 -248.350718)
			(xy 124.252988 -248.313881) (xy 124.291109 -248.282756) (xy 124.33373 -248.258149) (xy 124.379746 -248.240697)
			(xy 124.427965 -248.230853) (xy 124.47714 -248.228872) (xy 124.525995 -248.234804) (xy 124.573266 -248.248496)
			(xy 124.617728 -248.269594) (xy 124.658231 -248.29755) (xy 124.693724 -248.331642) (xy 124.723289 -248.370986)
			(xy 124.74616 -248.414563) (xy 124.761744 -248.461244) (xy 124.769639 -248.509821) (xy 124.770134 -248.534428)
			(xy 124.769639 -248.559035) (xy 124.761744 -248.607612) (xy 124.74616 -248.654293) (xy 124.723289 -248.69787)
			(xy 124.693724 -248.737214) (xy 124.658231 -248.771306) (xy 124.617728 -248.799262) (xy 124.573266 -248.82036)
			(xy 124.525995 -248.834052) (xy 124.47714 -248.839984) (xy 124.427965 -248.838003) (xy 124.379746 -248.828159)
			(xy 124.33373 -248.810707) (xy 124.291109 -248.7861) (xy 124.252988 -248.754975) (xy 124.220353 -248.718138)
			(xy 124.19405 -248.676542) (xy 124.174759 -248.631266) (xy 124.162982 -248.583482) (xy 124.159022 -248.534428)
			(xy 121.949972 -248.534428) (xy 121.949477 -248.559035) (xy 121.941582 -248.607612) (xy 121.925998 -248.654293)
			(xy 121.903127 -248.69787) (xy 121.873562 -248.737214) (xy 121.838069 -248.771306) (xy 121.797566 -248.799262)
			(xy 121.753104 -248.82036) (xy 121.705833 -248.834052) (xy 121.656978 -248.839984) (xy 121.607803 -248.838003)
			(xy 121.559584 -248.828159) (xy 121.513568 -248.810707) (xy 121.470947 -248.7861) (xy 121.432826 -248.754975)
			(xy 121.400191 -248.718138) (xy 121.373888 -248.676542) (xy 121.354597 -248.631266) (xy 121.34282 -248.583482)
			(xy 121.33886 -248.534428) (xy 119.130064 -248.534428) (xy 119.129569 -248.559035) (xy 119.121674 -248.607612)
			(xy 119.10609 -248.654293) (xy 119.083219 -248.69787) (xy 119.053654 -248.737214) (xy 119.018161 -248.771306)
			(xy 118.977658 -248.799262) (xy 118.933196 -248.82036) (xy 118.885925 -248.834052) (xy 118.83707 -248.839984)
			(xy 118.787895 -248.838003) (xy 118.739676 -248.828159) (xy 118.69366 -248.810707) (xy 118.651039 -248.7861)
			(xy 118.612918 -248.754975) (xy 118.580283 -248.718138) (xy 118.55398 -248.676542) (xy 118.534689 -248.631266)
			(xy 118.522912 -248.583482) (xy 118.518952 -248.534428) (xy 116.310156 -248.534428) (xy 116.309661 -248.559035)
			(xy 116.301766 -248.607612) (xy 116.286182 -248.654293) (xy 116.263311 -248.69787) (xy 116.233746 -248.737214)
			(xy 116.198253 -248.771306) (xy 116.15775 -248.799262) (xy 116.113288 -248.82036) (xy 116.066017 -248.834052)
			(xy 116.017162 -248.839984) (xy 115.967987 -248.838003) (xy 115.919768 -248.828159) (xy 115.873752 -248.810707)
			(xy 115.831131 -248.7861) (xy 115.79301 -248.754975) (xy 115.760375 -248.718138) (xy 115.734072 -248.676542)
			(xy 115.714781 -248.631266) (xy 115.703004 -248.583482) (xy 115.699044 -248.534428) (xy 115.370102 -248.534428)
			(xy 115.369607 -248.559035) (xy 115.361712 -248.607612) (xy 115.346128 -248.654293) (xy 115.323257 -248.69787)
			(xy 115.293692 -248.737214) (xy 115.258199 -248.771306) (xy 115.217696 -248.799262) (xy 115.173234 -248.82036)
			(xy 115.125963 -248.834052) (xy 115.077108 -248.839984) (xy 115.027933 -248.838003) (xy 114.979714 -248.828159)
			(xy 114.933698 -248.810707) (xy 114.891077 -248.7861) (xy 114.852956 -248.754975) (xy 114.820321 -248.718138)
			(xy 114.794018 -248.676542) (xy 114.774727 -248.631266) (xy 114.76295 -248.583482) (xy 114.75899 -248.534428)
			(xy 114.430048 -248.534428) (xy 114.429553 -248.559035) (xy 114.421658 -248.607612) (xy 114.406074 -248.654293)
			(xy 114.383203 -248.69787) (xy 114.353638 -248.737214) (xy 114.318145 -248.771306) (xy 114.277642 -248.799262)
			(xy 114.23318 -248.82036) (xy 114.185909 -248.834052) (xy 114.137054 -248.839984) (xy 114.087879 -248.838003)
			(xy 114.03966 -248.828159) (xy 113.993644 -248.810707) (xy 113.951023 -248.7861) (xy 113.912902 -248.754975)
			(xy 113.880267 -248.718138) (xy 113.853964 -248.676542) (xy 113.834673 -248.631266) (xy 113.822896 -248.583482)
			(xy 113.818936 -248.534428) (xy 113.489994 -248.534428) (xy 113.489499 -248.559035) (xy 113.481604 -248.607612)
			(xy 113.46602 -248.654293) (xy 113.443149 -248.69787) (xy 113.413584 -248.737214) (xy 113.378091 -248.771306)
			(xy 113.337588 -248.799262) (xy 113.293126 -248.82036) (xy 113.245855 -248.834052) (xy 113.197 -248.839984)
			(xy 113.147825 -248.838003) (xy 113.099606 -248.828159) (xy 113.05359 -248.810707) (xy 113.010969 -248.7861)
			(xy 112.972848 -248.754975) (xy 112.940213 -248.718138) (xy 112.91391 -248.676542) (xy 112.894619 -248.631266)
			(xy 112.882842 -248.583482) (xy 112.878882 -248.534428) (xy 110.676436 -248.534428) (xy 110.675941 -248.559035)
			(xy 110.668046 -248.607612) (xy 110.652462 -248.654293) (xy 110.629591 -248.69787) (xy 110.600026 -248.737214)
			(xy 110.564533 -248.771306) (xy 110.52403 -248.799262) (xy 110.479568 -248.82036) (xy 110.432297 -248.834052)
			(xy 110.383442 -248.839984) (xy 110.334267 -248.838003) (xy 110.286048 -248.828159) (xy 110.240032 -248.810707)
			(xy 110.197411 -248.7861) (xy 110.15929 -248.754975) (xy 110.126655 -248.718138) (xy 110.100352 -248.676542)
			(xy 110.081061 -248.631266) (xy 110.069284 -248.583482) (xy 110.065324 -248.534428) (xy 109.736986 -248.534428)
			(xy 109.732816 -248.58475) (xy 109.720412 -248.633727) (xy 109.700117 -248.679994) (xy 109.672482 -248.722289)
			(xy 109.638262 -248.759458) (xy 109.598391 -248.790488) (xy 109.553956 -248.814532) (xy 109.50617 -248.830933)
			(xy 109.456335 -248.839245) (xy 109.431074 -248.839736) (xy 108.49102 -248.839736) (xy 108.465764 -248.839189)
			(xy 108.415939 -248.830878) (xy 108.368162 -248.814479) (xy 108.323736 -248.790439) (xy 108.283873 -248.759415)
			(xy 108.249661 -248.722253) (xy 108.222032 -248.679966) (xy 108.20174 -248.633707) (xy 108.189339 -248.58474)
			(xy 108.185168 -248.5344) (xy 107.856273 -248.5344) (xy 107.856274 -248.534428) (xy 107.855779 -248.559035)
			(xy 107.847884 -248.607612) (xy 107.8323 -248.654293) (xy 107.809429 -248.69787) (xy 107.779864 -248.737214)
			(xy 107.744371 -248.771306) (xy 107.703868 -248.799262) (xy 107.659406 -248.82036) (xy 107.612135 -248.834052)
			(xy 107.56328 -248.839984) (xy 107.514105 -248.838003) (xy 107.465886 -248.828159) (xy 107.41987 -248.810707)
			(xy 107.377249 -248.7861) (xy 107.339128 -248.754975) (xy 107.306493 -248.718138) (xy 107.28019 -248.676542)
			(xy 107.260899 -248.631266) (xy 107.249122 -248.583482) (xy 107.245162 -248.534428) (xy 105.036366 -248.534428)
			(xy 105.035871 -248.559035) (xy 105.027976 -248.607612) (xy 105.012392 -248.654293) (xy 104.989521 -248.69787)
			(xy 104.959956 -248.737214) (xy 104.924463 -248.771306) (xy 104.88396 -248.799262) (xy 104.839498 -248.82036)
			(xy 104.792227 -248.834052) (xy 104.743372 -248.839984) (xy 104.694197 -248.838003) (xy 104.645978 -248.828159)
			(xy 104.599962 -248.810707) (xy 104.557341 -248.7861) (xy 104.51922 -248.754975) (xy 104.486585 -248.718138)
			(xy 104.460282 -248.676542) (xy 104.440991 -248.631266) (xy 104.429214 -248.583482) (xy 104.425254 -248.534428)
			(xy 102.216458 -248.534428) (xy 102.215963 -248.559035) (xy 102.208068 -248.607612) (xy 102.192484 -248.654293)
			(xy 102.169613 -248.69787) (xy 102.140048 -248.737214) (xy 102.104555 -248.771306) (xy 102.064052 -248.799262)
			(xy 102.01959 -248.82036) (xy 101.972319 -248.834052) (xy 101.923464 -248.839984) (xy 101.874289 -248.838003)
			(xy 101.82607 -248.828159) (xy 101.780054 -248.810707) (xy 101.737433 -248.7861) (xy 101.699312 -248.754975)
			(xy 101.666677 -248.718138) (xy 101.640374 -248.676542) (xy 101.621083 -248.631266) (xy 101.609306 -248.583482)
			(xy 101.605346 -248.534428) (xy 99.396296 -248.534428) (xy 99.396196 -248.546159) (xy 99.394419 -248.569553)
			(xy 99.39274 -248.581164) (xy 99.392232 -248.584974) (xy 99.392232 -248.585228) (xy 99.387195 -248.611523)
			(xy 99.369165 -248.66193) (xy 99.34264 -248.708431) (xy 99.308427 -248.749607) (xy 99.267572 -248.784201)
			(xy 99.221321 -248.811159) (xy 99.196398 -248.82094) (xy 99.188543 -248.824146) (xy 99.175404 -248.834863)
			(xy 99.166513 -248.849302) (xy 99.164394 -248.857516) (xy 99.146106 -248.93905) (xy 99.144825 -248.945837)
			(xy 99.145607 -248.959623) (xy 99.14763 -248.966228) (xy 99.15144 -248.977658) (xy 99.159822 -248.98604)
			(xy 99.273868 -249.100086) (xy 99.275138 -249.101102) (xy 99.275138 -249.101356) (xy 99.28219 -249.107419)
			(xy 99.299387 -249.114459) (xy 99.308666 -249.115072) (xy 99.331018 -249.11558) (xy 99.335544 -249.11556)
			(xy 99.344482 -249.114148) (xy 99.348798 -249.112786) (xy 99.371404 -249.104912) (xy 99.377754 -249.100086)
			(xy 99.397713 -249.085703) (xy 99.441296 -249.062886) (xy 99.487977 -249.047363) (xy 99.536544 -249.039535)
			(xy 99.561142 -249.039126) (xy 99.569524 -249.039126) (xy 99.595234 -249.040368) (xy 99.645718 -249.050392)
			(xy 99.693806 -249.068738) (xy 99.738139 -249.094885) (xy 99.777461 -249.128094) (xy 99.81066 -249.167425)
			(xy 99.836796 -249.211764) (xy 99.855129 -249.259858) (xy 99.865141 -249.310344) (xy 99.86645 -249.336052)
			(xy 99.86645 -249.344434) (xy 101.135192 -249.344434) (xy 101.139152 -249.29538) (xy 101.150929 -249.247596)
			(xy 101.17022 -249.20232) (xy 101.196523 -249.160724) (xy 101.229158 -249.123887) (xy 101.267279 -249.092762)
			(xy 101.3099 -249.068155) (xy 101.355916 -249.050703) (xy 101.404135 -249.040859) (xy 101.45331 -249.038878)
			(xy 101.502165 -249.04481) (xy 101.549436 -249.058502) (xy 101.593898 -249.0796) (xy 101.634401 -249.107556)
			(xy 101.669894 -249.141648) (xy 101.699459 -249.180992) (xy 101.72233 -249.224569) (xy 101.737914 -249.27125)
			(xy 101.745809 -249.319827) (xy 101.746304 -249.344434) (xy 103.0153 -249.344434) (xy 103.01926 -249.29538)
			(xy 103.031037 -249.247596) (xy 103.050328 -249.20232) (xy 103.076631 -249.160724) (xy 103.109266 -249.123887)
			(xy 103.147387 -249.092762) (xy 103.190008 -249.068155) (xy 103.236024 -249.050703) (xy 103.284243 -249.040859)
			(xy 103.333418 -249.038878) (xy 103.382273 -249.04481) (xy 103.429544 -249.058502) (xy 103.474006 -249.0796)
			(xy 103.514509 -249.107556) (xy 103.550002 -249.141648) (xy 103.579567 -249.180992) (xy 103.602438 -249.224569)
			(xy 103.618022 -249.27125) (xy 103.625917 -249.319827) (xy 103.626412 -249.344434) (xy 104.895154 -249.344434)
			(xy 104.899114 -249.29538) (xy 104.910891 -249.247596) (xy 104.930182 -249.20232) (xy 104.956485 -249.160724)
			(xy 104.98912 -249.123887) (xy 105.027241 -249.092762) (xy 105.069862 -249.068155) (xy 105.115878 -249.050703)
			(xy 105.164097 -249.040859) (xy 105.213272 -249.038878) (xy 105.262127 -249.04481) (xy 105.309398 -249.058502)
			(xy 105.35386 -249.0796) (xy 105.394363 -249.107556) (xy 105.429856 -249.141648) (xy 105.459421 -249.180992)
			(xy 105.482292 -249.224569) (xy 105.497876 -249.27125) (xy 105.505771 -249.319827) (xy 105.506266 -249.344434)
			(xy 106.775262 -249.344434) (xy 106.779222 -249.29538) (xy 106.790999 -249.247596) (xy 106.81029 -249.20232)
			(xy 106.836593 -249.160724) (xy 106.869228 -249.123887) (xy 106.907349 -249.092762) (xy 106.94997 -249.068155)
			(xy 106.995986 -249.050703) (xy 107.044205 -249.040859) (xy 107.09338 -249.038878) (xy 107.142235 -249.04481)
			(xy 107.189506 -249.058502) (xy 107.233968 -249.0796) (xy 107.274471 -249.107556) (xy 107.309964 -249.141648)
			(xy 107.339529 -249.180992) (xy 107.3624 -249.224569) (xy 107.377984 -249.27125) (xy 107.385879 -249.319827)
			(xy 107.386374 -249.344434) (xy 108.65537 -249.344434) (xy 108.65933 -249.29538) (xy 108.671107 -249.247596)
			(xy 108.690398 -249.20232) (xy 108.716701 -249.160724) (xy 108.749336 -249.123887) (xy 108.787457 -249.092762)
			(xy 108.830078 -249.068155) (xy 108.876094 -249.050703) (xy 108.924313 -249.040859) (xy 108.973488 -249.038878)
			(xy 109.022343 -249.04481) (xy 109.069614 -249.058502) (xy 109.114076 -249.0796) (xy 109.154579 -249.107556)
			(xy 109.190072 -249.141648) (xy 109.219637 -249.180992) (xy 109.242508 -249.224569) (xy 109.258092 -249.27125)
			(xy 109.265987 -249.319827) (xy 109.266482 -249.344434) (xy 109.266124 -249.362214) (xy 111.456473 -249.362214)
			(xy 111.460503 -249.309716) (xy 111.4725 -249.258448) (xy 111.492183 -249.209613) (xy 111.519089 -249.164354)
			(xy 111.552589 -249.123733) (xy 111.591897 -249.088702) (xy 111.636092 -249.060082) (xy 111.684137 -249.038543)
			(xy 111.734908 -249.024591) (xy 111.787213 -249.018553) (xy 111.839827 -249.02057) (xy 111.891517 -249.030594)
			(xy 111.94107 -249.048392) (xy 111.987326 -249.073545) (xy 112.0292 -249.105464) (xy 112.065712 -249.143402)
			(xy 112.096004 -249.186468) (xy 112.119367 -249.233653) (xy 112.135253 -249.283852) (xy 112.14329 -249.335888)
			(xy 112.143454 -249.344434) (xy 113.349036 -249.344434) (xy 113.352996 -249.29538) (xy 113.364773 -249.247596)
			(xy 113.384064 -249.20232) (xy 113.410367 -249.160724) (xy 113.443002 -249.123887) (xy 113.481123 -249.092762)
			(xy 113.523744 -249.068155) (xy 113.56976 -249.050703) (xy 113.617979 -249.040859) (xy 113.667154 -249.038878)
			(xy 113.716009 -249.04481) (xy 113.76328 -249.058502) (xy 113.807742 -249.0796) (xy 113.848245 -249.107556)
			(xy 113.883738 -249.141648) (xy 113.913303 -249.180992) (xy 113.936174 -249.224569) (xy 113.951758 -249.27125)
			(xy 113.959653 -249.319827) (xy 113.960148 -249.344434) (xy 115.22889 -249.344434) (xy 115.23285 -249.29538)
			(xy 115.244627 -249.247596) (xy 115.263918 -249.20232) (xy 115.290221 -249.160724) (xy 115.322856 -249.123887)
			(xy 115.360977 -249.092762) (xy 115.403598 -249.068155) (xy 115.449614 -249.050703) (xy 115.497833 -249.040859)
			(xy 115.547008 -249.038878) (xy 115.595863 -249.04481) (xy 115.643134 -249.058502) (xy 115.687596 -249.0796)
			(xy 115.728099 -249.107556) (xy 115.763592 -249.141648) (xy 115.793157 -249.180992) (xy 115.816028 -249.224569)
			(xy 115.831612 -249.27125) (xy 115.839507 -249.319827) (xy 115.840002 -249.344434) (xy 117.108998 -249.344434)
			(xy 117.112958 -249.29538) (xy 117.124735 -249.247596) (xy 117.144026 -249.20232) (xy 117.170329 -249.160724)
			(xy 117.202964 -249.123887) (xy 117.241085 -249.092762) (xy 117.283706 -249.068155) (xy 117.329722 -249.050703)
			(xy 117.377941 -249.040859) (xy 117.427116 -249.038878) (xy 117.475971 -249.04481) (xy 117.523242 -249.058502)
			(xy 117.567704 -249.0796) (xy 117.608207 -249.107556) (xy 117.6437 -249.141648) (xy 117.673265 -249.180992)
			(xy 117.696136 -249.224569) (xy 117.71172 -249.27125) (xy 117.719615 -249.319827) (xy 117.72011 -249.344434)
			(xy 118.988852 -249.344434) (xy 118.992812 -249.29538) (xy 119.004589 -249.247596) (xy 119.02388 -249.20232)
			(xy 119.050183 -249.160724) (xy 119.082818 -249.123887) (xy 119.120939 -249.092762) (xy 119.16356 -249.068155)
			(xy 119.209576 -249.050703) (xy 119.257795 -249.040859) (xy 119.30697 -249.038878) (xy 119.355825 -249.04481)
			(xy 119.403096 -249.058502) (xy 119.447558 -249.0796) (xy 119.488061 -249.107556) (xy 119.523554 -249.141648)
			(xy 119.553119 -249.180992) (xy 119.57599 -249.224569) (xy 119.591574 -249.27125) (xy 119.599469 -249.319827)
			(xy 119.599964 -249.344434) (xy 120.86896 -249.344434) (xy 120.87292 -249.29538) (xy 120.884697 -249.247596)
			(xy 120.903988 -249.20232) (xy 120.930291 -249.160724) (xy 120.962926 -249.123887) (xy 121.001047 -249.092762)
			(xy 121.043668 -249.068155) (xy 121.089684 -249.050703) (xy 121.137903 -249.040859) (xy 121.187078 -249.038878)
			(xy 121.235933 -249.04481) (xy 121.283204 -249.058502) (xy 121.327666 -249.0796) (xy 121.368169 -249.107556)
			(xy 121.403662 -249.141648) (xy 121.433227 -249.180992) (xy 121.456098 -249.224569) (xy 121.471682 -249.27125)
			(xy 121.479577 -249.319827) (xy 121.480072 -249.344434) (xy 122.748814 -249.344434) (xy 122.752774 -249.29538)
			(xy 122.764551 -249.247596) (xy 122.783842 -249.20232) (xy 122.810145 -249.160724) (xy 122.84278 -249.123887)
			(xy 122.880901 -249.092762) (xy 122.923522 -249.068155) (xy 122.969538 -249.050703) (xy 123.017757 -249.040859)
			(xy 123.066932 -249.038878) (xy 123.115787 -249.04481) (xy 123.163058 -249.058502) (xy 123.20752 -249.0796)
			(xy 123.248023 -249.107556) (xy 123.283516 -249.141648) (xy 123.313081 -249.180992) (xy 123.335952 -249.224569)
			(xy 123.351536 -249.27125) (xy 123.359431 -249.319827) (xy 123.359926 -249.344434) (xy 124.628922 -249.344434)
			(xy 124.632882 -249.29538) (xy 124.644659 -249.247596) (xy 124.66395 -249.20232) (xy 124.690253 -249.160724)
			(xy 124.722888 -249.123887) (xy 124.761009 -249.092762) (xy 124.80363 -249.068155) (xy 124.849646 -249.050703)
			(xy 124.897865 -249.040859) (xy 124.94704 -249.038878) (xy 124.995895 -249.04481) (xy 125.043166 -249.058502)
			(xy 125.087628 -249.0796) (xy 125.128131 -249.107556) (xy 125.163624 -249.141648) (xy 125.193189 -249.180992)
			(xy 125.21606 -249.224569) (xy 125.231644 -249.27125) (xy 125.239539 -249.319827) (xy 125.240034 -249.344434)
			(xy 125.239539 -249.369041) (xy 125.231644 -249.417618) (xy 125.21606 -249.464299) (xy 125.193189 -249.507876)
			(xy 125.163624 -249.54722) (xy 125.128131 -249.581312) (xy 125.087628 -249.609268) (xy 125.043166 -249.630366)
			(xy 124.995895 -249.644058) (xy 124.94704 -249.64999) (xy 124.897865 -249.648009) (xy 124.849646 -249.638165)
			(xy 124.80363 -249.620713) (xy 124.761009 -249.596106) (xy 124.722888 -249.564981) (xy 124.690253 -249.528144)
			(xy 124.66395 -249.486548) (xy 124.644659 -249.441272) (xy 124.632882 -249.393488) (xy 124.628922 -249.344434)
			(xy 123.359926 -249.344434) (xy 123.359431 -249.369041) (xy 123.351536 -249.417618) (xy 123.335952 -249.464299)
			(xy 123.313081 -249.507876) (xy 123.283516 -249.54722) (xy 123.248023 -249.581312) (xy 123.20752 -249.609268)
			(xy 123.163058 -249.630366) (xy 123.115787 -249.644058) (xy 123.066932 -249.64999) (xy 123.017757 -249.648009)
			(xy 122.969538 -249.638165) (xy 122.923522 -249.620713) (xy 122.880901 -249.596106) (xy 122.84278 -249.564981)
			(xy 122.810145 -249.528144) (xy 122.783842 -249.486548) (xy 122.764551 -249.441272) (xy 122.752774 -249.393488)
			(xy 122.748814 -249.344434) (xy 121.480072 -249.344434) (xy 121.479577 -249.369041) (xy 121.471682 -249.417618)
			(xy 121.456098 -249.464299) (xy 121.433227 -249.507876) (xy 121.403662 -249.54722) (xy 121.368169 -249.581312)
			(xy 121.327666 -249.609268) (xy 121.283204 -249.630366) (xy 121.235933 -249.644058) (xy 121.187078 -249.64999)
			(xy 121.137903 -249.648009) (xy 121.089684 -249.638165) (xy 121.043668 -249.620713) (xy 121.001047 -249.596106)
			(xy 120.962926 -249.564981) (xy 120.930291 -249.528144) (xy 120.903988 -249.486548) (xy 120.884697 -249.441272)
			(xy 120.87292 -249.393488) (xy 120.86896 -249.344434) (xy 119.599964 -249.344434) (xy 119.599469 -249.369041)
			(xy 119.591574 -249.417618) (xy 119.57599 -249.464299) (xy 119.553119 -249.507876) (xy 119.523554 -249.54722)
			(xy 119.488061 -249.581312) (xy 119.447558 -249.609268) (xy 119.403096 -249.630366) (xy 119.355825 -249.644058)
			(xy 119.30697 -249.64999) (xy 119.257795 -249.648009) (xy 119.209576 -249.638165) (xy 119.16356 -249.620713)
			(xy 119.120939 -249.596106) (xy 119.082818 -249.564981) (xy 119.050183 -249.528144) (xy 119.02388 -249.486548)
			(xy 119.004589 -249.441272) (xy 118.992812 -249.393488) (xy 118.988852 -249.344434) (xy 117.72011 -249.344434)
			(xy 117.719615 -249.369041) (xy 117.71172 -249.417618) (xy 117.696136 -249.464299) (xy 117.673265 -249.507876)
			(xy 117.6437 -249.54722) (xy 117.608207 -249.581312) (xy 117.567704 -249.609268) (xy 117.523242 -249.630366)
			(xy 117.475971 -249.644058) (xy 117.427116 -249.64999) (xy 117.377941 -249.648009) (xy 117.329722 -249.638165)
			(xy 117.283706 -249.620713) (xy 117.241085 -249.596106) (xy 117.202964 -249.564981) (xy 117.170329 -249.528144)
			(xy 117.144026 -249.486548) (xy 117.124735 -249.441272) (xy 117.112958 -249.393488) (xy 117.108998 -249.344434)
			(xy 115.840002 -249.344434) (xy 115.839507 -249.369041) (xy 115.831612 -249.417618) (xy 115.816028 -249.464299)
			(xy 115.793157 -249.507876) (xy 115.763592 -249.54722) (xy 115.728099 -249.581312) (xy 115.687596 -249.609268)
			(xy 115.643134 -249.630366) (xy 115.595863 -249.644058) (xy 115.547008 -249.64999) (xy 115.497833 -249.648009)
			(xy 115.449614 -249.638165) (xy 115.403598 -249.620713) (xy 115.360977 -249.596106) (xy 115.322856 -249.564981)
			(xy 115.290221 -249.528144) (xy 115.263918 -249.486548) (xy 115.244627 -249.441272) (xy 115.23285 -249.393488)
			(xy 115.22889 -249.344434) (xy 113.960148 -249.344434) (xy 113.959653 -249.369041) (xy 113.951758 -249.417618)
			(xy 113.936174 -249.464299) (xy 113.913303 -249.507876) (xy 113.883738 -249.54722) (xy 113.848245 -249.581312)
			(xy 113.807742 -249.609268) (xy 113.76328 -249.630366) (xy 113.716009 -249.644058) (xy 113.667154 -249.64999)
			(xy 113.617979 -249.648009) (xy 113.56976 -249.638165) (xy 113.523744 -249.620713) (xy 113.481123 -249.596106)
			(xy 113.443002 -249.564981) (xy 113.410367 -249.528144) (xy 113.384064 -249.486548) (xy 113.364773 -249.441272)
			(xy 113.352996 -249.393488) (xy 113.349036 -249.344434) (xy 112.143454 -249.344434) (xy 112.143794 -249.362214)
			(xy 112.14329 -249.38854) (xy 112.135253 -249.440576) (xy 112.119367 -249.490775) (xy 112.096004 -249.53796)
			(xy 112.065712 -249.581026) (xy 112.0292 -249.618964) (xy 111.987326 -249.650883) (xy 111.94107 -249.676036)
			(xy 111.891517 -249.693834) (xy 111.839827 -249.703858) (xy 111.787213 -249.705875) (xy 111.734908 -249.699837)
			(xy 111.684137 -249.685885) (xy 111.636092 -249.664346) (xy 111.591897 -249.635726) (xy 111.552589 -249.600695)
			(xy 111.519089 -249.560074) (xy 111.492183 -249.514815) (xy 111.4725 -249.46598) (xy 111.460503 -249.414712)
			(xy 111.456473 -249.362214) (xy 109.266124 -249.362214) (xy 109.265987 -249.369041) (xy 109.258092 -249.417618)
			(xy 109.242508 -249.464299) (xy 109.219637 -249.507876) (xy 109.190072 -249.54722) (xy 109.154579 -249.581312)
			(xy 109.114076 -249.609268) (xy 109.069614 -249.630366) (xy 109.022343 -249.644058) (xy 108.973488 -249.64999)
			(xy 108.924313 -249.648009) (xy 108.876094 -249.638165) (xy 108.830078 -249.620713) (xy 108.787457 -249.596106)
			(xy 108.749336 -249.564981) (xy 108.716701 -249.528144) (xy 108.690398 -249.486548) (xy 108.671107 -249.441272)
			(xy 108.65933 -249.393488) (xy 108.65537 -249.344434) (xy 107.386374 -249.344434) (xy 107.385879 -249.369041)
			(xy 107.377984 -249.417618) (xy 107.3624 -249.464299) (xy 107.339529 -249.507876) (xy 107.309964 -249.54722)
			(xy 107.274471 -249.581312) (xy 107.233968 -249.609268) (xy 107.189506 -249.630366) (xy 107.142235 -249.644058)
			(xy 107.09338 -249.64999) (xy 107.044205 -249.648009) (xy 106.995986 -249.638165) (xy 106.94997 -249.620713)
			(xy 106.907349 -249.596106) (xy 106.869228 -249.564981) (xy 106.836593 -249.528144) (xy 106.81029 -249.486548)
			(xy 106.790999 -249.441272) (xy 106.779222 -249.393488) (xy 106.775262 -249.344434) (xy 105.506266 -249.344434)
			(xy 105.505771 -249.369041) (xy 105.497876 -249.417618) (xy 105.482292 -249.464299) (xy 105.459421 -249.507876)
			(xy 105.429856 -249.54722) (xy 105.394363 -249.581312) (xy 105.35386 -249.609268) (xy 105.309398 -249.630366)
			(xy 105.262127 -249.644058) (xy 105.213272 -249.64999) (xy 105.164097 -249.648009) (xy 105.115878 -249.638165)
			(xy 105.069862 -249.620713) (xy 105.027241 -249.596106) (xy 104.98912 -249.564981) (xy 104.956485 -249.528144)
			(xy 104.930182 -249.486548) (xy 104.910891 -249.441272) (xy 104.899114 -249.393488) (xy 104.895154 -249.344434)
			(xy 103.626412 -249.344434) (xy 103.625917 -249.369041) (xy 103.618022 -249.417618) (xy 103.602438 -249.464299)
			(xy 103.579567 -249.507876) (xy 103.550002 -249.54722) (xy 103.514509 -249.581312) (xy 103.474006 -249.609268)
			(xy 103.429544 -249.630366) (xy 103.382273 -249.644058) (xy 103.333418 -249.64999) (xy 103.284243 -249.648009)
			(xy 103.236024 -249.638165) (xy 103.190008 -249.620713) (xy 103.147387 -249.596106) (xy 103.109266 -249.564981)
			(xy 103.076631 -249.528144) (xy 103.050328 -249.486548) (xy 103.031037 -249.441272) (xy 103.01926 -249.393488)
			(xy 103.0153 -249.344434) (xy 101.746304 -249.344434) (xy 101.745809 -249.369041) (xy 101.737914 -249.417618)
			(xy 101.72233 -249.464299) (xy 101.699459 -249.507876) (xy 101.669894 -249.54722) (xy 101.634401 -249.581312)
			(xy 101.593898 -249.609268) (xy 101.549436 -249.630366) (xy 101.502165 -249.644058) (xy 101.45331 -249.64999)
			(xy 101.404135 -249.648009) (xy 101.355916 -249.638165) (xy 101.3099 -249.620713) (xy 101.267279 -249.596106)
			(xy 101.229158 -249.564981) (xy 101.196523 -249.528144) (xy 101.17022 -249.486548) (xy 101.150929 -249.441272)
			(xy 101.139152 -249.393488) (xy 101.135192 -249.344434) (xy 99.86645 -249.344434) (xy 99.865972 -249.369026)
			(xy 99.858128 -249.417579) (xy 99.842615 -249.464252) (xy 99.819832 -249.50784) (xy 99.80549 -249.527822)
			(xy 99.800664 -249.534172) (xy 99.79279 -249.556778) (xy 99.791386 -249.561083) (xy 99.789988 -249.570029)
			(xy 99.789996 -249.574558) (xy 99.790504 -249.59691) (xy 99.791143 -249.606185) (xy 99.79817 -249.62338)
			(xy 99.80422 -249.630438) (xy 99.804982 -249.6312) (xy 100.015294 -249.841512) (xy 100.032566 -249.848878)
			(xy 100.042218 -249.849386) (xy 100.067592 -249.850825) (xy 100.117367 -249.861079) (xy 100.164757 -249.879435)
			(xy 100.208451 -249.905386) (xy 100.247244 -249.938216) (xy 100.280063 -249.977018) (xy 100.306002 -250.02072)
			(xy 100.324345 -250.068114) (xy 100.334585 -250.117892) (xy 100.336096 -250.143264) (xy 100.336604 -250.152916)
			(xy 100.337254 -250.15444) (xy 101.605346 -250.15444) (xy 101.609306 -250.105386) (xy 101.621083 -250.057602)
			(xy 101.640374 -250.012326) (xy 101.666677 -249.97073) (xy 101.699312 -249.933893) (xy 101.737433 -249.902768)
			(xy 101.780054 -249.878161) (xy 101.82607 -249.860709) (xy 101.874289 -249.850865) (xy 101.923464 -249.848884)
			(xy 101.972319 -249.854816) (xy 102.01959 -249.868508) (xy 102.064052 -249.889606) (xy 102.104555 -249.917562)
			(xy 102.140048 -249.951654) (xy 102.169613 -249.990998) (xy 102.192484 -250.034575) (xy 102.208068 -250.081256)
			(xy 102.215963 -250.129833) (xy 102.216458 -250.15444) (xy 103.4852 -250.15444) (xy 103.48916 -250.105386)
			(xy 103.500937 -250.057602) (xy 103.520228 -250.012326) (xy 103.546531 -249.97073) (xy 103.579166 -249.933893)
			(xy 103.617287 -249.902768) (xy 103.659908 -249.878161) (xy 103.705924 -249.860709) (xy 103.754143 -249.850865)
			(xy 103.803318 -249.848884) (xy 103.852173 -249.854816) (xy 103.899444 -249.868508) (xy 103.943906 -249.889606)
			(xy 103.984409 -249.917562) (xy 104.019902 -249.951654) (xy 104.049467 -249.990998) (xy 104.072338 -250.034575)
			(xy 104.087922 -250.081256) (xy 104.095817 -250.129833) (xy 104.096312 -250.15444) (xy 105.365308 -250.15444)
			(xy 105.369268 -250.105386) (xy 105.381045 -250.057602) (xy 105.400336 -250.012326) (xy 105.426639 -249.97073)
			(xy 105.459274 -249.933893) (xy 105.497395 -249.902768) (xy 105.540016 -249.878161) (xy 105.586032 -249.860709)
			(xy 105.634251 -249.850865) (xy 105.683426 -249.848884) (xy 105.732281 -249.854816) (xy 105.779552 -249.868508)
			(xy 105.824014 -249.889606) (xy 105.864517 -249.917562) (xy 105.90001 -249.951654) (xy 105.929575 -249.990998)
			(xy 105.952446 -250.034575) (xy 105.96803 -250.081256) (xy 105.975925 -250.129833) (xy 105.97642 -250.15444)
			(xy 107.245162 -250.15444) (xy 107.249122 -250.105386) (xy 107.260899 -250.057602) (xy 107.28019 -250.012326)
			(xy 107.306493 -249.97073) (xy 107.339128 -249.933893) (xy 107.377249 -249.902768) (xy 107.41987 -249.878161)
			(xy 107.465886 -249.860709) (xy 107.514105 -249.850865) (xy 107.56328 -249.848884) (xy 107.612135 -249.854816)
			(xy 107.659406 -249.868508) (xy 107.703868 -249.889606) (xy 107.744371 -249.917562) (xy 107.779864 -249.951654)
			(xy 107.809429 -249.990998) (xy 107.8323 -250.034575) (xy 107.847884 -250.081256) (xy 107.855779 -250.129833)
			(xy 107.856274 -250.15444) (xy 107.855779 -250.179047) (xy 107.847884 -250.227624) (xy 107.8323 -250.274305)
			(xy 107.809429 -250.317882) (xy 107.779864 -250.357226) (xy 107.744371 -250.391318) (xy 107.703868 -250.419274)
			(xy 107.659406 -250.440372) (xy 107.612135 -250.454064) (xy 107.56328 -250.459996) (xy 107.514105 -250.458015)
			(xy 107.465886 -250.448171) (xy 107.41987 -250.430719) (xy 107.377249 -250.406112) (xy 107.339128 -250.374987)
			(xy 107.306493 -250.33815) (xy 107.28019 -250.296554) (xy 107.260899 -250.251278) (xy 107.249122 -250.203494)
			(xy 107.245162 -250.15444) (xy 105.97642 -250.15444) (xy 105.975925 -250.179047) (xy 105.96803 -250.227624)
			(xy 105.952446 -250.274305) (xy 105.929575 -250.317882) (xy 105.90001 -250.357226) (xy 105.864517 -250.391318)
			(xy 105.824014 -250.419274) (xy 105.779552 -250.440372) (xy 105.732281 -250.454064) (xy 105.683426 -250.459996)
			(xy 105.634251 -250.458015) (xy 105.586032 -250.448171) (xy 105.540016 -250.430719) (xy 105.497395 -250.406112)
			(xy 105.459274 -250.374987) (xy 105.426639 -250.33815) (xy 105.400336 -250.296554) (xy 105.381045 -250.251278)
			(xy 105.369268 -250.203494) (xy 105.365308 -250.15444) (xy 104.096312 -250.15444) (xy 104.095817 -250.179047)
			(xy 104.087922 -250.227624) (xy 104.072338 -250.274305) (xy 104.049467 -250.317882) (xy 104.019902 -250.357226)
			(xy 103.984409 -250.391318) (xy 103.943906 -250.419274) (xy 103.899444 -250.440372) (xy 103.852173 -250.454064)
			(xy 103.803318 -250.459996) (xy 103.754143 -250.458015) (xy 103.705924 -250.448171) (xy 103.659908 -250.430719)
			(xy 103.617287 -250.406112) (xy 103.579166 -250.374987) (xy 103.546531 -250.33815) (xy 103.520228 -250.296554)
			(xy 103.500937 -250.251278) (xy 103.48916 -250.203494) (xy 103.4852 -250.15444) (xy 102.216458 -250.15444)
			(xy 102.215963 -250.179047) (xy 102.208068 -250.227624) (xy 102.192484 -250.274305) (xy 102.169613 -250.317882)
			(xy 102.140048 -250.357226) (xy 102.104555 -250.391318) (xy 102.064052 -250.419274) (xy 102.01959 -250.440372)
			(xy 101.972319 -250.454064) (xy 101.923464 -250.459996) (xy 101.874289 -250.458015) (xy 101.82607 -250.448171)
			(xy 101.780054 -250.430719) (xy 101.737433 -250.406112) (xy 101.699312 -250.374987) (xy 101.666677 -250.33815)
			(xy 101.640374 -250.296554) (xy 101.621083 -250.251278) (xy 101.609306 -250.203494) (xy 101.605346 -250.15444)
			(xy 100.337254 -250.15444) (xy 100.34397 -250.170188) (xy 100.543868 -250.370086) (xy 100.544376 -250.370594)
			(xy 100.55176 -250.377168) (xy 100.570059 -250.384604) (xy 100.579936 -250.385072) (xy 101.18852 -250.385072)
			(xy 101.198362 -250.385598) (xy 101.216539 -250.393169) (xy 101.223826 -250.399804) (xy 101.475032 -250.65101)
			(xy 101.480487 -250.65614) (xy 101.493655 -250.663253) (xy 101.50094 -250.66498) (xy 101.501194 -250.66498)
			(xy 101.526219 -250.670545) (xy 101.574083 -250.688897) (xy 101.618212 -250.714982) (xy 101.657366 -250.748069)
			(xy 101.690446 -250.787229) (xy 101.716525 -250.831361) (xy 101.734869 -250.879229) (xy 101.740462 -250.904248)
			(xy 101.740462 -250.904502) (xy 101.742211 -250.911782) (xy 101.7493 -250.92496) (xy 101.754432 -250.93041)
			(xy 101.900228 -251.076206) (xy 101.900736 -251.076714) (xy 101.908114 -251.083303) (xy 101.926414 -251.090766)
			(xy 101.936296 -251.091192) (xy 102.916736 -251.091192) (xy 102.926956 -251.090704) (xy 102.9457 -251.082557)
			(xy 102.953058 -251.075444) (xy 103.002842 -251.022104) (xy 103.006265 -251.018229) (xy 103.011634 -251.009396)
			(xy 103.01351 -251.004578) (xy 103.017066 -250.994672) (xy 103.016304 -250.984004) (xy 103.015796 -250.964446)
			(xy 103.016318 -250.939191) (xy 103.024631 -250.889369) (xy 103.041032 -250.841595) (xy 103.065073 -250.797172)
			(xy 103.096097 -250.757312) (xy 103.133259 -250.723102) (xy 103.175545 -250.695476) (xy 103.221801 -250.675186)
			(xy 103.270766 -250.662786) (xy 103.321104 -250.658615) (xy 103.371442 -250.662786) (xy 103.420407 -250.675186)
			(xy 103.466663 -250.695476) (xy 103.508949 -250.723102) (xy 103.546111 -250.757312) (xy 103.577135 -250.797172)
			(xy 103.601176 -250.841595) (xy 103.617577 -250.889369) (xy 103.62589 -250.939191) (xy 103.626412 -250.964446)
			(xy 103.625904 -250.984004) (xy 103.625142 -250.994672) (xy 103.628698 -251.004578) (xy 103.630548 -251.009408)
			(xy 103.635922 -251.018245) (xy 103.639366 -251.022104) (xy 103.68915 -251.07519) (xy 103.69665 -251.082453)
			(xy 103.715804 -251.090708) (xy 103.726234 -251.091192) (xy 104.79659 -251.091192) (xy 104.806814 -251.090712)
			(xy 104.825572 -251.082577) (xy 104.832912 -251.075444) (xy 104.882696 -251.022104) (xy 104.886129 -251.018236)
			(xy 104.891504 -251.009403) (xy 104.893364 -251.004578) (xy 104.89692 -250.994672) (xy 104.896158 -250.984004)
			(xy 104.89565 -250.964446) (xy 104.896172 -250.939191) (xy 104.904485 -250.889369) (xy 104.920886 -250.841595)
			(xy 104.944927 -250.797172) (xy 104.975951 -250.757312) (xy 105.013113 -250.723102) (xy 105.055399 -250.695476)
			(xy 105.101655 -250.675186) (xy 105.15062 -250.662786) (xy 105.200958 -250.658615) (xy 105.251296 -250.662786)
			(xy 105.300261 -250.675186) (xy 105.346517 -250.695476) (xy 105.388803 -250.723102) (xy 105.425965 -250.757312)
			(xy 105.456989 -250.797172) (xy 105.48103 -250.841595) (xy 105.497431 -250.889369) (xy 105.505744 -250.939191)
			(xy 105.506266 -250.964446) (xy 105.505758 -250.984004) (xy 105.504996 -250.994672) (xy 105.508552 -251.004578)
			(xy 105.510404 -251.009407) (xy 105.515782 -251.01824) (xy 105.51922 -251.022104) (xy 105.569004 -251.07519)
			(xy 105.576502 -251.08246) (xy 105.595655 -251.090732) (xy 105.606088 -251.091192) (xy 106.676698 -251.091192)
			(xy 106.686921 -251.090711) (xy 106.705677 -251.082574) (xy 106.71302 -251.075444) (xy 106.762804 -251.022104)
			(xy 106.766236 -251.018236) (xy 106.77161 -251.009403) (xy 106.773472 -251.004578) (xy 106.777028 -250.994672)
			(xy 106.776266 -250.984004) (xy 106.775758 -250.964446) (xy 106.77628 -250.939191) (xy 106.784593 -250.889369)
			(xy 106.800994 -250.841595) (xy 106.825035 -250.797172) (xy 106.856059 -250.757312) (xy 106.893221 -250.723102)
			(xy 106.935507 -250.695476) (xy 106.981763 -250.675186) (xy 107.030728 -250.662786) (xy 107.081066 -250.658615)
			(xy 107.131404 -250.662786) (xy 107.180369 -250.675186) (xy 107.226625 -250.695476) (xy 107.268911 -250.723102)
			(xy 107.306073 -250.757312) (xy 107.337097 -250.797172) (xy 107.361138 -250.841595) (xy 107.377539 -250.889369)
			(xy 107.385852 -250.939191) (xy 107.386374 -250.964446) (xy 107.385866 -250.984004) (xy 107.385104 -250.994672)
			(xy 107.38866 -251.004578) (xy 107.390513 -251.009407) (xy 107.395891 -251.018239) (xy 107.399328 -251.022104)
			(xy 107.449112 -251.07519) (xy 107.45661 -251.082459) (xy 107.475763 -251.090728) (xy 107.486196 -251.091192)
			(xy 108.44276 -251.091192) (xy 108.452598 -251.090658) (xy 108.470761 -251.083072) (xy 108.478066 -251.07646)
			(xy 108.660438 -250.894088) (xy 108.666788 -250.88342) (xy 108.668566 -250.877324) (xy 108.676269 -250.853266)
			(xy 108.698447 -250.807884) (xy 108.727792 -250.766772) (xy 108.763503 -250.73105) (xy 108.804607 -250.701693)
			(xy 108.849983 -250.679501) (xy 108.874052 -250.671838) (xy 108.880148 -250.67006) (xy 108.890816 -250.66371)
			(xy 109.109002 -250.445524) (xy 109.114304 -250.440534) (xy 109.127083 -250.433568) (xy 109.134148 -250.431808)
			(xy 109.134402 -250.431808) (xy 109.145859 -250.428784) (xy 109.164403 -250.414079) (xy 109.169962 -250.403614)
			(xy 109.181392 -250.379484) (xy 109.18501 -250.370723) (xy 109.186307 -250.351831) (xy 109.183932 -250.342654)
			(xy 109.178852 -250.326652) (xy 109.174788 -250.32081) (xy 109.163131 -250.302146) (xy 109.144717 -250.262181)
			(xy 109.132222 -250.219989) (xy 109.125907 -250.176442) (xy 109.125512 -250.15444) (xy 109.125766 -250.147582)
			(xy 109.126739 -250.123946) (xy 109.135079 -250.077383) (xy 109.150503 -250.032665) (xy 109.172642 -249.990862)
			(xy 109.200966 -249.952975) (xy 109.234796 -249.919912) (xy 109.273321 -249.892464) (xy 109.315621 -249.871288)
			(xy 109.360681 -249.856892) (xy 109.407422 -249.849621) (xy 109.431074 -249.849132) (xy 109.455067 -249.849576)
			(xy 109.502464 -249.85708) (xy 109.548102 -249.871907) (xy 109.590859 -249.893691) (xy 109.629681 -249.921897)
			(xy 109.663612 -249.95583) (xy 109.691816 -249.994653) (xy 109.713599 -250.037411) (xy 109.728423 -250.08305)
			(xy 109.735925 -250.130447) (xy 109.736382 -250.15444) (xy 109.735985 -250.177269) (xy 109.729188 -250.222417)
			(xy 109.715721 -250.266042) (xy 109.706156 -250.286774) (xy 109.700314 -250.298966) (xy 109.701838 -250.32462)
			(xy 109.7534 -250.406916) (xy 109.758243 -250.414044) (xy 109.771699 -250.424793) (xy 109.787967 -250.430442)
			(xy 109.79658 -250.430792) (xy 112.81918 -250.430792) (xy 112.827789 -250.43045) (xy 112.844039 -250.424758)
			(xy 112.857511 -250.414036) (xy 112.86236 -250.406916) (xy 112.913922 -250.32462) (xy 112.915446 -250.298966)
			(xy 112.909604 -250.286774) (xy 112.900098 -250.26602) (xy 112.886651 -250.222398) (xy 112.879827 -250.177263)
			(xy 112.879378 -250.15444) (xy 112.8799 -250.129185) (xy 112.888213 -250.079363) (xy 112.904614 -250.031589)
			(xy 112.928655 -249.987166) (xy 112.959679 -249.947306) (xy 112.996841 -249.913096) (xy 113.039127 -249.88547)
			(xy 113.085383 -249.86518) (xy 113.134348 -249.85278) (xy 113.184686 -249.848609) (xy 113.235024 -249.85278)
			(xy 113.283989 -249.86518) (xy 113.330245 -249.88547) (xy 113.372531 -249.913096) (xy 113.409693 -249.947306)
			(xy 113.440717 -249.987166) (xy 113.464758 -250.031589) (xy 113.481159 -250.079363) (xy 113.489472 -250.129185)
			(xy 113.489994 -250.15444) (xy 113.489597 -250.177269) (xy 113.4828 -250.222417) (xy 113.469333 -250.266043)
			(xy 113.459768 -250.286774) (xy 113.453926 -250.298966) (xy 113.45545 -250.32462) (xy 113.507012 -250.406916)
			(xy 113.511856 -250.414042) (xy 113.525312 -250.424788) (xy 113.54158 -250.430434) (xy 113.550192 -250.430792)
			(xy 114.699288 -250.430792) (xy 114.707896 -250.430449) (xy 114.724144 -250.424755) (xy 114.737614 -250.414032)
			(xy 114.742468 -250.406916) (xy 114.79403 -250.32462) (xy 114.795554 -250.298966) (xy 114.789712 -250.286774)
			(xy 114.780206 -250.26602) (xy 114.766759 -250.222398) (xy 114.759934 -250.177263) (xy 114.759486 -250.15444)
			(xy 114.759929 -250.130445) (xy 114.767431 -250.083044) (xy 114.782256 -250.037401) (xy 114.804039 -249.994638)
			(xy 114.832244 -249.955811) (xy 114.866176 -249.921874) (xy 114.904999 -249.893663) (xy 114.947758 -249.871873)
			(xy 114.993399 -249.857042) (xy 115.040799 -249.849533) (xy 115.064794 -249.849132) (xy 115.077557 -249.849269)
			(xy 115.102992 -249.851427) (xy 115.115594 -249.85345) (xy 115.115594 -249.853196) (xy 115.139184 -249.857688)
			(xy 115.18468 -249.873045) (xy 115.227216 -249.895326) (xy 115.265746 -249.923983) (xy 115.299322 -249.958312)
			(xy 115.327119 -249.997467) (xy 115.348452 -250.040486) (xy 115.362798 -250.086311) (xy 115.3668 -250.10999)
			(xy 115.368832 -250.12396) (xy 115.370356 -250.15444) (xy 116.638844 -250.15444) (xy 116.642804 -250.105386)
			(xy 116.654581 -250.057602) (xy 116.673872 -250.012326) (xy 116.700175 -249.97073) (xy 116.73281 -249.933893)
			(xy 116.770931 -249.902768) (xy 116.813552 -249.878161) (xy 116.859568 -249.860709) (xy 116.907787 -249.850865)
			(xy 116.956962 -249.848884) (xy 117.005817 -249.854816) (xy 117.053088 -249.868508) (xy 117.09755 -249.889606)
			(xy 117.138053 -249.917562) (xy 117.173546 -249.951654) (xy 117.203111 -249.990998) (xy 117.225982 -250.034575)
			(xy 117.241566 -250.081256) (xy 117.249461 -250.129833) (xy 117.249956 -250.15444) (xy 117.249461 -250.179047)
			(xy 117.241566 -250.227624) (xy 117.225982 -250.274305) (xy 117.203111 -250.317882) (xy 117.173546 -250.357226)
			(xy 117.138053 -250.391318) (xy 117.09755 -250.419274) (xy 117.053088 -250.440372) (xy 117.005817 -250.454064)
			(xy 116.956962 -250.459996) (xy 116.907787 -250.458015) (xy 116.859568 -250.448171) (xy 116.813552 -250.430719)
			(xy 116.770931 -250.406112) (xy 116.73281 -250.374987) (xy 116.700175 -250.33815) (xy 116.673872 -250.296554)
			(xy 116.654581 -250.251278) (xy 116.642804 -250.203494) (xy 116.638844 -250.15444) (xy 115.370356 -250.15444)
			(xy 115.36979 -250.1813) (xy 115.360397 -250.234192) (xy 115.341907 -250.284629) (xy 115.314889 -250.33106)
			(xy 115.280175 -250.372056) (xy 115.259866 -250.389644) (xy 115.251738 -250.396502) (xy 115.246912 -250.4059)
			(xy 115.244617 -250.410747) (xy 115.24192 -250.421123) (xy 115.241578 -250.426474) (xy 115.238022 -250.499118)
			(xy 115.238022 -250.505214) (xy 115.239027 -250.514255) (xy 115.246588 -250.530783) (xy 115.252754 -250.537472)
			(xy 115.379754 -250.664472) (xy 115.384972 -250.669373) (xy 115.397481 -250.67632) (xy 115.404392 -250.678188)
			(xy 115.404646 -250.678188) (xy 115.411683 -250.679561) (xy 115.425993 -250.678789) (xy 115.43284 -250.676664)
			(xy 115.456533 -250.668788) (xy 115.505676 -250.659988) (xy 115.53063 -250.659138) (xy 115.533678 -250.659138)
			(xy 115.557597 -250.659523) (xy 115.60487 -250.666823) (xy 115.650428 -250.681405) (xy 115.693154 -250.702913)
			(xy 115.732004 -250.730819) (xy 115.766028 -250.764442) (xy 115.794392 -250.802959) (xy 115.816404 -250.845428)
			(xy 115.831525 -250.890809) (xy 115.839385 -250.937993) (xy 115.840002 -250.961906) (xy 115.840002 -250.97232)
			(xy 115.847622 -250.990354) (xy 115.855242 -250.99772) (xy 115.862596 -251.004376) (xy 115.880896 -251.011973)
			(xy 115.890802 -251.012452) (xy 117.058694 -251.012452) (xy 117.068592 -251.011932) (xy 117.086884 -251.004348)
			(xy 117.094254 -250.99772) (xy 117.101874 -250.990354) (xy 117.109494 -250.97232) (xy 117.109494 -250.961906)
			(xy 117.11021 -250.936806) (xy 117.118838 -250.887344) (xy 117.13545 -250.839962) (xy 117.159597 -250.795941)
			(xy 117.190628 -250.756469) (xy 117.208808 -250.739148) (xy 117.225783 -250.724191) (xy 117.263318 -250.698932)
			(xy 117.304166 -250.679485) (xy 117.347436 -250.666274) (xy 117.392181 -250.659588) (xy 117.414802 -250.659138)
			(xy 117.434586 -250.659452) (xy 117.473826 -250.664547) (xy 117.493034 -250.669298) (xy 117.501718 -250.671184)
			(xy 117.519404 -250.66959) (xy 117.535501 -250.66209) (xy 117.542056 -250.65609) (xy 117.856762 -250.341384)
			(xy 117.863997 -250.334663) (xy 117.882202 -250.327052) (xy 117.892068 -250.326652) (xy 118.425468 -250.326652)
			(xy 118.433892 -250.326305) (xy 118.449838 -250.320867) (xy 118.45671 -250.315984) (xy 118.461028 -250.312428)
			(xy 118.520718 -250.241054) (xy 118.526306 -250.219718) (xy 118.524274 -250.208542) (xy 118.522091 -250.195633)
			(xy 118.519674 -250.169562) (xy 118.519448 -250.156472) (xy 118.519448 -250.152408) (xy 118.520067 -250.128521)
			(xy 118.527819 -250.081373) (xy 118.542823 -250.036008) (xy 118.564712 -249.993535) (xy 118.592951 -249.954992)
			(xy 118.626851 -249.921319) (xy 118.665583 -249.893339) (xy 118.708202 -249.871735) (xy 118.753666 -249.857036)
			(xy 118.800865 -249.8496) (xy 118.824756 -249.849132) (xy 118.84875 -249.849575) (xy 118.896149 -249.857076)
			(xy 118.94179 -249.871902) (xy 118.984549 -249.893685) (xy 119.023373 -249.921891) (xy 119.057307 -249.955824)
			(xy 119.085513 -249.994648) (xy 119.107297 -250.037407) (xy 119.122123 -250.083047) (xy 119.129625 -250.130446)
			(xy 119.130064 -250.15444) (xy 120.398806 -250.15444) (xy 120.402766 -250.105386) (xy 120.414543 -250.057602)
			(xy 120.433834 -250.012326) (xy 120.460137 -249.97073) (xy 120.492772 -249.933893) (xy 120.530893 -249.902768)
			(xy 120.573514 -249.878161) (xy 120.61953 -249.860709) (xy 120.667749 -249.850865) (xy 120.716924 -249.848884)
			(xy 120.765779 -249.854816) (xy 120.81305 -249.868508) (xy 120.857512 -249.889606) (xy 120.898015 -249.917562)
			(xy 120.933508 -249.951654) (xy 120.963073 -249.990998) (xy 120.985944 -250.034575) (xy 121.001528 -250.081256)
			(xy 121.009423 -250.129833) (xy 121.009918 -250.15444) (xy 121.009423 -250.179047) (xy 121.001528 -250.227624)
			(xy 120.985944 -250.274305) (xy 120.963073 -250.317882) (xy 120.933508 -250.357226) (xy 120.898015 -250.391318)
			(xy 120.857512 -250.419274) (xy 120.81305 -250.440372) (xy 120.765779 -250.454064) (xy 120.716924 -250.459996)
			(xy 120.667749 -250.458015) (xy 120.61953 -250.448171) (xy 120.573514 -250.430719) (xy 120.530893 -250.406112)
			(xy 120.492772 -250.374987) (xy 120.460137 -250.33815) (xy 120.433834 -250.296554) (xy 120.414543 -250.251278)
			(xy 120.402766 -250.203494) (xy 120.398806 -250.15444) (xy 119.130064 -250.15444) (xy 119.12952 -250.180731)
			(xy 119.12052 -250.232538) (xy 119.102777 -250.282037) (xy 119.076815 -250.327763) (xy 119.043402 -250.368365)
			(xy 119.003526 -250.402641) (xy 118.98122 -250.416568) (xy 118.97106 -250.422664) (xy 118.95836 -250.442222)
			(xy 118.947184 -250.531376) (xy 118.946302 -250.542967) (xy 118.953856 -250.564924) (xy 118.961662 -250.57354)
			(xy 119.092726 -250.704604) (xy 119.126508 -250.708922) (xy 119.141748 -250.700286) (xy 119.165136 -250.687358)
			(xy 119.215322 -250.669007) (xy 119.267938 -250.659686) (xy 119.294656 -250.659138) (xy 119.31865 -250.659581)
			(xy 119.366048 -250.667082) (xy 119.411689 -250.681908) (xy 119.454448 -250.703691) (xy 119.493272 -250.731897)
			(xy 119.527204 -250.76583) (xy 119.55541 -250.804654) (xy 119.577193 -250.847413) (xy 119.592018 -250.893054)
			(xy 119.599519 -250.940452) (xy 119.599964 -250.964446) (xy 119.599778 -250.980503) (xy 119.596472 -251.012446)
			(xy 119.59336 -251.0282) (xy 119.59082 -251.039376) (xy 119.596154 -251.061728) (xy 119.65178 -251.130562)
			(xy 119.659411 -251.139077) (xy 119.679988 -251.148974) (xy 119.691404 -251.149612) (xy 120.78462 -251.149612)
			(xy 120.794462 -251.149086) (xy 120.812637 -251.141513) (xy 120.819926 -251.13488) (xy 120.875298 -251.079508)
			(xy 120.88241 -251.0536) (xy 120.879108 -251.040392) (xy 120.874538 -251.021418) (xy 120.869699 -250.982691)
			(xy 120.869456 -250.963176) (xy 120.869456 -250.961652) (xy 120.870118 -250.937941) (xy 120.877874 -250.891146)
			(xy 120.892773 -250.846113) (xy 120.914456 -250.803926) (xy 120.942401 -250.7656) (xy 120.975937 -250.732055)
			(xy 121.014256 -250.704099) (xy 121.056437 -250.682405) (xy 121.101465 -250.667494) (xy 121.148258 -250.659726)
			(xy 121.17197 -250.659138) (xy 121.173494 -250.659138) (xy 121.193009 -250.659381) (xy 121.231736 -250.664219)
			(xy 121.25071 -250.66879) (xy 121.263918 -250.672092) (xy 121.289826 -250.66498) (xy 121.355358 -250.599448)
			(xy 121.413524 -250.541536) (xy 121.428014 -250.528004) (xy 121.462357 -250.508227) (xy 121.500643 -250.497985)
			(xy 121.520458 -250.49734) (xy 121.539254 -250.49734) (xy 121.548237 -250.496326) (xy 121.564646 -250.488773)
			(xy 121.571258 -250.482608) (xy 121.621042 -250.432824) (xy 121.62828 -250.426112) (xy 121.646486 -250.418523)
			(xy 121.656348 -250.418092) (xy 122.21337 -250.418092) (xy 122.226104 -250.417392) (xy 122.248502 -250.405264)
			(xy 122.256042 -250.394978) (xy 122.308366 -250.314714) (xy 122.310398 -250.289314) (xy 122.305318 -250.277376)
			(xy 122.297127 -250.257927) (xy 122.285585 -250.217337) (xy 122.279762 -250.17554) (xy 122.27941 -250.15444)
			(xy 122.27941 -250.149614) (xy 122.280234 -250.125869) (xy 122.288328 -250.079054) (xy 122.303575 -250.034058)
			(xy 122.325608 -249.991966) (xy 122.353894 -249.953796) (xy 122.387752 -249.920467) (xy 122.426363 -249.892784)
			(xy 122.468796 -249.871417) (xy 122.514027 -249.856879) (xy 122.560963 -249.849523) (xy 122.584718 -249.849132)
			(xy 122.608709 -249.84958) (xy 122.6561 -249.857089) (xy 122.701733 -249.871919) (xy 122.744483 -249.893706)
			(xy 122.783299 -249.921913) (xy 122.817225 -249.955845) (xy 122.845424 -249.994666) (xy 122.867203 -250.037421)
			(xy 122.882025 -250.083056) (xy 122.889525 -250.130449) (xy 122.890026 -250.15444) (xy 124.159022 -250.15444)
			(xy 124.162982 -250.105386) (xy 124.174759 -250.057602) (xy 124.19405 -250.012326) (xy 124.220353 -249.97073)
			(xy 124.252988 -249.933893) (xy 124.291109 -249.902768) (xy 124.33373 -249.878161) (xy 124.379746 -249.860709)
			(xy 124.427965 -249.850865) (xy 124.47714 -249.848884) (xy 124.525995 -249.854816) (xy 124.573266 -249.868508)
			(xy 124.617728 -249.889606) (xy 124.658231 -249.917562) (xy 124.693724 -249.951654) (xy 124.723289 -249.990998)
			(xy 124.74616 -250.034575) (xy 124.761744 -250.081256) (xy 124.769639 -250.129833) (xy 124.770134 -250.15444)
			(xy 124.769639 -250.179047) (xy 124.761744 -250.227624) (xy 124.74616 -250.274305) (xy 124.723289 -250.317882)
			(xy 124.693724 -250.357226) (xy 124.658231 -250.391318) (xy 124.617728 -250.419274) (xy 124.573266 -250.440372)
			(xy 124.525995 -250.454064) (xy 124.47714 -250.459996) (xy 124.427965 -250.458015) (xy 124.379746 -250.448171)
			(xy 124.33373 -250.430719) (xy 124.291109 -250.406112) (xy 124.252988 -250.374987) (xy 124.220353 -250.33815)
			(xy 124.19405 -250.296554) (xy 124.174759 -250.251278) (xy 124.162982 -250.203494) (xy 124.159022 -250.15444)
			(xy 122.890026 -250.15444) (xy 122.889593 -250.177994) (xy 122.88236 -250.224543) (xy 122.868056 -250.269426)
			(xy 122.847022 -250.311577) (xy 122.819758 -250.349993) (xy 122.786912 -250.38376) (xy 122.76836 -250.39828)
			(xy 122.75947 -250.405138) (xy 122.749056 -250.424188) (xy 122.74296 -250.51004) (xy 122.742697 -250.520947)
			(xy 122.750328 -250.541361) (xy 122.757692 -250.54941) (xy 122.880374 -250.672092) (xy 122.887814 -250.678967)
			(xy 122.906521 -250.686693) (xy 122.926761 -250.686555) (xy 122.936254 -250.683014) (xy 122.964329 -250.671968)
			(xy 123.023443 -250.659943) (xy 123.053602 -250.659138) (xy 123.05919 -250.659138) (xy 123.082716 -250.659927)
			(xy 123.129115 -250.66785) (xy 123.173748 -250.682801) (xy 123.215557 -250.704425) (xy 123.253552 -250.73221)
			(xy 123.286833 -250.765497) (xy 123.314609 -250.803498) (xy 123.336225 -250.845312) (xy 123.351166 -250.889948)
			(xy 123.359079 -250.936349) (xy 123.359926 -250.959874) (xy 123.359926 -250.9647) (xy 123.359175 -250.99505)
			(xy 123.347139 -251.054547) (xy 123.33605 -251.08281) (xy 123.332522 -251.092295) (xy 123.332444 -251.112516)
			(xy 123.340154 -251.131209) (xy 123.346972 -251.13869) (xy 123.490228 -251.281946) (xy 123.490736 -251.282454)
			(xy 123.498116 -251.289039) (xy 123.516415 -251.296495) (xy 123.526296 -251.296932) (xy 124.616464 -251.296932)
		)
		(stroke
			(width 0)
			(type solid)
		)
		(fill yes)
		(layer "In6.Cu")
		(net "PVDDCR_CPU0_P1")
	)
	(gr_poly
		(pts
			(xy 350.733868 -251.273056) (xy 350.913446 -251.273056) (xy 350.922478 -251.272751) (xy 350.93945 -251.266575)
			(xy 350.953204 -251.25487) (xy 350.957896 -251.247148) (xy 351.00006 -251.172218) (xy 351.004142 -251.164245)
			(xy 351.007015 -251.146575) (xy 351.003644 -251.128994) (xy 350.999298 -251.121164) (xy 350.985658 -251.097278)
			(xy 350.966281 -251.045804) (xy 350.956433 -250.991692) (xy 350.955864 -250.964192) (xy 350.955864 -250.958096)
			(xy 350.956857 -250.933171) (xy 350.965944 -250.884125) (xy 350.982882 -250.837209) (xy 351.007219 -250.793669)
			(xy 351.038309 -250.754664) (xy 351.075325 -250.721229) (xy 351.117282 -250.694255) (xy 351.163066 -250.674459)
			(xy 351.211458 -250.662366) (xy 351.261172 -250.6583) (xy 351.310886 -250.662366) (xy 351.359278 -250.674459)
			(xy 351.405062 -250.694255) (xy 351.447019 -250.721229) (xy 351.484035 -250.754664) (xy 351.515125 -250.793669)
			(xy 351.539462 -250.837209) (xy 351.5564 -250.884125) (xy 351.565487 -250.933171) (xy 351.56648 -250.958096)
			(xy 351.56648 -250.964192) (xy 351.565898 -250.991692) (xy 351.556058 -251.045805) (xy 351.536694 -251.097283)
			(xy 351.523046 -251.121164) (xy 351.518737 -251.129015) (xy 351.515347 -251.146588) (xy 351.518181 -251.16426)
			(xy 351.522284 -251.172218) (xy 351.564702 -251.247402) (xy 351.569422 -251.255044) (xy 351.583089 -251.266684)
			(xy 351.599924 -251.272919) (xy 351.608898 -251.27331) (xy 352.001074 -251.27331) (xy 352.004884 -251.273056)
			(xy 352.7933 -251.273056) (xy 352.802328 -251.272743) (xy 352.819285 -251.266554) (xy 352.833023 -251.254846)
			(xy 352.83775 -251.247148) (xy 352.879914 -251.172218) (xy 352.883999 -251.164246) (xy 352.886875 -251.146575)
			(xy 352.883501 -251.128994) (xy 352.879152 -251.121164) (xy 352.86551 -251.097278) (xy 352.846129 -251.045805)
			(xy 352.83628 -250.991693) (xy 352.835718 -250.964192) (xy 352.835718 -250.958096) (xy 352.836711 -250.933171)
			(xy 352.845798 -250.884125) (xy 352.862736 -250.837209) (xy 352.887073 -250.793669) (xy 352.918163 -250.754664)
			(xy 352.955179 -250.721229) (xy 352.997136 -250.694255) (xy 353.04292 -250.674459) (xy 353.091312 -250.662366)
			(xy 353.141026 -250.6583) (xy 353.19074 -250.662366) (xy 353.239132 -250.674459) (xy 353.284916 -250.694255)
			(xy 353.326873 -250.721229) (xy 353.363889 -250.754664) (xy 353.394979 -250.793669) (xy 353.419316 -250.837209)
			(xy 353.436254 -250.884125) (xy 353.445341 -250.933171) (xy 353.446334 -250.958096) (xy 353.446334 -250.964192)
			(xy 353.445751 -250.991692) (xy 353.43591 -251.045804) (xy 353.416544 -251.097281) (xy 353.4029 -251.121164)
			(xy 353.398595 -251.129016) (xy 353.395208 -251.146588) (xy 353.398039 -251.164259) (xy 353.402138 -251.172218)
			(xy 353.444556 -251.247402) (xy 353.449274 -251.25505) (xy 353.462939 -251.266702) (xy 353.479774 -251.272952)
			(xy 353.488752 -251.27331) (xy 353.881182 -251.27331) (xy 353.884992 -251.273056) (xy 354.673408 -251.273056)
			(xy 354.682435 -251.272741) (xy 354.69939 -251.266551) (xy 354.713126 -251.254842) (xy 354.717858 -251.247148)
			(xy 354.760022 -251.172218) (xy 354.764106 -251.164245) (xy 354.766982 -251.146575) (xy 354.763608 -251.128994)
			(xy 354.75926 -251.121164) (xy 354.745618 -251.097278) (xy 354.726237 -251.045805) (xy 354.716387 -250.991693)
			(xy 354.715826 -250.964192) (xy 354.715826 -250.958096) (xy 354.716819 -250.933171) (xy 354.725906 -250.884125)
			(xy 354.742844 -250.837209) (xy 354.767181 -250.793669) (xy 354.798271 -250.754664) (xy 354.835287 -250.721229)
			(xy 354.877244 -250.694255) (xy 354.923028 -250.674459) (xy 354.97142 -250.662366) (xy 355.021134 -250.6583)
			(xy 355.070848 -250.662366) (xy 355.11924 -250.674459) (xy 355.165024 -250.694255) (xy 355.206981 -250.721229)
			(xy 355.243997 -250.754664) (xy 355.275087 -250.793669) (xy 355.299424 -250.837209) (xy 355.316362 -250.884125)
			(xy 355.325449 -250.933171) (xy 355.326442 -250.958096) (xy 355.326442 -250.964192) (xy 355.325859 -250.991692)
			(xy 355.316018 -251.045804) (xy 355.296653 -251.097281) (xy 355.283008 -251.121164) (xy 355.278702 -251.129015)
			(xy 355.275315 -251.146588) (xy 355.278146 -251.164259) (xy 355.282246 -251.172218) (xy 355.324664 -251.247402)
			(xy 355.329382 -251.255049) (xy 355.343048 -251.266699) (xy 355.359883 -251.272946) (xy 355.36886 -251.27331)
			(xy 355.761036 -251.27331) (xy 355.764846 -251.273056) (xy 356.28326 -251.273056) (xy 356.292217 -251.272081)
			(xy 356.30862 -251.264663) (xy 356.315264 -251.258578) (xy 356.580948 -250.992894) (xy 356.587551 -250.985719)
			(xy 356.595248 -250.967823) (xy 356.595934 -250.958096) (xy 356.595934 -250.957842) (xy 356.596996 -250.931885)
			(xy 356.60685 -250.88088) (xy 356.625192 -250.832278) (xy 356.651492 -250.787479) (xy 356.684993 -250.747777)
			(xy 356.724729 -250.714316) (xy 356.769553 -250.68806) (xy 356.818174 -250.669767) (xy 356.869188 -250.659964)
			(xy 356.895146 -250.658884) (xy 356.904798 -250.65863) (xy 356.931976 -250.647454) (xy 356.93731 -250.64212)
			(xy 356.9462 -250.63831) (xy 357.233728 -250.63831) (xy 357.237792 -250.638056) (xy 361.208828 -250.638056)
			(xy 361.212892 -250.63831) (xy 361.976924 -250.63831) (xy 361.980988 -250.638056) (xy 363.088682 -250.638056)
			(xy 363.092746 -250.63831) (xy 363.518958 -250.63831) (xy 363.528796 -250.638844) (xy 363.546959 -250.646429)
			(xy 363.554264 -250.653042) (xy 363.577886 -250.676664) (xy 363.587538 -250.680474) (xy 363.610471 -250.690114)
			(xy 363.65311 -250.715734) (xy 363.691031 -250.747927) (xy 363.723232 -250.785842) (xy 363.74886 -250.828475)
			(xy 363.75848 -250.851416) (xy 363.76229 -250.861068) (xy 364.159546 -251.258324) (xy 364.166943 -251.265172)
			(xy 364.185542 -251.272901) (xy 364.195614 -251.27331) (xy 364.788958 -251.27331) (xy 364.798797 -251.272777)
			(xy 364.816962 -251.265194) (xy 364.824264 -251.258578) (xy 365.046006 -251.036836) (xy 365.053626 -251.014738)
			(xy 365.052102 -251.0028) (xy 365.050927 -250.993191) (xy 365.049655 -250.973872) (xy 365.049562 -250.964192)
			(xy 365.050033 -250.9402) (xy 365.05754 -250.892808) (xy 365.072368 -250.847173) (xy 365.094151 -250.804419)
			(xy 365.122354 -250.765599) (xy 365.156282 -250.731669) (xy 365.1951 -250.703463) (xy 365.237853 -250.681676)
			(xy 365.283486 -250.666845) (xy 365.330878 -250.659335) (xy 365.35487 -250.658884) (xy 365.36455 -250.658986)
			(xy 365.383868 -250.660259) (xy 365.393478 -250.661424) (xy 365.405416 -250.662948) (xy 365.427514 -250.655328)
			(xy 365.6838 -250.399042) (xy 365.69104 -250.392332) (xy 365.709244 -250.384741) (xy 365.719106 -250.38431)
			(xy 366.380522 -250.38431) (xy 366.392596 -250.383647) (xy 366.414091 -250.372648) (xy 366.42167 -250.363228)
			(xy 366.46866 -250.29795) (xy 366.475239 -250.287642) (xy 366.47883 -250.263492) (xy 366.475518 -250.251722)
			(xy 366.468147 -250.228336) (xy 366.460104 -250.179969) (xy 366.459516 -250.155456) (xy 366.459516 -250.15063)
			(xy 366.460251 -250.126823) (xy 366.468197 -250.079863) (xy 366.483338 -250.034706) (xy 366.505309 -249.992448)
			(xy 366.533575 -249.954114) (xy 366.56745 -249.920635) (xy 366.606114 -249.892823) (xy 366.648627 -249.871351)
			(xy 366.693959 -249.856742) (xy 366.74101 -249.84935) (xy 366.764824 -249.848878) (xy 366.788427 -249.849319)
			(xy 366.83507 -249.856583) (xy 366.880041 -249.870936) (xy 366.92227 -249.892034) (xy 366.960751 -249.919377)
			(xy 366.994568 -249.952313) (xy 367.022917 -249.990058) (xy 367.045123 -250.031715) (xy 367.060658 -250.076291)
			(xy 367.069151 -250.122727) (xy 367.070132 -250.146312) (xy 367.070132 -250.154186) (xy 368.338874 -250.154186)
			(xy 368.342834 -250.105132) (xy 368.354611 -250.057348) (xy 368.373902 -250.012072) (xy 368.400205 -249.970476)
			(xy 368.43284 -249.933639) (xy 368.470961 -249.902514) (xy 368.513582 -249.877907) (xy 368.559598 -249.860455)
			(xy 368.607817 -249.850611) (xy 368.656992 -249.84863) (xy 368.705847 -249.854562) (xy 368.753118 -249.868254)
			(xy 368.79758 -249.889352) (xy 368.838083 -249.917308) (xy 368.873576 -249.9514) (xy 368.903141 -249.990744)
			(xy 368.926012 -250.034321) (xy 368.941596 -250.081002) (xy 368.949491 -250.129579) (xy 368.949986 -250.154186)
			(xy 368.949491 -250.178793) (xy 368.941596 -250.22737) (xy 368.926012 -250.274051) (xy 368.903141 -250.317628)
			(xy 368.873576 -250.356972) (xy 368.838083 -250.391064) (xy 368.79758 -250.41902) (xy 368.753118 -250.440118)
			(xy 368.705847 -250.45381) (xy 368.656992 -250.459742) (xy 368.607817 -250.457761) (xy 368.559598 -250.447917)
			(xy 368.513582 -250.430465) (xy 368.470961 -250.405858) (xy 368.43284 -250.374733) (xy 368.400205 -250.337896)
			(xy 368.373902 -250.2963) (xy 368.354611 -250.251024) (xy 368.342834 -250.20324) (xy 368.338874 -250.154186)
			(xy 367.070132 -250.154186) (xy 367.069566 -250.180693) (xy 367.060415 -250.232912) (xy 367.042387 -250.282766)
			(xy 367.016023 -250.32876) (xy 366.99952 -250.349512) (xy 366.999012 -250.35002) (xy 366.99344 -250.357442)
			(xy 366.987566 -250.37503) (xy 366.987582 -250.38431) (xy 366.987582 -250.384564) (xy 366.988398 -250.39403)
			(xy 366.996104 -250.411382) (xy 367.002568 -250.418346) (xy 367.235994 -250.651772) (xy 367.251996 -250.659138)
			(xy 367.260886 -250.6599) (xy 367.284514 -250.662387) (xy 367.330645 -250.67374) (xy 367.374462 -250.692098)
			(xy 367.414908 -250.71702) (xy 367.451008 -250.747905) (xy 367.48189 -250.784006) (xy 367.506809 -250.824453)
			(xy 367.525166 -250.868271) (xy 367.536516 -250.914403) (xy 367.539016 -250.93803) (xy 367.539778 -250.94692)
			(xy 367.547144 -250.962922) (xy 367.842546 -251.258324) (xy 367.849943 -251.265172) (xy 367.868542 -251.272901)
			(xy 367.878614 -251.27331) (xy 368.471958 -251.27331) (xy 368.481797 -251.272777) (xy 368.499962 -251.265194)
			(xy 368.507264 -251.258578) (xy 368.795808 -250.970034) (xy 368.801929 -250.963468) (xy 368.80948 -250.947197)
			(xy 368.81054 -250.938284) (xy 368.81301 -250.914628) (xy 368.824345 -250.868439) (xy 368.842704 -250.824565)
			(xy 368.867642 -250.784068) (xy 368.898558 -250.747928) (xy 368.934703 -250.717017) (xy 368.975204 -250.692084)
			(xy 369.01908 -250.673731) (xy 369.065271 -250.662403) (xy 369.088924 -250.6599) (xy 369.097807 -250.658734)
			(xy 369.114045 -250.651196) (xy 369.120674 -250.645168) (xy 369.3668 -250.399042) (xy 369.37404 -250.392332)
			(xy 369.392244 -250.384741) (xy 369.402106 -250.38431) (xy 370.140484 -250.38431) (xy 370.152551 -250.383634)
			(xy 370.174024 -250.37262) (xy 370.181632 -250.363228) (xy 370.228622 -250.29795) (xy 370.235194 -250.28764)
			(xy 370.238782 -250.263493) (xy 370.23548 -250.251722) (xy 370.228108 -250.228336) (xy 370.220063 -250.179969)
			(xy 370.219478 -250.155456) (xy 370.219478 -250.15063) (xy 370.220213 -250.126825) (xy 370.228159 -250.079868)
			(xy 370.243302 -250.034715) (xy 370.265273 -249.992462) (xy 370.29354 -249.954133) (xy 370.327417 -249.92066)
			(xy 370.366081 -249.892854) (xy 370.408594 -249.871391) (xy 370.453925 -249.85679) (xy 370.500974 -249.849407)
			(xy 370.524786 -249.848878) (xy 370.548373 -249.849323) (xy 370.594985 -249.856587) (xy 370.639926 -249.870929)
			(xy 370.682129 -249.892009) (xy 370.72059 -249.919326) (xy 370.754395 -249.952229) (xy 370.78274 -249.989938)
			(xy 370.804953 -250.031555) (xy 370.820505 -250.076093) (xy 370.829026 -250.122491) (xy 370.830094 -250.146058)
			(xy 370.830094 -250.154186) (xy 372.09909 -250.154186) (xy 372.10305 -250.105132) (xy 372.114827 -250.057348)
			(xy 372.134118 -250.012072) (xy 372.160421 -249.970476) (xy 372.193056 -249.933639) (xy 372.231177 -249.902514)
			(xy 372.273798 -249.877907) (xy 372.319814 -249.860455) (xy 372.368033 -249.850611) (xy 372.417208 -249.84863)
			(xy 372.466063 -249.854562) (xy 372.513334 -249.868254) (xy 372.557796 -249.889352) (xy 372.598299 -249.917308)
			(xy 372.633792 -249.9514) (xy 372.663357 -249.990744) (xy 372.686228 -250.034321) (xy 372.701812 -250.081002)
			(xy 372.709707 -250.129579) (xy 372.710202 -250.154186) (xy 372.709707 -250.178793) (xy 372.701812 -250.22737)
			(xy 372.686228 -250.274051) (xy 372.663357 -250.317628) (xy 372.633792 -250.356972) (xy 372.598299 -250.391064)
			(xy 372.557796 -250.41902) (xy 372.513334 -250.440118) (xy 372.466063 -250.45381) (xy 372.417208 -250.459742)
			(xy 372.368033 -250.457761) (xy 372.319814 -250.447917) (xy 372.273798 -250.430465) (xy 372.231177 -250.405858)
			(xy 372.193056 -250.374733) (xy 372.160421 -250.337896) (xy 372.134118 -250.2963) (xy 372.114827 -250.251024)
			(xy 372.10305 -250.20324) (xy 372.09909 -250.154186) (xy 370.830094 -250.154186) (xy 370.829484 -250.181573)
			(xy 370.819722 -250.23547) (xy 370.800507 -250.286763) (xy 370.772456 -250.33381) (xy 370.75491 -250.354846)
			(xy 370.748853 -250.36236) (xy 370.742314 -250.380503) (xy 370.74221 -250.390152) (xy 370.744496 -250.45797)
			(xy 370.745222 -250.46748) (xy 370.752788 -250.484972) (xy 370.759228 -250.492006) (xy 370.92255 -250.655328)
			(xy 370.944394 -250.662694) (xy 370.956332 -250.661424) (xy 370.965878 -250.660258) (xy 370.98507 -250.658988)
			(xy 370.994686 -250.658884) (xy 371.01868 -250.659329) (xy 371.066078 -250.666834) (xy 371.111718 -250.681661)
			(xy 371.154476 -250.703446) (xy 371.193301 -250.731651) (xy 371.227235 -250.765583) (xy 371.255443 -250.804405)
			(xy 371.27723 -250.847162) (xy 371.292061 -250.892801) (xy 371.299569 -250.940198) (xy 371.299994 -250.964192)
			(xy 371.299885 -250.973808) (xy 371.298612 -250.992999) (xy 371.297454 -251.002546) (xy 371.296184 -251.014484)
			(xy 371.30355 -251.036328) (xy 371.398546 -251.131324) (xy 371.405943 -251.138172) (xy 371.424542 -251.145901)
			(xy 371.434614 -251.14631) (xy 372.477284 -251.14631) (xy 372.488524 -251.145728) (xy 372.508838 -251.136104)
			(xy 372.5164 -251.127768) (xy 372.572534 -251.059188) (xy 372.578122 -251.036836) (xy 372.575836 -251.02566)
			(xy 372.57288 -251.010465) (xy 372.569702 -250.979671) (xy 372.569486 -250.964192) (xy 372.569957 -250.940201)
			(xy 372.577464 -250.89281) (xy 372.592292 -250.847177) (xy 372.614076 -250.804425) (xy 372.64228 -250.765607)
			(xy 372.676208 -250.731678) (xy 372.715026 -250.703475) (xy 372.757778 -250.681692) (xy 372.803412 -250.666864)
			(xy 372.850803 -250.659357) (xy 372.874794 -250.658884) (xy 372.899364 -250.659376) (xy 372.947868 -250.667251)
			(xy 372.994483 -250.682797) (xy 373.038004 -250.705614) (xy 373.077305 -250.73511) (xy 373.111372 -250.770524)
			(xy 373.125746 -250.790456) (xy 373.13235 -250.799854) (xy 373.1514 -250.81103) (xy 373.238776 -250.819158)
			(xy 373.249995 -250.819582) (xy 373.271077 -250.811942) (xy 373.279416 -250.804426) (xy 373.978678 -250.105164)
			(xy 373.985536 -250.092972) (xy 373.98706 -250.08586) (xy 373.992998 -250.062151) (xy 374.011382 -250.016866)
			(xy 374.036743 -249.975088) (xy 374.068436 -249.937883) (xy 374.105649 -249.9062) (xy 374.147433 -249.880848)
			(xy 374.192722 -249.862475) (xy 374.216422 -249.856498) (xy 374.223534 -249.854974) (xy 374.235726 -249.848116)
			(xy 374.497092 -249.58675) (xy 374.503401 -249.579913) (xy 374.511069 -249.562978) (xy 374.51221 -249.544424)
			(xy 374.509792 -249.535442) (xy 374.504712 -249.519948) (xy 374.500902 -249.513852) (xy 374.488731 -249.494923)
			(xy 374.469478 -249.454248) (xy 374.456393 -249.41119) (xy 374.449758 -249.36668) (xy 374.44934 -249.34418)
			(xy 374.451118 -249.311668) (xy 374.452642 -249.300746) (xy 374.456631 -249.276132) (xy 374.471551 -249.228556)
			(xy 374.493992 -249.184031) (xy 374.508268 -249.163586) (xy 374.51284 -249.15749) (xy 374.52046 -249.135138)
			(xy 374.521722 -249.131191) (xy 374.523124 -249.123024) (xy 374.523254 -249.118882) (xy 374.523254 -247.949466)
			(xy 374.523159 -247.945321) (xy 374.521757 -247.937148) (xy 374.52046 -247.93321) (xy 374.51284 -247.910858)
			(xy 374.508268 -247.904762) (xy 374.494376 -247.88499) (xy 374.472341 -247.841987) (xy 374.457342 -247.796054)
			(xy 374.449749 -247.748334) (xy 374.449753 -247.700014) (xy 374.457354 -247.652296) (xy 374.472361 -247.606366)
			(xy 374.494403 -247.563366) (xy 374.508268 -247.543574) (xy 374.51284 -247.537478) (xy 374.52046 -247.515126)
			(xy 374.521721 -247.511179) (xy 374.523121 -247.503012) (xy 374.523254 -247.49887) (xy 374.523254 -247.29567)
			(xy 374.522523 -247.283425) (xy 374.511239 -247.261685) (xy 374.501664 -247.254014) (xy 374.435116 -247.207532)
			(xy 374.430044 -247.204218) (xy 374.418747 -247.199851) (xy 374.412764 -247.198896) (xy 374.400318 -247.197118)
			(xy 374.391936 -247.199912) (xy 374.366068 -247.208977) (xy 374.31215 -247.218808) (xy 374.284748 -247.21947)
			(xy 374.259491 -247.218981) (xy 374.209664 -247.210674) (xy 374.161885 -247.194278) (xy 374.117457 -247.170241)
			(xy 374.077591 -247.139218) (xy 374.043376 -247.102056) (xy 374.015745 -247.059769) (xy 373.995452 -247.01351)
			(xy 373.98305 -246.964542) (xy 373.978878 -246.9142) (xy 373.98305 -246.863858) (xy 373.995452 -246.81489)
			(xy 374.015745 -246.768631) (xy 374.043376 -246.726344) (xy 374.077591 -246.689182) (xy 374.117457 -246.658159)
			(xy 374.161885 -246.634122) (xy 374.209664 -246.617726) (xy 374.259491 -246.609419) (xy 374.284748 -246.608854)
			(xy 374.298464 -246.608854) (xy 374.321572 -246.610337) (xy 374.366982 -246.619387) (xy 374.388888 -246.626888)
			(xy 374.400826 -246.631206) (xy 374.424956 -246.627904) (xy 374.501664 -246.57431) (xy 374.51129 -246.566686)
			(xy 374.522563 -246.544915) (xy 374.523254 -246.532654) (xy 374.523254 -246.329454) (xy 374.523158 -246.325309)
			(xy 374.521754 -246.317137) (xy 374.52046 -246.313198) (xy 374.51284 -246.290846) (xy 374.508268 -246.28475)
			(xy 374.494377 -246.264978) (xy 374.472344 -246.221975) (xy 374.457346 -246.176043) (xy 374.449755 -246.128324)
			(xy 374.449761 -246.080005) (xy 374.457363 -246.032288) (xy 374.472372 -245.986359) (xy 374.494414 -245.943361)
			(xy 374.508268 -245.923562) (xy 374.51284 -245.917466) (xy 374.52046 -245.895114) (xy 374.521721 -245.891167)
			(xy 374.523118 -245.883) (xy 374.523254 -245.878858) (xy 374.523254 -244.709442) (xy 374.523157 -244.705297)
			(xy 374.521751 -244.697126) (xy 374.52046 -244.693186) (xy 374.51284 -244.670834) (xy 374.508268 -244.664738)
			(xy 374.494453 -244.645005) (xy 374.472546 -244.602108) (xy 374.457631 -244.556307) (xy 374.450076 -244.508736)
			(xy 374.449594 -244.484652) (xy 374.449594 -244.484144) (xy 374.450049 -244.460407) (xy 374.457409 -244.413506)
			(xy 374.471942 -244.368311) (xy 374.493297 -244.325911) (xy 374.506744 -244.306344) (xy 374.517412 -244.291104)
			(xy 374.514618 -244.254274) (xy 374.241822 -243.981478) (xy 374.228868 -243.974366) (xy 374.221502 -243.972842)
			(xy 374.199788 -243.967849) (xy 374.157994 -243.952411) (xy 374.118892 -243.931055) (xy 374.100852 -243.917978)
			(xy 374.100598 -243.917724) (xy 374.09374 -243.912644) (xy 374.086374 -243.910104) (xy 374.082367 -243.908817)
			(xy 374.074071 -243.907407) (xy 374.069864 -243.90731) (xy 374.024906 -243.90731) (xy 374.02008 -243.908326)
			(xy 373.969475 -243.917624) (xy 373.867058 -243.927548) (xy 373.81561 -243.928138) (xy 373.53494 -243.928138)
			(xy 373.521478 -243.929916) (xy 373.503444 -243.934996) (xy 373.497856 -243.938298) (xy 373.474424 -243.951231)
			(xy 373.424152 -243.969583) (xy 373.371452 -243.978901) (xy 373.317936 -243.978901) (xy 373.265236 -243.969583)
			(xy 373.214964 -243.951231) (xy 373.191532 -243.938298) (xy 373.185944 -243.934996) (xy 373.16791 -243.929916)
			(xy 373.154448 -243.928138) (xy 372.874032 -243.928138) (xy 372.822585 -243.927516) (xy 372.720171 -243.917595)
			(xy 372.669562 -243.908326) (xy 372.664736 -243.90731) (xy 372.624096 -243.90731) (xy 372.615714 -243.908072)
			(xy 372.603268 -243.910104) (xy 372.595902 -243.912644) (xy 372.589044 -243.917724) (xy 372.58879 -243.917724)
			(xy 372.568803 -243.932228) (xy 372.525128 -243.955271) (xy 372.478315 -243.97099) (xy 372.429584 -243.978977)
			(xy 372.404894 -243.979446) (xy 372.381074 -243.978965) (xy 372.334018 -243.971519) (xy 372.28869 -243.956855)
			(xy 372.24619 -243.935329) (xy 372.226586 -243.921788) (xy 372.22049 -243.91747) (xy 372.190518 -243.90731)
			(xy 371.679216 -243.90731) (xy 371.649244 -243.91747) (xy 371.643148 -243.921788) (xy 371.623558 -243.935351)
			(xy 371.581054 -243.956877) (xy 371.535722 -243.971537) (xy 371.488662 -243.978976) (xy 371.46484 -243.979446)
			(xy 371.440151 -243.978951) (xy 371.391422 -243.970969) (xy 371.344611 -243.955256) (xy 371.300936 -243.932219)
			(xy 371.280944 -243.917724) (xy 371.28069 -243.917724) (xy 371.273832 -243.912644) (xy 371.266466 -243.910104)
			(xy 371.262459 -243.908818) (xy 371.254163 -243.907409) (xy 371.249956 -243.90731) (xy 371.204744 -243.90731)
			(xy 371.199918 -243.908326) (xy 371.149313 -243.917625) (xy 371.046897 -243.927554) (xy 370.995448 -243.928138)
			(xy 370.715032 -243.928138) (xy 370.70157 -243.929916) (xy 370.683536 -243.934996) (xy 370.677948 -243.938298)
			(xy 370.654516 -243.951231) (xy 370.604244 -243.969583) (xy 370.551544 -243.978901) (xy 370.498028 -243.978901)
			(xy 370.445328 -243.969583) (xy 370.395056 -243.951231) (xy 370.371624 -243.938298) (xy 370.366036 -243.934996)
			(xy 370.348002 -243.929916) (xy 370.33454 -243.928138) (xy 370.054124 -243.928138) (xy 370.002677 -243.927516)
			(xy 369.900263 -243.917594) (xy 369.849654 -243.908326) (xy 369.844828 -243.90731) (xy 369.803934 -243.90731)
			(xy 369.795552 -243.908072) (xy 369.783106 -243.910104) (xy 369.77574 -243.912644) (xy 369.768882 -243.917724)
			(xy 369.768628 -243.917724) (xy 369.74864 -243.932224) (xy 369.704963 -243.955258) (xy 369.65815 -243.970967)
			(xy 369.609421 -243.978945) (xy 369.584732 -243.979446) (xy 369.560911 -243.978968) (xy 369.513853 -243.971527)
			(xy 369.468521 -243.956867) (xy 369.426017 -243.935345) (xy 369.406424 -243.921788) (xy 369.400328 -243.91747)
			(xy 369.370356 -243.90731) (xy 368.859054 -243.90731) (xy 368.829082 -243.91747) (xy 368.822986 -243.921788)
			(xy 368.803397 -243.935353) (xy 368.760894 -243.956884) (xy 368.715561 -243.97155) (xy 368.668501 -243.978996)
			(xy 368.644678 -243.979446) (xy 368.619988 -243.978954) (xy 368.571257 -243.970978) (xy 368.524442 -243.955269)
			(xy 368.480762 -243.932236) (xy 368.460782 -243.917724) (xy 368.460528 -243.917724) (xy 368.45367 -243.912644)
			(xy 368.446304 -243.910104) (xy 368.442296 -243.908823) (xy 368.434 -243.907424) (xy 368.429794 -243.90731)
			(xy 368.384836 -243.90731) (xy 368.38001 -243.908326) (xy 368.329405 -243.917625) (xy 368.226989 -243.927552)
			(xy 368.17554 -243.928138) (xy 367.895124 -243.928138) (xy 367.881662 -243.929916) (xy 367.863628 -243.934996)
			(xy 367.85804 -243.938298) (xy 367.834608 -243.951231) (xy 367.784336 -243.969583) (xy 367.731636 -243.978901)
			(xy 367.67812 -243.978901) (xy 367.62542 -243.969583) (xy 367.575148 -243.951231) (xy 367.551716 -243.938298)
			(xy 367.546128 -243.934996) (xy 367.528094 -243.929916) (xy 367.514632 -243.928138) (xy 367.233962 -243.928138)
			(xy 367.182516 -243.927513) (xy 367.080102 -243.917585) (xy 367.029492 -243.908326) (xy 367.024666 -243.90731)
			(xy 366.984026 -243.90731) (xy 366.975644 -243.908072) (xy 366.963198 -243.910104) (xy 366.955832 -243.912644)
			(xy 366.948974 -243.917724) (xy 366.94872 -243.917724) (xy 366.928732 -243.932224) (xy 366.885055 -243.955256)
			(xy 366.838242 -243.970965) (xy 366.789513 -243.978941) (xy 366.764824 -243.979446) (xy 366.741003 -243.978967)
			(xy 366.693946 -243.971525) (xy 366.648615 -243.956865) (xy 366.606111 -243.935342) (xy 366.586516 -243.921788)
			(xy 366.58042 -243.91747) (xy 366.550448 -243.90731) (xy 366.039146 -243.90731) (xy 366.009174 -243.91747)
			(xy 366.003078 -243.921788) (xy 365.983489 -243.935353) (xy 365.940985 -243.956883) (xy 365.895653 -243.971548)
			(xy 365.848592 -243.978992) (xy 365.82477 -243.979446) (xy 365.80008 -243.978953) (xy 365.751349 -243.970976)
			(xy 365.704535 -243.955266) (xy 365.660857 -243.932232) (xy 365.640874 -243.917724) (xy 365.64062 -243.917724)
			(xy 365.633762 -243.912644) (xy 365.626396 -243.910104) (xy 365.622388 -243.908824) (xy 365.614092 -243.907426)
			(xy 365.609886 -243.90731) (xy 365.564928 -243.90731) (xy 365.560102 -243.908326) (xy 365.509497 -243.917625)
			(xy 365.407081 -243.927551) (xy 365.355632 -243.928138) (xy 365.074962 -243.928138) (xy 365.0615 -243.929916)
			(xy 365.043466 -243.934996) (xy 365.037878 -243.938298) (xy 365.014446 -243.951231) (xy 364.964174 -243.969583)
			(xy 364.911474 -243.978901) (xy 364.857958 -243.978901) (xy 364.805258 -243.969583) (xy 364.754986 -243.951231)
			(xy 364.731554 -243.938298) (xy 364.725966 -243.934996) (xy 364.707932 -243.929916) (xy 364.69447 -243.928138)
			(xy 364.435898 -243.928138) (xy 364.425829 -243.927713) (xy 364.407231 -243.919991) (xy 364.39983 -243.913152)
			(xy 364.338362 -243.851684) (xy 364.33034 -243.844518) (xy 364.310255 -243.836891) (xy 364.2995 -243.836952)
			(xy 364.212378 -243.842286) (xy 364.193074 -243.852446) (xy 364.18647 -243.861082) (xy 364.171903 -243.879176)
			(xy 364.138224 -243.911164) (xy 364.10009 -243.937684) (xy 364.05838 -243.958125) (xy 364.014057 -243.972016)
			(xy 363.968141 -243.979036) (xy 363.944916 -243.979446) (xy 363.920923 -243.978977) (xy 363.873527 -243.971473)
			(xy 363.827888 -243.956647) (xy 363.785131 -243.934865) (xy 363.746307 -243.906663) (xy 363.712372 -243.872734)
			(xy 363.684163 -243.833915) (xy 363.662373 -243.791162) (xy 363.64754 -243.745526) (xy 363.640028 -243.698131)
			(xy 363.639608 -243.674138) (xy 363.640036 -243.651071) (xy 363.646991 -243.605465) (xy 363.660733 -243.561426)
			(xy 363.680949 -243.519957) (xy 363.707178 -243.482006) (xy 363.738822 -243.448435) (xy 363.756702 -243.433854)
			(xy 363.75721 -243.433346) (xy 363.764548 -243.427105) (xy 363.774332 -243.410527) (xy 363.77626 -243.401088)
			(xy 363.787182 -243.332762) (xy 363.788322 -243.323271) (xy 363.784284 -243.304601) (xy 363.779308 -243.29644)
			(xy 363.7788 -243.295932) (xy 363.778546 -243.295678) (xy 363.773974 -243.28882) (xy 363.77118 -243.284502)
			(xy 363.63402 -243.147342) (xy 363.604048 -243.141246) (xy 363.589824 -243.147088) (xy 363.562402 -243.157498)
			(xy 363.504847 -243.168758) (xy 363.475524 -243.16944) (xy 363.474762 -243.16944) (xy 363.450513 -243.168971)
			(xy 363.402625 -243.161298) (xy 363.356552 -243.146152) (xy 363.313453 -243.123914) (xy 363.274411 -243.095142)
			(xy 363.240408 -243.06056) (xy 363.212299 -243.021037) (xy 363.190792 -242.977569) (xy 363.176426 -242.931247)
			(xy 363.172502 -242.907312) (xy 363.170978 -242.89766) (xy 363.16158 -242.880896) (xy 363.099604 -242.831366)
			(xy 363.095807 -242.828469) (xy 363.087366 -242.824002) (xy 363.08284 -242.822476) (xy 363.074204 -242.819682)
			(xy 363.034072 -242.822222) (xy 363.033818 -242.822222) (xy 363.004862 -242.822984) (xy 362.70692 -242.822984)
			(xy 362.666868 -242.822426) (xy 362.587205 -242.814022) (xy 362.547916 -242.80622) (xy 362.545376 -242.805712)
			(xy 362.534708 -242.804696) (xy 362.524294 -242.805712) (xy 362.521754 -242.80622) (xy 362.482468 -242.814041)
			(xy 362.402803 -242.822445) (xy 362.36275 -242.822984) (xy 362.064808 -242.822984) (xy 362.024558 -242.822459)
			(xy 361.944499 -242.814053) (xy 361.865756 -242.797331) (xy 361.78919 -242.772476) (xy 361.715639 -242.739761)
			(xy 361.680506 -242.720114) (xy 361.674918 -242.716812) (xy 361.655868 -242.711478) (xy 361.642406 -242.7097)
			(xy 360.746802 -242.7097) (xy 360.736732 -242.709277) (xy 360.718127 -242.701563) (xy 360.710734 -242.694714)
			(xy 358.668574 -240.652554) (xy 358.66123 -240.645742) (xy 358.642767 -240.63801) (xy 358.63276 -240.637568)
			(xy 358.561386 -240.63706) (xy 358.551536 -240.637474) (xy 358.53325 -240.644796) (xy 358.525826 -240.651284)
			(xy 358.525318 -240.651792) (xy 358.525064 -240.652046) (xy 358.507832 -240.668334) (xy 358.469267 -240.695916)
			(xy 358.426899 -240.717202) (xy 358.381749 -240.731678) (xy 358.334903 -240.738996) (xy 358.311196 -240.739422)
			(xy 358.287205 -240.738951) (xy 358.239813 -240.731445) (xy 358.194178 -240.716617) (xy 358.151425 -240.694833)
			(xy 358.112606 -240.66663) (xy 358.078676 -240.632702) (xy 358.050472 -240.593884) (xy 358.028687 -240.551131)
			(xy 358.013858 -240.505497) (xy 358.00635 -240.458105) (xy 358.005888 -240.434114) (xy 358.006342 -240.410411)
			(xy 358.013678 -240.363575) (xy 358.02816 -240.318434) (xy 358.049442 -240.276073) (xy 358.077011 -240.237507)
			(xy 358.093264 -240.220246) (xy 358.093518 -240.219992) (xy 358.094026 -240.219484) (xy 358.100549 -240.212081)
			(xy 358.107879 -240.193783) (xy 358.10825 -240.183924) (xy 358.107742 -240.11255) (xy 358.107212 -240.10256)
			(xy 358.099505 -240.08412) (xy 358.092756 -240.076736) (xy 358.08666 -240.07064) (xy 358.08285 -240.061496)
			(xy 358.081076 -240.056868) (xy 358.079157 -240.047147) (xy 358.07904 -240.042192) (xy 358.07904 -239.038638)
			(xy 358.078943 -239.034493) (xy 358.077536 -239.026323) (xy 358.076246 -239.022382) (xy 358.068626 -238.999776)
			(xy 358.064308 -238.99368) (xy 358.050546 -238.973998) (xy 358.028726 -238.931216) (xy 358.013873 -238.885546)
			(xy 358.006354 -238.838114) (xy 358.006353 -238.790089) (xy 358.013872 -238.742657) (xy 358.028724 -238.696987)
			(xy 358.050544 -238.654205) (xy 358.064308 -238.634524) (xy 358.068626 -238.628428) (xy 358.076246 -238.605822)
			(xy 358.077507 -238.601875) (xy 358.078907 -238.593708) (xy 358.07904 -238.589566) (xy 358.07904 -238.387636)
			(xy 358.078323 -238.375384) (xy 358.067052 -238.353623) (xy 358.05745 -238.34598) (xy 357.979472 -238.290862)
			(xy 357.955342 -238.28756) (xy 357.943404 -238.291624) (xy 357.918626 -238.299902) (xy 357.86716 -238.308847)
			(xy 357.841042 -238.309404) (xy 357.815782 -238.308915) (xy 357.765951 -238.300606) (xy 357.718167 -238.284207)
			(xy 357.673735 -238.260167) (xy 357.633866 -238.229141) (xy 357.599648 -238.191975) (xy 357.572014 -238.149683)
			(xy 357.551719 -238.10342) (xy 357.539316 -238.054447) (xy 357.535144 -238.0041) (xy 357.539316 -237.953753)
			(xy 357.551719 -237.90478) (xy 357.572014 -237.858517) (xy 357.599648 -237.816225) (xy 357.633866 -237.779059)
			(xy 357.673735 -237.748033) (xy 357.718167 -237.723993) (xy 357.765951 -237.707594) (xy 357.815782 -237.699285)
			(xy 357.841042 -237.698788) (xy 357.852387 -237.698871) (xy 357.875017 -237.700525) (xy 357.886254 -237.70209)
			(xy 357.897957 -237.703269) (xy 357.920339 -237.696129) (xy 357.92918 -237.688374) (xy 357.995728 -237.623604)
			(xy 358.003602 -237.601252) (xy 358.002078 -237.589568) (xy 357.987093 -237.460574) (xy 357.966216 -237.201696)
			(xy 357.955755 -236.942187) (xy 357.955088 -236.812328) (xy 357.955088 -236.790738) (xy 357.954617 -236.780495)
			(xy 357.946616 -236.761635) (xy 357.939594 -236.754162) (xy 357.879904 -236.69625) (xy 357.860854 -236.688884)
			(xy 357.85044 -236.689138) (xy 357.841042 -236.689392) (xy 357.815783 -236.688903) (xy 357.765954 -236.680594)
			(xy 357.718172 -236.664196) (xy 357.673741 -236.640157) (xy 357.633874 -236.609132) (xy 357.599657 -236.571967)
			(xy 357.572025 -236.529677) (xy 357.55173 -236.483416) (xy 357.539328 -236.434445) (xy 357.535156 -236.3841)
			(xy 357.539328 -236.333755) (xy 357.55173 -236.284784) (xy 357.572025 -236.238523) (xy 357.599657 -236.196233)
			(xy 357.633874 -236.159068) (xy 357.673741 -236.128043) (xy 357.718172 -236.104004) (xy 357.765954 -236.087606)
			(xy 357.815783 -236.079297) (xy 357.841042 -236.078776) (xy 357.85044 -236.07903) (xy 357.860854 -236.079284)
			(xy 357.879904 -236.071918) (xy 357.939848 -236.013752) (xy 357.946772 -236.006385) (xy 357.954655 -235.987784)
			(xy 357.955088 -235.977684) (xy 357.955088 -233.550714) (xy 357.954613 -233.540473) (xy 357.946605 -233.52162)
			(xy 357.939594 -233.514138) (xy 357.879904 -233.456226) (xy 357.860854 -233.44886) (xy 357.85044 -233.449114)
			(xy 357.841042 -233.449368) (xy 357.815785 -233.448879) (xy 357.76596 -233.440571) (xy 357.718182 -233.424174)
			(xy 357.673755 -233.400137) (xy 357.63389 -233.369114) (xy 357.599676 -233.331953) (xy 357.572046 -233.289666)
			(xy 357.551753 -233.243408) (xy 357.539352 -233.194441) (xy 357.53518 -233.1441) (xy 357.539352 -233.093759)
			(xy 357.551753 -233.044792) (xy 357.572046 -232.998534) (xy 357.599676 -232.956247) (xy 357.63389 -232.919086)
			(xy 357.673755 -232.888063) (xy 357.718182 -232.864026) (xy 357.76596 -232.847629) (xy 357.815785 -232.839321)
			(xy 357.841042 -232.838752) (xy 357.85044 -232.839006) (xy 357.860854 -232.83926) (xy 357.879904 -232.831894)
			(xy 357.939848 -232.773728) (xy 357.946769 -232.766359) (xy 357.954643 -232.747758) (xy 357.955088 -232.73766)
			(xy 357.955088 -230.31069) (xy 357.954627 -230.300443) (xy 357.946639 -230.281569) (xy 357.939594 -230.274114)
			(xy 357.879904 -230.216202) (xy 357.860854 -230.208836) (xy 357.85044 -230.20909) (xy 357.841042 -230.209344)
			(xy 357.815779 -230.208855) (xy 357.765941 -230.200544) (xy 357.718151 -230.184144) (xy 357.673713 -230.1601)
			(xy 357.633839 -230.12907) (xy 357.599616 -230.091899) (xy 357.571979 -230.049602) (xy 357.551681 -230.003333)
			(xy 357.539277 -229.954353) (xy 357.535104 -229.904) (xy 357.539277 -229.853647) (xy 357.551681 -229.804667)
			(xy 357.571979 -229.758398) (xy 357.599616 -229.716101) (xy 357.633839 -229.67893) (xy 357.673713 -229.6479)
			(xy 357.718151 -229.623856) (xy 357.765941 -229.607456) (xy 357.815779 -229.599145) (xy 357.841042 -229.598728)
			(xy 357.85044 -229.598982) (xy 357.860854 -229.599236) (xy 357.879904 -229.59187) (xy 357.939848 -229.533704)
			(xy 357.946765 -229.526334) (xy 357.95463 -229.507733) (xy 357.955088 -229.497636) (xy 357.955088 -227.89007)
			(xy 357.95451 -227.834018) (xy 357.945096 -227.72231) (xy 357.926336 -227.611786) (xy 357.898363 -227.503228)
			(xy 357.861375 -227.397402) (xy 357.83901 -227.346002) (xy 357.83701 -227.341869) (xy 357.831774 -227.334329)
			(xy 357.828596 -227.331016) (xy 357.734616 -227.237036) (xy 357.725747 -227.229011) (xy 357.703089 -227.221445)
			(xy 357.691182 -227.222558) (xy 357.679244 -227.224336) (xy 357.659686 -227.238306) (xy 357.637842 -227.279454)
			(xy 357.638096 -227.305616) (xy 357.6447 -227.317046) (xy 357.657876 -227.34114) (xy 357.676626 -227.392749)
			(xy 357.686198 -227.446818) (xy 357.686864 -227.474272) (xy 357.686377 -227.499082) (xy 357.678615 -227.54809)
			(xy 357.663282 -227.59528) (xy 357.640755 -227.639491) (xy 357.61159 -227.679634) (xy 357.576504 -227.71472)
			(xy 357.536361 -227.743885) (xy 357.49215 -227.766412) (xy 357.44496 -227.781745) (xy 357.395952 -227.789507)
			(xy 357.346332 -227.789507) (xy 357.297324 -227.781745) (xy 357.250134 -227.766412) (xy 357.205923 -227.743885)
			(xy 357.16578 -227.71472) (xy 357.130694 -227.679634) (xy 357.101529 -227.639491) (xy 357.079002 -227.59528)
			(xy 357.063669 -227.54809) (xy 357.055907 -227.499082) (xy 357.05542 -227.474272) (xy 357.055894 -227.449644)
			(xy 357.063544 -227.400985) (xy 357.078654 -227.354104) (xy 357.100857 -227.310136) (xy 357.114856 -227.289868)
			(xy 357.119662 -227.282717) (xy 357.124607 -227.266225) (xy 357.124508 -227.25761) (xy 357.12273 -227.227892)
			(xy 357.121846 -227.218593) (xy 357.11428 -227.201532) (xy 357.107998 -227.194618) (xy 357.069136 -227.155756)
			(xy 357.057198 -227.149152) (xy 357.050594 -227.147374) (xy 357.006589 -227.136076) (xy 356.920086 -227.108269)
			(xy 356.83568 -227.074632) (xy 356.753762 -227.035322) (xy 356.714044 -227.013262) (xy 356.71379 -227.013008)
			(xy 356.698296 -227.004118) (xy 356.660196 -226.981766) (xy 356.647754 -226.97442) (xy 356.623363 -226.958922)
			(xy 356.611428 -226.950778) (xy 356.573735 -226.924215) (xy 356.501715 -226.866616) (xy 356.433848 -226.804176)
			(xy 356.401878 -226.770946) (xy 356.401624 -226.770692) (xy 356.392584 -226.762259) (xy 356.369225 -226.75428)
			(xy 356.35692 -226.755452) (xy 356.26167 -226.770438) (xy 356.241858 -226.78517) (xy 356.23627 -226.7966)
			(xy 356.225215 -226.818456) (xy 356.197209 -226.858633) (xy 356.16315 -226.893825) (xy 356.12391 -226.92313)
			(xy 356.080496 -226.945796) (xy 356.03402 -226.961243) (xy 355.985675 -226.969073) (xy 355.961188 -226.969574)
			(xy 355.935936 -226.969052) (xy 355.886121 -226.960737) (xy 355.838355 -226.944337) (xy 355.793939 -226.920299)
			(xy 355.754085 -226.889278) (xy 355.71988 -226.85212) (xy 355.692258 -226.80984) (xy 355.671971 -226.76359)
			(xy 355.659573 -226.714631) (xy 355.655403 -226.6643) (xy 355.659573 -226.613969) (xy 355.671971 -226.56501)
			(xy 355.692258 -226.51876) (xy 355.71988 -226.47648) (xy 355.754085 -226.439322) (xy 355.793939 -226.408301)
			(xy 355.838355 -226.384263) (xy 355.886121 -226.367863) (xy 355.935936 -226.359548) (xy 355.961188 -226.358958)
			(xy 355.985318 -226.359974) (xy 355.998018 -226.36099) (xy 356.020878 -226.351084) (xy 356.081584 -226.276408)
			(xy 356.088757 -226.266439) (xy 356.093672 -226.242417) (xy 356.090982 -226.230434) (xy 356.090982 -226.229672)
			(xy 356.075488 -226.172522) (xy 356.07371 -226.165664) (xy 356.067106 -226.153726) (xy 355.219762 -225.306382)
			(xy 355.186234 -225.30181) (xy 355.171248 -225.310192) (xy 355.148222 -225.322547) (xy 355.098999 -225.340079)
			(xy 355.047514 -225.348999) (xy 355.021388 -225.349562) (xy 354.997397 -225.349115) (xy 354.950005 -225.341606)
			(xy 354.904372 -225.326776) (xy 354.861621 -225.304989) (xy 354.822805 -225.276783) (xy 354.788879 -225.242851)
			(xy 354.76068 -225.204029) (xy 354.738902 -225.161274) (xy 354.72408 -225.115638) (xy 354.716581 -225.068245)
			(xy 354.71608 -225.044254) (xy 354.716615 -225.018126) (xy 354.725523 -224.966635) (xy 354.743087 -224.917419)
			(xy 354.75545 -224.894394) (xy 354.763832 -224.879408) (xy 354.75926 -224.84588) (xy 354.42652 -224.51314)
			(xy 354.418646 -224.50933) (xy 354.395736 -224.497702) (xy 354.353843 -224.467966) (xy 354.317518 -224.431638)
			(xy 354.287786 -224.389743) (xy 354.276152 -224.366836) (xy 354.272342 -224.358962) (xy 354.089716 -224.176336)
			(xy 354.078794 -224.165414) (xy 354.04933 -224.159318) (xy 353.934268 -224.204784) (xy 353.916742 -224.229422)
			(xy 353.916234 -224.244662) (xy 353.914811 -224.270708) (xy 353.904197 -224.321775) (xy 353.885065 -224.370297)
			(xy 353.85797 -224.414865) (xy 353.823699 -224.454184) (xy 353.783248 -224.487112) (xy 353.737793 -224.512691)
			(xy 353.688654 -224.530179) (xy 353.637259 -224.539068) (xy 353.61118 -224.539556) (xy 353.585922 -224.539033)
			(xy 353.536095 -224.530716) (xy 353.488316 -224.51431) (xy 353.443889 -224.490265) (xy 353.404026 -224.459236)
			(xy 353.369813 -224.422068) (xy 353.342184 -224.379777) (xy 353.321893 -224.333515) (xy 353.309492 -224.284544)
			(xy 353.30532 -224.2342) (xy 353.309492 -224.183856) (xy 353.321893 -224.134885) (xy 353.342184 -224.088623)
			(xy 353.369813 -224.046332) (xy 353.404026 -224.009164) (xy 353.443889 -223.978135) (xy 353.488316 -223.95409)
			(xy 353.536095 -223.937684) (xy 353.585922 -223.929367) (xy 353.61118 -223.92894) (xy 353.636 -223.929424)
			(xy 353.684987 -223.93745) (xy 353.732031 -223.953294) (xy 353.754182 -223.9645) (xy 353.76612 -223.97085)
			(xy 353.792536 -223.970088) (xy 353.878642 -223.918272) (xy 353.885919 -223.913457) (xy 353.896961 -223.899962)
			(xy 353.902862 -223.883555) (xy 353.90328 -223.874838) (xy 353.90328 -223.697038) (xy 353.902713 -223.685932)
			(xy 353.893356 -223.665785) (xy 353.885246 -223.658176) (xy 353.86695 -223.642251) (xy 353.835151 -223.605627)
			(xy 353.809546 -223.564433) (xy 353.790781 -223.519708) (xy 353.779328 -223.472576) (xy 353.775475 -223.424227)
			(xy 353.779319 -223.375877) (xy 353.790764 -223.328744) (xy 353.809521 -223.284015) (xy 353.835119 -223.242816)
			(xy 353.866911 -223.206186) (xy 353.885246 -223.190308) (xy 353.893372 -223.182714) (xy 353.902704 -223.162555)
			(xy 353.90328 -223.151446) (xy 353.90328 -222.547434) (xy 353.903059 -222.540189) (xy 353.89906 -222.526263)
			(xy 353.895406 -222.520002) (xy 353.869673 -222.478718) (xy 353.823584 -222.393037) (xy 353.783865 -222.304223)
			(xy 353.766882 -222.258636) (xy 353.747698 -222.203924) (xy 353.717765 -222.091905) (xy 353.697661 -221.977711)
			(xy 353.687539 -221.862204) (xy 353.686872 -221.80423) (xy 353.686872 -221.716854) (xy 353.68644 -221.706788)
			(xy 353.678711 -221.688198) (xy 353.671886 -221.680786) (xy 353.16922 -221.17812) (xy 353.166172 -221.175072)
			(xy 353.018598 -221.070678) (xy 353.012014 -221.066347) (xy 352.99701 -221.061556) (xy 352.989134 -221.06128)
			(xy 340.360762 -221.06128) (xy 340.350694 -221.061709) (xy 340.332098 -221.069431) (xy 340.324694 -221.076266)
			(xy 339.976206 -221.424754) (xy 339.96884 -221.431866) (xy 339.96122 -221.450662) (xy 339.96122 -221.80423)
			(xy 345.315298 -221.80423) (xy 345.319258 -221.755176) (xy 345.331035 -221.707392) (xy 345.350326 -221.662116)
			(xy 345.376629 -221.62052) (xy 345.409264 -221.583683) (xy 345.447385 -221.552558) (xy 345.490006 -221.527951)
			(xy 345.536022 -221.510499) (xy 345.584241 -221.500655) (xy 345.633416 -221.498674) (xy 345.682271 -221.504606)
			(xy 345.729542 -221.518298) (xy 345.774004 -221.539396) (xy 345.814507 -221.567352) (xy 345.85 -221.601444)
			(xy 345.879565 -221.640788) (xy 345.902436 -221.684365) (xy 345.91802 -221.731046) (xy 345.925915 -221.779623)
			(xy 345.92641 -221.80423) (xy 349.07526 -221.80423) (xy 349.07922 -221.755176) (xy 349.090997 -221.707392)
			(xy 349.110288 -221.662116) (xy 349.136591 -221.62052) (xy 349.169226 -221.583683) (xy 349.207347 -221.552558)
			(xy 349.249968 -221.527951) (xy 349.295984 -221.510499) (xy 349.344203 -221.500655) (xy 349.393378 -221.498674)
			(xy 349.442233 -221.504606) (xy 349.489504 -221.518298) (xy 349.533966 -221.539396) (xy 349.574469 -221.567352)
			(xy 349.609962 -221.601444) (xy 349.639527 -221.640788) (xy 349.662398 -221.684365) (xy 349.677982 -221.731046)
			(xy 349.685877 -221.779623) (xy 349.686372 -221.80423) (xy 350.955368 -221.80423) (xy 350.959328 -221.755176)
			(xy 350.971105 -221.707392) (xy 350.990396 -221.662116) (xy 351.016699 -221.62052) (xy 351.049334 -221.583683)
			(xy 351.087455 -221.552558) (xy 351.130076 -221.527951) (xy 351.176092 -221.510499) (xy 351.224311 -221.500655)
			(xy 351.273486 -221.498674) (xy 351.322341 -221.504606) (xy 351.369612 -221.518298) (xy 351.414074 -221.539396)
			(xy 351.454577 -221.567352) (xy 351.49007 -221.601444) (xy 351.519635 -221.640788) (xy 351.542506 -221.684365)
			(xy 351.55809 -221.731046) (xy 351.565985 -221.779623) (xy 351.56648 -221.80423) (xy 351.565985 -221.828837)
			(xy 351.55809 -221.877414) (xy 351.542506 -221.924095) (xy 351.519635 -221.967672) (xy 351.49007 -222.007016)
			(xy 351.454577 -222.041108) (xy 351.414074 -222.069064) (xy 351.369612 -222.090162) (xy 351.322341 -222.103854)
			(xy 351.273486 -222.109786) (xy 351.224311 -222.107805) (xy 351.176092 -222.097961) (xy 351.130076 -222.080509)
			(xy 351.087455 -222.055902) (xy 351.049334 -222.024777) (xy 351.016699 -221.98794) (xy 350.990396 -221.946344)
			(xy 350.971105 -221.901068) (xy 350.959328 -221.853284) (xy 350.955368 -221.80423) (xy 349.686372 -221.80423)
			(xy 349.685877 -221.828837) (xy 349.677982 -221.877414) (xy 349.662398 -221.924095) (xy 349.639527 -221.967672)
			(xy 349.609962 -222.007016) (xy 349.574469 -222.041108) (xy 349.533966 -222.069064) (xy 349.489504 -222.090162)
			(xy 349.442233 -222.103854) (xy 349.393378 -222.109786) (xy 349.344203 -222.107805) (xy 349.295984 -222.097961)
			(xy 349.249968 -222.080509) (xy 349.207347 -222.055902) (xy 349.169226 -222.024777) (xy 349.136591 -221.98794)
			(xy 349.110288 -221.946344) (xy 349.090997 -221.901068) (xy 349.07922 -221.853284) (xy 349.07526 -221.80423)
			(xy 345.92641 -221.80423) (xy 345.925915 -221.828837) (xy 345.91802 -221.877414) (xy 345.902436 -221.924095)
			(xy 345.879565 -221.967672) (xy 345.85 -222.007016) (xy 345.814507 -222.041108) (xy 345.774004 -222.069064)
			(xy 345.729542 -222.090162) (xy 345.682271 -222.103854) (xy 345.633416 -222.109786) (xy 345.584241 -222.107805)
			(xy 345.536022 -222.097961) (xy 345.490006 -222.080509) (xy 345.447385 -222.055902) (xy 345.409264 -222.024777)
			(xy 345.376629 -221.98794) (xy 345.350326 -221.946344) (xy 345.331035 -221.901068) (xy 345.319258 -221.853284)
			(xy 345.315298 -221.80423) (xy 339.96122 -221.80423) (xy 339.96122 -222.614236) (xy 340.145382 -222.614236)
			(xy 340.149342 -222.565182) (xy 340.161119 -222.517398) (xy 340.18041 -222.472122) (xy 340.206713 -222.430526)
			(xy 340.239348 -222.393689) (xy 340.277469 -222.362564) (xy 340.32009 -222.337957) (xy 340.366106 -222.320505)
			(xy 340.414325 -222.310661) (xy 340.4635 -222.30868) (xy 340.512355 -222.314612) (xy 340.559626 -222.328304)
			(xy 340.604088 -222.349402) (xy 340.644591 -222.377358) (xy 340.680084 -222.41145) (xy 340.709649 -222.450794)
			(xy 340.73252 -222.494371) (xy 340.748104 -222.541052) (xy 340.755999 -222.589629) (xy 340.756494 -222.614236)
			(xy 342.96529 -222.614236) (xy 342.96925 -222.565182) (xy 342.981027 -222.517398) (xy 343.000318 -222.472122)
			(xy 343.026621 -222.430526) (xy 343.059256 -222.393689) (xy 343.097377 -222.362564) (xy 343.139998 -222.337957)
			(xy 343.186014 -222.320505) (xy 343.234233 -222.310661) (xy 343.283408 -222.30868) (xy 343.332263 -222.314612)
			(xy 343.379534 -222.328304) (xy 343.423996 -222.349402) (xy 343.464499 -222.377358) (xy 343.499992 -222.41145)
			(xy 343.529557 -222.450794) (xy 343.552428 -222.494371) (xy 343.568012 -222.541052) (xy 343.575907 -222.589629)
			(xy 343.576402 -222.614236) (xy 345.785198 -222.614236) (xy 345.789158 -222.565182) (xy 345.800935 -222.517398)
			(xy 345.820226 -222.472122) (xy 345.846529 -222.430526) (xy 345.879164 -222.393689) (xy 345.917285 -222.362564)
			(xy 345.959906 -222.337957) (xy 346.005922 -222.320505) (xy 346.054141 -222.310661) (xy 346.103316 -222.30868)
			(xy 346.152171 -222.314612) (xy 346.199442 -222.328304) (xy 346.243904 -222.349402) (xy 346.284407 -222.377358)
			(xy 346.3199 -222.41145) (xy 346.349465 -222.450794) (xy 346.372336 -222.494371) (xy 346.38792 -222.541052)
			(xy 346.395815 -222.589629) (xy 346.39631 -222.614236) (xy 348.60536 -222.614236) (xy 348.60932 -222.565182)
			(xy 348.621097 -222.517398) (xy 348.640388 -222.472122) (xy 348.666691 -222.430526) (xy 348.699326 -222.393689)
			(xy 348.737447 -222.362564) (xy 348.780068 -222.337957) (xy 348.826084 -222.320505) (xy 348.874303 -222.310661)
			(xy 348.923478 -222.30868) (xy 348.972333 -222.314612) (xy 349.019604 -222.328304) (xy 349.064066 -222.349402)
			(xy 349.104569 -222.377358) (xy 349.140062 -222.41145) (xy 349.169627 -222.450794) (xy 349.192498 -222.494371)
			(xy 349.208082 -222.541052) (xy 349.215977 -222.589629) (xy 349.216472 -222.614236) (xy 351.425268 -222.614236)
			(xy 351.429228 -222.565182) (xy 351.441005 -222.517398) (xy 351.460296 -222.472122) (xy 351.486599 -222.430526)
			(xy 351.519234 -222.393689) (xy 351.557355 -222.362564) (xy 351.599976 -222.337957) (xy 351.645992 -222.320505)
			(xy 351.694211 -222.310661) (xy 351.743386 -222.30868) (xy 351.792241 -222.314612) (xy 351.839512 -222.328304)
			(xy 351.883974 -222.349402) (xy 351.924477 -222.377358) (xy 351.95997 -222.41145) (xy 351.989535 -222.450794)
			(xy 352.012406 -222.494371) (xy 352.02799 -222.541052) (xy 352.035885 -222.589629) (xy 352.03638 -222.614236)
			(xy 352.035885 -222.638843) (xy 352.02799 -222.68742) (xy 352.012406 -222.734101) (xy 351.989535 -222.777678)
			(xy 351.95997 -222.817022) (xy 351.924477 -222.851114) (xy 351.883974 -222.87907) (xy 351.839512 -222.900168)
			(xy 351.792241 -222.91386) (xy 351.743386 -222.919792) (xy 351.694211 -222.917811) (xy 351.645992 -222.907967)
			(xy 351.599976 -222.890515) (xy 351.557355 -222.865908) (xy 351.519234 -222.834783) (xy 351.486599 -222.797946)
			(xy 351.460296 -222.75635) (xy 351.441005 -222.711074) (xy 351.429228 -222.66329) (xy 351.425268 -222.614236)
			(xy 349.216472 -222.614236) (xy 349.215977 -222.638843) (xy 349.208082 -222.68742) (xy 349.192498 -222.734101)
			(xy 349.169627 -222.777678) (xy 349.140062 -222.817022) (xy 349.104569 -222.851114) (xy 349.064066 -222.87907)
			(xy 349.019604 -222.900168) (xy 348.972333 -222.91386) (xy 348.923478 -222.919792) (xy 348.874303 -222.917811)
			(xy 348.826084 -222.907967) (xy 348.780068 -222.890515) (xy 348.737447 -222.865908) (xy 348.699326 -222.834783)
			(xy 348.666691 -222.797946) (xy 348.640388 -222.75635) (xy 348.621097 -222.711074) (xy 348.60932 -222.66329)
			(xy 348.60536 -222.614236) (xy 346.39631 -222.614236) (xy 346.395815 -222.638843) (xy 346.38792 -222.68742)
			(xy 346.372336 -222.734101) (xy 346.349465 -222.777678) (xy 346.3199 -222.817022) (xy 346.284407 -222.851114)
			(xy 346.243904 -222.87907) (xy 346.199442 -222.900168) (xy 346.152171 -222.91386) (xy 346.103316 -222.919792)
			(xy 346.054141 -222.917811) (xy 346.005922 -222.907967) (xy 345.959906 -222.890515) (xy 345.917285 -222.865908)
			(xy 345.879164 -222.834783) (xy 345.846529 -222.797946) (xy 345.820226 -222.75635) (xy 345.800935 -222.711074)
			(xy 345.789158 -222.66329) (xy 345.785198 -222.614236) (xy 343.576402 -222.614236) (xy 343.575907 -222.638843)
			(xy 343.568012 -222.68742) (xy 343.552428 -222.734101) (xy 343.529557 -222.777678) (xy 343.499992 -222.817022)
			(xy 343.464499 -222.851114) (xy 343.423996 -222.87907) (xy 343.379534 -222.900168) (xy 343.332263 -222.91386)
			(xy 343.283408 -222.919792) (xy 343.234233 -222.917811) (xy 343.186014 -222.907967) (xy 343.139998 -222.890515)
			(xy 343.097377 -222.865908) (xy 343.059256 -222.834783) (xy 343.026621 -222.797946) (xy 343.000318 -222.75635)
			(xy 342.981027 -222.711074) (xy 342.96925 -222.66329) (xy 342.96529 -222.614236) (xy 340.756494 -222.614236)
			(xy 340.755999 -222.638843) (xy 340.748104 -222.68742) (xy 340.73252 -222.734101) (xy 340.709649 -222.777678)
			(xy 340.680084 -222.817022) (xy 340.644591 -222.851114) (xy 340.604088 -222.87907) (xy 340.559626 -222.900168)
			(xy 340.512355 -222.91386) (xy 340.4635 -222.919792) (xy 340.414325 -222.917811) (xy 340.366106 -222.907967)
			(xy 340.32009 -222.890515) (xy 340.277469 -222.865908) (xy 340.239348 -222.834783) (xy 340.206713 -222.797946)
			(xy 340.18041 -222.75635) (xy 340.161119 -222.711074) (xy 340.149342 -222.66329) (xy 340.145382 -222.614236)
			(xy 339.96122 -222.614236) (xy 339.96122 -223.424242) (xy 341.555336 -223.424242) (xy 341.559296 -223.375188)
			(xy 341.571073 -223.327404) (xy 341.590364 -223.282128) (xy 341.616667 -223.240532) (xy 341.649302 -223.203695)
			(xy 341.687423 -223.17257) (xy 341.730044 -223.147963) (xy 341.77606 -223.130511) (xy 341.824279 -223.120667)
			(xy 341.873454 -223.118686) (xy 341.922309 -223.124618) (xy 341.96958 -223.13831) (xy 342.014042 -223.159408)
			(xy 342.054545 -223.187364) (xy 342.090038 -223.221456) (xy 342.119603 -223.2608) (xy 342.142474 -223.304377)
			(xy 342.158058 -223.351058) (xy 342.165953 -223.399635) (xy 342.166448 -223.424242) (xy 342.49539 -223.424242)
			(xy 342.49935 -223.375188) (xy 342.511127 -223.327404) (xy 342.530418 -223.282128) (xy 342.556721 -223.240532)
			(xy 342.589356 -223.203695) (xy 342.627477 -223.17257) (xy 342.670098 -223.147963) (xy 342.716114 -223.130511)
			(xy 342.764333 -223.120667) (xy 342.813508 -223.118686) (xy 342.862363 -223.124618) (xy 342.909634 -223.13831)
			(xy 342.954096 -223.159408) (xy 342.994599 -223.187364) (xy 343.030092 -223.221456) (xy 343.059657 -223.2608)
			(xy 343.082528 -223.304377) (xy 343.098112 -223.351058) (xy 343.106007 -223.399635) (xy 343.106502 -223.424242)
			(xy 343.43519 -223.424242) (xy 343.43915 -223.375188) (xy 343.450927 -223.327404) (xy 343.470218 -223.282128)
			(xy 343.496521 -223.240532) (xy 343.529156 -223.203695) (xy 343.567277 -223.17257) (xy 343.609898 -223.147963)
			(xy 343.655914 -223.130511) (xy 343.704133 -223.120667) (xy 343.753308 -223.118686) (xy 343.802163 -223.124618)
			(xy 343.849434 -223.13831) (xy 343.893896 -223.159408) (xy 343.934399 -223.187364) (xy 343.969892 -223.221456)
			(xy 343.999457 -223.2608) (xy 344.022328 -223.304377) (xy 344.037912 -223.351058) (xy 344.045807 -223.399635)
			(xy 344.046302 -223.424242) (xy 346.255352 -223.424242) (xy 346.259312 -223.375188) (xy 346.271089 -223.327404)
			(xy 346.29038 -223.282128) (xy 346.316683 -223.240532) (xy 346.349318 -223.203695) (xy 346.387439 -223.17257)
			(xy 346.43006 -223.147963) (xy 346.476076 -223.130511) (xy 346.524295 -223.120667) (xy 346.57347 -223.118686)
			(xy 346.622325 -223.124618) (xy 346.669596 -223.13831) (xy 346.714058 -223.159408) (xy 346.754561 -223.187364)
			(xy 346.790054 -223.221456) (xy 346.819619 -223.2608) (xy 346.84249 -223.304377) (xy 346.858074 -223.351058)
			(xy 346.865969 -223.399635) (xy 346.866464 -223.424242) (xy 347.195406 -223.424242) (xy 347.199366 -223.375188)
			(xy 347.211143 -223.327404) (xy 347.230434 -223.282128) (xy 347.256737 -223.240532) (xy 347.289372 -223.203695)
			(xy 347.327493 -223.17257) (xy 347.370114 -223.147963) (xy 347.41613 -223.130511) (xy 347.464349 -223.120667)
			(xy 347.513524 -223.118686) (xy 347.562379 -223.124618) (xy 347.60965 -223.13831) (xy 347.654112 -223.159408)
			(xy 347.694615 -223.187364) (xy 347.730108 -223.221456) (xy 347.759673 -223.2608) (xy 347.782544 -223.304377)
			(xy 347.798128 -223.351058) (xy 347.806023 -223.399635) (xy 347.806518 -223.424242) (xy 348.135206 -223.424242)
			(xy 348.139166 -223.375188) (xy 348.150943 -223.327404) (xy 348.170234 -223.282128) (xy 348.196537 -223.240532)
			(xy 348.229172 -223.203695) (xy 348.267293 -223.17257) (xy 348.309914 -223.147963) (xy 348.35593 -223.130511)
			(xy 348.404149 -223.120667) (xy 348.453324 -223.118686) (xy 348.502179 -223.124618) (xy 348.54945 -223.13831)
			(xy 348.593912 -223.159408) (xy 348.634415 -223.187364) (xy 348.669908 -223.221456) (xy 348.699473 -223.2608)
			(xy 348.722344 -223.304377) (xy 348.737928 -223.351058) (xy 348.745823 -223.399635) (xy 348.746318 -223.424242)
			(xy 349.07526 -223.424242) (xy 349.07922 -223.375188) (xy 349.090997 -223.327404) (xy 349.110288 -223.282128)
			(xy 349.136591 -223.240532) (xy 349.169226 -223.203695) (xy 349.207347 -223.17257) (xy 349.249968 -223.147963)
			(xy 349.295984 -223.130511) (xy 349.344203 -223.120667) (xy 349.393378 -223.118686) (xy 349.442233 -223.124618)
			(xy 349.489504 -223.13831) (xy 349.533966 -223.159408) (xy 349.574469 -223.187364) (xy 349.609962 -223.221456)
			(xy 349.639527 -223.2608) (xy 349.662398 -223.304377) (xy 349.677982 -223.351058) (xy 349.685877 -223.399635)
			(xy 349.686372 -223.424242) (xy 351.895422 -223.424242) (xy 351.899382 -223.375188) (xy 351.911159 -223.327404)
			(xy 351.93045 -223.282128) (xy 351.956753 -223.240532) (xy 351.989388 -223.203695) (xy 352.027509 -223.17257)
			(xy 352.07013 -223.147963) (xy 352.116146 -223.130511) (xy 352.164365 -223.120667) (xy 352.21354 -223.118686)
			(xy 352.262395 -223.124618) (xy 352.309666 -223.13831) (xy 352.354128 -223.159408) (xy 352.394631 -223.187364)
			(xy 352.430124 -223.221456) (xy 352.459689 -223.2608) (xy 352.48256 -223.304377) (xy 352.498144 -223.351058)
			(xy 352.506039 -223.399635) (xy 352.506534 -223.424242) (xy 352.835476 -223.424242) (xy 352.839436 -223.375188)
			(xy 352.851213 -223.327404) (xy 352.870504 -223.282128) (xy 352.896807 -223.240532) (xy 352.929442 -223.203695)
			(xy 352.967563 -223.17257) (xy 353.010184 -223.147963) (xy 353.0562 -223.130511) (xy 353.104419 -223.120667)
			(xy 353.153594 -223.118686) (xy 353.202449 -223.124618) (xy 353.24972 -223.13831) (xy 353.294182 -223.159408)
			(xy 353.334685 -223.187364) (xy 353.370178 -223.221456) (xy 353.399743 -223.2608) (xy 353.422614 -223.304377)
			(xy 353.438198 -223.351058) (xy 353.446093 -223.399635) (xy 353.446588 -223.424242) (xy 353.446093 -223.448849)
			(xy 353.438198 -223.497426) (xy 353.422614 -223.544107) (xy 353.399743 -223.587684) (xy 353.370178 -223.627028)
			(xy 353.334685 -223.66112) (xy 353.294182 -223.689076) (xy 353.24972 -223.710174) (xy 353.202449 -223.723866)
			(xy 353.153594 -223.729798) (xy 353.104419 -223.727817) (xy 353.0562 -223.717973) (xy 353.010184 -223.700521)
			(xy 352.967563 -223.675914) (xy 352.929442 -223.644789) (xy 352.896807 -223.607952) (xy 352.870504 -223.566356)
			(xy 352.851213 -223.52108) (xy 352.839436 -223.473296) (xy 352.835476 -223.424242) (xy 352.506534 -223.424242)
			(xy 352.506039 -223.448849) (xy 352.498144 -223.497426) (xy 352.48256 -223.544107) (xy 352.459689 -223.587684)
			(xy 352.430124 -223.627028) (xy 352.394631 -223.66112) (xy 352.354128 -223.689076) (xy 352.309666 -223.710174)
			(xy 352.262395 -223.723866) (xy 352.21354 -223.729798) (xy 352.164365 -223.727817) (xy 352.116146 -223.717973)
			(xy 352.07013 -223.700521) (xy 352.027509 -223.675914) (xy 351.989388 -223.644789) (xy 351.956753 -223.607952)
			(xy 351.93045 -223.566356) (xy 351.911159 -223.52108) (xy 351.899382 -223.473296) (xy 351.895422 -223.424242)
			(xy 349.686372 -223.424242) (xy 349.685877 -223.448849) (xy 349.677982 -223.497426) (xy 349.662398 -223.544107)
			(xy 349.639527 -223.587684) (xy 349.609962 -223.627028) (xy 349.574469 -223.66112) (xy 349.533966 -223.689076)
			(xy 349.489504 -223.710174) (xy 349.442233 -223.723866) (xy 349.393378 -223.729798) (xy 349.344203 -223.727817)
			(xy 349.295984 -223.717973) (xy 349.249968 -223.700521) (xy 349.207347 -223.675914) (xy 349.169226 -223.644789)
			(xy 349.136591 -223.607952) (xy 349.110288 -223.566356) (xy 349.090997 -223.52108) (xy 349.07922 -223.473296)
			(xy 349.07526 -223.424242) (xy 348.746318 -223.424242) (xy 348.745823 -223.448849) (xy 348.737928 -223.497426)
			(xy 348.722344 -223.544107) (xy 348.699473 -223.587684) (xy 348.669908 -223.627028) (xy 348.634415 -223.66112)
			(xy 348.593912 -223.689076) (xy 348.54945 -223.710174) (xy 348.502179 -223.723866) (xy 348.453324 -223.729798)
			(xy 348.404149 -223.727817) (xy 348.35593 -223.717973) (xy 348.309914 -223.700521) (xy 348.267293 -223.675914)
			(xy 348.229172 -223.644789) (xy 348.196537 -223.607952) (xy 348.170234 -223.566356) (xy 348.150943 -223.52108)
			(xy 348.139166 -223.473296) (xy 348.135206 -223.424242) (xy 347.806518 -223.424242) (xy 347.806023 -223.448849)
			(xy 347.798128 -223.497426) (xy 347.782544 -223.544107) (xy 347.759673 -223.587684) (xy 347.730108 -223.627028)
			(xy 347.694615 -223.66112) (xy 347.654112 -223.689076) (xy 347.60965 -223.710174) (xy 347.562379 -223.723866)
			(xy 347.513524 -223.729798) (xy 347.464349 -223.727817) (xy 347.41613 -223.717973) (xy 347.370114 -223.700521)
			(xy 347.327493 -223.675914) (xy 347.289372 -223.644789) (xy 347.256737 -223.607952) (xy 347.230434 -223.566356)
			(xy 347.211143 -223.52108) (xy 347.199366 -223.473296) (xy 347.195406 -223.424242) (xy 346.866464 -223.424242)
			(xy 346.865969 -223.448849) (xy 346.858074 -223.497426) (xy 346.84249 -223.544107) (xy 346.819619 -223.587684)
			(xy 346.790054 -223.627028) (xy 346.754561 -223.66112) (xy 346.714058 -223.689076) (xy 346.669596 -223.710174)
			(xy 346.622325 -223.723866) (xy 346.57347 -223.729798) (xy 346.524295 -223.727817) (xy 346.476076 -223.717973)
			(xy 346.43006 -223.700521) (xy 346.387439 -223.675914) (xy 346.349318 -223.644789) (xy 346.316683 -223.607952)
			(xy 346.29038 -223.566356) (xy 346.271089 -223.52108) (xy 346.259312 -223.473296) (xy 346.255352 -223.424242)
			(xy 344.046302 -223.424242) (xy 344.045807 -223.448849) (xy 344.037912 -223.497426) (xy 344.022328 -223.544107)
			(xy 343.999457 -223.587684) (xy 343.969892 -223.627028) (xy 343.934399 -223.66112) (xy 343.893896 -223.689076)
			(xy 343.849434 -223.710174) (xy 343.802163 -223.723866) (xy 343.753308 -223.729798) (xy 343.704133 -223.727817)
			(xy 343.655914 -223.717973) (xy 343.609898 -223.700521) (xy 343.567277 -223.675914) (xy 343.529156 -223.644789)
			(xy 343.496521 -223.607952) (xy 343.470218 -223.566356) (xy 343.450927 -223.52108) (xy 343.43915 -223.473296)
			(xy 343.43519 -223.424242) (xy 343.106502 -223.424242) (xy 343.106007 -223.448849) (xy 343.098112 -223.497426)
			(xy 343.082528 -223.544107) (xy 343.059657 -223.587684) (xy 343.030092 -223.627028) (xy 342.994599 -223.66112)
			(xy 342.954096 -223.689076) (xy 342.909634 -223.710174) (xy 342.862363 -223.723866) (xy 342.813508 -223.729798)
			(xy 342.764333 -223.727817) (xy 342.716114 -223.717973) (xy 342.670098 -223.700521) (xy 342.627477 -223.675914)
			(xy 342.589356 -223.644789) (xy 342.556721 -223.607952) (xy 342.530418 -223.566356) (xy 342.511127 -223.52108)
			(xy 342.49935 -223.473296) (xy 342.49539 -223.424242) (xy 342.166448 -223.424242) (xy 342.165953 -223.448849)
			(xy 342.158058 -223.497426) (xy 342.142474 -223.544107) (xy 342.119603 -223.587684) (xy 342.090038 -223.627028)
			(xy 342.054545 -223.66112) (xy 342.014042 -223.689076) (xy 341.96958 -223.710174) (xy 341.922309 -223.723866)
			(xy 341.873454 -223.729798) (xy 341.824279 -223.727817) (xy 341.77606 -223.717973) (xy 341.730044 -223.700521)
			(xy 341.687423 -223.675914) (xy 341.649302 -223.644789) (xy 341.616667 -223.607952) (xy 341.590364 -223.566356)
			(xy 341.571073 -223.52108) (xy 341.559296 -223.473296) (xy 341.555336 -223.424242) (xy 339.96122 -223.424242)
			(xy 339.96122 -224.234248) (xy 341.085182 -224.234248) (xy 341.089142 -224.185194) (xy 341.100919 -224.13741)
			(xy 341.12021 -224.092134) (xy 341.146513 -224.050538) (xy 341.179148 -224.013701) (xy 341.217269 -223.982576)
			(xy 341.25989 -223.957969) (xy 341.305906 -223.940517) (xy 341.354125 -223.930673) (xy 341.4033 -223.928692)
			(xy 341.452155 -223.934624) (xy 341.499426 -223.948316) (xy 341.543888 -223.969414) (xy 341.584391 -223.99737)
			(xy 341.619884 -224.031462) (xy 341.649449 -224.070806) (xy 341.67232 -224.114383) (xy 341.687904 -224.161064)
			(xy 341.695799 -224.209641) (xy 341.696294 -224.234248) (xy 343.905344 -224.234248) (xy 343.909304 -224.185194)
			(xy 343.921081 -224.13741) (xy 343.940372 -224.092134) (xy 343.966675 -224.050538) (xy 343.99931 -224.013701)
			(xy 344.037431 -223.982576) (xy 344.080052 -223.957969) (xy 344.126068 -223.940517) (xy 344.174287 -223.930673)
			(xy 344.223462 -223.928692) (xy 344.272317 -223.934624) (xy 344.319588 -223.948316) (xy 344.36405 -223.969414)
			(xy 344.404553 -223.99737) (xy 344.440046 -224.031462) (xy 344.469611 -224.070806) (xy 344.492482 -224.114383)
			(xy 344.508066 -224.161064) (xy 344.515961 -224.209641) (xy 344.516456 -224.234248) (xy 344.845398 -224.234248)
			(xy 344.849358 -224.185194) (xy 344.861135 -224.13741) (xy 344.880426 -224.092134) (xy 344.906729 -224.050538)
			(xy 344.939364 -224.013701) (xy 344.977485 -223.982576) (xy 345.020106 -223.957969) (xy 345.066122 -223.940517)
			(xy 345.114341 -223.930673) (xy 345.163516 -223.928692) (xy 345.212371 -223.934624) (xy 345.259642 -223.948316)
			(xy 345.304104 -223.969414) (xy 345.344607 -223.99737) (xy 345.3801 -224.031462) (xy 345.409665 -224.070806)
			(xy 345.432536 -224.114383) (xy 345.44812 -224.161064) (xy 345.456015 -224.209641) (xy 345.45651 -224.234248)
			(xy 345.785198 -224.234248) (xy 345.789158 -224.185194) (xy 345.800935 -224.13741) (xy 345.820226 -224.092134)
			(xy 345.846529 -224.050538) (xy 345.879164 -224.013701) (xy 345.917285 -223.982576) (xy 345.959906 -223.957969)
			(xy 346.005922 -223.940517) (xy 346.054141 -223.930673) (xy 346.103316 -223.928692) (xy 346.152171 -223.934624)
			(xy 346.199442 -223.948316) (xy 346.243904 -223.969414) (xy 346.284407 -223.99737) (xy 346.3199 -224.031462)
			(xy 346.349465 -224.070806) (xy 346.372336 -224.114383) (xy 346.38792 -224.161064) (xy 346.395815 -224.209641)
			(xy 346.39631 -224.234248) (xy 346.725252 -224.234248) (xy 346.729212 -224.185194) (xy 346.740989 -224.13741)
			(xy 346.76028 -224.092134) (xy 346.786583 -224.050538) (xy 346.819218 -224.013701) (xy 346.857339 -223.982576)
			(xy 346.89996 -223.957969) (xy 346.945976 -223.940517) (xy 346.994195 -223.930673) (xy 347.04337 -223.928692)
			(xy 347.092225 -223.934624) (xy 347.139496 -223.948316) (xy 347.183958 -223.969414) (xy 347.224461 -223.99737)
			(xy 347.259954 -224.031462) (xy 347.289519 -224.070806) (xy 347.31239 -224.114383) (xy 347.327974 -224.161064)
			(xy 347.335869 -224.209641) (xy 347.336364 -224.234248) (xy 347.665306 -224.234248) (xy 347.669266 -224.185194)
			(xy 347.681043 -224.13741) (xy 347.700334 -224.092134) (xy 347.726637 -224.050538) (xy 347.759272 -224.013701)
			(xy 347.797393 -223.982576) (xy 347.840014 -223.957969) (xy 347.88603 -223.940517) (xy 347.934249 -223.930673)
			(xy 347.983424 -223.928692) (xy 348.032279 -223.934624) (xy 348.07955 -223.948316) (xy 348.124012 -223.969414)
			(xy 348.164515 -223.99737) (xy 348.200008 -224.031462) (xy 348.229573 -224.070806) (xy 348.252444 -224.114383)
			(xy 348.268028 -224.161064) (xy 348.275923 -224.209641) (xy 348.276418 -224.234248) (xy 348.60536 -224.234248)
			(xy 348.60932 -224.185194) (xy 348.621097 -224.13741) (xy 348.640388 -224.092134) (xy 348.666691 -224.050538)
			(xy 348.699326 -224.013701) (xy 348.737447 -223.982576) (xy 348.780068 -223.957969) (xy 348.826084 -223.940517)
			(xy 348.874303 -223.930673) (xy 348.923478 -223.928692) (xy 348.972333 -223.934624) (xy 349.019604 -223.948316)
			(xy 349.064066 -223.969414) (xy 349.104569 -223.99737) (xy 349.140062 -224.031462) (xy 349.169627 -224.070806)
			(xy 349.192498 -224.114383) (xy 349.208082 -224.161064) (xy 349.215977 -224.209641) (xy 349.216472 -224.234248)
			(xy 349.545414 -224.234248) (xy 349.549374 -224.185194) (xy 349.561151 -224.13741) (xy 349.580442 -224.092134)
			(xy 349.606745 -224.050538) (xy 349.63938 -224.013701) (xy 349.677501 -223.982576) (xy 349.720122 -223.957969)
			(xy 349.766138 -223.940517) (xy 349.814357 -223.930673) (xy 349.863532 -223.928692) (xy 349.912387 -223.934624)
			(xy 349.959658 -223.948316) (xy 350.00412 -223.969414) (xy 350.044623 -223.99737) (xy 350.080116 -224.031462)
			(xy 350.109681 -224.070806) (xy 350.132552 -224.114383) (xy 350.148136 -224.161064) (xy 350.156031 -224.209641)
			(xy 350.156526 -224.234248) (xy 350.485214 -224.234248) (xy 350.489174 -224.185194) (xy 350.500951 -224.13741)
			(xy 350.520242 -224.092134) (xy 350.546545 -224.050538) (xy 350.57918 -224.013701) (xy 350.617301 -223.982576)
			(xy 350.659922 -223.957969) (xy 350.705938 -223.940517) (xy 350.754157 -223.930673) (xy 350.803332 -223.928692)
			(xy 350.852187 -223.934624) (xy 350.899458 -223.948316) (xy 350.94392 -223.969414) (xy 350.984423 -223.99737)
			(xy 351.019916 -224.031462) (xy 351.049481 -224.070806) (xy 351.072352 -224.114383) (xy 351.087936 -224.161064)
			(xy 351.095831 -224.209641) (xy 351.096326 -224.234248) (xy 351.425268 -224.234248) (xy 351.429228 -224.185194)
			(xy 351.441005 -224.13741) (xy 351.460296 -224.092134) (xy 351.486599 -224.050538) (xy 351.519234 -224.013701)
			(xy 351.557355 -223.982576) (xy 351.599976 -223.957969) (xy 351.645992 -223.940517) (xy 351.694211 -223.930673)
			(xy 351.743386 -223.928692) (xy 351.792241 -223.934624) (xy 351.839512 -223.948316) (xy 351.883974 -223.969414)
			(xy 351.924477 -223.99737) (xy 351.95997 -224.031462) (xy 351.989535 -224.070806) (xy 352.012406 -224.114383)
			(xy 352.02799 -224.161064) (xy 352.035885 -224.209641) (xy 352.03638 -224.234248) (xy 352.365322 -224.234248)
			(xy 352.369282 -224.185194) (xy 352.381059 -224.13741) (xy 352.40035 -224.092134) (xy 352.426653 -224.050538)
			(xy 352.459288 -224.013701) (xy 352.497409 -223.982576) (xy 352.54003 -223.957969) (xy 352.586046 -223.940517)
			(xy 352.634265 -223.930673) (xy 352.68344 -223.928692) (xy 352.732295 -223.934624) (xy 352.779566 -223.948316)
			(xy 352.824028 -223.969414) (xy 352.864531 -223.99737) (xy 352.900024 -224.031462) (xy 352.929589 -224.070806)
			(xy 352.95246 -224.114383) (xy 352.968044 -224.161064) (xy 352.975939 -224.209641) (xy 352.976434 -224.234248)
			(xy 352.975939 -224.258855) (xy 352.968044 -224.307432) (xy 352.95246 -224.354113) (xy 352.929589 -224.39769)
			(xy 352.900024 -224.437034) (xy 352.864531 -224.471126) (xy 352.824028 -224.499082) (xy 352.779566 -224.52018)
			(xy 352.732295 -224.533872) (xy 352.68344 -224.539804) (xy 352.634265 -224.537823) (xy 352.586046 -224.527979)
			(xy 352.54003 -224.510527) (xy 352.497409 -224.48592) (xy 352.459288 -224.454795) (xy 352.426653 -224.417958)
			(xy 352.40035 -224.376362) (xy 352.381059 -224.331086) (xy 352.369282 -224.283302) (xy 352.365322 -224.234248)
			(xy 352.03638 -224.234248) (xy 352.035885 -224.258855) (xy 352.02799 -224.307432) (xy 352.012406 -224.354113)
			(xy 351.989535 -224.39769) (xy 351.95997 -224.437034) (xy 351.924477 -224.471126) (xy 351.883974 -224.499082)
			(xy 351.839512 -224.52018) (xy 351.792241 -224.533872) (xy 351.743386 -224.539804) (xy 351.694211 -224.537823)
			(xy 351.645992 -224.527979) (xy 351.599976 -224.510527) (xy 351.557355 -224.48592) (xy 351.519234 -224.454795)
			(xy 351.486599 -224.417958) (xy 351.460296 -224.376362) (xy 351.441005 -224.331086) (xy 351.429228 -224.283302)
			(xy 351.425268 -224.234248) (xy 351.096326 -224.234248) (xy 351.095831 -224.258855) (xy 351.087936 -224.307432)
			(xy 351.072352 -224.354113) (xy 351.049481 -224.39769) (xy 351.019916 -224.437034) (xy 350.984423 -224.471126)
			(xy 350.94392 -224.499082) (xy 350.899458 -224.52018) (xy 350.852187 -224.533872) (xy 350.803332 -224.539804)
			(xy 350.754157 -224.537823) (xy 350.705938 -224.527979) (xy 350.659922 -224.510527) (xy 350.617301 -224.48592)
			(xy 350.57918 -224.454795) (xy 350.546545 -224.417958) (xy 350.520242 -224.376362) (xy 350.500951 -224.331086)
			(xy 350.489174 -224.283302) (xy 350.485214 -224.234248) (xy 350.156526 -224.234248) (xy 350.156031 -224.258855)
			(xy 350.148136 -224.307432) (xy 350.132552 -224.354113) (xy 350.109681 -224.39769) (xy 350.080116 -224.437034)
			(xy 350.044623 -224.471126) (xy 350.00412 -224.499082) (xy 349.959658 -224.52018) (xy 349.912387 -224.533872)
			(xy 349.863532 -224.539804) (xy 349.814357 -224.537823) (xy 349.766138 -224.527979) (xy 349.720122 -224.510527)
			(xy 349.677501 -224.48592) (xy 349.63938 -224.454795) (xy 349.606745 -224.417958) (xy 349.580442 -224.376362)
			(xy 349.561151 -224.331086) (xy 349.549374 -224.283302) (xy 349.545414 -224.234248) (xy 349.216472 -224.234248)
			(xy 349.215977 -224.258855) (xy 349.208082 -224.307432) (xy 349.192498 -224.354113) (xy 349.169627 -224.39769)
			(xy 349.140062 -224.437034) (xy 349.104569 -224.471126) (xy 349.064066 -224.499082) (xy 349.019604 -224.52018)
			(xy 348.972333 -224.533872) (xy 348.923478 -224.539804) (xy 348.874303 -224.537823) (xy 348.826084 -224.527979)
			(xy 348.780068 -224.510527) (xy 348.737447 -224.48592) (xy 348.699326 -224.454795) (xy 348.666691 -224.417958)
			(xy 348.640388 -224.376362) (xy 348.621097 -224.331086) (xy 348.60932 -224.283302) (xy 348.60536 -224.234248)
			(xy 348.276418 -224.234248) (xy 348.275923 -224.258855) (xy 348.268028 -224.307432) (xy 348.252444 -224.354113)
			(xy 348.229573 -224.39769) (xy 348.200008 -224.437034) (xy 348.164515 -224.471126) (xy 348.124012 -224.499082)
			(xy 348.07955 -224.52018) (xy 348.032279 -224.533872) (xy 347.983424 -224.539804) (xy 347.934249 -224.537823)
			(xy 347.88603 -224.527979) (xy 347.840014 -224.510527) (xy 347.797393 -224.48592) (xy 347.759272 -224.454795)
			(xy 347.726637 -224.417958) (xy 347.700334 -224.376362) (xy 347.681043 -224.331086) (xy 347.669266 -224.283302)
			(xy 347.665306 -224.234248) (xy 347.336364 -224.234248) (xy 347.335869 -224.258855) (xy 347.327974 -224.307432)
			(xy 347.31239 -224.354113) (xy 347.289519 -224.39769) (xy 347.259954 -224.437034) (xy 347.224461 -224.471126)
			(xy 347.183958 -224.499082) (xy 347.139496 -224.52018) (xy 347.092225 -224.533872) (xy 347.04337 -224.539804)
			(xy 346.994195 -224.537823) (xy 346.945976 -224.527979) (xy 346.89996 -224.510527) (xy 346.857339 -224.48592)
			(xy 346.819218 -224.454795) (xy 346.786583 -224.417958) (xy 346.76028 -224.376362) (xy 346.740989 -224.331086)
			(xy 346.729212 -224.283302) (xy 346.725252 -224.234248) (xy 346.39631 -224.234248) (xy 346.395815 -224.258855)
			(xy 346.38792 -224.307432) (xy 346.372336 -224.354113) (xy 346.349465 -224.39769) (xy 346.3199 -224.437034)
			(xy 346.284407 -224.471126) (xy 346.243904 -224.499082) (xy 346.199442 -224.52018) (xy 346.152171 -224.533872)
			(xy 346.103316 -224.539804) (xy 346.054141 -224.537823) (xy 346.005922 -224.527979) (xy 345.959906 -224.510527)
			(xy 345.917285 -224.48592) (xy 345.879164 -224.454795) (xy 345.846529 -224.417958) (xy 345.820226 -224.376362)
			(xy 345.800935 -224.331086) (xy 345.789158 -224.283302) (xy 345.785198 -224.234248) (xy 345.45651 -224.234248)
			(xy 345.456015 -224.258855) (xy 345.44812 -224.307432) (xy 345.432536 -224.354113) (xy 345.409665 -224.39769)
			(xy 345.3801 -224.437034) (xy 345.344607 -224.471126) (xy 345.304104 -224.499082) (xy 345.259642 -224.52018)
			(xy 345.212371 -224.533872) (xy 345.163516 -224.539804) (xy 345.114341 -224.537823) (xy 345.066122 -224.527979)
			(xy 345.020106 -224.510527) (xy 344.977485 -224.48592) (xy 344.939364 -224.454795) (xy 344.906729 -224.417958)
			(xy 344.880426 -224.376362) (xy 344.861135 -224.331086) (xy 344.849358 -224.283302) (xy 344.845398 -224.234248)
			(xy 344.516456 -224.234248) (xy 344.515961 -224.258855) (xy 344.508066 -224.307432) (xy 344.492482 -224.354113)
			(xy 344.469611 -224.39769) (xy 344.440046 -224.437034) (xy 344.404553 -224.471126) (xy 344.36405 -224.499082)
			(xy 344.319588 -224.52018) (xy 344.272317 -224.533872) (xy 344.223462 -224.539804) (xy 344.174287 -224.537823)
			(xy 344.126068 -224.527979) (xy 344.080052 -224.510527) (xy 344.037431 -224.48592) (xy 343.99931 -224.454795)
			(xy 343.966675 -224.417958) (xy 343.940372 -224.376362) (xy 343.921081 -224.331086) (xy 343.909304 -224.283302)
			(xy 343.905344 -224.234248) (xy 341.696294 -224.234248) (xy 341.695799 -224.258855) (xy 341.687904 -224.307432)
			(xy 341.67232 -224.354113) (xy 341.649449 -224.39769) (xy 341.619884 -224.437034) (xy 341.584391 -224.471126)
			(xy 341.543888 -224.499082) (xy 341.499426 -224.52018) (xy 341.452155 -224.533872) (xy 341.4033 -224.539804)
			(xy 341.354125 -224.537823) (xy 341.305906 -224.527979) (xy 341.25989 -224.510527) (xy 341.217269 -224.48592)
			(xy 341.179148 -224.454795) (xy 341.146513 -224.417958) (xy 341.12021 -224.376362) (xy 341.100919 -224.331086)
			(xy 341.089142 -224.283302) (xy 341.085182 -224.234248) (xy 339.96122 -224.234248) (xy 339.96122 -224.669604)
			(xy 339.961658 -224.679026) (xy 339.968433 -224.696612) (xy 339.974428 -224.703894) (xy 340.000336 -224.732596)
			(xy 340.016084 -224.740724) (xy 340.02472 -224.741994) (xy 340.048636 -224.745922) (xy 340.094904 -224.760346)
			(xy 340.138314 -224.781895) (xy 340.177776 -224.810028) (xy 340.212301 -224.84404) (xy 340.241022 -224.883076)
			(xy 340.263218 -224.926159) (xy 340.278333 -224.972206) (xy 340.285986 -225.020061) (xy 340.285986 -225.044254)
			(xy 340.615282 -225.044254) (xy 340.619242 -224.9952) (xy 340.631019 -224.947416) (xy 340.65031 -224.90214)
			(xy 340.676613 -224.860544) (xy 340.709248 -224.823707) (xy 340.747369 -224.792582) (xy 340.78999 -224.767975)
			(xy 340.836006 -224.750523) (xy 340.884225 -224.740679) (xy 340.9334 -224.738698) (xy 340.982255 -224.74463)
			(xy 341.029526 -224.758322) (xy 341.073988 -224.77942) (xy 341.114491 -224.807376) (xy 341.149984 -224.841468)
			(xy 341.179549 -224.880812) (xy 341.20242 -224.924389) (xy 341.218004 -224.97107) (xy 341.225899 -225.019647)
			(xy 341.226394 -225.044254) (xy 341.544905 -225.044254) (xy 341.549 -224.993526) (xy 341.561179 -224.944112)
			(xy 341.581127 -224.897292) (xy 341.608328 -224.854278) (xy 341.642076 -224.816184) (xy 341.681498 -224.783997)
			(xy 341.725572 -224.758551) (xy 341.773158 -224.740504) (xy 341.823022 -224.730324) (xy 341.873874 -224.728275)
			(xy 341.924395 -224.734409) (xy 341.973279 -224.748569) (xy 342.019258 -224.770386) (xy 342.061142 -224.799296)
			(xy 342.097846 -224.834551) (xy 342.128419 -224.875237) (xy 342.15207 -224.9203) (xy 342.168186 -224.968574)
			(xy 342.17635 -225.018808) (xy 342.176862 -225.044254) (xy 342.49539 -225.044254) (xy 342.49935 -224.9952)
			(xy 342.511127 -224.947416) (xy 342.530418 -224.90214) (xy 342.556721 -224.860544) (xy 342.589356 -224.823707)
			(xy 342.627477 -224.792582) (xy 342.670098 -224.767975) (xy 342.716114 -224.750523) (xy 342.764333 -224.740679)
			(xy 342.813508 -224.738698) (xy 342.862363 -224.74463) (xy 342.909634 -224.758322) (xy 342.954096 -224.77942)
			(xy 342.994599 -224.807376) (xy 343.030092 -224.841468) (xy 343.059657 -224.880812) (xy 343.082528 -224.924389)
			(xy 343.098112 -224.97107) (xy 343.106007 -225.019647) (xy 343.106502 -225.044254) (xy 343.43519 -225.044254)
			(xy 343.43915 -224.9952) (xy 343.450927 -224.947416) (xy 343.470218 -224.90214) (xy 343.496521 -224.860544)
			(xy 343.529156 -224.823707) (xy 343.567277 -224.792582) (xy 343.609898 -224.767975) (xy 343.655914 -224.750523)
			(xy 343.704133 -224.740679) (xy 343.753308 -224.738698) (xy 343.802163 -224.74463) (xy 343.849434 -224.758322)
			(xy 343.893896 -224.77942) (xy 343.934399 -224.807376) (xy 343.969892 -224.841468) (xy 343.999457 -224.880812)
			(xy 344.022328 -224.924389) (xy 344.037912 -224.97107) (xy 344.045807 -225.019647) (xy 344.046302 -225.044254)
			(xy 345.315298 -225.044254) (xy 345.319258 -224.9952) (xy 345.331035 -224.947416) (xy 345.350326 -224.90214)
			(xy 345.376629 -224.860544) (xy 345.409264 -224.823707) (xy 345.447385 -224.792582) (xy 345.490006 -224.767975)
			(xy 345.536022 -224.750523) (xy 345.584241 -224.740679) (xy 345.633416 -224.738698) (xy 345.682271 -224.74463)
			(xy 345.729542 -224.758322) (xy 345.774004 -224.77942) (xy 345.814507 -224.807376) (xy 345.85 -224.841468)
			(xy 345.879565 -224.880812) (xy 345.902436 -224.924389) (xy 345.91802 -224.97107) (xy 345.925915 -225.019647)
			(xy 345.92641 -225.044254) (xy 346.255352 -225.044254) (xy 346.259312 -224.9952) (xy 346.271089 -224.947416)
			(xy 346.29038 -224.90214) (xy 346.316683 -224.860544) (xy 346.349318 -224.823707) (xy 346.387439 -224.792582)
			(xy 346.43006 -224.767975) (xy 346.476076 -224.750523) (xy 346.524295 -224.740679) (xy 346.57347 -224.738698)
			(xy 346.622325 -224.74463) (xy 346.669596 -224.758322) (xy 346.714058 -224.77942) (xy 346.754561 -224.807376)
			(xy 346.790054 -224.841468) (xy 346.819619 -224.880812) (xy 346.84249 -224.924389) (xy 346.858074 -224.97107)
			(xy 346.865969 -225.019647) (xy 346.866464 -225.044254) (xy 348.135206 -225.044254) (xy 348.139166 -224.9952)
			(xy 348.150943 -224.947416) (xy 348.170234 -224.90214) (xy 348.196537 -224.860544) (xy 348.229172 -224.823707)
			(xy 348.267293 -224.792582) (xy 348.309914 -224.767975) (xy 348.35593 -224.750523) (xy 348.404149 -224.740679)
			(xy 348.453324 -224.738698) (xy 348.502179 -224.74463) (xy 348.54945 -224.758322) (xy 348.593912 -224.77942)
			(xy 348.634415 -224.807376) (xy 348.669908 -224.841468) (xy 348.699473 -224.880812) (xy 348.722344 -224.924389)
			(xy 348.737928 -224.97107) (xy 348.745823 -225.019647) (xy 348.746318 -225.044254) (xy 349.07526 -225.044254)
			(xy 349.07922 -224.9952) (xy 349.090997 -224.947416) (xy 349.110288 -224.90214) (xy 349.136591 -224.860544)
			(xy 349.169226 -224.823707) (xy 349.207347 -224.792582) (xy 349.249968 -224.767975) (xy 349.295984 -224.750523)
			(xy 349.344203 -224.740679) (xy 349.393378 -224.738698) (xy 349.442233 -224.74463) (xy 349.489504 -224.758322)
			(xy 349.533966 -224.77942) (xy 349.574469 -224.807376) (xy 349.609962 -224.841468) (xy 349.639527 -224.880812)
			(xy 349.662398 -224.924389) (xy 349.677982 -224.97107) (xy 349.685877 -225.019647) (xy 349.686372 -225.044254)
			(xy 353.77553 -225.044254) (xy 353.77949 -224.9952) (xy 353.791267 -224.947416) (xy 353.810558 -224.90214)
			(xy 353.836861 -224.860544) (xy 353.869496 -224.823707) (xy 353.907617 -224.792582) (xy 353.950238 -224.767975)
			(xy 353.996254 -224.750523) (xy 354.044473 -224.740679) (xy 354.093648 -224.738698) (xy 354.142503 -224.74463)
			(xy 354.189774 -224.758322) (xy 354.234236 -224.77942) (xy 354.274739 -224.807376) (xy 354.310232 -224.841468)
			(xy 354.339797 -224.880812) (xy 354.362668 -224.924389) (xy 354.378252 -224.97107) (xy 354.386147 -225.019647)
			(xy 354.386642 -225.044254) (xy 354.386147 -225.068861) (xy 354.378252 -225.117438) (xy 354.362668 -225.164119)
			(xy 354.339797 -225.207696) (xy 354.310232 -225.24704) (xy 354.274739 -225.281132) (xy 354.234236 -225.309088)
			(xy 354.189774 -225.330186) (xy 354.142503 -225.343878) (xy 354.093648 -225.34981) (xy 354.044473 -225.347829)
			(xy 353.996254 -225.337985) (xy 353.950238 -225.320533) (xy 353.907617 -225.295926) (xy 353.869496 -225.264801)
			(xy 353.836861 -225.227964) (xy 353.810558 -225.186368) (xy 353.791267 -225.141092) (xy 353.77949 -225.093308)
			(xy 353.77553 -225.044254) (xy 349.686372 -225.044254) (xy 349.685877 -225.068861) (xy 349.677982 -225.117438)
			(xy 349.662398 -225.164119) (xy 349.639527 -225.207696) (xy 349.609962 -225.24704) (xy 349.574469 -225.281132)
			(xy 349.533966 -225.309088) (xy 349.489504 -225.330186) (xy 349.442233 -225.343878) (xy 349.393378 -225.34981)
			(xy 349.344203 -225.347829) (xy 349.295984 -225.337985) (xy 349.249968 -225.320533) (xy 349.207347 -225.295926)
			(xy 349.169226 -225.264801) (xy 349.136591 -225.227964) (xy 349.110288 -225.186368) (xy 349.090997 -225.141092)
			(xy 349.07922 -225.093308) (xy 349.07526 -225.044254) (xy 348.746318 -225.044254) (xy 348.745823 -225.068861)
			(xy 348.737928 -225.117438) (xy 348.722344 -225.164119) (xy 348.699473 -225.207696) (xy 348.669908 -225.24704)
			(xy 348.634415 -225.281132) (xy 348.593912 -225.309088) (xy 348.54945 -225.330186) (xy 348.502179 -225.343878)
			(xy 348.453324 -225.34981) (xy 348.404149 -225.347829) (xy 348.35593 -225.337985) (xy 348.309914 -225.320533)
			(xy 348.267293 -225.295926) (xy 348.229172 -225.264801) (xy 348.196537 -225.227964) (xy 348.170234 -225.186368)
			(xy 348.150943 -225.141092) (xy 348.139166 -225.093308) (xy 348.135206 -225.044254) (xy 346.866464 -225.044254)
			(xy 346.865969 -225.068861) (xy 346.858074 -225.117438) (xy 346.84249 -225.164119) (xy 346.819619 -225.207696)
			(xy 346.790054 -225.24704) (xy 346.754561 -225.281132) (xy 346.714058 -225.309088) (xy 346.669596 -225.330186)
			(xy 346.622325 -225.343878) (xy 346.57347 -225.34981) (xy 346.524295 -225.347829) (xy 346.476076 -225.337985)
			(xy 346.43006 -225.320533) (xy 346.387439 -225.295926) (xy 346.349318 -225.264801) (xy 346.316683 -225.227964)
			(xy 346.29038 -225.186368) (xy 346.271089 -225.141092) (xy 346.259312 -225.093308) (xy 346.255352 -225.044254)
			(xy 345.92641 -225.044254) (xy 345.925915 -225.068861) (xy 345.91802 -225.117438) (xy 345.902436 -225.164119)
			(xy 345.879565 -225.207696) (xy 345.85 -225.24704) (xy 345.814507 -225.281132) (xy 345.774004 -225.309088)
			(xy 345.729542 -225.330186) (xy 345.682271 -225.343878) (xy 345.633416 -225.34981) (xy 345.584241 -225.347829)
			(xy 345.536022 -225.337985) (xy 345.490006 -225.320533) (xy 345.447385 -225.295926) (xy 345.409264 -225.264801)
			(xy 345.376629 -225.227964) (xy 345.350326 -225.186368) (xy 345.331035 -225.141092) (xy 345.319258 -225.093308)
			(xy 345.315298 -225.044254) (xy 344.046302 -225.044254) (xy 344.045807 -225.068861) (xy 344.037912 -225.117438)
			(xy 344.022328 -225.164119) (xy 343.999457 -225.207696) (xy 343.969892 -225.24704) (xy 343.934399 -225.281132)
			(xy 343.893896 -225.309088) (xy 343.849434 -225.330186) (xy 343.802163 -225.343878) (xy 343.753308 -225.34981)
			(xy 343.704133 -225.347829) (xy 343.655914 -225.337985) (xy 343.609898 -225.320533) (xy 343.567277 -225.295926)
			(xy 343.529156 -225.264801) (xy 343.496521 -225.227964) (xy 343.470218 -225.186368) (xy 343.450927 -225.141092)
			(xy 343.43915 -225.093308) (xy 343.43519 -225.044254) (xy 343.106502 -225.044254) (xy 343.106007 -225.068861)
			(xy 343.098112 -225.117438) (xy 343.082528 -225.164119) (xy 343.059657 -225.207696) (xy 343.030092 -225.24704)
			(xy 342.994599 -225.281132) (xy 342.954096 -225.309088) (xy 342.909634 -225.330186) (xy 342.862363 -225.343878)
			(xy 342.813508 -225.34981) (xy 342.764333 -225.347829) (xy 342.716114 -225.337985) (xy 342.670098 -225.320533)
			(xy 342.627477 -225.295926) (xy 342.589356 -225.264801) (xy 342.556721 -225.227964) (xy 342.530418 -225.186368)
			(xy 342.511127 -225.141092) (xy 342.49935 -225.093308) (xy 342.49539 -225.044254) (xy 342.176862 -225.044254)
			(xy 342.17635 -225.0697) (xy 342.168186 -225.119934) (xy 342.15207 -225.168208) (xy 342.128419 -225.213271)
			(xy 342.097846 -225.253957) (xy 342.061142 -225.289212) (xy 342.019258 -225.318122) (xy 341.973279 -225.339939)
			(xy 341.924395 -225.354099) (xy 341.873874 -225.360233) (xy 341.823022 -225.358184) (xy 341.773158 -225.348004)
			(xy 341.725572 -225.329957) (xy 341.681498 -225.304511) (xy 341.642076 -225.272324) (xy 341.608328 -225.23423)
			(xy 341.581127 -225.191216) (xy 341.561179 -225.144396) (xy 341.549 -225.094982) (xy 341.544905 -225.044254)
			(xy 341.226394 -225.044254) (xy 341.225899 -225.068861) (xy 341.218004 -225.117438) (xy 341.20242 -225.164119)
			(xy 341.179549 -225.207696) (xy 341.149984 -225.24704) (xy 341.114491 -225.281132) (xy 341.073988 -225.309088)
			(xy 341.029526 -225.330186) (xy 340.982255 -225.343878) (xy 340.9334 -225.34981) (xy 340.884225 -225.347829)
			(xy 340.836006 -225.337985) (xy 340.78999 -225.320533) (xy 340.747369 -225.295926) (xy 340.709248 -225.264801)
			(xy 340.676613 -225.227964) (xy 340.65031 -225.186368) (xy 340.631019 -225.141092) (xy 340.619242 -225.093308)
			(xy 340.615282 -225.044254) (xy 340.285986 -225.044254) (xy 340.285987 -225.068525) (xy 340.278336 -225.116382)
			(xy 340.263223 -225.162429) (xy 340.241028 -225.205512) (xy 340.212309 -225.24455) (xy 340.177786 -225.278564)
			(xy 340.138325 -225.306699) (xy 340.094916 -225.32825) (xy 340.048649 -225.342675) (xy 340.02472 -225.346514)
			(xy 340.016084 -225.347784) (xy 340.000336 -225.355912) (xy 339.974428 -225.384614) (xy 339.968337 -225.39184)
			(xy 339.961544 -225.40946) (xy 339.96122 -225.418904) (xy 339.96122 -225.85426) (xy 340.134951 -225.85426)
			(xy 340.139046 -225.803532) (xy 340.151225 -225.754118) (xy 340.171173 -225.707298) (xy 340.198374 -225.664284)
			(xy 340.232122 -225.62619) (xy 340.271544 -225.594003) (xy 340.315618 -225.568557) (xy 340.363204 -225.55051)
			(xy 340.413068 -225.54033) (xy 340.46392 -225.538281) (xy 340.514441 -225.544415) (xy 340.563325 -225.558575)
			(xy 340.609304 -225.580392) (xy 340.651188 -225.609302) (xy 340.687892 -225.644557) (xy 340.718465 -225.685243)
			(xy 340.742116 -225.730306) (xy 340.758232 -225.77858) (xy 340.766396 -225.828814) (xy 340.766908 -225.85426)
			(xy 341.085182 -225.85426) (xy 341.089142 -225.805206) (xy 341.100919 -225.757422) (xy 341.12021 -225.712146)
			(xy 341.146513 -225.67055) (xy 341.179148 -225.633713) (xy 341.217269 -225.602588) (xy 341.25989 -225.577981)
			(xy 341.305906 -225.560529) (xy 341.354125 -225.550685) (xy 341.4033 -225.548704) (xy 341.452155 -225.554636)
			(xy 341.499426 -225.568328) (xy 341.543888 -225.589426) (xy 341.584391 -225.617382) (xy 341.619884 -225.651474)
			(xy 341.649449 -225.690818) (xy 341.67232 -225.734395) (xy 341.687904 -225.781076) (xy 341.695799 -225.829653)
			(xy 341.696294 -225.85426) (xy 342.014805 -225.85426) (xy 342.0189 -225.803532) (xy 342.031079 -225.754118)
			(xy 342.051027 -225.707298) (xy 342.078228 -225.664284) (xy 342.111976 -225.62619) (xy 342.151398 -225.594003)
			(xy 342.195472 -225.568557) (xy 342.243058 -225.55051) (xy 342.292922 -225.54033) (xy 342.343774 -225.538281)
			(xy 342.394295 -225.544415) (xy 342.443179 -225.558575) (xy 342.489158 -225.580392) (xy 342.531042 -225.609302)
			(xy 342.567746 -225.644557) (xy 342.598319 -225.685243) (xy 342.62197 -225.730306) (xy 342.638086 -225.77858)
			(xy 342.64625 -225.828814) (xy 342.646762 -225.85426) (xy 342.954859 -225.85426) (xy 342.958954 -225.803532)
			(xy 342.971133 -225.754118) (xy 342.991081 -225.707298) (xy 343.018282 -225.664284) (xy 343.05203 -225.62619)
			(xy 343.091452 -225.594003) (xy 343.135526 -225.568557) (xy 343.183112 -225.55051) (xy 343.232976 -225.54033)
			(xy 343.283828 -225.538281) (xy 343.334349 -225.544415) (xy 343.383233 -225.558575) (xy 343.429212 -225.580392)
			(xy 343.471096 -225.609302) (xy 343.5078 -225.644557) (xy 343.538373 -225.685243) (xy 343.562024 -225.730306)
			(xy 343.57814 -225.77858) (xy 343.586304 -225.828814) (xy 343.586816 -225.85426) (xy 344.845398 -225.85426)
			(xy 344.849358 -225.805206) (xy 344.861135 -225.757422) (xy 344.880426 -225.712146) (xy 344.906729 -225.67055)
			(xy 344.939364 -225.633713) (xy 344.977485 -225.602588) (xy 345.020106 -225.577981) (xy 345.066122 -225.560529)
			(xy 345.114341 -225.550685) (xy 345.163516 -225.548704) (xy 345.212371 -225.554636) (xy 345.259642 -225.568328)
			(xy 345.304104 -225.589426) (xy 345.344607 -225.617382) (xy 345.3801 -225.651474) (xy 345.409665 -225.690818)
			(xy 345.432536 -225.734395) (xy 345.44812 -225.781076) (xy 345.456015 -225.829653) (xy 345.45651 -225.85426)
			(xy 345.785198 -225.85426) (xy 345.789158 -225.805206) (xy 345.800935 -225.757422) (xy 345.820226 -225.712146)
			(xy 345.846529 -225.67055) (xy 345.879164 -225.633713) (xy 345.917285 -225.602588) (xy 345.959906 -225.577981)
			(xy 346.005922 -225.560529) (xy 346.054141 -225.550685) (xy 346.103316 -225.548704) (xy 346.152171 -225.554636)
			(xy 346.199442 -225.568328) (xy 346.243904 -225.589426) (xy 346.284407 -225.617382) (xy 346.3199 -225.651474)
			(xy 346.349465 -225.690818) (xy 346.372336 -225.734395) (xy 346.38792 -225.781076) (xy 346.395815 -225.829653)
			(xy 346.39631 -225.85426) (xy 347.665306 -225.85426) (xy 347.669266 -225.805206) (xy 347.681043 -225.757422)
			(xy 347.700334 -225.712146) (xy 347.726637 -225.67055) (xy 347.759272 -225.633713) (xy 347.797393 -225.602588)
			(xy 347.840014 -225.577981) (xy 347.88603 -225.560529) (xy 347.934249 -225.550685) (xy 347.983424 -225.548704)
			(xy 348.032279 -225.554636) (xy 348.07955 -225.568328) (xy 348.124012 -225.589426) (xy 348.164515 -225.617382)
			(xy 348.200008 -225.651474) (xy 348.229573 -225.690818) (xy 348.252444 -225.734395) (xy 348.268028 -225.781076)
			(xy 348.275923 -225.829653) (xy 348.276418 -225.85426) (xy 348.60536 -225.85426) (xy 348.60932 -225.805206)
			(xy 348.621097 -225.757422) (xy 348.640388 -225.712146) (xy 348.666691 -225.67055) (xy 348.699326 -225.633713)
			(xy 348.737447 -225.602588) (xy 348.780068 -225.577981) (xy 348.826084 -225.560529) (xy 348.874303 -225.550685)
			(xy 348.923478 -225.548704) (xy 348.972333 -225.554636) (xy 349.019604 -225.568328) (xy 349.064066 -225.589426)
			(xy 349.104569 -225.617382) (xy 349.140062 -225.651474) (xy 349.169627 -225.690818) (xy 349.192498 -225.734395)
			(xy 349.208082 -225.781076) (xy 349.215977 -225.829653) (xy 349.216472 -225.85426) (xy 350.485214 -225.85426)
			(xy 350.489174 -225.805206) (xy 350.500951 -225.757422) (xy 350.520242 -225.712146) (xy 350.546545 -225.67055)
			(xy 350.57918 -225.633713) (xy 350.617301 -225.602588) (xy 350.659922 -225.577981) (xy 350.705938 -225.560529)
			(xy 350.754157 -225.550685) (xy 350.803332 -225.548704) (xy 350.852187 -225.554636) (xy 350.899458 -225.568328)
			(xy 350.94392 -225.589426) (xy 350.984423 -225.617382) (xy 351.019916 -225.651474) (xy 351.049481 -225.690818)
			(xy 351.072352 -225.734395) (xy 351.087936 -225.781076) (xy 351.095831 -225.829653) (xy 351.096326 -225.85426)
			(xy 351.425268 -225.85426) (xy 351.429228 -225.805206) (xy 351.441005 -225.757422) (xy 351.460296 -225.712146)
			(xy 351.486599 -225.67055) (xy 351.519234 -225.633713) (xy 351.557355 -225.602588) (xy 351.599976 -225.577981)
			(xy 351.645992 -225.560529) (xy 351.694211 -225.550685) (xy 351.743386 -225.548704) (xy 351.792241 -225.554636)
			(xy 351.839512 -225.568328) (xy 351.883974 -225.589426) (xy 351.924477 -225.617382) (xy 351.95997 -225.651474)
			(xy 351.989535 -225.690818) (xy 352.012406 -225.734395) (xy 352.02799 -225.781076) (xy 352.035885 -225.829653)
			(xy 352.03638 -225.85426) (xy 353.305376 -225.85426) (xy 353.309336 -225.805206) (xy 353.321113 -225.757422)
			(xy 353.340404 -225.712146) (xy 353.366707 -225.67055) (xy 353.399342 -225.633713) (xy 353.437463 -225.602588)
			(xy 353.480084 -225.577981) (xy 353.5261 -225.560529) (xy 353.574319 -225.550685) (xy 353.623494 -225.548704)
			(xy 353.672349 -225.554636) (xy 353.71962 -225.568328) (xy 353.764082 -225.589426) (xy 353.804585 -225.617382)
			(xy 353.840078 -225.651474) (xy 353.869643 -225.690818) (xy 353.892514 -225.734395) (xy 353.908098 -225.781076)
			(xy 353.915993 -225.829653) (xy 353.916488 -225.85426) (xy 354.24543 -225.85426) (xy 354.24939 -225.805206)
			(xy 354.261167 -225.757422) (xy 354.280458 -225.712146) (xy 354.306761 -225.67055) (xy 354.339396 -225.633713)
			(xy 354.377517 -225.602588) (xy 354.420138 -225.577981) (xy 354.466154 -225.560529) (xy 354.514373 -225.550685)
			(xy 354.563548 -225.548704) (xy 354.612403 -225.554636) (xy 354.659674 -225.568328) (xy 354.704136 -225.589426)
			(xy 354.744639 -225.617382) (xy 354.780132 -225.651474) (xy 354.809697 -225.690818) (xy 354.832568 -225.734395)
			(xy 354.848152 -225.781076) (xy 354.856047 -225.829653) (xy 354.856542 -225.85426) (xy 354.856047 -225.878867)
			(xy 354.848152 -225.927444) (xy 354.832568 -225.974125) (xy 354.809697 -226.017702) (xy 354.780132 -226.057046)
			(xy 354.744639 -226.091138) (xy 354.704136 -226.119094) (xy 354.659674 -226.140192) (xy 354.612403 -226.153884)
			(xy 354.563548 -226.159816) (xy 354.514373 -226.157835) (xy 354.466154 -226.147991) (xy 354.420138 -226.130539)
			(xy 354.377517 -226.105932) (xy 354.339396 -226.074807) (xy 354.306761 -226.03797) (xy 354.280458 -225.996374)
			(xy 354.261167 -225.951098) (xy 354.24939 -225.903314) (xy 354.24543 -225.85426) (xy 353.916488 -225.85426)
			(xy 353.915993 -225.878867) (xy 353.908098 -225.927444) (xy 353.892514 -225.974125) (xy 353.869643 -226.017702)
			(xy 353.840078 -226.057046) (xy 353.804585 -226.091138) (xy 353.764082 -226.119094) (xy 353.71962 -226.140192)
			(xy 353.672349 -226.153884) (xy 353.623494 -226.159816) (xy 353.574319 -226.157835) (xy 353.5261 -226.147991)
			(xy 353.480084 -226.130539) (xy 353.437463 -226.105932) (xy 353.399342 -226.074807) (xy 353.366707 -226.03797)
			(xy 353.340404 -225.996374) (xy 353.321113 -225.951098) (xy 353.309336 -225.903314) (xy 353.305376 -225.85426)
			(xy 352.03638 -225.85426) (xy 352.035885 -225.878867) (xy 352.02799 -225.927444) (xy 352.012406 -225.974125)
			(xy 351.989535 -226.017702) (xy 351.95997 -226.057046) (xy 351.924477 -226.091138) (xy 351.883974 -226.119094)
			(xy 351.839512 -226.140192) (xy 351.792241 -226.153884) (xy 351.743386 -226.159816) (xy 351.694211 -226.157835)
			(xy 351.645992 -226.147991) (xy 351.599976 -226.130539) (xy 351.557355 -226.105932) (xy 351.519234 -226.074807)
			(xy 351.486599 -226.03797) (xy 351.460296 -225.996374) (xy 351.441005 -225.951098) (xy 351.429228 -225.903314)
			(xy 351.425268 -225.85426) (xy 351.096326 -225.85426) (xy 351.095831 -225.878867) (xy 351.087936 -225.927444)
			(xy 351.072352 -225.974125) (xy 351.049481 -226.017702) (xy 351.019916 -226.057046) (xy 350.984423 -226.091138)
			(xy 350.94392 -226.119094) (xy 350.899458 -226.140192) (xy 350.852187 -226.153884) (xy 350.803332 -226.159816)
			(xy 350.754157 -226.157835) (xy 350.705938 -226.147991) (xy 350.659922 -226.130539) (xy 350.617301 -226.105932)
			(xy 350.57918 -226.074807) (xy 350.546545 -226.03797) (xy 350.520242 -225.996374) (xy 350.500951 -225.951098)
			(xy 350.489174 -225.903314) (xy 350.485214 -225.85426) (xy 349.216472 -225.85426) (xy 349.215977 -225.878867)
			(xy 349.208082 -225.927444) (xy 349.192498 -225.974125) (xy 349.169627 -226.017702) (xy 349.140062 -226.057046)
			(xy 349.104569 -226.091138) (xy 349.064066 -226.119094) (xy 349.019604 -226.140192) (xy 348.972333 -226.153884)
			(xy 348.923478 -226.159816) (xy 348.874303 -226.157835) (xy 348.826084 -226.147991) (xy 348.780068 -226.130539)
			(xy 348.737447 -226.105932) (xy 348.699326 -226.074807) (xy 348.666691 -226.03797) (xy 348.640388 -225.996374)
			(xy 348.621097 -225.951098) (xy 348.60932 -225.903314) (xy 348.60536 -225.85426) (xy 348.276418 -225.85426)
			(xy 348.275923 -225.878867) (xy 348.268028 -225.927444) (xy 348.252444 -225.974125) (xy 348.229573 -226.017702)
			(xy 348.200008 -226.057046) (xy 348.164515 -226.091138) (xy 348.124012 -226.119094) (xy 348.07955 -226.140192)
			(xy 348.032279 -226.153884) (xy 347.983424 -226.159816) (xy 347.934249 -226.157835) (xy 347.88603 -226.147991)
			(xy 347.840014 -226.130539) (xy 347.797393 -226.105932) (xy 347.759272 -226.074807) (xy 347.726637 -226.03797)
			(xy 347.700334 -225.996374) (xy 347.681043 -225.951098) (xy 347.669266 -225.903314) (xy 347.665306 -225.85426)
			(xy 346.39631 -225.85426) (xy 346.395815 -225.878867) (xy 346.38792 -225.927444) (xy 346.372336 -225.974125)
			(xy 346.349465 -226.017702) (xy 346.3199 -226.057046) (xy 346.284407 -226.091138) (xy 346.243904 -226.119094)
			(xy 346.199442 -226.140192) (xy 346.152171 -226.153884) (xy 346.103316 -226.159816) (xy 346.054141 -226.157835)
			(xy 346.005922 -226.147991) (xy 345.959906 -226.130539) (xy 345.917285 -226.105932) (xy 345.879164 -226.074807)
			(xy 345.846529 -226.03797) (xy 345.820226 -225.996374) (xy 345.800935 -225.951098) (xy 345.789158 -225.903314)
			(xy 345.785198 -225.85426) (xy 345.45651 -225.85426) (xy 345.456015 -225.878867) (xy 345.44812 -225.927444)
			(xy 345.432536 -225.974125) (xy 345.409665 -226.017702) (xy 345.3801 -226.057046) (xy 345.344607 -226.091138)
			(xy 345.304104 -226.119094) (xy 345.259642 -226.140192) (xy 345.212371 -226.153884) (xy 345.163516 -226.159816)
			(xy 345.114341 -226.157835) (xy 345.066122 -226.147991) (xy 345.020106 -226.130539) (xy 344.977485 -226.105932)
			(xy 344.939364 -226.074807) (xy 344.906729 -226.03797) (xy 344.880426 -225.996374) (xy 344.861135 -225.951098)
			(xy 344.849358 -225.903314) (xy 344.845398 -225.85426) (xy 343.586816 -225.85426) (xy 343.586304 -225.879706)
			(xy 343.57814 -225.92994) (xy 343.562024 -225.978214) (xy 343.538373 -226.023277) (xy 343.5078 -226.063963)
			(xy 343.471096 -226.099218) (xy 343.429212 -226.128128) (xy 343.383233 -226.149945) (xy 343.334349 -226.164105)
			(xy 343.283828 -226.170239) (xy 343.232976 -226.16819) (xy 343.183112 -226.15801) (xy 343.135526 -226.139963)
			(xy 343.091452 -226.114517) (xy 343.05203 -226.08233) (xy 343.018282 -226.044236) (xy 342.991081 -226.001222)
			(xy 342.971133 -225.954402) (xy 342.958954 -225.904988) (xy 342.954859 -225.85426) (xy 342.646762 -225.85426)
			(xy 342.64625 -225.879706) (xy 342.638086 -225.92994) (xy 342.62197 -225.978214) (xy 342.598319 -226.023277)
			(xy 342.567746 -226.063963) (xy 342.531042 -226.099218) (xy 342.489158 -226.128128) (xy 342.443179 -226.149945)
			(xy 342.394295 -226.164105) (xy 342.343774 -226.170239) (xy 342.292922 -226.16819) (xy 342.243058 -226.15801)
			(xy 342.195472 -226.139963) (xy 342.151398 -226.114517) (xy 342.111976 -226.08233) (xy 342.078228 -226.044236)
			(xy 342.051027 -226.001222) (xy 342.031079 -225.954402) (xy 342.0189 -225.904988) (xy 342.014805 -225.85426)
			(xy 341.696294 -225.85426) (xy 341.695799 -225.878867) (xy 341.687904 -225.927444) (xy 341.67232 -225.974125)
			(xy 341.649449 -226.017702) (xy 341.619884 -226.057046) (xy 341.584391 -226.091138) (xy 341.543888 -226.119094)
			(xy 341.499426 -226.140192) (xy 341.452155 -226.153884) (xy 341.4033 -226.159816) (xy 341.354125 -226.157835)
			(xy 341.305906 -226.147991) (xy 341.25989 -226.130539) (xy 341.217269 -226.105932) (xy 341.179148 -226.074807)
			(xy 341.146513 -226.03797) (xy 341.12021 -225.996374) (xy 341.100919 -225.951098) (xy 341.089142 -225.903314)
			(xy 341.085182 -225.85426) (xy 340.766908 -225.85426) (xy 340.766396 -225.879706) (xy 340.758232 -225.92994)
			(xy 340.742116 -225.978214) (xy 340.718465 -226.023277) (xy 340.687892 -226.063963) (xy 340.651188 -226.099218)
			(xy 340.609304 -226.128128) (xy 340.563325 -226.149945) (xy 340.514441 -226.164105) (xy 340.46392 -226.170239)
			(xy 340.413068 -226.16819) (xy 340.363204 -226.15801) (xy 340.315618 -226.139963) (xy 340.271544 -226.114517)
			(xy 340.232122 -226.08233) (xy 340.198374 -226.044236) (xy 340.171173 -226.001222) (xy 340.151225 -225.954402)
			(xy 340.139046 -225.904988) (xy 340.134951 -225.85426) (xy 339.96122 -225.85426) (xy 339.96122 -226.143058)
			(xy 339.961654 -226.153123) (xy 339.969386 -226.17171) (xy 339.976206 -226.179126) (xy 340.228174 -226.431094)
			(xy 340.235576 -226.437929) (xy 340.254175 -226.445638) (xy 340.264242 -226.44608) (xy 340.678516 -226.44608)
			(xy 340.683063 -226.445952) (xy 340.692003 -226.444284) (xy 340.696296 -226.442778) (xy 340.720172 -226.433888)
			(xy 340.726776 -226.428554) (xy 340.74746 -226.412232) (xy 340.793262 -226.386194) (xy 340.842844 -226.368378)
			(xy 340.894744 -226.359309) (xy 340.921086 -226.358704) (xy 340.947435 -226.35925) (xy 340.999352 -226.368288)
			(xy 341.048943 -226.386113) (xy 341.094732 -226.412197) (xy 341.115396 -226.428554) (xy 341.122 -226.433888)
			(xy 341.145876 -226.442778) (xy 341.150164 -226.4443) (xy 341.159108 -226.445967) (xy 341.163656 -226.44608)
			(xy 341.612474 -226.44608) (xy 341.621917 -226.445585) (xy 341.639499 -226.438672) (xy 341.646764 -226.432618)
			(xy 341.664373 -226.416932) (xy 341.70337 -226.390415) (xy 341.745871 -226.369981) (xy 341.790934 -226.356083)
			(xy 341.837562 -226.349029) (xy 341.86114 -226.348544) (xy 341.884727 -226.348952) (xy 341.931376 -226.355963)
			(xy 341.976457 -226.369853) (xy 342.018963 -226.390312) (xy 342.057943 -226.41688) (xy 342.075516 -226.432618)
			(xy 342.08272 -226.43877) (xy 342.100341 -226.445688) (xy 342.109806 -226.44608) (xy 342.558624 -226.44608)
			(xy 342.563172 -226.44596) (xy 342.572119 -226.444307) (xy 342.576404 -226.442778) (xy 342.60028 -226.433888)
			(xy 342.606884 -226.428554) (xy 342.627566 -226.412225) (xy 342.673366 -226.386174) (xy 342.722948 -226.368343)
			(xy 342.774849 -226.359258) (xy 342.801194 -226.358704) (xy 342.827543 -226.359251) (xy 342.879459 -226.368289)
			(xy 342.929049 -226.386116) (xy 342.974837 -226.4122) (xy 342.995504 -226.428554) (xy 343.002108 -226.433888)
			(xy 343.025984 -226.442778) (xy 343.030272 -226.4443) (xy 343.039216 -226.445964) (xy 343.043764 -226.44608)
			(xy 343.492328 -226.44608) (xy 343.501774 -226.445593) (xy 343.519368 -226.438692) (xy 343.526618 -226.432618)
			(xy 343.544227 -226.416929) (xy 343.583222 -226.390406) (xy 343.625722 -226.369967) (xy 343.670786 -226.356062)
			(xy 343.717415 -226.349002) (xy 343.740994 -226.348544) (xy 343.765805 -226.34903) (xy 343.814816 -226.356791)
			(xy 343.862009 -226.372124) (xy 343.906224 -226.394649) (xy 343.94637 -226.423814) (xy 343.98146 -226.4589)
			(xy 344.01063 -226.499042) (xy 344.033161 -226.543254) (xy 344.048499 -226.590445) (xy 344.056267 -226.639455)
			(xy 344.056716 -226.664266) (xy 344.375244 -226.664266) (xy 344.379204 -226.615212) (xy 344.390981 -226.567428)
			(xy 344.410272 -226.522152) (xy 344.436575 -226.480556) (xy 344.46921 -226.443719) (xy 344.507331 -226.412594)
			(xy 344.549952 -226.387987) (xy 344.595968 -226.370535) (xy 344.644187 -226.360691) (xy 344.693362 -226.35871)
			(xy 344.742217 -226.364642) (xy 344.789488 -226.378334) (xy 344.83395 -226.399432) (xy 344.874453 -226.427388)
			(xy 344.909946 -226.46148) (xy 344.939511 -226.500824) (xy 344.962382 -226.544401) (xy 344.977966 -226.591082)
			(xy 344.985861 -226.639659) (xy 344.986356 -226.664266) (xy 345.304867 -226.664266) (xy 345.308962 -226.613538)
			(xy 345.321141 -226.564124) (xy 345.341089 -226.517304) (xy 345.36829 -226.47429) (xy 345.402038 -226.436196)
			(xy 345.44146 -226.404009) (xy 345.485534 -226.378563) (xy 345.53312 -226.360516) (xy 345.582984 -226.350336)
			(xy 345.633836 -226.348287) (xy 345.684357 -226.354421) (xy 345.733241 -226.368581) (xy 345.77922 -226.390398)
			(xy 345.821104 -226.419308) (xy 345.857808 -226.454563) (xy 345.888381 -226.495249) (xy 345.912032 -226.540312)
			(xy 345.928148 -226.588586) (xy 345.936312 -226.63882) (xy 345.936824 -226.664266) (xy 346.244921 -226.664266)
			(xy 346.249016 -226.613538) (xy 346.261195 -226.564124) (xy 346.281143 -226.517304) (xy 346.308344 -226.47429)
			(xy 346.342092 -226.436196) (xy 346.381514 -226.404009) (xy 346.425588 -226.378563) (xy 346.473174 -226.360516)
			(xy 346.523038 -226.350336) (xy 346.57389 -226.348287) (xy 346.624411 -226.354421) (xy 346.673295 -226.368581)
			(xy 346.719274 -226.390398) (xy 346.761158 -226.419308) (xy 346.797862 -226.454563) (xy 346.828435 -226.495249)
			(xy 346.852086 -226.540312) (xy 346.868202 -226.588586) (xy 346.876366 -226.63882) (xy 346.876878 -226.664266)
			(xy 347.195406 -226.664266) (xy 347.199366 -226.615212) (xy 347.211143 -226.567428) (xy 347.230434 -226.522152)
			(xy 347.256737 -226.480556) (xy 347.289372 -226.443719) (xy 347.327493 -226.412594) (xy 347.370114 -226.387987)
			(xy 347.41613 -226.370535) (xy 347.464349 -226.360691) (xy 347.513524 -226.35871) (xy 347.562379 -226.364642)
			(xy 347.60965 -226.378334) (xy 347.654112 -226.399432) (xy 347.694615 -226.427388) (xy 347.730108 -226.46148)
			(xy 347.759673 -226.500824) (xy 347.782544 -226.544401) (xy 347.798128 -226.591082) (xy 347.806023 -226.639659)
			(xy 347.806518 -226.664266) (xy 348.124775 -226.664266) (xy 348.12887 -226.613538) (xy 348.141049 -226.564124)
			(xy 348.160997 -226.517304) (xy 348.188198 -226.47429) (xy 348.221946 -226.436196) (xy 348.261368 -226.404009)
			(xy 348.305442 -226.378563) (xy 348.353028 -226.360516) (xy 348.402892 -226.350336) (xy 348.453744 -226.348287)
			(xy 348.504265 -226.354421) (xy 348.553149 -226.368581) (xy 348.599128 -226.390398) (xy 348.641012 -226.419308)
			(xy 348.677716 -226.454563) (xy 348.708289 -226.495249) (xy 348.73194 -226.540312) (xy 348.748056 -226.588586)
			(xy 348.75622 -226.63882) (xy 348.756732 -226.664266) (xy 349.064829 -226.664266) (xy 349.068924 -226.613538)
			(xy 349.081103 -226.564124) (xy 349.101051 -226.517304) (xy 349.128252 -226.47429) (xy 349.162 -226.436196)
			(xy 349.201422 -226.404009) (xy 349.245496 -226.378563) (xy 349.293082 -226.360516) (xy 349.342946 -226.350336)
			(xy 349.393798 -226.348287) (xy 349.444319 -226.354421) (xy 349.493203 -226.368581) (xy 349.539182 -226.390398)
			(xy 349.581066 -226.419308) (xy 349.61777 -226.454563) (xy 349.648343 -226.495249) (xy 349.671994 -226.540312)
			(xy 349.68811 -226.588586) (xy 349.696274 -226.63882) (xy 349.696786 -226.664266) (xy 350.015314 -226.664266)
			(xy 350.019274 -226.615212) (xy 350.031051 -226.567428) (xy 350.050342 -226.522152) (xy 350.076645 -226.480556)
			(xy 350.10928 -226.443719) (xy 350.147401 -226.412594) (xy 350.190022 -226.387987) (xy 350.236038 -226.370535)
			(xy 350.284257 -226.360691) (xy 350.333432 -226.35871) (xy 350.382287 -226.364642) (xy 350.429558 -226.378334)
			(xy 350.47402 -226.399432) (xy 350.514523 -226.427388) (xy 350.550016 -226.46148) (xy 350.579581 -226.500824)
			(xy 350.602452 -226.544401) (xy 350.618036 -226.591082) (xy 350.625931 -226.639659) (xy 350.626426 -226.664266)
			(xy 350.944937 -226.664266) (xy 350.949032 -226.613538) (xy 350.961211 -226.564124) (xy 350.981159 -226.517304)
			(xy 351.00836 -226.47429) (xy 351.042108 -226.436196) (xy 351.08153 -226.404009) (xy 351.125604 -226.378563)
			(xy 351.17319 -226.360516) (xy 351.223054 -226.350336) (xy 351.273906 -226.348287) (xy 351.324427 -226.354421)
			(xy 351.373311 -226.368581) (xy 351.41929 -226.390398) (xy 351.461174 -226.419308) (xy 351.497878 -226.454563)
			(xy 351.528451 -226.495249) (xy 351.552102 -226.540312) (xy 351.568218 -226.588586) (xy 351.576382 -226.63882)
			(xy 351.576894 -226.664266) (xy 351.884991 -226.664266) (xy 351.889086 -226.613538) (xy 351.901265 -226.564124)
			(xy 351.921213 -226.517304) (xy 351.948414 -226.47429) (xy 351.982162 -226.436196) (xy 352.021584 -226.404009)
			(xy 352.065658 -226.378563) (xy 352.113244 -226.360516) (xy 352.163108 -226.350336) (xy 352.21396 -226.348287)
			(xy 352.264481 -226.354421) (xy 352.313365 -226.368581) (xy 352.359344 -226.390398) (xy 352.401228 -226.419308)
			(xy 352.437932 -226.454563) (xy 352.468505 -226.495249) (xy 352.492156 -226.540312) (xy 352.508272 -226.588586)
			(xy 352.516436 -226.63882) (xy 352.516948 -226.664266) (xy 352.835222 -226.664266) (xy 352.839182 -226.615212)
			(xy 352.850959 -226.567428) (xy 352.87025 -226.522152) (xy 352.896553 -226.480556) (xy 352.929188 -226.443719)
			(xy 352.967309 -226.412594) (xy 353.00993 -226.387987) (xy 353.055946 -226.370535) (xy 353.104165 -226.360691)
			(xy 353.15334 -226.35871) (xy 353.202195 -226.364642) (xy 353.249466 -226.378334) (xy 353.293928 -226.399432)
			(xy 353.334431 -226.427388) (xy 353.369924 -226.46148) (xy 353.399489 -226.500824) (xy 353.42236 -226.544401)
			(xy 353.437944 -226.591082) (xy 353.445839 -226.639659) (xy 353.446334 -226.664266) (xy 353.764845 -226.664266)
			(xy 353.76894 -226.613538) (xy 353.781119 -226.564124) (xy 353.801067 -226.517304) (xy 353.828268 -226.47429)
			(xy 353.862016 -226.436196) (xy 353.901438 -226.404009) (xy 353.945512 -226.378563) (xy 353.993098 -226.360516)
			(xy 354.042962 -226.350336) (xy 354.093814 -226.348287) (xy 354.144335 -226.354421) (xy 354.193219 -226.368581)
			(xy 354.239198 -226.390398) (xy 354.281082 -226.419308) (xy 354.317786 -226.454563) (xy 354.348359 -226.495249)
			(xy 354.37201 -226.540312) (xy 354.388126 -226.588586) (xy 354.39629 -226.63882) (xy 354.396802 -226.664266)
			(xy 354.704899 -226.664266) (xy 354.708994 -226.613538) (xy 354.721173 -226.564124) (xy 354.741121 -226.517304)
			(xy 354.768322 -226.47429) (xy 354.80207 -226.436196) (xy 354.841492 -226.404009) (xy 354.885566 -226.378563)
			(xy 354.933152 -226.360516) (xy 354.983016 -226.350336) (xy 355.033868 -226.348287) (xy 355.084389 -226.354421)
			(xy 355.133273 -226.368581) (xy 355.179252 -226.390398) (xy 355.221136 -226.419308) (xy 355.25784 -226.454563)
			(xy 355.288413 -226.495249) (xy 355.312064 -226.540312) (xy 355.32818 -226.588586) (xy 355.336344 -226.63882)
			(xy 355.336856 -226.664266) (xy 355.336344 -226.689712) (xy 355.32818 -226.739946) (xy 355.312064 -226.78822)
			(xy 355.288413 -226.833283) (xy 355.25784 -226.873969) (xy 355.221136 -226.909224) (xy 355.179252 -226.938134)
			(xy 355.133273 -226.959951) (xy 355.084389 -226.974111) (xy 355.033868 -226.980245) (xy 354.983016 -226.978196)
			(xy 354.933152 -226.968016) (xy 354.885566 -226.949969) (xy 354.841492 -226.924523) (xy 354.80207 -226.892336)
			(xy 354.768322 -226.854242) (xy 354.741121 -226.811228) (xy 354.721173 -226.764408) (xy 354.708994 -226.714994)
			(xy 354.704899 -226.664266) (xy 354.396802 -226.664266) (xy 354.39629 -226.689712) (xy 354.388126 -226.739946)
			(xy 354.37201 -226.78822) (xy 354.348359 -226.833283) (xy 354.317786 -226.873969) (xy 354.281082 -226.909224)
			(xy 354.239198 -226.938134) (xy 354.193219 -226.959951) (xy 354.144335 -226.974111) (xy 354.093814 -226.980245)
			(xy 354.042962 -226.978196) (xy 353.993098 -226.968016) (xy 353.945512 -226.949969) (xy 353.901438 -226.924523)
			(xy 353.862016 -226.892336) (xy 353.828268 -226.854242) (xy 353.801067 -226.811228) (xy 353.781119 -226.764408)
			(xy 353.76894 -226.714994) (xy 353.764845 -226.664266) (xy 353.446334 -226.664266) (xy 353.445839 -226.688873)
			(xy 353.437944 -226.73745) (xy 353.42236 -226.784131) (xy 353.399489 -226.827708) (xy 353.369924 -226.867052)
			(xy 353.334431 -226.901144) (xy 353.293928 -226.9291) (xy 353.249466 -226.950198) (xy 353.202195 -226.96389)
			(xy 353.15334 -226.969822) (xy 353.104165 -226.967841) (xy 353.055946 -226.957997) (xy 353.00993 -226.940545)
			(xy 352.967309 -226.915938) (xy 352.929188 -226.884813) (xy 352.896553 -226.847976) (xy 352.87025 -226.80638)
			(xy 352.850959 -226.761104) (xy 352.839182 -226.71332) (xy 352.835222 -226.664266) (xy 352.516948 -226.664266)
			(xy 352.516436 -226.689712) (xy 352.508272 -226.739946) (xy 352.492156 -226.78822) (xy 352.468505 -226.833283)
			(xy 352.437932 -226.873969) (xy 352.401228 -226.909224) (xy 352.359344 -226.938134) (xy 352.313365 -226.959951)
			(xy 352.264481 -226.974111) (xy 352.21396 -226.980245) (xy 352.163108 -226.978196) (xy 352.113244 -226.968016)
			(xy 352.065658 -226.949969) (xy 352.021584 -226.924523) (xy 351.982162 -226.892336) (xy 351.948414 -226.854242)
			(xy 351.921213 -226.811228) (xy 351.901265 -226.764408) (xy 351.889086 -226.714994) (xy 351.884991 -226.664266)
			(xy 351.576894 -226.664266) (xy 351.576382 -226.689712) (xy 351.568218 -226.739946) (xy 351.552102 -226.78822)
			(xy 351.528451 -226.833283) (xy 351.497878 -226.873969) (xy 351.461174 -226.909224) (xy 351.41929 -226.938134)
			(xy 351.373311 -226.959951) (xy 351.324427 -226.974111) (xy 351.273906 -226.980245) (xy 351.223054 -226.978196)
			(xy 351.17319 -226.968016) (xy 351.125604 -226.949969) (xy 351.08153 -226.924523) (xy 351.042108 -226.892336)
			(xy 351.00836 -226.854242) (xy 350.981159 -226.811228) (xy 350.961211 -226.764408) (xy 350.949032 -226.714994)
			(xy 350.944937 -226.664266) (xy 350.626426 -226.664266) (xy 350.625931 -226.688873) (xy 350.618036 -226.73745)
			(xy 350.602452 -226.784131) (xy 350.579581 -226.827708) (xy 350.550016 -226.867052) (xy 350.514523 -226.901144)
			(xy 350.47402 -226.9291) (xy 350.429558 -226.950198) (xy 350.382287 -226.96389) (xy 350.333432 -226.969822)
			(xy 350.284257 -226.967841) (xy 350.236038 -226.957997) (xy 350.190022 -226.940545) (xy 350.147401 -226.915938)
			(xy 350.10928 -226.884813) (xy 350.076645 -226.847976) (xy 350.050342 -226.80638) (xy 350.031051 -226.761104)
			(xy 350.019274 -226.71332) (xy 350.015314 -226.664266) (xy 349.696786 -226.664266) (xy 349.696274 -226.689712)
			(xy 349.68811 -226.739946) (xy 349.671994 -226.78822) (xy 349.648343 -226.833283) (xy 349.61777 -226.873969)
			(xy 349.581066 -226.909224) (xy 349.539182 -226.938134) (xy 349.493203 -226.959951) (xy 349.444319 -226.974111)
			(xy 349.393798 -226.980245) (xy 349.342946 -226.978196) (xy 349.293082 -226.968016) (xy 349.245496 -226.949969)
			(xy 349.201422 -226.924523) (xy 349.162 -226.892336) (xy 349.128252 -226.854242) (xy 349.101051 -226.811228)
			(xy 349.081103 -226.764408) (xy 349.068924 -226.714994) (xy 349.064829 -226.664266) (xy 348.756732 -226.664266)
			(xy 348.75622 -226.689712) (xy 348.748056 -226.739946) (xy 348.73194 -226.78822) (xy 348.708289 -226.833283)
			(xy 348.677716 -226.873969) (xy 348.641012 -226.909224) (xy 348.599128 -226.938134) (xy 348.553149 -226.959951)
			(xy 348.504265 -226.974111) (xy 348.453744 -226.980245) (xy 348.402892 -226.978196) (xy 348.353028 -226.968016)
			(xy 348.305442 -226.949969) (xy 348.261368 -226.924523) (xy 348.221946 -226.892336) (xy 348.188198 -226.854242)
			(xy 348.160997 -226.811228) (xy 348.141049 -226.764408) (xy 348.12887 -226.714994) (xy 348.124775 -226.664266)
			(xy 347.806518 -226.664266) (xy 347.806023 -226.688873) (xy 347.798128 -226.73745) (xy 347.782544 -226.784131)
			(xy 347.759673 -226.827708) (xy 347.730108 -226.867052) (xy 347.694615 -226.901144) (xy 347.654112 -226.9291)
			(xy 347.60965 -226.950198) (xy 347.562379 -226.96389) (xy 347.513524 -226.969822) (xy 347.464349 -226.967841)
			(xy 347.41613 -226.957997) (xy 347.370114 -226.940545) (xy 347.327493 -226.915938) (xy 347.289372 -226.884813)
			(xy 347.256737 -226.847976) (xy 347.230434 -226.80638) (xy 347.211143 -226.761104) (xy 347.199366 -226.71332)
			(xy 347.195406 -226.664266) (xy 346.876878 -226.664266) (xy 346.876366 -226.689712) (xy 346.868202 -226.739946)
			(xy 346.852086 -226.78822) (xy 346.828435 -226.833283) (xy 346.797862 -226.873969) (xy 346.761158 -226.909224)
			(xy 346.719274 -226.938134) (xy 346.673295 -226.959951) (xy 346.624411 -226.974111) (xy 346.57389 -226.980245)
			(xy 346.523038 -226.978196) (xy 346.473174 -226.968016) (xy 346.425588 -226.949969) (xy 346.381514 -226.924523)
			(xy 346.342092 -226.892336) (xy 346.308344 -226.854242) (xy 346.281143 -226.811228) (xy 346.261195 -226.764408)
			(xy 346.249016 -226.714994) (xy 346.244921 -226.664266) (xy 345.936824 -226.664266) (xy 345.936312 -226.689712)
			(xy 345.928148 -226.739946) (xy 345.912032 -226.78822) (xy 345.888381 -226.833283) (xy 345.857808 -226.873969)
			(xy 345.821104 -226.909224) (xy 345.77922 -226.938134) (xy 345.733241 -226.959951) (xy 345.684357 -226.974111)
			(xy 345.633836 -226.980245) (xy 345.582984 -226.978196) (xy 345.53312 -226.968016) (xy 345.485534 -226.949969)
			(xy 345.44146 -226.924523) (xy 345.402038 -226.892336) (xy 345.36829 -226.854242) (xy 345.341089 -226.811228)
			(xy 345.321141 -226.764408) (xy 345.308962 -226.714994) (xy 345.304867 -226.664266) (xy 344.986356 -226.664266)
			(xy 344.985861 -226.688873) (xy 344.977966 -226.73745) (xy 344.962382 -226.784131) (xy 344.939511 -226.827708)
			(xy 344.909946 -226.867052) (xy 344.874453 -226.901144) (xy 344.83395 -226.9291) (xy 344.789488 -226.950198)
			(xy 344.742217 -226.96389) (xy 344.693362 -226.969822) (xy 344.644187 -226.967841) (xy 344.595968 -226.957997)
			(xy 344.549952 -226.940545) (xy 344.507331 -226.915938) (xy 344.46921 -226.884813) (xy 344.436575 -226.847976)
			(xy 344.410272 -226.80638) (xy 344.390981 -226.761104) (xy 344.379204 -226.71332) (xy 344.375244 -226.664266)
			(xy 344.056716 -226.664266) (xy 344.056083 -226.692713) (xy 344.045854 -226.748681) (xy 344.036396 -226.775518)
			(xy 344.031062 -226.789742) (xy 344.037412 -226.818952) (xy 344.101674 -226.883214) (xy 344.108521 -226.890612)
			(xy 344.116254 -226.90921) (xy 344.11666 -226.919282) (xy 344.11666 -227.067364) (xy 344.117127 -227.077238)
			(xy 344.124578 -227.095529) (xy 344.131138 -227.102924) (xy 344.181176 -227.153724) (xy 344.188323 -227.160401)
			(xy 344.20622 -227.168249) (xy 344.215974 -227.168964) (xy 344.216482 -227.168964) (xy 344.241441 -227.169902)
			(xy 344.290569 -227.178896) (xy 344.337578 -227.195764) (xy 344.381216 -227.220057) (xy 344.42032 -227.251127)
			(xy 344.453846 -227.288146) (xy 344.480902 -227.330127) (xy 344.500766 -227.375951) (xy 344.512909 -227.424397)
			(xy 344.517007 -227.474172) (xy 344.516999 -227.474272) (xy 346.725252 -227.474272) (xy 346.729212 -227.425218)
			(xy 346.740989 -227.377434) (xy 346.76028 -227.332158) (xy 346.786583 -227.290562) (xy 346.819218 -227.253725)
			(xy 346.857339 -227.2226) (xy 346.89996 -227.197993) (xy 346.945976 -227.180541) (xy 346.994195 -227.170697)
			(xy 347.04337 -227.168716) (xy 347.092225 -227.174648) (xy 347.139496 -227.18834) (xy 347.183958 -227.209438)
			(xy 347.224461 -227.237394) (xy 347.259954 -227.271486) (xy 347.289519 -227.31083) (xy 347.31239 -227.354407)
			(xy 347.327974 -227.401088) (xy 347.335869 -227.449665) (xy 347.336364 -227.474272) (xy 349.545414 -227.474272)
			(xy 349.549374 -227.425218) (xy 349.561151 -227.377434) (xy 349.580442 -227.332158) (xy 349.606745 -227.290562)
			(xy 349.63938 -227.253725) (xy 349.677501 -227.2226) (xy 349.720122 -227.197993) (xy 349.766138 -227.180541)
			(xy 349.814357 -227.170697) (xy 349.863532 -227.168716) (xy 349.912387 -227.174648) (xy 349.959658 -227.18834)
			(xy 350.00412 -227.209438) (xy 350.044623 -227.237394) (xy 350.080116 -227.271486) (xy 350.109681 -227.31083)
			(xy 350.132552 -227.354407) (xy 350.148136 -227.401088) (xy 350.156031 -227.449665) (xy 350.156526 -227.474272)
			(xy 352.365322 -227.474272) (xy 352.369282 -227.425218) (xy 352.381059 -227.377434) (xy 352.40035 -227.332158)
			(xy 352.426653 -227.290562) (xy 352.459288 -227.253725) (xy 352.497409 -227.2226) (xy 352.54003 -227.197993)
			(xy 352.586046 -227.180541) (xy 352.634265 -227.170697) (xy 352.68344 -227.168716) (xy 352.732295 -227.174648)
			(xy 352.779566 -227.18834) (xy 352.824028 -227.209438) (xy 352.864531 -227.237394) (xy 352.900024 -227.271486)
			(xy 352.929589 -227.31083) (xy 352.95246 -227.354407) (xy 352.968044 -227.401088) (xy 352.975939 -227.449665)
			(xy 352.976434 -227.474272) (xy 355.18523 -227.474272) (xy 355.18919 -227.425218) (xy 355.200967 -227.377434)
			(xy 355.220258 -227.332158) (xy 355.246561 -227.290562) (xy 355.279196 -227.253725) (xy 355.317317 -227.2226)
			(xy 355.359938 -227.197993) (xy 355.405954 -227.180541) (xy 355.454173 -227.170697) (xy 355.503348 -227.168716)
			(xy 355.552203 -227.174648) (xy 355.599474 -227.18834) (xy 355.643936 -227.209438) (xy 355.684439 -227.237394)
			(xy 355.719932 -227.271486) (xy 355.749497 -227.31083) (xy 355.772368 -227.354407) (xy 355.787952 -227.401088)
			(xy 355.795847 -227.449665) (xy 355.796342 -227.474272) (xy 356.114853 -227.474272) (xy 356.118948 -227.423544)
			(xy 356.131127 -227.37413) (xy 356.151075 -227.32731) (xy 356.178276 -227.284296) (xy 356.212024 -227.246202)
			(xy 356.251446 -227.214015) (xy 356.29552 -227.188569) (xy 356.343106 -227.170522) (xy 356.39297 -227.160342)
			(xy 356.443822 -227.158293) (xy 356.494343 -227.164427) (xy 356.543227 -227.178587) (xy 356.589206 -227.200404)
			(xy 356.63109 -227.229314) (xy 356.667794 -227.264569) (xy 356.698367 -227.305255) (xy 356.722018 -227.350318)
			(xy 356.738134 -227.398592) (xy 356.746298 -227.448826) (xy 356.74681 -227.474272) (xy 356.746298 -227.499718)
			(xy 356.738134 -227.549952) (xy 356.722018 -227.598226) (xy 356.698367 -227.643289) (xy 356.667794 -227.683975)
			(xy 356.63109 -227.71923) (xy 356.589206 -227.74814) (xy 356.543227 -227.769957) (xy 356.494343 -227.784117)
			(xy 356.443822 -227.790251) (xy 356.39297 -227.788202) (xy 356.343106 -227.778022) (xy 356.29552 -227.759975)
			(xy 356.251446 -227.734529) (xy 356.212024 -227.702342) (xy 356.178276 -227.664248) (xy 356.151075 -227.621234)
			(xy 356.131127 -227.574414) (xy 356.118948 -227.525) (xy 356.114853 -227.474272) (xy 355.796342 -227.474272)
			(xy 355.795847 -227.498879) (xy 355.787952 -227.547456) (xy 355.772368 -227.594137) (xy 355.749497 -227.637714)
			(xy 355.719932 -227.677058) (xy 355.684439 -227.71115) (xy 355.643936 -227.739106) (xy 355.599474 -227.760204)
			(xy 355.552203 -227.773896) (xy 355.503348 -227.779828) (xy 355.454173 -227.777847) (xy 355.405954 -227.768003)
			(xy 355.359938 -227.750551) (xy 355.317317 -227.725944) (xy 355.279196 -227.694819) (xy 355.246561 -227.657982)
			(xy 355.220258 -227.616386) (xy 355.200967 -227.57111) (xy 355.18919 -227.523326) (xy 355.18523 -227.474272)
			(xy 352.976434 -227.474272) (xy 352.975939 -227.498879) (xy 352.968044 -227.547456) (xy 352.95246 -227.594137)
			(xy 352.929589 -227.637714) (xy 352.900024 -227.677058) (xy 352.864531 -227.71115) (xy 352.824028 -227.739106)
			(xy 352.779566 -227.760204) (xy 352.732295 -227.773896) (xy 352.68344 -227.779828) (xy 352.634265 -227.777847)
			(xy 352.586046 -227.768003) (xy 352.54003 -227.750551) (xy 352.497409 -227.725944) (xy 352.459288 -227.694819)
			(xy 352.426653 -227.657982) (xy 352.40035 -227.616386) (xy 352.381059 -227.57111) (xy 352.369282 -227.523326)
			(xy 352.365322 -227.474272) (xy 350.156526 -227.474272) (xy 350.156031 -227.498879) (xy 350.148136 -227.547456)
			(xy 350.132552 -227.594137) (xy 350.109681 -227.637714) (xy 350.080116 -227.677058) (xy 350.044623 -227.71115)
			(xy 350.00412 -227.739106) (xy 349.959658 -227.760204) (xy 349.912387 -227.773896) (xy 349.863532 -227.779828)
			(xy 349.814357 -227.777847) (xy 349.766138 -227.768003) (xy 349.720122 -227.750551) (xy 349.677501 -227.725944)
			(xy 349.63938 -227.694819) (xy 349.606745 -227.657982) (xy 349.580442 -227.616386) (xy 349.561151 -227.57111)
			(xy 349.549374 -227.523326) (xy 349.545414 -227.474272) (xy 347.336364 -227.474272) (xy 347.335869 -227.498879)
			(xy 347.327974 -227.547456) (xy 347.31239 -227.594137) (xy 347.289519 -227.637714) (xy 347.259954 -227.677058)
			(xy 347.224461 -227.71115) (xy 347.183958 -227.739106) (xy 347.139496 -227.760204) (xy 347.092225 -227.773896)
			(xy 347.04337 -227.779828) (xy 346.994195 -227.777847) (xy 346.945976 -227.768003) (xy 346.89996 -227.750551)
			(xy 346.857339 -227.725944) (xy 346.819218 -227.694819) (xy 346.786583 -227.657982) (xy 346.76028 -227.616386)
			(xy 346.740989 -227.57111) (xy 346.729212 -227.523326) (xy 346.725252 -227.474272) (xy 344.516999 -227.474272)
			(xy 344.512951 -227.523951) (xy 344.500848 -227.572407) (xy 344.481022 -227.618248) (xy 344.454002 -227.660251)
			(xy 344.420506 -227.697298) (xy 344.381429 -227.728401) (xy 344.337811 -227.75273) (xy 344.290816 -227.769638)
			(xy 344.241696 -227.778673) (xy 344.216736 -227.77958) (xy 344.215974 -227.77958) (xy 344.206223 -227.780313)
			(xy 344.188328 -227.788152) (xy 344.181176 -227.79482) (xy 344.131138 -227.84562) (xy 344.124552 -227.853)
			(xy 344.117091 -227.871299) (xy 344.11666 -227.88118) (xy 344.11666 -228.284278) (xy 344.375244 -228.284278)
			(xy 344.379204 -228.235224) (xy 344.390981 -228.18744) (xy 344.410272 -228.142164) (xy 344.436575 -228.100568)
			(xy 344.46921 -228.063731) (xy 344.507331 -228.032606) (xy 344.549952 -228.007999) (xy 344.595968 -227.990547)
			(xy 344.644187 -227.980703) (xy 344.693362 -227.978722) (xy 344.742217 -227.984654) (xy 344.789488 -227.998346)
			(xy 344.83395 -228.019444) (xy 344.874453 -228.0474) (xy 344.909946 -228.081492) (xy 344.939511 -228.120836)
			(xy 344.962382 -228.164413) (xy 344.977966 -228.211094) (xy 344.985861 -228.259671) (xy 344.986356 -228.284278)
			(xy 345.304867 -228.284278) (xy 345.308962 -228.23355) (xy 345.321141 -228.184136) (xy 345.341089 -228.137316)
			(xy 345.36829 -228.094302) (xy 345.402038 -228.056208) (xy 345.44146 -228.024021) (xy 345.485534 -227.998575)
			(xy 345.53312 -227.980528) (xy 345.582984 -227.970348) (xy 345.633836 -227.968299) (xy 345.684357 -227.974433)
			(xy 345.733241 -227.988593) (xy 345.77922 -228.01041) (xy 345.821104 -228.03932) (xy 345.857808 -228.074575)
			(xy 345.888381 -228.115261) (xy 345.912032 -228.160324) (xy 345.928148 -228.208598) (xy 345.936312 -228.258832)
			(xy 345.936824 -228.284278) (xy 346.244921 -228.284278) (xy 346.249016 -228.23355) (xy 346.261195 -228.184136)
			(xy 346.281143 -228.137316) (xy 346.308344 -228.094302) (xy 346.342092 -228.056208) (xy 346.381514 -228.024021)
			(xy 346.425588 -227.998575) (xy 346.473174 -227.980528) (xy 346.523038 -227.970348) (xy 346.57389 -227.968299)
			(xy 346.624411 -227.974433) (xy 346.673295 -227.988593) (xy 346.719274 -228.01041) (xy 346.761158 -228.03932)
			(xy 346.797862 -228.074575) (xy 346.828435 -228.115261) (xy 346.852086 -228.160324) (xy 346.868202 -228.208598)
			(xy 346.876366 -228.258832) (xy 346.876878 -228.284278) (xy 347.195406 -228.284278) (xy 347.199366 -228.235224)
			(xy 347.211143 -228.18744) (xy 347.230434 -228.142164) (xy 347.256737 -228.100568) (xy 347.289372 -228.063731)
			(xy 347.327493 -228.032606) (xy 347.370114 -228.007999) (xy 347.41613 -227.990547) (xy 347.464349 -227.980703)
			(xy 347.513524 -227.978722) (xy 347.562379 -227.984654) (xy 347.60965 -227.998346) (xy 347.654112 -228.019444)
			(xy 347.694615 -228.0474) (xy 347.730108 -228.081492) (xy 347.759673 -228.120836) (xy 347.782544 -228.164413)
			(xy 347.798128 -228.211094) (xy 347.806023 -228.259671) (xy 347.806518 -228.284278) (xy 348.124775 -228.284278)
			(xy 348.12887 -228.23355) (xy 348.141049 -228.184136) (xy 348.160997 -228.137316) (xy 348.188198 -228.094302)
			(xy 348.221946 -228.056208) (xy 348.261368 -228.024021) (xy 348.305442 -227.998575) (xy 348.353028 -227.980528)
			(xy 348.402892 -227.970348) (xy 348.453744 -227.968299) (xy 348.504265 -227.974433) (xy 348.553149 -227.988593)
			(xy 348.599128 -228.01041) (xy 348.641012 -228.03932) (xy 348.677716 -228.074575) (xy 348.708289 -228.115261)
			(xy 348.73194 -228.160324) (xy 348.748056 -228.208598) (xy 348.75622 -228.258832) (xy 348.756732 -228.284278)
			(xy 349.064829 -228.284278) (xy 349.068924 -228.23355) (xy 349.081103 -228.184136) (xy 349.101051 -228.137316)
			(xy 349.128252 -228.094302) (xy 349.162 -228.056208) (xy 349.201422 -228.024021) (xy 349.245496 -227.998575)
			(xy 349.293082 -227.980528) (xy 349.342946 -227.970348) (xy 349.393798 -227.968299) (xy 349.444319 -227.974433)
			(xy 349.493203 -227.988593) (xy 349.539182 -228.01041) (xy 349.581066 -228.03932) (xy 349.61777 -228.074575)
			(xy 349.648343 -228.115261) (xy 349.671994 -228.160324) (xy 349.68811 -228.208598) (xy 349.696274 -228.258832)
			(xy 349.696786 -228.284278) (xy 350.015314 -228.284278) (xy 350.019274 -228.235224) (xy 350.031051 -228.18744)
			(xy 350.050342 -228.142164) (xy 350.076645 -228.100568) (xy 350.10928 -228.063731) (xy 350.147401 -228.032606)
			(xy 350.190022 -228.007999) (xy 350.236038 -227.990547) (xy 350.284257 -227.980703) (xy 350.333432 -227.978722)
			(xy 350.382287 -227.984654) (xy 350.429558 -227.998346) (xy 350.47402 -228.019444) (xy 350.514523 -228.0474)
			(xy 350.550016 -228.081492) (xy 350.579581 -228.120836) (xy 350.602452 -228.164413) (xy 350.618036 -228.211094)
			(xy 350.625931 -228.259671) (xy 350.626426 -228.284278) (xy 350.944937 -228.284278) (xy 350.949032 -228.23355)
			(xy 350.961211 -228.184136) (xy 350.981159 -228.137316) (xy 351.00836 -228.094302) (xy 351.042108 -228.056208)
			(xy 351.08153 -228.024021) (xy 351.125604 -227.998575) (xy 351.17319 -227.980528) (xy 351.223054 -227.970348)
			(xy 351.273906 -227.968299) (xy 351.324427 -227.974433) (xy 351.373311 -227.988593) (xy 351.41929 -228.01041)
			(xy 351.461174 -228.03932) (xy 351.497878 -228.074575) (xy 351.528451 -228.115261) (xy 351.552102 -228.160324)
			(xy 351.568218 -228.208598) (xy 351.576382 -228.258832) (xy 351.576894 -228.284278) (xy 351.884991 -228.284278)
			(xy 351.889086 -228.23355) (xy 351.901265 -228.184136) (xy 351.921213 -228.137316) (xy 351.948414 -228.094302)
			(xy 351.982162 -228.056208) (xy 352.021584 -228.024021) (xy 352.065658 -227.998575) (xy 352.113244 -227.980528)
			(xy 352.163108 -227.970348) (xy 352.21396 -227.968299) (xy 352.264481 -227.974433) (xy 352.313365 -227.988593)
			(xy 352.359344 -228.01041) (xy 352.401228 -228.03932) (xy 352.437932 -228.074575) (xy 352.468505 -228.115261)
			(xy 352.492156 -228.160324) (xy 352.508272 -228.208598) (xy 352.516436 -228.258832) (xy 352.516948 -228.284278)
			(xy 352.835222 -228.284278) (xy 352.839182 -228.235224) (xy 352.850959 -228.18744) (xy 352.87025 -228.142164)
			(xy 352.896553 -228.100568) (xy 352.929188 -228.063731) (xy 352.967309 -228.032606) (xy 353.00993 -228.007999)
			(xy 353.055946 -227.990547) (xy 353.104165 -227.980703) (xy 353.15334 -227.978722) (xy 353.202195 -227.984654)
			(xy 353.249466 -227.998346) (xy 353.293928 -228.019444) (xy 353.334431 -228.0474) (xy 353.369924 -228.081492)
			(xy 353.399489 -228.120836) (xy 353.42236 -228.164413) (xy 353.437944 -228.211094) (xy 353.445839 -228.259671)
			(xy 353.446334 -228.284278) (xy 353.764845 -228.284278) (xy 353.76894 -228.23355) (xy 353.781119 -228.184136)
			(xy 353.801067 -228.137316) (xy 353.828268 -228.094302) (xy 353.862016 -228.056208) (xy 353.901438 -228.024021)
			(xy 353.945512 -227.998575) (xy 353.993098 -227.980528) (xy 354.042962 -227.970348) (xy 354.093814 -227.968299)
			(xy 354.144335 -227.974433) (xy 354.193219 -227.988593) (xy 354.239198 -228.01041) (xy 354.281082 -228.03932)
			(xy 354.317786 -228.074575) (xy 354.348359 -228.115261) (xy 354.37201 -228.160324) (xy 354.388126 -228.208598)
			(xy 354.39629 -228.258832) (xy 354.396802 -228.284278) (xy 354.704899 -228.284278) (xy 354.708994 -228.23355)
			(xy 354.721173 -228.184136) (xy 354.741121 -228.137316) (xy 354.768322 -228.094302) (xy 354.80207 -228.056208)
			(xy 354.841492 -228.024021) (xy 354.885566 -227.998575) (xy 354.933152 -227.980528) (xy 354.983016 -227.970348)
			(xy 355.033868 -227.968299) (xy 355.084389 -227.974433) (xy 355.133273 -227.988593) (xy 355.179252 -228.01041)
			(xy 355.221136 -228.03932) (xy 355.25784 -228.074575) (xy 355.288413 -228.115261) (xy 355.312064 -228.160324)
			(xy 355.32818 -228.208598) (xy 355.336344 -228.258832) (xy 355.336856 -228.284278) (xy 355.655384 -228.284278)
			(xy 355.659344 -228.235224) (xy 355.671121 -228.18744) (xy 355.690412 -228.142164) (xy 355.716715 -228.100568)
			(xy 355.74935 -228.063731) (xy 355.787471 -228.032606) (xy 355.830092 -228.007999) (xy 355.876108 -227.990547)
			(xy 355.924327 -227.980703) (xy 355.973502 -227.978722) (xy 356.022357 -227.984654) (xy 356.069628 -227.998346)
			(xy 356.11409 -228.019444) (xy 356.154593 -228.0474) (xy 356.190086 -228.081492) (xy 356.219651 -228.120836)
			(xy 356.242522 -228.164413) (xy 356.258106 -228.211094) (xy 356.266001 -228.259671) (xy 356.266496 -228.284278)
			(xy 356.266001 -228.308885) (xy 356.258106 -228.357462) (xy 356.242522 -228.404143) (xy 356.219651 -228.44772)
			(xy 356.190086 -228.487064) (xy 356.154593 -228.521156) (xy 356.11409 -228.549112) (xy 356.069628 -228.57021)
			(xy 356.022357 -228.583902) (xy 355.973502 -228.589834) (xy 355.924327 -228.587853) (xy 355.876108 -228.578009)
			(xy 355.830092 -228.560557) (xy 355.787471 -228.53595) (xy 355.74935 -228.504825) (xy 355.716715 -228.467988)
			(xy 355.690412 -228.426392) (xy 355.671121 -228.381116) (xy 355.659344 -228.333332) (xy 355.655384 -228.284278)
			(xy 355.336856 -228.284278) (xy 355.336344 -228.309724) (xy 355.32818 -228.359958) (xy 355.312064 -228.408232)
			(xy 355.288413 -228.453295) (xy 355.25784 -228.493981) (xy 355.221136 -228.529236) (xy 355.179252 -228.558146)
			(xy 355.133273 -228.579963) (xy 355.084389 -228.594123) (xy 355.033868 -228.600257) (xy 354.983016 -228.598208)
			(xy 354.933152 -228.588028) (xy 354.885566 -228.569981) (xy 354.841492 -228.544535) (xy 354.80207 -228.512348)
			(xy 354.768322 -228.474254) (xy 354.741121 -228.43124) (xy 354.721173 -228.38442) (xy 354.708994 -228.335006)
			(xy 354.704899 -228.284278) (xy 354.396802 -228.284278) (xy 354.39629 -228.309724) (xy 354.388126 -228.359958)
			(xy 354.37201 -228.408232) (xy 354.348359 -228.453295) (xy 354.317786 -228.493981) (xy 354.281082 -228.529236)
			(xy 354.239198 -228.558146) (xy 354.193219 -228.579963) (xy 354.144335 -228.594123) (xy 354.093814 -228.600257)
			(xy 354.042962 -228.598208) (xy 353.993098 -228.588028) (xy 353.945512 -228.569981) (xy 353.901438 -228.544535)
			(xy 353.862016 -228.512348) (xy 353.828268 -228.474254) (xy 353.801067 -228.43124) (xy 353.781119 -228.38442)
			(xy 353.76894 -228.335006) (xy 353.764845 -228.284278) (xy 353.446334 -228.284278) (xy 353.445839 -228.308885)
			(xy 353.437944 -228.357462) (xy 353.42236 -228.404143) (xy 353.399489 -228.44772) (xy 353.369924 -228.487064)
			(xy 353.334431 -228.521156) (xy 353.293928 -228.549112) (xy 353.249466 -228.57021) (xy 353.202195 -228.583902)
			(xy 353.15334 -228.589834) (xy 353.104165 -228.587853) (xy 353.055946 -228.578009) (xy 353.00993 -228.560557)
			(xy 352.967309 -228.53595) (xy 352.929188 -228.504825) (xy 352.896553 -228.467988) (xy 352.87025 -228.426392)
			(xy 352.850959 -228.381116) (xy 352.839182 -228.333332) (xy 352.835222 -228.284278) (xy 352.516948 -228.284278)
			(xy 352.516436 -228.309724) (xy 352.508272 -228.359958) (xy 352.492156 -228.408232) (xy 352.468505 -228.453295)
			(xy 352.437932 -228.493981) (xy 352.401228 -228.529236) (xy 352.359344 -228.558146) (xy 352.313365 -228.579963)
			(xy 352.264481 -228.594123) (xy 352.21396 -228.600257) (xy 352.163108 -228.598208) (xy 352.113244 -228.588028)
			(xy 352.065658 -228.569981) (xy 352.021584 -228.544535) (xy 351.982162 -228.512348) (xy 351.948414 -228.474254)
			(xy 351.921213 -228.43124) (xy 351.901265 -228.38442) (xy 351.889086 -228.335006) (xy 351.884991 -228.284278)
			(xy 351.576894 -228.284278) (xy 351.576382 -228.309724) (xy 351.568218 -228.359958) (xy 351.552102 -228.408232)
			(xy 351.528451 -228.453295) (xy 351.497878 -228.493981) (xy 351.461174 -228.529236) (xy 351.41929 -228.558146)
			(xy 351.373311 -228.579963) (xy 351.324427 -228.594123) (xy 351.273906 -228.600257) (xy 351.223054 -228.598208)
			(xy 351.17319 -228.588028) (xy 351.125604 -228.569981) (xy 351.08153 -228.544535) (xy 351.042108 -228.512348)
			(xy 351.00836 -228.474254) (xy 350.981159 -228.43124) (xy 350.961211 -228.38442) (xy 350.949032 -228.335006)
			(xy 350.944937 -228.284278) (xy 350.626426 -228.284278) (xy 350.625931 -228.308885) (xy 350.618036 -228.357462)
			(xy 350.602452 -228.404143) (xy 350.579581 -228.44772) (xy 350.550016 -228.487064) (xy 350.514523 -228.521156)
			(xy 350.47402 -228.549112) (xy 350.429558 -228.57021) (xy 350.382287 -228.583902) (xy 350.333432 -228.589834)
			(xy 350.284257 -228.587853) (xy 350.236038 -228.578009) (xy 350.190022 -228.560557) (xy 350.147401 -228.53595)
			(xy 350.10928 -228.504825) (xy 350.076645 -228.467988) (xy 350.050342 -228.426392) (xy 350.031051 -228.381116)
			(xy 350.019274 -228.333332) (xy 350.015314 -228.284278) (xy 349.696786 -228.284278) (xy 349.696274 -228.309724)
			(xy 349.68811 -228.359958) (xy 349.671994 -228.408232) (xy 349.648343 -228.453295) (xy 349.61777 -228.493981)
			(xy 349.581066 -228.529236) (xy 349.539182 -228.558146) (xy 349.493203 -228.579963) (xy 349.444319 -228.594123)
			(xy 349.393798 -228.600257) (xy 349.342946 -228.598208) (xy 349.293082 -228.588028) (xy 349.245496 -228.569981)
			(xy 349.201422 -228.544535) (xy 349.162 -228.512348) (xy 349.128252 -228.474254) (xy 349.101051 -228.43124)
			(xy 349.081103 -228.38442) (xy 349.068924 -228.335006) (xy 349.064829 -228.284278) (xy 348.756732 -228.284278)
			(xy 348.75622 -228.309724) (xy 348.748056 -228.359958) (xy 348.73194 -228.408232) (xy 348.708289 -228.453295)
			(xy 348.677716 -228.493981) (xy 348.641012 -228.529236) (xy 348.599128 -228.558146) (xy 348.553149 -228.579963)
			(xy 348.504265 -228.594123) (xy 348.453744 -228.600257) (xy 348.402892 -228.598208) (xy 348.353028 -228.588028)
			(xy 348.305442 -228.569981) (xy 348.261368 -228.544535) (xy 348.221946 -228.512348) (xy 348.188198 -228.474254)
			(xy 348.160997 -228.43124) (xy 348.141049 -228.38442) (xy 348.12887 -228.335006) (xy 348.124775 -228.284278)
			(xy 347.806518 -228.284278) (xy 347.806023 -228.308885) (xy 347.798128 -228.357462) (xy 347.782544 -228.404143)
			(xy 347.759673 -228.44772) (xy 347.730108 -228.487064) (xy 347.694615 -228.521156) (xy 347.654112 -228.549112)
			(xy 347.60965 -228.57021) (xy 347.562379 -228.583902) (xy 347.513524 -228.589834) (xy 347.464349 -228.587853)
			(xy 347.41613 -228.578009) (xy 347.370114 -228.560557) (xy 347.327493 -228.53595) (xy 347.289372 -228.504825)
			(xy 347.256737 -228.467988) (xy 347.230434 -228.426392) (xy 347.211143 -228.381116) (xy 347.199366 -228.333332)
			(xy 347.195406 -228.284278) (xy 346.876878 -228.284278) (xy 346.876366 -228.309724) (xy 346.868202 -228.359958)
			(xy 346.852086 -228.408232) (xy 346.828435 -228.453295) (xy 346.797862 -228.493981) (xy 346.761158 -228.529236)
			(xy 346.719274 -228.558146) (xy 346.673295 -228.579963) (xy 346.624411 -228.594123) (xy 346.57389 -228.600257)
			(xy 346.523038 -228.598208) (xy 346.473174 -228.588028) (xy 346.425588 -228.569981) (xy 346.381514 -228.544535)
			(xy 346.342092 -228.512348) (xy 346.308344 -228.474254) (xy 346.281143 -228.43124) (xy 346.261195 -228.38442)
			(xy 346.249016 -228.335006) (xy 346.244921 -228.284278) (xy 345.936824 -228.284278) (xy 345.936312 -228.309724)
			(xy 345.928148 -228.359958) (xy 345.912032 -228.408232) (xy 345.888381 -228.453295) (xy 345.857808 -228.493981)
			(xy 345.821104 -228.529236) (xy 345.77922 -228.558146) (xy 345.733241 -228.579963) (xy 345.684357 -228.594123)
			(xy 345.633836 -228.600257) (xy 345.582984 -228.598208) (xy 345.53312 -228.588028) (xy 345.485534 -228.569981)
			(xy 345.44146 -228.544535) (xy 345.402038 -228.512348) (xy 345.36829 -228.474254) (xy 345.341089 -228.43124)
			(xy 345.321141 -228.38442) (xy 345.308962 -228.335006) (xy 345.304867 -228.284278) (xy 344.986356 -228.284278)
			(xy 344.985861 -228.308885) (xy 344.977966 -228.357462) (xy 344.962382 -228.404143) (xy 344.939511 -228.44772)
			(xy 344.909946 -228.487064) (xy 344.874453 -228.521156) (xy 344.83395 -228.549112) (xy 344.789488 -228.57021)
			(xy 344.742217 -228.583902) (xy 344.693362 -228.589834) (xy 344.644187 -228.587853) (xy 344.595968 -228.578009)
			(xy 344.549952 -228.560557) (xy 344.507331 -228.53595) (xy 344.46921 -228.504825) (xy 344.436575 -228.467988)
			(xy 344.410272 -228.426392) (xy 344.390981 -228.381116) (xy 344.379204 -228.333332) (xy 344.375244 -228.284278)
			(xy 344.11666 -228.284278) (xy 344.11666 -228.687376) (xy 344.117129 -228.697249) (xy 344.124583 -228.715537)
			(xy 344.131138 -228.722936) (xy 344.181176 -228.773736) (xy 344.188324 -228.780412) (xy 344.20622 -228.788259)
			(xy 344.215974 -228.788976) (xy 344.216482 -228.788976) (xy 344.24144 -228.789913) (xy 344.290566 -228.798907)
			(xy 344.337574 -228.815775) (xy 344.38121 -228.840067) (xy 344.420312 -228.871136) (xy 344.453837 -228.908153)
			(xy 344.480892 -228.950133) (xy 344.500755 -228.995955) (xy 344.512897 -229.044399) (xy 344.516995 -229.094173)
			(xy 344.516986 -229.094284) (xy 344.845398 -229.094284) (xy 344.849358 -229.04523) (xy 344.861135 -228.997446)
			(xy 344.880426 -228.95217) (xy 344.906729 -228.910574) (xy 344.939364 -228.873737) (xy 344.977485 -228.842612)
			(xy 345.020106 -228.818005) (xy 345.066122 -228.800553) (xy 345.114341 -228.790709) (xy 345.163516 -228.788728)
			(xy 345.212371 -228.79466) (xy 345.259642 -228.808352) (xy 345.304104 -228.82945) (xy 345.344607 -228.857406)
			(xy 345.3801 -228.891498) (xy 345.409665 -228.930842) (xy 345.432536 -228.974419) (xy 345.44812 -229.0211)
			(xy 345.456015 -229.069677) (xy 345.45651 -229.094284) (xy 345.785198 -229.094284) (xy 345.789158 -229.04523)
			(xy 345.800935 -228.997446) (xy 345.820226 -228.95217) (xy 345.846529 -228.910574) (xy 345.879164 -228.873737)
			(xy 345.917285 -228.842612) (xy 345.959906 -228.818005) (xy 346.005922 -228.800553) (xy 346.054141 -228.790709)
			(xy 346.103316 -228.788728) (xy 346.152171 -228.79466) (xy 346.199442 -228.808352) (xy 346.243904 -228.82945)
			(xy 346.284407 -228.857406) (xy 346.3199 -228.891498) (xy 346.349465 -228.930842) (xy 346.372336 -228.974419)
			(xy 346.38792 -229.0211) (xy 346.395815 -229.069677) (xy 346.39631 -229.094284) (xy 346.725252 -229.094284)
			(xy 346.729212 -229.04523) (xy 346.740989 -228.997446) (xy 346.76028 -228.95217) (xy 346.786583 -228.910574)
			(xy 346.819218 -228.873737) (xy 346.857339 -228.842612) (xy 346.89996 -228.818005) (xy 346.945976 -228.800553)
			(xy 346.994195 -228.790709) (xy 347.04337 -228.788728) (xy 347.092225 -228.79466) (xy 347.139496 -228.808352)
			(xy 347.183958 -228.82945) (xy 347.224461 -228.857406) (xy 347.259954 -228.891498) (xy 347.289519 -228.930842)
			(xy 347.31239 -228.974419) (xy 347.327974 -229.0211) (xy 347.335869 -229.069677) (xy 347.336364 -229.094284)
			(xy 347.665306 -229.094284) (xy 347.669266 -229.04523) (xy 347.681043 -228.997446) (xy 347.700334 -228.95217)
			(xy 347.726637 -228.910574) (xy 347.759272 -228.873737) (xy 347.797393 -228.842612) (xy 347.840014 -228.818005)
			(xy 347.88603 -228.800553) (xy 347.934249 -228.790709) (xy 347.983424 -228.788728) (xy 348.032279 -228.79466)
			(xy 348.07955 -228.808352) (xy 348.124012 -228.82945) (xy 348.164515 -228.857406) (xy 348.200008 -228.891498)
			(xy 348.229573 -228.930842) (xy 348.252444 -228.974419) (xy 348.268028 -229.0211) (xy 348.275923 -229.069677)
			(xy 348.276418 -229.094284) (xy 348.60536 -229.094284) (xy 348.60932 -229.04523) (xy 348.621097 -228.997446)
			(xy 348.640388 -228.95217) (xy 348.666691 -228.910574) (xy 348.699326 -228.873737) (xy 348.737447 -228.842612)
			(xy 348.780068 -228.818005) (xy 348.826084 -228.800553) (xy 348.874303 -228.790709) (xy 348.923478 -228.788728)
			(xy 348.972333 -228.79466) (xy 349.019604 -228.808352) (xy 349.064066 -228.82945) (xy 349.104569 -228.857406)
			(xy 349.140062 -228.891498) (xy 349.169627 -228.930842) (xy 349.192498 -228.974419) (xy 349.208082 -229.0211)
			(xy 349.215977 -229.069677) (xy 349.216472 -229.094284) (xy 349.545414 -229.094284) (xy 349.549374 -229.04523)
			(xy 349.561151 -228.997446) (xy 349.580442 -228.95217) (xy 349.606745 -228.910574) (xy 349.63938 -228.873737)
			(xy 349.677501 -228.842612) (xy 349.720122 -228.818005) (xy 349.766138 -228.800553) (xy 349.814357 -228.790709)
			(xy 349.863532 -228.788728) (xy 349.912387 -228.79466) (xy 349.959658 -228.808352) (xy 350.00412 -228.82945)
			(xy 350.044623 -228.857406) (xy 350.080116 -228.891498) (xy 350.109681 -228.930842) (xy 350.132552 -228.974419)
			(xy 350.148136 -229.0211) (xy 350.156031 -229.069677) (xy 350.156526 -229.094284) (xy 350.485214 -229.094284)
			(xy 350.489174 -229.04523) (xy 350.500951 -228.997446) (xy 350.520242 -228.95217) (xy 350.546545 -228.910574)
			(xy 350.57918 -228.873737) (xy 350.617301 -228.842612) (xy 350.659922 -228.818005) (xy 350.705938 -228.800553)
			(xy 350.754157 -228.790709) (xy 350.803332 -228.788728) (xy 350.852187 -228.79466) (xy 350.899458 -228.808352)
			(xy 350.94392 -228.82945) (xy 350.984423 -228.857406) (xy 351.019916 -228.891498) (xy 351.049481 -228.930842)
			(xy 351.072352 -228.974419) (xy 351.087936 -229.0211) (xy 351.095831 -229.069677) (xy 351.096326 -229.094284)
			(xy 351.425268 -229.094284) (xy 351.429228 -229.04523) (xy 351.441005 -228.997446) (xy 351.460296 -228.95217)
			(xy 351.486599 -228.910574) (xy 351.519234 -228.873737) (xy 351.557355 -228.842612) (xy 351.599976 -228.818005)
			(xy 351.645992 -228.800553) (xy 351.694211 -228.790709) (xy 351.743386 -228.788728) (xy 351.792241 -228.79466)
			(xy 351.839512 -228.808352) (xy 351.883974 -228.82945) (xy 351.924477 -228.857406) (xy 351.95997 -228.891498)
			(xy 351.989535 -228.930842) (xy 352.012406 -228.974419) (xy 352.02799 -229.0211) (xy 352.035885 -229.069677)
			(xy 352.03638 -229.094284) (xy 352.365322 -229.094284) (xy 352.369282 -229.04523) (xy 352.381059 -228.997446)
			(xy 352.40035 -228.95217) (xy 352.426653 -228.910574) (xy 352.459288 -228.873737) (xy 352.497409 -228.842612)
			(xy 352.54003 -228.818005) (xy 352.586046 -228.800553) (xy 352.634265 -228.790709) (xy 352.68344 -228.788728)
			(xy 352.732295 -228.79466) (xy 352.779566 -228.808352) (xy 352.824028 -228.82945) (xy 352.864531 -228.857406)
			(xy 352.900024 -228.891498) (xy 352.929589 -228.930842) (xy 352.95246 -228.974419) (xy 352.968044 -229.0211)
			(xy 352.975939 -229.069677) (xy 352.976434 -229.094284) (xy 353.305376 -229.094284) (xy 353.309336 -229.04523)
			(xy 353.321113 -228.997446) (xy 353.340404 -228.95217) (xy 353.366707 -228.910574) (xy 353.399342 -228.873737)
			(xy 353.437463 -228.842612) (xy 353.480084 -228.818005) (xy 353.5261 -228.800553) (xy 353.574319 -228.790709)
			(xy 353.623494 -228.788728) (xy 353.672349 -228.79466) (xy 353.71962 -228.808352) (xy 353.764082 -228.82945)
			(xy 353.804585 -228.857406) (xy 353.840078 -228.891498) (xy 353.869643 -228.930842) (xy 353.892514 -228.974419)
			(xy 353.908098 -229.0211) (xy 353.915993 -229.069677) (xy 353.916488 -229.094284) (xy 354.24543 -229.094284)
			(xy 354.24939 -229.04523) (xy 354.261167 -228.997446) (xy 354.280458 -228.95217) (xy 354.306761 -228.910574)
			(xy 354.339396 -228.873737) (xy 354.377517 -228.842612) (xy 354.420138 -228.818005) (xy 354.466154 -228.800553)
			(xy 354.514373 -228.790709) (xy 354.563548 -228.788728) (xy 354.612403 -228.79466) (xy 354.659674 -228.808352)
			(xy 354.704136 -228.82945) (xy 354.744639 -228.857406) (xy 354.780132 -228.891498) (xy 354.809697 -228.930842)
			(xy 354.832568 -228.974419) (xy 354.848152 -229.0211) (xy 354.856047 -229.069677) (xy 354.856542 -229.094284)
			(xy 355.18523 -229.094284) (xy 355.18919 -229.04523) (xy 355.200967 -228.997446) (xy 355.220258 -228.95217)
			(xy 355.246561 -228.910574) (xy 355.279196 -228.873737) (xy 355.317317 -228.842612) (xy 355.359938 -228.818005)
			(xy 355.405954 -228.800553) (xy 355.454173 -228.790709) (xy 355.503348 -228.788728) (xy 355.552203 -228.79466)
			(xy 355.599474 -228.808352) (xy 355.643936 -228.82945) (xy 355.684439 -228.857406) (xy 355.719932 -228.891498)
			(xy 355.749497 -228.930842) (xy 355.772368 -228.974419) (xy 355.787952 -229.0211) (xy 355.795847 -229.069677)
			(xy 355.796342 -229.094284) (xy 356.114853 -229.094284) (xy 356.118948 -229.043556) (xy 356.131127 -228.994142)
			(xy 356.151075 -228.947322) (xy 356.178276 -228.904308) (xy 356.212024 -228.866214) (xy 356.251446 -228.834027)
			(xy 356.29552 -228.808581) (xy 356.343106 -228.790534) (xy 356.39297 -228.780354) (xy 356.443822 -228.778305)
			(xy 356.494343 -228.784439) (xy 356.543227 -228.798599) (xy 356.589206 -228.820416) (xy 356.63109 -228.849326)
			(xy 356.667794 -228.884581) (xy 356.698367 -228.925267) (xy 356.722018 -228.97033) (xy 356.738134 -229.018604)
			(xy 356.746298 -229.068838) (xy 356.74681 -229.094284) (xy 357.054907 -229.094284) (xy 357.059002 -229.043556)
			(xy 357.071181 -228.994142) (xy 357.091129 -228.947322) (xy 357.11833 -228.904308) (xy 357.152078 -228.866214)
			(xy 357.1915 -228.834027) (xy 357.235574 -228.808581) (xy 357.28316 -228.790534) (xy 357.333024 -228.780354)
			(xy 357.383876 -228.778305) (xy 357.434397 -228.784439) (xy 357.483281 -228.798599) (xy 357.52926 -228.820416)
			(xy 357.571144 -228.849326) (xy 357.607848 -228.884581) (xy 357.638421 -228.925267) (xy 357.662072 -228.97033)
			(xy 357.678188 -229.018604) (xy 357.686352 -229.068838) (xy 357.686864 -229.094284) (xy 357.686352 -229.11973)
			(xy 357.678188 -229.169964) (xy 357.662072 -229.218238) (xy 357.638421 -229.263301) (xy 357.607848 -229.303987)
			(xy 357.571144 -229.339242) (xy 357.52926 -229.368152) (xy 357.483281 -229.389969) (xy 357.434397 -229.404129)
			(xy 357.383876 -229.410263) (xy 357.333024 -229.408214) (xy 357.28316 -229.398034) (xy 357.235574 -229.379987)
			(xy 357.1915 -229.354541) (xy 357.152078 -229.322354) (xy 357.11833 -229.28426) (xy 357.091129 -229.241246)
			(xy 357.071181 -229.194426) (xy 357.059002 -229.145012) (xy 357.054907 -229.094284) (xy 356.74681 -229.094284)
			(xy 356.746298 -229.11973) (xy 356.738134 -229.169964) (xy 356.722018 -229.218238) (xy 356.698367 -229.263301)
			(xy 356.667794 -229.303987) (xy 356.63109 -229.339242) (xy 356.589206 -229.368152) (xy 356.543227 -229.389969)
			(xy 356.494343 -229.404129) (xy 356.443822 -229.410263) (xy 356.39297 -229.408214) (xy 356.343106 -229.398034)
			(xy 356.29552 -229.379987) (xy 356.251446 -229.354541) (xy 356.212024 -229.322354) (xy 356.178276 -229.28426)
			(xy 356.151075 -229.241246) (xy 356.131127 -229.194426) (xy 356.118948 -229.145012) (xy 356.114853 -229.094284)
			(xy 355.796342 -229.094284) (xy 355.795847 -229.118891) (xy 355.787952 -229.167468) (xy 355.772368 -229.214149)
			(xy 355.749497 -229.257726) (xy 355.719932 -229.29707) (xy 355.684439 -229.331162) (xy 355.643936 -229.359118)
			(xy 355.599474 -229.380216) (xy 355.552203 -229.393908) (xy 355.503348 -229.39984) (xy 355.454173 -229.397859)
			(xy 355.405954 -229.388015) (xy 355.359938 -229.370563) (xy 355.317317 -229.345956) (xy 355.279196 -229.314831)
			(xy 355.246561 -229.277994) (xy 355.220258 -229.236398) (xy 355.200967 -229.191122) (xy 355.18919 -229.143338)
			(xy 355.18523 -229.094284) (xy 354.856542 -229.094284) (xy 354.856047 -229.118891) (xy 354.848152 -229.167468)
			(xy 354.832568 -229.214149) (xy 354.809697 -229.257726) (xy 354.780132 -229.29707) (xy 354.744639 -229.331162)
			(xy 354.704136 -229.359118) (xy 354.659674 -229.380216) (xy 354.612403 -229.393908) (xy 354.563548 -229.39984)
			(xy 354.514373 -229.397859) (xy 354.466154 -229.388015) (xy 354.420138 -229.370563) (xy 354.377517 -229.345956)
			(xy 354.339396 -229.314831) (xy 354.306761 -229.277994) (xy 354.280458 -229.236398) (xy 354.261167 -229.191122)
			(xy 354.24939 -229.143338) (xy 354.24543 -229.094284) (xy 353.916488 -229.094284) (xy 353.915993 -229.118891)
			(xy 353.908098 -229.167468) (xy 353.892514 -229.214149) (xy 353.869643 -229.257726) (xy 353.840078 -229.29707)
			(xy 353.804585 -229.331162) (xy 353.764082 -229.359118) (xy 353.71962 -229.380216) (xy 353.672349 -229.393908)
			(xy 353.623494 -229.39984) (xy 353.574319 -229.397859) (xy 353.5261 -229.388015) (xy 353.480084 -229.370563)
			(xy 353.437463 -229.345956) (xy 353.399342 -229.314831) (xy 353.366707 -229.277994) (xy 353.340404 -229.236398)
			(xy 353.321113 -229.191122) (xy 353.309336 -229.143338) (xy 353.305376 -229.094284) (xy 352.976434 -229.094284)
			(xy 352.975939 -229.118891) (xy 352.968044 -229.167468) (xy 352.95246 -229.214149) (xy 352.929589 -229.257726)
			(xy 352.900024 -229.29707) (xy 352.864531 -229.331162) (xy 352.824028 -229.359118) (xy 352.779566 -229.380216)
			(xy 352.732295 -229.393908) (xy 352.68344 -229.39984) (xy 352.634265 -229.397859) (xy 352.586046 -229.388015)
			(xy 352.54003 -229.370563) (xy 352.497409 -229.345956) (xy 352.459288 -229.314831) (xy 352.426653 -229.277994)
			(xy 352.40035 -229.236398) (xy 352.381059 -229.191122) (xy 352.369282 -229.143338) (xy 352.365322 -229.094284)
			(xy 352.03638 -229.094284) (xy 352.035885 -229.118891) (xy 352.02799 -229.167468) (xy 352.012406 -229.214149)
			(xy 351.989535 -229.257726) (xy 351.95997 -229.29707) (xy 351.924477 -229.331162) (xy 351.883974 -229.359118)
			(xy 351.839512 -229.380216) (xy 351.792241 -229.393908) (xy 351.743386 -229.39984) (xy 351.694211 -229.397859)
			(xy 351.645992 -229.388015) (xy 351.599976 -229.370563) (xy 351.557355 -229.345956) (xy 351.519234 -229.314831)
			(xy 351.486599 -229.277994) (xy 351.460296 -229.236398) (xy 351.441005 -229.191122) (xy 351.429228 -229.143338)
			(xy 351.425268 -229.094284) (xy 351.096326 -229.094284) (xy 351.095831 -229.118891) (xy 351.087936 -229.167468)
			(xy 351.072352 -229.214149) (xy 351.049481 -229.257726) (xy 351.019916 -229.29707) (xy 350.984423 -229.331162)
			(xy 350.94392 -229.359118) (xy 350.899458 -229.380216) (xy 350.852187 -229.393908) (xy 350.803332 -229.39984)
			(xy 350.754157 -229.397859) (xy 350.705938 -229.388015) (xy 350.659922 -229.370563) (xy 350.617301 -229.345956)
			(xy 350.57918 -229.314831) (xy 350.546545 -229.277994) (xy 350.520242 -229.236398) (xy 350.500951 -229.191122)
			(xy 350.489174 -229.143338) (xy 350.485214 -229.094284) (xy 350.156526 -229.094284) (xy 350.156031 -229.118891)
			(xy 350.148136 -229.167468) (xy 350.132552 -229.214149) (xy 350.109681 -229.257726) (xy 350.080116 -229.29707)
			(xy 350.044623 -229.331162) (xy 350.00412 -229.359118) (xy 349.959658 -229.380216) (xy 349.912387 -229.393908)
			(xy 349.863532 -229.39984) (xy 349.814357 -229.397859) (xy 349.766138 -229.388015) (xy 349.720122 -229.370563)
			(xy 349.677501 -229.345956) (xy 349.63938 -229.314831) (xy 349.606745 -229.277994) (xy 349.580442 -229.236398)
			(xy 349.561151 -229.191122) (xy 349.549374 -229.143338) (xy 349.545414 -229.094284) (xy 349.216472 -229.094284)
			(xy 349.215977 -229.118891) (xy 349.208082 -229.167468) (xy 349.192498 -229.214149) (xy 349.169627 -229.257726)
			(xy 349.140062 -229.29707) (xy 349.104569 -229.331162) (xy 349.064066 -229.359118) (xy 349.019604 -229.380216)
			(xy 348.972333 -229.393908) (xy 348.923478 -229.39984) (xy 348.874303 -229.397859) (xy 348.826084 -229.388015)
			(xy 348.780068 -229.370563) (xy 348.737447 -229.345956) (xy 348.699326 -229.314831) (xy 348.666691 -229.277994)
			(xy 348.640388 -229.236398) (xy 348.621097 -229.191122) (xy 348.60932 -229.143338) (xy 348.60536 -229.094284)
			(xy 348.276418 -229.094284) (xy 348.275923 -229.118891) (xy 348.268028 -229.167468) (xy 348.252444 -229.214149)
			(xy 348.229573 -229.257726) (xy 348.200008 -229.29707) (xy 348.164515 -229.331162) (xy 348.124012 -229.359118)
			(xy 348.07955 -229.380216) (xy 348.032279 -229.393908) (xy 347.983424 -229.39984) (xy 347.934249 -229.397859)
			(xy 347.88603 -229.388015) (xy 347.840014 -229.370563) (xy 347.797393 -229.345956) (xy 347.759272 -229.314831)
			(xy 347.726637 -229.277994) (xy 347.700334 -229.236398) (xy 347.681043 -229.191122) (xy 347.669266 -229.143338)
			(xy 347.665306 -229.094284) (xy 347.336364 -229.094284) (xy 347.335869 -229.118891) (xy 347.327974 -229.167468)
			(xy 347.31239 -229.214149) (xy 347.289519 -229.257726) (xy 347.259954 -229.29707) (xy 347.224461 -229.331162)
			(xy 347.183958 -229.359118) (xy 347.139496 -229.380216) (xy 347.092225 -229.393908) (xy 347.04337 -229.39984)
			(xy 346.994195 -229.397859) (xy 346.945976 -229.388015) (xy 346.89996 -229.370563) (xy 346.857339 -229.345956)
			(xy 346.819218 -229.314831) (xy 346.786583 -229.277994) (xy 346.76028 -229.236398) (xy 346.740989 -229.191122)
			(xy 346.729212 -229.143338) (xy 346.725252 -229.094284) (xy 346.39631 -229.094284) (xy 346.395815 -229.118891)
			(xy 346.38792 -229.167468) (xy 346.372336 -229.214149) (xy 346.349465 -229.257726) (xy 346.3199 -229.29707)
			(xy 346.284407 -229.331162) (xy 346.243904 -229.359118) (xy 346.199442 -229.380216) (xy 346.152171 -229.393908)
			(xy 346.103316 -229.39984) (xy 346.054141 -229.397859) (xy 346.005922 -229.388015) (xy 345.959906 -229.370563)
			(xy 345.917285 -229.345956) (xy 345.879164 -229.314831) (xy 345.846529 -229.277994) (xy 345.820226 -229.236398)
			(xy 345.800935 -229.191122) (xy 345.789158 -229.143338) (xy 345.785198 -229.094284) (xy 345.45651 -229.094284)
			(xy 345.456015 -229.118891) (xy 345.44812 -229.167468) (xy 345.432536 -229.214149) (xy 345.409665 -229.257726)
			(xy 345.3801 -229.29707) (xy 345.344607 -229.331162) (xy 345.304104 -229.359118) (xy 345.259642 -229.380216)
			(xy 345.212371 -229.393908) (xy 345.163516 -229.39984) (xy 345.114341 -229.397859) (xy 345.066122 -229.388015)
			(xy 345.020106 -229.370563) (xy 344.977485 -229.345956) (xy 344.939364 -229.314831) (xy 344.906729 -229.277994)
			(xy 344.880426 -229.236398) (xy 344.861135 -229.191122) (xy 344.849358 -229.143338) (xy 344.845398 -229.094284)
			(xy 344.516986 -229.094284) (xy 344.512939 -229.14395) (xy 344.500837 -229.192404) (xy 344.481012 -229.238242)
			(xy 344.453992 -229.280244) (xy 344.420498 -229.31729) (xy 344.381422 -229.348391) (xy 344.337806 -229.372719)
			(xy 344.290812 -229.389626) (xy 344.241694 -229.398661) (xy 344.216736 -229.399592) (xy 344.215974 -229.399592)
			(xy 344.206224 -229.400325) (xy 344.18833 -229.408166) (xy 344.181176 -229.414832) (xy 344.131138 -229.465632)
			(xy 344.124554 -229.473013) (xy 344.117097 -229.491311) (xy 344.11666 -229.501192) (xy 344.11666 -229.904036)
			(xy 344.375244 -229.904036) (xy 344.379204 -229.854982) (xy 344.390981 -229.807198) (xy 344.410272 -229.761922)
			(xy 344.436575 -229.720326) (xy 344.46921 -229.683489) (xy 344.507331 -229.652364) (xy 344.549952 -229.627757)
			(xy 344.595968 -229.610305) (xy 344.644187 -229.600461) (xy 344.693362 -229.59848) (xy 344.742217 -229.604412)
			(xy 344.789488 -229.618104) (xy 344.83395 -229.639202) (xy 344.874453 -229.667158) (xy 344.909946 -229.70125)
			(xy 344.939511 -229.740594) (xy 344.962382 -229.784171) (xy 344.977966 -229.830852) (xy 344.985861 -229.879429)
			(xy 344.986356 -229.904036) (xy 345.304867 -229.904036) (xy 345.308962 -229.853308) (xy 345.321141 -229.803894)
			(xy 345.341089 -229.757074) (xy 345.36829 -229.71406) (xy 345.402038 -229.675966) (xy 345.44146 -229.643779)
			(xy 345.485534 -229.618333) (xy 345.53312 -229.600286) (xy 345.582984 -229.590106) (xy 345.633836 -229.588057)
			(xy 345.684357 -229.594191) (xy 345.733241 -229.608351) (xy 345.77922 -229.630168) (xy 345.821104 -229.659078)
			(xy 345.857808 -229.694333) (xy 345.888381 -229.735019) (xy 345.912032 -229.780082) (xy 345.928148 -229.828356)
			(xy 345.936312 -229.87859) (xy 345.936824 -229.904036) (xy 346.244921 -229.904036) (xy 346.249016 -229.853308)
			(xy 346.261195 -229.803894) (xy 346.281143 -229.757074) (xy 346.308344 -229.71406) (xy 346.342092 -229.675966)
			(xy 346.381514 -229.643779) (xy 346.425588 -229.618333) (xy 346.473174 -229.600286) (xy 346.523038 -229.590106)
			(xy 346.57389 -229.588057) (xy 346.624411 -229.594191) (xy 346.673295 -229.608351) (xy 346.719274 -229.630168)
			(xy 346.761158 -229.659078) (xy 346.797862 -229.694333) (xy 346.828435 -229.735019) (xy 346.852086 -229.780082)
			(xy 346.868202 -229.828356) (xy 346.876366 -229.87859) (xy 346.876878 -229.904036) (xy 347.195406 -229.904036)
			(xy 347.199366 -229.854982) (xy 347.211143 -229.807198) (xy 347.230434 -229.761922) (xy 347.256737 -229.720326)
			(xy 347.289372 -229.683489) (xy 347.327493 -229.652364) (xy 347.370114 -229.627757) (xy 347.41613 -229.610305)
			(xy 347.464349 -229.600461) (xy 347.513524 -229.59848) (xy 347.562379 -229.604412) (xy 347.60965 -229.618104)
			(xy 347.654112 -229.639202) (xy 347.694615 -229.667158) (xy 347.730108 -229.70125) (xy 347.759673 -229.740594)
			(xy 347.782544 -229.784171) (xy 347.798128 -229.830852) (xy 347.806023 -229.879429) (xy 347.806518 -229.904036)
			(xy 348.124775 -229.904036) (xy 348.12887 -229.853308) (xy 348.141049 -229.803894) (xy 348.160997 -229.757074)
			(xy 348.188198 -229.71406) (xy 348.221946 -229.675966) (xy 348.261368 -229.643779) (xy 348.305442 -229.618333)
			(xy 348.353028 -229.600286) (xy 348.402892 -229.590106) (xy 348.453744 -229.588057) (xy 348.504265 -229.594191)
			(xy 348.553149 -229.608351) (xy 348.599128 -229.630168) (xy 348.641012 -229.659078) (xy 348.677716 -229.694333)
			(xy 348.708289 -229.735019) (xy 348.73194 -229.780082) (xy 348.748056 -229.828356) (xy 348.75622 -229.87859)
			(xy 348.756732 -229.904036) (xy 349.064829 -229.904036) (xy 349.068924 -229.853308) (xy 349.081103 -229.803894)
			(xy 349.101051 -229.757074) (xy 349.128252 -229.71406) (xy 349.162 -229.675966) (xy 349.201422 -229.643779)
			(xy 349.245496 -229.618333) (xy 349.293082 -229.600286) (xy 349.342946 -229.590106) (xy 349.393798 -229.588057)
			(xy 349.444319 -229.594191) (xy 349.493203 -229.608351) (xy 349.539182 -229.630168) (xy 349.581066 -229.659078)
			(xy 349.61777 -229.694333) (xy 349.648343 -229.735019) (xy 349.671994 -229.780082) (xy 349.68811 -229.828356)
			(xy 349.696274 -229.87859) (xy 349.696786 -229.904036) (xy 350.015314 -229.904036) (xy 350.019274 -229.854982)
			(xy 350.031051 -229.807198) (xy 350.050342 -229.761922) (xy 350.076645 -229.720326) (xy 350.10928 -229.683489)
			(xy 350.147401 -229.652364) (xy 350.190022 -229.627757) (xy 350.236038 -229.610305) (xy 350.284257 -229.600461)
			(xy 350.333432 -229.59848) (xy 350.382287 -229.604412) (xy 350.429558 -229.618104) (xy 350.47402 -229.639202)
			(xy 350.514523 -229.667158) (xy 350.550016 -229.70125) (xy 350.579581 -229.740594) (xy 350.602452 -229.784171)
			(xy 350.618036 -229.830852) (xy 350.625931 -229.879429) (xy 350.626426 -229.904036) (xy 350.944937 -229.904036)
			(xy 350.949032 -229.853308) (xy 350.961211 -229.803894) (xy 350.981159 -229.757074) (xy 351.00836 -229.71406)
			(xy 351.042108 -229.675966) (xy 351.08153 -229.643779) (xy 351.125604 -229.618333) (xy 351.17319 -229.600286)
			(xy 351.223054 -229.590106) (xy 351.273906 -229.588057) (xy 351.324427 -229.594191) (xy 351.373311 -229.608351)
			(xy 351.41929 -229.630168) (xy 351.461174 -229.659078) (xy 351.497878 -229.694333) (xy 351.528451 -229.735019)
			(xy 351.552102 -229.780082) (xy 351.568218 -229.828356) (xy 351.576382 -229.87859) (xy 351.576894 -229.904036)
			(xy 351.884991 -229.904036) (xy 351.889086 -229.853308) (xy 351.901265 -229.803894) (xy 351.921213 -229.757074)
			(xy 351.948414 -229.71406) (xy 351.982162 -229.675966) (xy 352.021584 -229.643779) (xy 352.065658 -229.618333)
			(xy 352.113244 -229.600286) (xy 352.163108 -229.590106) (xy 352.21396 -229.588057) (xy 352.264481 -229.594191)
			(xy 352.313365 -229.608351) (xy 352.359344 -229.630168) (xy 352.401228 -229.659078) (xy 352.437932 -229.694333)
			(xy 352.468505 -229.735019) (xy 352.492156 -229.780082) (xy 352.508272 -229.828356) (xy 352.516436 -229.87859)
			(xy 352.516948 -229.904036) (xy 352.835222 -229.904036) (xy 352.839182 -229.854982) (xy 352.850959 -229.807198)
			(xy 352.87025 -229.761922) (xy 352.896553 -229.720326) (xy 352.929188 -229.683489) (xy 352.967309 -229.652364)
			(xy 353.00993 -229.627757) (xy 353.055946 -229.610305) (xy 353.104165 -229.600461) (xy 353.15334 -229.59848)
			(xy 353.202195 -229.604412) (xy 353.249466 -229.618104) (xy 353.293928 -229.639202) (xy 353.334431 -229.667158)
			(xy 353.369924 -229.70125) (xy 353.399489 -229.740594) (xy 353.42236 -229.784171) (xy 353.437944 -229.830852)
			(xy 353.445839 -229.879429) (xy 353.446334 -229.904036) (xy 353.764845 -229.904036) (xy 353.76894 -229.853308)
			(xy 353.781119 -229.803894) (xy 353.801067 -229.757074) (xy 353.828268 -229.71406) (xy 353.862016 -229.675966)
			(xy 353.901438 -229.643779) (xy 353.945512 -229.618333) (xy 353.993098 -229.600286) (xy 354.042962 -229.590106)
			(xy 354.093814 -229.588057) (xy 354.144335 -229.594191) (xy 354.193219 -229.608351) (xy 354.239198 -229.630168)
			(xy 354.281082 -229.659078) (xy 354.317786 -229.694333) (xy 354.348359 -229.735019) (xy 354.37201 -229.780082)
			(xy 354.388126 -229.828356) (xy 354.39629 -229.87859) (xy 354.396802 -229.904036) (xy 354.704899 -229.904036)
			(xy 354.708994 -229.853308) (xy 354.721173 -229.803894) (xy 354.741121 -229.757074) (xy 354.768322 -229.71406)
			(xy 354.80207 -229.675966) (xy 354.841492 -229.643779) (xy 354.885566 -229.618333) (xy 354.933152 -229.600286)
			(xy 354.983016 -229.590106) (xy 355.033868 -229.588057) (xy 355.084389 -229.594191) (xy 355.133273 -229.608351)
			(xy 355.179252 -229.630168) (xy 355.221136 -229.659078) (xy 355.25784 -229.694333) (xy 355.288413 -229.735019)
			(xy 355.312064 -229.780082) (xy 355.32818 -229.828356) (xy 355.336344 -229.87859) (xy 355.336856 -229.904036)
			(xy 355.655384 -229.904036) (xy 355.659344 -229.854982) (xy 355.671121 -229.807198) (xy 355.690412 -229.761922)
			(xy 355.716715 -229.720326) (xy 355.74935 -229.683489) (xy 355.787471 -229.652364) (xy 355.830092 -229.627757)
			(xy 355.876108 -229.610305) (xy 355.924327 -229.600461) (xy 355.973502 -229.59848) (xy 356.022357 -229.604412)
			(xy 356.069628 -229.618104) (xy 356.11409 -229.639202) (xy 356.154593 -229.667158) (xy 356.190086 -229.70125)
			(xy 356.219651 -229.740594) (xy 356.242522 -229.784171) (xy 356.258106 -229.830852) (xy 356.266001 -229.879429)
			(xy 356.266496 -229.904036) (xy 356.595438 -229.904036) (xy 356.599398 -229.854982) (xy 356.611175 -229.807198)
			(xy 356.630466 -229.761922) (xy 356.656769 -229.720326) (xy 356.689404 -229.683489) (xy 356.727525 -229.652364)
			(xy 356.770146 -229.627757) (xy 356.816162 -229.610305) (xy 356.864381 -229.600461) (xy 356.913556 -229.59848)
			(xy 356.962411 -229.604412) (xy 357.009682 -229.618104) (xy 357.054144 -229.639202) (xy 357.094647 -229.667158)
			(xy 357.13014 -229.70125) (xy 357.159705 -229.740594) (xy 357.182576 -229.784171) (xy 357.19816 -229.830852)
			(xy 357.206055 -229.879429) (xy 357.20655 -229.904036) (xy 357.206055 -229.928643) (xy 357.19816 -229.97722)
			(xy 357.182576 -230.023901) (xy 357.159705 -230.067478) (xy 357.13014 -230.106822) (xy 357.094647 -230.140914)
			(xy 357.054144 -230.16887) (xy 357.009682 -230.189968) (xy 356.962411 -230.20366) (xy 356.913556 -230.209592)
			(xy 356.864381 -230.207611) (xy 356.816162 -230.197767) (xy 356.770146 -230.180315) (xy 356.727525 -230.155708)
			(xy 356.689404 -230.124583) (xy 356.656769 -230.087746) (xy 356.630466 -230.04615) (xy 356.611175 -230.000874)
			(xy 356.599398 -229.95309) (xy 356.595438 -229.904036) (xy 356.266496 -229.904036) (xy 356.266001 -229.928643)
			(xy 356.258106 -229.97722) (xy 356.242522 -230.023901) (xy 356.219651 -230.067478) (xy 356.190086 -230.106822)
			(xy 356.154593 -230.140914) (xy 356.11409 -230.16887) (xy 356.069628 -230.189968) (xy 356.022357 -230.20366)
			(xy 355.973502 -230.209592) (xy 355.924327 -230.207611) (xy 355.876108 -230.197767) (xy 355.830092 -230.180315)
			(xy 355.787471 -230.155708) (xy 355.74935 -230.124583) (xy 355.716715 -230.087746) (xy 355.690412 -230.04615)
			(xy 355.671121 -230.000874) (xy 355.659344 -229.95309) (xy 355.655384 -229.904036) (xy 355.336856 -229.904036)
			(xy 355.336344 -229.929482) (xy 355.32818 -229.979716) (xy 355.312064 -230.02799) (xy 355.288413 -230.073053)
			(xy 355.25784 -230.113739) (xy 355.221136 -230.148994) (xy 355.179252 -230.177904) (xy 355.133273 -230.199721)
			(xy 355.084389 -230.213881) (xy 355.033868 -230.220015) (xy 354.983016 -230.217966) (xy 354.933152 -230.207786)
			(xy 354.885566 -230.189739) (xy 354.841492 -230.164293) (xy 354.80207 -230.132106) (xy 354.768322 -230.094012)
			(xy 354.741121 -230.050998) (xy 354.721173 -230.004178) (xy 354.708994 -229.954764) (xy 354.704899 -229.904036)
			(xy 354.396802 -229.904036) (xy 354.39629 -229.929482) (xy 354.388126 -229.979716) (xy 354.37201 -230.02799)
			(xy 354.348359 -230.073053) (xy 354.317786 -230.113739) (xy 354.281082 -230.148994) (xy 354.239198 -230.177904)
			(xy 354.193219 -230.199721) (xy 354.144335 -230.213881) (xy 354.093814 -230.220015) (xy 354.042962 -230.217966)
			(xy 353.993098 -230.207786) (xy 353.945512 -230.189739) (xy 353.901438 -230.164293) (xy 353.862016 -230.132106)
			(xy 353.828268 -230.094012) (xy 353.801067 -230.050998) (xy 353.781119 -230.004178) (xy 353.76894 -229.954764)
			(xy 353.764845 -229.904036) (xy 353.446334 -229.904036) (xy 353.445839 -229.928643) (xy 353.437944 -229.97722)
			(xy 353.42236 -230.023901) (xy 353.399489 -230.067478) (xy 353.369924 -230.106822) (xy 353.334431 -230.140914)
			(xy 353.293928 -230.16887) (xy 353.249466 -230.189968) (xy 353.202195 -230.20366) (xy 353.15334 -230.209592)
			(xy 353.104165 -230.207611) (xy 353.055946 -230.197767) (xy 353.00993 -230.180315) (xy 352.967309 -230.155708)
			(xy 352.929188 -230.124583) (xy 352.896553 -230.087746) (xy 352.87025 -230.04615) (xy 352.850959 -230.000874)
			(xy 352.839182 -229.95309) (xy 352.835222 -229.904036) (xy 352.516948 -229.904036) (xy 352.516436 -229.929482)
			(xy 352.508272 -229.979716) (xy 352.492156 -230.02799) (xy 352.468505 -230.073053) (xy 352.437932 -230.113739)
			(xy 352.401228 -230.148994) (xy 352.359344 -230.177904) (xy 352.313365 -230.199721) (xy 352.264481 -230.213881)
			(xy 352.21396 -230.220015) (xy 352.163108 -230.217966) (xy 352.113244 -230.207786) (xy 352.065658 -230.189739)
			(xy 352.021584 -230.164293) (xy 351.982162 -230.132106) (xy 351.948414 -230.094012) (xy 351.921213 -230.050998)
			(xy 351.901265 -230.004178) (xy 351.889086 -229.954764) (xy 351.884991 -229.904036) (xy 351.576894 -229.904036)
			(xy 351.576382 -229.929482) (xy 351.568218 -229.979716) (xy 351.552102 -230.02799) (xy 351.528451 -230.073053)
			(xy 351.497878 -230.113739) (xy 351.461174 -230.148994) (xy 351.41929 -230.177904) (xy 351.373311 -230.199721)
			(xy 351.324427 -230.213881) (xy 351.273906 -230.220015) (xy 351.223054 -230.217966) (xy 351.17319 -230.207786)
			(xy 351.125604 -230.189739) (xy 351.08153 -230.164293) (xy 351.042108 -230.132106) (xy 351.00836 -230.094012)
			(xy 350.981159 -230.050998) (xy 350.961211 -230.004178) (xy 350.949032 -229.954764) (xy 350.944937 -229.904036)
			(xy 350.626426 -229.904036) (xy 350.625931 -229.928643) (xy 350.618036 -229.97722) (xy 350.602452 -230.023901)
			(xy 350.579581 -230.067478) (xy 350.550016 -230.106822) (xy 350.514523 -230.140914) (xy 350.47402 -230.16887)
			(xy 350.429558 -230.189968) (xy 350.382287 -230.20366) (xy 350.333432 -230.209592) (xy 350.284257 -230.207611)
			(xy 350.236038 -230.197767) (xy 350.190022 -230.180315) (xy 350.147401 -230.155708) (xy 350.10928 -230.124583)
			(xy 350.076645 -230.087746) (xy 350.050342 -230.04615) (xy 350.031051 -230.000874) (xy 350.019274 -229.95309)
			(xy 350.015314 -229.904036) (xy 349.696786 -229.904036) (xy 349.696274 -229.929482) (xy 349.68811 -229.979716)
			(xy 349.671994 -230.02799) (xy 349.648343 -230.073053) (xy 349.61777 -230.113739) (xy 349.581066 -230.148994)
			(xy 349.539182 -230.177904) (xy 349.493203 -230.199721) (xy 349.444319 -230.213881) (xy 349.393798 -230.220015)
			(xy 349.342946 -230.217966) (xy 349.293082 -230.207786) (xy 349.245496 -230.189739) (xy 349.201422 -230.164293)
			(xy 349.162 -230.132106) (xy 349.128252 -230.094012) (xy 349.101051 -230.050998) (xy 349.081103 -230.004178)
			(xy 349.068924 -229.954764) (xy 349.064829 -229.904036) (xy 348.756732 -229.904036) (xy 348.75622 -229.929482)
			(xy 348.748056 -229.979716) (xy 348.73194 -230.02799) (xy 348.708289 -230.073053) (xy 348.677716 -230.113739)
			(xy 348.641012 -230.148994) (xy 348.599128 -230.177904) (xy 348.553149 -230.199721) (xy 348.504265 -230.213881)
			(xy 348.453744 -230.220015) (xy 348.402892 -230.217966) (xy 348.353028 -230.207786) (xy 348.305442 -230.189739)
			(xy 348.261368 -230.164293) (xy 348.221946 -230.132106) (xy 348.188198 -230.094012) (xy 348.160997 -230.050998)
			(xy 348.141049 -230.004178) (xy 348.12887 -229.954764) (xy 348.124775 -229.904036) (xy 347.806518 -229.904036)
			(xy 347.806023 -229.928643) (xy 347.798128 -229.97722) (xy 347.782544 -230.023901) (xy 347.759673 -230.067478)
			(xy 347.730108 -230.106822) (xy 347.694615 -230.140914) (xy 347.654112 -230.16887) (xy 347.60965 -230.189968)
			(xy 347.562379 -230.20366) (xy 347.513524 -230.209592) (xy 347.464349 -230.207611) (xy 347.41613 -230.197767)
			(xy 347.370114 -230.180315) (xy 347.327493 -230.155708) (xy 347.289372 -230.124583) (xy 347.256737 -230.087746)
			(xy 347.230434 -230.04615) (xy 347.211143 -230.000874) (xy 347.199366 -229.95309) (xy 347.195406 -229.904036)
			(xy 346.876878 -229.904036) (xy 346.876366 -229.929482) (xy 346.868202 -229.979716) (xy 346.852086 -230.02799)
			(xy 346.828435 -230.073053) (xy 346.797862 -230.113739) (xy 346.761158 -230.148994) (xy 346.719274 -230.177904)
			(xy 346.673295 -230.199721) (xy 346.624411 -230.213881) (xy 346.57389 -230.220015) (xy 346.523038 -230.217966)
			(xy 346.473174 -230.207786) (xy 346.425588 -230.189739) (xy 346.381514 -230.164293) (xy 346.342092 -230.132106)
			(xy 346.308344 -230.094012) (xy 346.281143 -230.050998) (xy 346.261195 -230.004178) (xy 346.249016 -229.954764)
			(xy 346.244921 -229.904036) (xy 345.936824 -229.904036) (xy 345.936312 -229.929482) (xy 345.928148 -229.979716)
			(xy 345.912032 -230.02799) (xy 345.888381 -230.073053) (xy 345.857808 -230.113739) (xy 345.821104 -230.148994)
			(xy 345.77922 -230.177904) (xy 345.733241 -230.199721) (xy 345.684357 -230.213881) (xy 345.633836 -230.220015)
			(xy 345.582984 -230.217966) (xy 345.53312 -230.207786) (xy 345.485534 -230.189739) (xy 345.44146 -230.164293)
			(xy 345.402038 -230.132106) (xy 345.36829 -230.094012) (xy 345.341089 -230.050998) (xy 345.321141 -230.004178)
			(xy 345.308962 -229.954764) (xy 345.304867 -229.904036) (xy 344.986356 -229.904036) (xy 344.985861 -229.928643)
			(xy 344.977966 -229.97722) (xy 344.962382 -230.023901) (xy 344.939511 -230.067478) (xy 344.909946 -230.106822)
			(xy 344.874453 -230.140914) (xy 344.83395 -230.16887) (xy 344.789488 -230.189968) (xy 344.742217 -230.20366)
			(xy 344.693362 -230.209592) (xy 344.644187 -230.207611) (xy 344.595968 -230.197767) (xy 344.549952 -230.180315)
			(xy 344.507331 -230.155708) (xy 344.46921 -230.124583) (xy 344.436575 -230.087746) (xy 344.410272 -230.04615)
			(xy 344.390981 -230.000874) (xy 344.379204 -229.95309) (xy 344.375244 -229.904036) (xy 344.11666 -229.904036)
			(xy 344.11666 -230.307388) (xy 344.117132 -230.31726) (xy 344.124588 -230.335545) (xy 344.131138 -230.342948)
			(xy 344.181176 -230.393748) (xy 344.188324 -230.400423) (xy 344.206221 -230.408267) (xy 344.215974 -230.408988)
			(xy 344.216482 -230.408988) (xy 344.241439 -230.409925) (xy 344.290563 -230.418919) (xy 344.337569 -230.435786)
			(xy 344.381203 -230.460077) (xy 344.420304 -230.491145) (xy 344.453827 -230.528161) (xy 344.480881 -230.570139)
			(xy 344.500744 -230.615959) (xy 344.512885 -230.664401) (xy 344.516983 -230.714173) (xy 344.516973 -230.714296)
			(xy 346.725252 -230.714296) (xy 346.729212 -230.665242) (xy 346.740989 -230.617458) (xy 346.76028 -230.572182)
			(xy 346.786583 -230.530586) (xy 346.819218 -230.493749) (xy 346.857339 -230.462624) (xy 346.89996 -230.438017)
			(xy 346.945976 -230.420565) (xy 346.994195 -230.410721) (xy 347.04337 -230.40874) (xy 347.092225 -230.414672)
			(xy 347.139496 -230.428364) (xy 347.183958 -230.449462) (xy 347.224461 -230.477418) (xy 347.259954 -230.51151)
			(xy 347.289519 -230.550854) (xy 347.31239 -230.594431) (xy 347.327974 -230.641112) (xy 347.335869 -230.689689)
			(xy 347.336364 -230.714296) (xy 349.545414 -230.714296) (xy 349.549374 -230.665242) (xy 349.561151 -230.617458)
			(xy 349.580442 -230.572182) (xy 349.606745 -230.530586) (xy 349.63938 -230.493749) (xy 349.677501 -230.462624)
			(xy 349.720122 -230.438017) (xy 349.766138 -230.420565) (xy 349.814357 -230.410721) (xy 349.863532 -230.40874)
			(xy 349.912387 -230.414672) (xy 349.959658 -230.428364) (xy 350.00412 -230.449462) (xy 350.044623 -230.477418)
			(xy 350.080116 -230.51151) (xy 350.109681 -230.550854) (xy 350.132552 -230.594431) (xy 350.148136 -230.641112)
			(xy 350.156031 -230.689689) (xy 350.156526 -230.714296) (xy 352.365322 -230.714296) (xy 352.369282 -230.665242)
			(xy 352.381059 -230.617458) (xy 352.40035 -230.572182) (xy 352.426653 -230.530586) (xy 352.459288 -230.493749)
			(xy 352.497409 -230.462624) (xy 352.54003 -230.438017) (xy 352.586046 -230.420565) (xy 352.634265 -230.410721)
			(xy 352.68344 -230.40874) (xy 352.732295 -230.414672) (xy 352.779566 -230.428364) (xy 352.824028 -230.449462)
			(xy 352.864531 -230.477418) (xy 352.900024 -230.51151) (xy 352.929589 -230.550854) (xy 352.95246 -230.594431)
			(xy 352.968044 -230.641112) (xy 352.975939 -230.689689) (xy 352.976429 -230.714042) (xy 355.18523 -230.714042)
			(xy 355.18919 -230.664988) (xy 355.200967 -230.617204) (xy 355.220258 -230.571928) (xy 355.246561 -230.530332)
			(xy 355.279196 -230.493495) (xy 355.317317 -230.46237) (xy 355.359938 -230.437763) (xy 355.405954 -230.420311)
			(xy 355.454173 -230.410467) (xy 355.503348 -230.408486) (xy 355.552203 -230.414418) (xy 355.599474 -230.42811)
			(xy 355.643936 -230.449208) (xy 355.684439 -230.477164) (xy 355.719932 -230.511256) (xy 355.749497 -230.5506)
			(xy 355.772368 -230.594177) (xy 355.787952 -230.640858) (xy 355.795847 -230.689435) (xy 355.796342 -230.714042)
			(xy 355.796337 -230.714296) (xy 356.114853 -230.714296) (xy 356.118948 -230.663568) (xy 356.131127 -230.614154)
			(xy 356.151075 -230.567334) (xy 356.178276 -230.52432) (xy 356.212024 -230.486226) (xy 356.251446 -230.454039)
			(xy 356.29552 -230.428593) (xy 356.343106 -230.410546) (xy 356.39297 -230.400366) (xy 356.443822 -230.398317)
			(xy 356.494343 -230.404451) (xy 356.543227 -230.418611) (xy 356.589206 -230.440428) (xy 356.63109 -230.469338)
			(xy 356.667794 -230.504593) (xy 356.698367 -230.545279) (xy 356.722018 -230.590342) (xy 356.738134 -230.638616)
			(xy 356.746298 -230.68885) (xy 356.74681 -230.714296) (xy 357.054907 -230.714296) (xy 357.059002 -230.663568)
			(xy 357.071181 -230.614154) (xy 357.091129 -230.567334) (xy 357.11833 -230.52432) (xy 357.152078 -230.486226)
			(xy 357.1915 -230.454039) (xy 357.235574 -230.428593) (xy 357.28316 -230.410546) (xy 357.333024 -230.400366)
			(xy 357.383876 -230.398317) (xy 357.434397 -230.404451) (xy 357.483281 -230.418611) (xy 357.52926 -230.440428)
			(xy 357.571144 -230.469338) (xy 357.607848 -230.504593) (xy 357.638421 -230.545279) (xy 357.662072 -230.590342)
			(xy 357.678188 -230.638616) (xy 357.686352 -230.68885) (xy 357.686864 -230.714296) (xy 357.686352 -230.739742)
			(xy 357.678188 -230.789976) (xy 357.662072 -230.83825) (xy 357.638421 -230.883313) (xy 357.607848 -230.923999)
			(xy 357.571144 -230.959254) (xy 357.52926 -230.988164) (xy 357.483281 -231.009981) (xy 357.434397 -231.024141)
			(xy 357.383876 -231.030275) (xy 357.333024 -231.028226) (xy 357.28316 -231.018046) (xy 357.235574 -230.999999)
			(xy 357.1915 -230.974553) (xy 357.152078 -230.942366) (xy 357.11833 -230.904272) (xy 357.091129 -230.861258)
			(xy 357.071181 -230.814438) (xy 357.059002 -230.765024) (xy 357.054907 -230.714296) (xy 356.74681 -230.714296)
			(xy 356.746298 -230.739742) (xy 356.738134 -230.789976) (xy 356.722018 -230.83825) (xy 356.698367 -230.883313)
			(xy 356.667794 -230.923999) (xy 356.63109 -230.959254) (xy 356.589206 -230.988164) (xy 356.543227 -231.009981)
			(xy 356.494343 -231.024141) (xy 356.443822 -231.030275) (xy 356.39297 -231.028226) (xy 356.343106 -231.018046)
			(xy 356.29552 -230.999999) (xy 356.251446 -230.974553) (xy 356.212024 -230.942366) (xy 356.178276 -230.904272)
			(xy 356.151075 -230.861258) (xy 356.131127 -230.814438) (xy 356.118948 -230.765024) (xy 356.114853 -230.714296)
			(xy 355.796337 -230.714296) (xy 355.795847 -230.738649) (xy 355.787952 -230.787226) (xy 355.772368 -230.833907)
			(xy 355.749497 -230.877484) (xy 355.719932 -230.916828) (xy 355.684439 -230.95092) (xy 355.643936 -230.978876)
			(xy 355.599474 -230.999974) (xy 355.552203 -231.013666) (xy 355.503348 -231.019598) (xy 355.454173 -231.017617)
			(xy 355.405954 -231.007773) (xy 355.359938 -230.990321) (xy 355.317317 -230.965714) (xy 355.279196 -230.934589)
			(xy 355.246561 -230.897752) (xy 355.220258 -230.856156) (xy 355.200967 -230.81088) (xy 355.18919 -230.763096)
			(xy 355.18523 -230.714042) (xy 352.976429 -230.714042) (xy 352.976434 -230.714296) (xy 352.975939 -230.738903)
			(xy 352.968044 -230.78748) (xy 352.95246 -230.834161) (xy 352.929589 -230.877738) (xy 352.900024 -230.917082)
			(xy 352.864531 -230.951174) (xy 352.824028 -230.97913) (xy 352.779566 -231.000228) (xy 352.732295 -231.01392)
			(xy 352.68344 -231.019852) (xy 352.634265 -231.017871) (xy 352.586046 -231.008027) (xy 352.54003 -230.990575)
			(xy 352.497409 -230.965968) (xy 352.459288 -230.934843) (xy 352.426653 -230.898006) (xy 352.40035 -230.85641)
			(xy 352.381059 -230.811134) (xy 352.369282 -230.76335) (xy 352.365322 -230.714296) (xy 350.156526 -230.714296)
			(xy 350.156031 -230.738903) (xy 350.148136 -230.78748) (xy 350.132552 -230.834161) (xy 350.109681 -230.877738)
			(xy 350.080116 -230.917082) (xy 350.044623 -230.951174) (xy 350.00412 -230.97913) (xy 349.959658 -231.000228)
			(xy 349.912387 -231.01392) (xy 349.863532 -231.019852) (xy 349.814357 -231.017871) (xy 349.766138 -231.008027)
			(xy 349.720122 -230.990575) (xy 349.677501 -230.965968) (xy 349.63938 -230.934843) (xy 349.606745 -230.898006)
			(xy 349.580442 -230.85641) (xy 349.561151 -230.811134) (xy 349.549374 -230.76335) (xy 349.545414 -230.714296)
			(xy 347.336364 -230.714296) (xy 347.335869 -230.738903) (xy 347.327974 -230.78748) (xy 347.31239 -230.834161)
			(xy 347.289519 -230.877738) (xy 347.259954 -230.917082) (xy 347.224461 -230.951174) (xy 347.183958 -230.97913)
			(xy 347.139496 -231.000228) (xy 347.092225 -231.01392) (xy 347.04337 -231.019852) (xy 346.994195 -231.017871)
			(xy 346.945976 -231.008027) (xy 346.89996 -230.990575) (xy 346.857339 -230.965968) (xy 346.819218 -230.934843)
			(xy 346.786583 -230.898006) (xy 346.76028 -230.85641) (xy 346.740989 -230.811134) (xy 346.729212 -230.76335)
			(xy 346.725252 -230.714296) (xy 344.516973 -230.714296) (xy 344.512927 -230.763948) (xy 344.500825 -230.8124)
			(xy 344.481001 -230.858237) (xy 344.453982 -230.900237) (xy 344.420489 -230.937281) (xy 344.381415 -230.968381)
			(xy 344.337801 -230.992709) (xy 344.290809 -231.009615) (xy 344.241693 -231.018649) (xy 344.216736 -231.019604)
			(xy 344.215974 -231.019604) (xy 344.206221 -231.020334) (xy 344.188319 -231.028165) (xy 344.181176 -231.034844)
			(xy 344.131138 -231.085644) (xy 344.124555 -231.093025) (xy 344.117103 -231.111324) (xy 344.11666 -231.121204)
			(xy 344.11666 -231.524048) (xy 344.375244 -231.524048) (xy 344.379204 -231.474994) (xy 344.390981 -231.42721)
			(xy 344.410272 -231.381934) (xy 344.436575 -231.340338) (xy 344.46921 -231.303501) (xy 344.507331 -231.272376)
			(xy 344.549952 -231.247769) (xy 344.595968 -231.230317) (xy 344.644187 -231.220473) (xy 344.693362 -231.218492)
			(xy 344.742217 -231.224424) (xy 344.789488 -231.238116) (xy 344.83395 -231.259214) (xy 344.874453 -231.28717)
			(xy 344.909946 -231.321262) (xy 344.939511 -231.360606) (xy 344.962382 -231.404183) (xy 344.977966 -231.450864)
			(xy 344.985861 -231.499441) (xy 344.986356 -231.524048) (xy 345.304867 -231.524048) (xy 345.308962 -231.47332)
			(xy 345.321141 -231.423906) (xy 345.341089 -231.377086) (xy 345.36829 -231.334072) (xy 345.402038 -231.295978)
			(xy 345.44146 -231.263791) (xy 345.485534 -231.238345) (xy 345.53312 -231.220298) (xy 345.582984 -231.210118)
			(xy 345.633836 -231.208069) (xy 345.684357 -231.214203) (xy 345.733241 -231.228363) (xy 345.77922 -231.25018)
			(xy 345.821104 -231.27909) (xy 345.857808 -231.314345) (xy 345.888381 -231.355031) (xy 345.912032 -231.400094)
			(xy 345.928148 -231.448368) (xy 345.936312 -231.498602) (xy 345.936824 -231.524048) (xy 346.244921 -231.524048)
			(xy 346.249016 -231.47332) (xy 346.261195 -231.423906) (xy 346.281143 -231.377086) (xy 346.308344 -231.334072)
			(xy 346.342092 -231.295978) (xy 346.381514 -231.263791) (xy 346.425588 -231.238345) (xy 346.473174 -231.220298)
			(xy 346.523038 -231.210118) (xy 346.57389 -231.208069) (xy 346.624411 -231.214203) (xy 346.673295 -231.228363)
			(xy 346.719274 -231.25018) (xy 346.761158 -231.27909) (xy 346.797862 -231.314345) (xy 346.828435 -231.355031)
			(xy 346.852086 -231.400094) (xy 346.868202 -231.448368) (xy 346.876366 -231.498602) (xy 346.876878 -231.524048)
			(xy 347.195406 -231.524048) (xy 347.199366 -231.474994) (xy 347.211143 -231.42721) (xy 347.230434 -231.381934)
			(xy 347.256737 -231.340338) (xy 347.289372 -231.303501) (xy 347.327493 -231.272376) (xy 347.370114 -231.247769)
			(xy 347.41613 -231.230317) (xy 347.464349 -231.220473) (xy 347.513524 -231.218492) (xy 347.562379 -231.224424)
			(xy 347.60965 -231.238116) (xy 347.654112 -231.259214) (xy 347.694615 -231.28717) (xy 347.730108 -231.321262)
			(xy 347.759673 -231.360606) (xy 347.782544 -231.404183) (xy 347.798128 -231.450864) (xy 347.806023 -231.499441)
			(xy 347.806518 -231.524048) (xy 348.135206 -231.524048) (xy 348.139166 -231.474994) (xy 348.150943 -231.42721)
			(xy 348.170234 -231.381934) (xy 348.196537 -231.340338) (xy 348.229172 -231.303501) (xy 348.267293 -231.272376)
			(xy 348.309914 -231.247769) (xy 348.35593 -231.230317) (xy 348.404149 -231.220473) (xy 348.453324 -231.218492)
			(xy 348.502179 -231.224424) (xy 348.54945 -231.238116) (xy 348.593912 -231.259214) (xy 348.634415 -231.28717)
			(xy 348.669908 -231.321262) (xy 348.699473 -231.360606) (xy 348.722344 -231.404183) (xy 348.737928 -231.450864)
			(xy 348.745823 -231.499441) (xy 348.746318 -231.524048) (xy 349.07526 -231.524048) (xy 349.07922 -231.474994)
			(xy 349.090997 -231.42721) (xy 349.110288 -231.381934) (xy 349.136591 -231.340338) (xy 349.169226 -231.303501)
			(xy 349.207347 -231.272376) (xy 349.249968 -231.247769) (xy 349.295984 -231.230317) (xy 349.344203 -231.220473)
			(xy 349.393378 -231.218492) (xy 349.442233 -231.224424) (xy 349.489504 -231.238116) (xy 349.533966 -231.259214)
			(xy 349.574469 -231.28717) (xy 349.609962 -231.321262) (xy 349.639527 -231.360606) (xy 349.662398 -231.404183)
			(xy 349.677982 -231.450864) (xy 349.685877 -231.499441) (xy 349.686372 -231.524048) (xy 350.015314 -231.524048)
			(xy 350.019274 -231.474994) (xy 350.031051 -231.42721) (xy 350.050342 -231.381934) (xy 350.076645 -231.340338)
			(xy 350.10928 -231.303501) (xy 350.147401 -231.272376) (xy 350.190022 -231.247769) (xy 350.236038 -231.230317)
			(xy 350.284257 -231.220473) (xy 350.333432 -231.218492) (xy 350.382287 -231.224424) (xy 350.429558 -231.238116)
			(xy 350.47402 -231.259214) (xy 350.514523 -231.28717) (xy 350.550016 -231.321262) (xy 350.579581 -231.360606)
			(xy 350.602452 -231.404183) (xy 350.618036 -231.450864) (xy 350.625931 -231.499441) (xy 350.626426 -231.524048)
			(xy 350.955368 -231.524048) (xy 350.959328 -231.474994) (xy 350.971105 -231.42721) (xy 350.990396 -231.381934)
			(xy 351.016699 -231.340338) (xy 351.049334 -231.303501) (xy 351.087455 -231.272376) (xy 351.130076 -231.247769)
			(xy 351.176092 -231.230317) (xy 351.224311 -231.220473) (xy 351.273486 -231.218492) (xy 351.322341 -231.224424)
			(xy 351.369612 -231.238116) (xy 351.414074 -231.259214) (xy 351.454577 -231.28717) (xy 351.49007 -231.321262)
			(xy 351.519635 -231.360606) (xy 351.542506 -231.404183) (xy 351.55809 -231.450864) (xy 351.565985 -231.499441)
			(xy 351.56648 -231.524048) (xy 351.895422 -231.524048) (xy 351.899382 -231.474994) (xy 351.911159 -231.42721)
			(xy 351.93045 -231.381934) (xy 351.956753 -231.340338) (xy 351.989388 -231.303501) (xy 352.027509 -231.272376)
			(xy 352.07013 -231.247769) (xy 352.116146 -231.230317) (xy 352.164365 -231.220473) (xy 352.21354 -231.218492)
			(xy 352.262395 -231.224424) (xy 352.309666 -231.238116) (xy 352.354128 -231.259214) (xy 352.394631 -231.28717)
			(xy 352.430124 -231.321262) (xy 352.459689 -231.360606) (xy 352.48256 -231.404183) (xy 352.498144 -231.450864)
			(xy 352.506039 -231.499441) (xy 352.506534 -231.524048) (xy 352.835222 -231.524048) (xy 352.839182 -231.474994)
			(xy 352.850959 -231.42721) (xy 352.87025 -231.381934) (xy 352.896553 -231.340338) (xy 352.929188 -231.303501)
			(xy 352.967309 -231.272376) (xy 353.00993 -231.247769) (xy 353.055946 -231.230317) (xy 353.104165 -231.220473)
			(xy 353.15334 -231.218492) (xy 353.202195 -231.224424) (xy 353.249466 -231.238116) (xy 353.293928 -231.259214)
			(xy 353.334431 -231.28717) (xy 353.369924 -231.321262) (xy 353.399489 -231.360606) (xy 353.42236 -231.404183)
			(xy 353.437944 -231.450864) (xy 353.445839 -231.499441) (xy 353.446334 -231.524048) (xy 353.775276 -231.524048)
			(xy 353.779236 -231.474994) (xy 353.791013 -231.42721) (xy 353.810304 -231.381934) (xy 353.836607 -231.340338)
			(xy 353.869242 -231.303501) (xy 353.907363 -231.272376) (xy 353.949984 -231.247769) (xy 353.996 -231.230317)
			(xy 354.044219 -231.220473) (xy 354.093394 -231.218492) (xy 354.142249 -231.224424) (xy 354.18952 -231.238116)
			(xy 354.233982 -231.259214) (xy 354.274485 -231.28717) (xy 354.309978 -231.321262) (xy 354.339543 -231.360606)
			(xy 354.362414 -231.404183) (xy 354.377998 -231.450864) (xy 354.385893 -231.499441) (xy 354.386388 -231.524048)
			(xy 354.71533 -231.524048) (xy 354.71929 -231.474994) (xy 354.731067 -231.42721) (xy 354.750358 -231.381934)
			(xy 354.776661 -231.340338) (xy 354.809296 -231.303501) (xy 354.847417 -231.272376) (xy 354.890038 -231.247769)
			(xy 354.936054 -231.230317) (xy 354.984273 -231.220473) (xy 355.033448 -231.218492) (xy 355.082303 -231.224424)
			(xy 355.129574 -231.238116) (xy 355.174036 -231.259214) (xy 355.214539 -231.28717) (xy 355.250032 -231.321262)
			(xy 355.279597 -231.360606) (xy 355.302468 -231.404183) (xy 355.318052 -231.450864) (xy 355.325947 -231.499441)
			(xy 355.326442 -231.524048) (xy 355.655384 -231.524048) (xy 355.659344 -231.474994) (xy 355.671121 -231.42721)
			(xy 355.690412 -231.381934) (xy 355.716715 -231.340338) (xy 355.74935 -231.303501) (xy 355.787471 -231.272376)
			(xy 355.830092 -231.247769) (xy 355.876108 -231.230317) (xy 355.924327 -231.220473) (xy 355.973502 -231.218492)
			(xy 356.022357 -231.224424) (xy 356.069628 -231.238116) (xy 356.11409 -231.259214) (xy 356.154593 -231.28717)
			(xy 356.190086 -231.321262) (xy 356.219651 -231.360606) (xy 356.242522 -231.404183) (xy 356.258106 -231.450864)
			(xy 356.266001 -231.499441) (xy 356.266496 -231.524048) (xy 356.266001 -231.548655) (xy 356.258106 -231.597232)
			(xy 356.242522 -231.643913) (xy 356.219651 -231.68749) (xy 356.190086 -231.726834) (xy 356.154593 -231.760926)
			(xy 356.11409 -231.788882) (xy 356.069628 -231.80998) (xy 356.022357 -231.823672) (xy 355.973502 -231.829604)
			(xy 355.924327 -231.827623) (xy 355.876108 -231.817779) (xy 355.830092 -231.800327) (xy 355.787471 -231.77572)
			(xy 355.74935 -231.744595) (xy 355.716715 -231.707758) (xy 355.690412 -231.666162) (xy 355.671121 -231.620886)
			(xy 355.659344 -231.573102) (xy 355.655384 -231.524048) (xy 355.326442 -231.524048) (xy 355.325947 -231.548655)
			(xy 355.318052 -231.597232) (xy 355.302468 -231.643913) (xy 355.279597 -231.68749) (xy 355.250032 -231.726834)
			(xy 355.214539 -231.760926) (xy 355.174036 -231.788882) (xy 355.129574 -231.80998) (xy 355.082303 -231.823672)
			(xy 355.033448 -231.829604) (xy 354.984273 -231.827623) (xy 354.936054 -231.817779) (xy 354.890038 -231.800327)
			(xy 354.847417 -231.77572) (xy 354.809296 -231.744595) (xy 354.776661 -231.707758) (xy 354.750358 -231.666162)
			(xy 354.731067 -231.620886) (xy 354.71929 -231.573102) (xy 354.71533 -231.524048) (xy 354.386388 -231.524048)
			(xy 354.385893 -231.548655) (xy 354.377998 -231.597232) (xy 354.362414 -231.643913) (xy 354.339543 -231.68749)
			(xy 354.309978 -231.726834) (xy 354.274485 -231.760926) (xy 354.233982 -231.788882) (xy 354.18952 -231.80998)
			(xy 354.142249 -231.823672) (xy 354.093394 -231.829604) (xy 354.044219 -231.827623) (xy 353.996 -231.817779)
			(xy 353.949984 -231.800327) (xy 353.907363 -231.77572) (xy 353.869242 -231.744595) (xy 353.836607 -231.707758)
			(xy 353.810304 -231.666162) (xy 353.791013 -231.620886) (xy 353.779236 -231.573102) (xy 353.775276 -231.524048)
			(xy 353.446334 -231.524048) (xy 353.445839 -231.548655) (xy 353.437944 -231.597232) (xy 353.42236 -231.643913)
			(xy 353.399489 -231.68749) (xy 353.369924 -231.726834) (xy 353.334431 -231.760926) (xy 353.293928 -231.788882)
			(xy 353.249466 -231.80998) (xy 353.202195 -231.823672) (xy 353.15334 -231.829604) (xy 353.104165 -231.827623)
			(xy 353.055946 -231.817779) (xy 353.00993 -231.800327) (xy 352.967309 -231.77572) (xy 352.929188 -231.744595)
			(xy 352.896553 -231.707758) (xy 352.87025 -231.666162) (xy 352.850959 -231.620886) (xy 352.839182 -231.573102)
			(xy 352.835222 -231.524048) (xy 352.506534 -231.524048) (xy 352.506039 -231.548655) (xy 352.498144 -231.597232)
			(xy 352.48256 -231.643913) (xy 352.459689 -231.68749) (xy 352.430124 -231.726834) (xy 352.394631 -231.760926)
			(xy 352.354128 -231.788882) (xy 352.309666 -231.80998) (xy 352.262395 -231.823672) (xy 352.21354 -231.829604)
			(xy 352.164365 -231.827623) (xy 352.116146 -231.817779) (xy 352.07013 -231.800327) (xy 352.027509 -231.77572)
			(xy 351.989388 -231.744595) (xy 351.956753 -231.707758) (xy 351.93045 -231.666162) (xy 351.911159 -231.620886)
			(xy 351.899382 -231.573102) (xy 351.895422 -231.524048) (xy 351.56648 -231.524048) (xy 351.565985 -231.548655)
			(xy 351.55809 -231.597232) (xy 351.542506 -231.643913) (xy 351.519635 -231.68749) (xy 351.49007 -231.726834)
			(xy 351.454577 -231.760926) (xy 351.414074 -231.788882) (xy 351.369612 -231.80998) (xy 351.322341 -231.823672)
			(xy 351.273486 -231.829604) (xy 351.224311 -231.827623) (xy 351.176092 -231.817779) (xy 351.130076 -231.800327)
			(xy 351.087455 -231.77572) (xy 351.049334 -231.744595) (xy 351.016699 -231.707758) (xy 350.990396 -231.666162)
			(xy 350.971105 -231.620886) (xy 350.959328 -231.573102) (xy 350.955368 -231.524048) (xy 350.626426 -231.524048)
			(xy 350.625931 -231.548655) (xy 350.618036 -231.597232) (xy 350.602452 -231.643913) (xy 350.579581 -231.68749)
			(xy 350.550016 -231.726834) (xy 350.514523 -231.760926) (xy 350.47402 -231.788882) (xy 350.429558 -231.80998)
			(xy 350.382287 -231.823672) (xy 350.333432 -231.829604) (xy 350.284257 -231.827623) (xy 350.236038 -231.817779)
			(xy 350.190022 -231.800327) (xy 350.147401 -231.77572) (xy 350.10928 -231.744595) (xy 350.076645 -231.707758)
			(xy 350.050342 -231.666162) (xy 350.031051 -231.620886) (xy 350.019274 -231.573102) (xy 350.015314 -231.524048)
			(xy 349.686372 -231.524048) (xy 349.685877 -231.548655) (xy 349.677982 -231.597232) (xy 349.662398 -231.643913)
			(xy 349.639527 -231.68749) (xy 349.609962 -231.726834) (xy 349.574469 -231.760926) (xy 349.533966 -231.788882)
			(xy 349.489504 -231.80998) (xy 349.442233 -231.823672) (xy 349.393378 -231.829604) (xy 349.344203 -231.827623)
			(xy 349.295984 -231.817779) (xy 349.249968 -231.800327) (xy 349.207347 -231.77572) (xy 349.169226 -231.744595)
			(xy 349.136591 -231.707758) (xy 349.110288 -231.666162) (xy 349.090997 -231.620886) (xy 349.07922 -231.573102)
			(xy 349.07526 -231.524048) (xy 348.746318 -231.524048) (xy 348.745823 -231.548655) (xy 348.737928 -231.597232)
			(xy 348.722344 -231.643913) (xy 348.699473 -231.68749) (xy 348.669908 -231.726834) (xy 348.634415 -231.760926)
			(xy 348.593912 -231.788882) (xy 348.54945 -231.80998) (xy 348.502179 -231.823672) (xy 348.453324 -231.829604)
			(xy 348.404149 -231.827623) (xy 348.35593 -231.817779) (xy 348.309914 -231.800327) (xy 348.267293 -231.77572)
			(xy 348.229172 -231.744595) (xy 348.196537 -231.707758) (xy 348.170234 -231.666162) (xy 348.150943 -231.620886)
			(xy 348.139166 -231.573102) (xy 348.135206 -231.524048) (xy 347.806518 -231.524048) (xy 347.806023 -231.548655)
			(xy 347.798128 -231.597232) (xy 347.782544 -231.643913) (xy 347.759673 -231.68749) (xy 347.730108 -231.726834)
			(xy 347.694615 -231.760926) (xy 347.654112 -231.788882) (xy 347.60965 -231.80998) (xy 347.562379 -231.823672)
			(xy 347.513524 -231.829604) (xy 347.464349 -231.827623) (xy 347.41613 -231.817779) (xy 347.370114 -231.800327)
			(xy 347.327493 -231.77572) (xy 347.289372 -231.744595) (xy 347.256737 -231.707758) (xy 347.230434 -231.666162)
			(xy 347.211143 -231.620886) (xy 347.199366 -231.573102) (xy 347.195406 -231.524048) (xy 346.876878 -231.524048)
			(xy 346.876366 -231.549494) (xy 346.868202 -231.599728) (xy 346.852086 -231.648002) (xy 346.828435 -231.693065)
			(xy 346.797862 -231.733751) (xy 346.761158 -231.769006) (xy 346.719274 -231.797916) (xy 346.673295 -231.819733)
			(xy 346.624411 -231.833893) (xy 346.57389 -231.840027) (xy 346.523038 -231.837978) (xy 346.473174 -231.827798)
			(xy 346.425588 -231.809751) (xy 346.381514 -231.784305) (xy 346.342092 -231.752118) (xy 346.308344 -231.714024)
			(xy 346.281143 -231.67101) (xy 346.261195 -231.62419) (xy 346.249016 -231.574776) (xy 346.244921 -231.524048)
			(xy 345.936824 -231.524048) (xy 345.936312 -231.549494) (xy 345.928148 -231.599728) (xy 345.912032 -231.648002)
			(xy 345.888381 -231.693065) (xy 345.857808 -231.733751) (xy 345.821104 -231.769006) (xy 345.77922 -231.797916)
			(xy 345.733241 -231.819733) (xy 345.684357 -231.833893) (xy 345.633836 -231.840027) (xy 345.582984 -231.837978)
			(xy 345.53312 -231.827798) (xy 345.485534 -231.809751) (xy 345.44146 -231.784305) (xy 345.402038 -231.752118)
			(xy 345.36829 -231.714024) (xy 345.341089 -231.67101) (xy 345.321141 -231.62419) (xy 345.308962 -231.574776)
			(xy 345.304867 -231.524048) (xy 344.986356 -231.524048) (xy 344.985861 -231.548655) (xy 344.977966 -231.597232)
			(xy 344.962382 -231.643913) (xy 344.939511 -231.68749) (xy 344.909946 -231.726834) (xy 344.874453 -231.760926)
			(xy 344.83395 -231.788882) (xy 344.789488 -231.80998) (xy 344.742217 -231.823672) (xy 344.693362 -231.829604)
			(xy 344.644187 -231.827623) (xy 344.595968 -231.817779) (xy 344.549952 -231.800327) (xy 344.507331 -231.77572)
			(xy 344.46921 -231.744595) (xy 344.436575 -231.707758) (xy 344.410272 -231.666162) (xy 344.390981 -231.620886)
			(xy 344.379204 -231.573102) (xy 344.375244 -231.524048) (xy 344.11666 -231.524048) (xy 344.11666 -231.927146)
			(xy 344.117124 -231.937022) (xy 344.12457 -231.955317) (xy 344.131138 -231.962706) (xy 344.181176 -232.013506)
			(xy 344.188322 -232.020185) (xy 344.206219 -232.028036) (xy 344.215974 -232.028746) (xy 344.216482 -232.028746)
			(xy 344.241443 -232.029684) (xy 344.290573 -232.038678) (xy 344.337586 -232.055548) (xy 344.381226 -232.079842)
			(xy 344.420332 -232.110914) (xy 344.45386 -232.147935) (xy 344.480918 -232.189918) (xy 344.500783 -232.235745)
			(xy 344.512927 -232.284193) (xy 344.517025 -232.333972) (xy 344.517018 -232.334054) (xy 344.845398 -232.334054)
			(xy 344.849358 -232.285) (xy 344.861135 -232.237216) (xy 344.880426 -232.19194) (xy 344.906729 -232.150344)
			(xy 344.939364 -232.113507) (xy 344.977485 -232.082382) (xy 345.020106 -232.057775) (xy 345.066122 -232.040323)
			(xy 345.114341 -232.030479) (xy 345.163516 -232.028498) (xy 345.212371 -232.03443) (xy 345.259642 -232.048122)
			(xy 345.304104 -232.06922) (xy 345.344607 -232.097176) (xy 345.3801 -232.131268) (xy 345.409665 -232.170612)
			(xy 345.432536 -232.214189) (xy 345.44812 -232.26087) (xy 345.456015 -232.309447) (xy 345.45651 -232.334054)
			(xy 345.785198 -232.334054) (xy 345.789158 -232.285) (xy 345.800935 -232.237216) (xy 345.820226 -232.19194)
			(xy 345.846529 -232.150344) (xy 345.879164 -232.113507) (xy 345.917285 -232.082382) (xy 345.959906 -232.057775)
			(xy 346.005922 -232.040323) (xy 346.054141 -232.030479) (xy 346.103316 -232.028498) (xy 346.152171 -232.03443)
			(xy 346.199442 -232.048122) (xy 346.243904 -232.06922) (xy 346.284407 -232.097176) (xy 346.3199 -232.131268)
			(xy 346.349465 -232.170612) (xy 346.372336 -232.214189) (xy 346.38792 -232.26087) (xy 346.395815 -232.309447)
			(xy 346.39631 -232.334054) (xy 346.725252 -232.334054) (xy 346.729212 -232.285) (xy 346.740989 -232.237216)
			(xy 346.76028 -232.19194) (xy 346.786583 -232.150344) (xy 346.819218 -232.113507) (xy 346.857339 -232.082382)
			(xy 346.89996 -232.057775) (xy 346.945976 -232.040323) (xy 346.994195 -232.030479) (xy 347.04337 -232.028498)
			(xy 347.092225 -232.03443) (xy 347.139496 -232.048122) (xy 347.183958 -232.06922) (xy 347.224461 -232.097176)
			(xy 347.259954 -232.131268) (xy 347.289519 -232.170612) (xy 347.31239 -232.214189) (xy 347.327974 -232.26087)
			(xy 347.335869 -232.309447) (xy 347.336364 -232.334054) (xy 347.665306 -232.334054) (xy 347.669266 -232.285)
			(xy 347.681043 -232.237216) (xy 347.700334 -232.19194) (xy 347.726637 -232.150344) (xy 347.759272 -232.113507)
			(xy 347.797393 -232.082382) (xy 347.840014 -232.057775) (xy 347.88603 -232.040323) (xy 347.934249 -232.030479)
			(xy 347.983424 -232.028498) (xy 348.032279 -232.03443) (xy 348.07955 -232.048122) (xy 348.124012 -232.06922)
			(xy 348.164515 -232.097176) (xy 348.200008 -232.131268) (xy 348.229573 -232.170612) (xy 348.252444 -232.214189)
			(xy 348.268028 -232.26087) (xy 348.275923 -232.309447) (xy 348.276418 -232.334054) (xy 348.60536 -232.334054)
			(xy 348.60932 -232.285) (xy 348.621097 -232.237216) (xy 348.640388 -232.19194) (xy 348.666691 -232.150344)
			(xy 348.699326 -232.113507) (xy 348.737447 -232.082382) (xy 348.780068 -232.057775) (xy 348.826084 -232.040323)
			(xy 348.874303 -232.030479) (xy 348.923478 -232.028498) (xy 348.972333 -232.03443) (xy 349.019604 -232.048122)
			(xy 349.064066 -232.06922) (xy 349.104569 -232.097176) (xy 349.140062 -232.131268) (xy 349.169627 -232.170612)
			(xy 349.192498 -232.214189) (xy 349.208082 -232.26087) (xy 349.215977 -232.309447) (xy 349.216472 -232.334054)
			(xy 349.545414 -232.334054) (xy 349.549374 -232.285) (xy 349.561151 -232.237216) (xy 349.580442 -232.19194)
			(xy 349.606745 -232.150344) (xy 349.63938 -232.113507) (xy 349.677501 -232.082382) (xy 349.720122 -232.057775)
			(xy 349.766138 -232.040323) (xy 349.814357 -232.030479) (xy 349.863532 -232.028498) (xy 349.912387 -232.03443)
			(xy 349.959658 -232.048122) (xy 350.00412 -232.06922) (xy 350.044623 -232.097176) (xy 350.080116 -232.131268)
			(xy 350.109681 -232.170612) (xy 350.132552 -232.214189) (xy 350.148136 -232.26087) (xy 350.156031 -232.309447)
			(xy 350.156526 -232.334054) (xy 350.485214 -232.334054) (xy 350.489174 -232.285) (xy 350.500951 -232.237216)
			(xy 350.520242 -232.19194) (xy 350.546545 -232.150344) (xy 350.57918 -232.113507) (xy 350.617301 -232.082382)
			(xy 350.659922 -232.057775) (xy 350.705938 -232.040323) (xy 350.754157 -232.030479) (xy 350.803332 -232.028498)
			(xy 350.852187 -232.03443) (xy 350.899458 -232.048122) (xy 350.94392 -232.06922) (xy 350.984423 -232.097176)
			(xy 351.019916 -232.131268) (xy 351.049481 -232.170612) (xy 351.072352 -232.214189) (xy 351.087936 -232.26087)
			(xy 351.095831 -232.309447) (xy 351.096326 -232.334054) (xy 351.425268 -232.334054) (xy 351.429228 -232.285)
			(xy 351.441005 -232.237216) (xy 351.460296 -232.19194) (xy 351.486599 -232.150344) (xy 351.519234 -232.113507)
			(xy 351.557355 -232.082382) (xy 351.599976 -232.057775) (xy 351.645992 -232.040323) (xy 351.694211 -232.030479)
			(xy 351.743386 -232.028498) (xy 351.792241 -232.03443) (xy 351.839512 -232.048122) (xy 351.883974 -232.06922)
			(xy 351.924477 -232.097176) (xy 351.95997 -232.131268) (xy 351.989535 -232.170612) (xy 352.012406 -232.214189)
			(xy 352.02799 -232.26087) (xy 352.035885 -232.309447) (xy 352.03638 -232.334054) (xy 352.365322 -232.334054)
			(xy 352.369282 -232.285) (xy 352.381059 -232.237216) (xy 352.40035 -232.19194) (xy 352.426653 -232.150344)
			(xy 352.459288 -232.113507) (xy 352.497409 -232.082382) (xy 352.54003 -232.057775) (xy 352.586046 -232.040323)
			(xy 352.634265 -232.030479) (xy 352.68344 -232.028498) (xy 352.732295 -232.03443) (xy 352.779566 -232.048122)
			(xy 352.824028 -232.06922) (xy 352.864531 -232.097176) (xy 352.900024 -232.131268) (xy 352.929589 -232.170612)
			(xy 352.95246 -232.214189) (xy 352.968044 -232.26087) (xy 352.975939 -232.309447) (xy 352.976434 -232.334054)
			(xy 353.305376 -232.334054) (xy 353.309336 -232.285) (xy 353.321113 -232.237216) (xy 353.340404 -232.19194)
			(xy 353.366707 -232.150344) (xy 353.399342 -232.113507) (xy 353.437463 -232.082382) (xy 353.480084 -232.057775)
			(xy 353.5261 -232.040323) (xy 353.574319 -232.030479) (xy 353.623494 -232.028498) (xy 353.672349 -232.03443)
			(xy 353.71962 -232.048122) (xy 353.764082 -232.06922) (xy 353.804585 -232.097176) (xy 353.840078 -232.131268)
			(xy 353.869643 -232.170612) (xy 353.892514 -232.214189) (xy 353.908098 -232.26087) (xy 353.915993 -232.309447)
			(xy 353.916488 -232.334054) (xy 354.24543 -232.334054) (xy 354.24939 -232.285) (xy 354.261167 -232.237216)
			(xy 354.280458 -232.19194) (xy 354.306761 -232.150344) (xy 354.339396 -232.113507) (xy 354.377517 -232.082382)
			(xy 354.420138 -232.057775) (xy 354.466154 -232.040323) (xy 354.514373 -232.030479) (xy 354.563548 -232.028498)
			(xy 354.612403 -232.03443) (xy 354.659674 -232.048122) (xy 354.704136 -232.06922) (xy 354.744639 -232.097176)
			(xy 354.780132 -232.131268) (xy 354.809697 -232.170612) (xy 354.832568 -232.214189) (xy 354.848152 -232.26087)
			(xy 354.856047 -232.309447) (xy 354.856542 -232.334054) (xy 355.18523 -232.334054) (xy 355.18919 -232.285)
			(xy 355.200967 -232.237216) (xy 355.220258 -232.19194) (xy 355.246561 -232.150344) (xy 355.279196 -232.113507)
			(xy 355.317317 -232.082382) (xy 355.359938 -232.057775) (xy 355.405954 -232.040323) (xy 355.454173 -232.030479)
			(xy 355.503348 -232.028498) (xy 355.552203 -232.03443) (xy 355.599474 -232.048122) (xy 355.643936 -232.06922)
			(xy 355.684439 -232.097176) (xy 355.719932 -232.131268) (xy 355.749497 -232.170612) (xy 355.772368 -232.214189)
			(xy 355.787952 -232.26087) (xy 355.795847 -232.309447) (xy 355.796342 -232.334054) (xy 356.125284 -232.334054)
			(xy 356.129244 -232.285) (xy 356.141021 -232.237216) (xy 356.160312 -232.19194) (xy 356.186615 -232.150344)
			(xy 356.21925 -232.113507) (xy 356.257371 -232.082382) (xy 356.299992 -232.057775) (xy 356.346008 -232.040323)
			(xy 356.394227 -232.030479) (xy 356.443402 -232.028498) (xy 356.492257 -232.03443) (xy 356.539528 -232.048122)
			(xy 356.58399 -232.06922) (xy 356.624493 -232.097176) (xy 356.659986 -232.131268) (xy 356.689551 -232.170612)
			(xy 356.712422 -232.214189) (xy 356.728006 -232.26087) (xy 356.735901 -232.309447) (xy 356.736396 -232.334054)
			(xy 357.065338 -232.334054) (xy 357.069298 -232.285) (xy 357.081075 -232.237216) (xy 357.100366 -232.19194)
			(xy 357.126669 -232.150344) (xy 357.159304 -232.113507) (xy 357.197425 -232.082382) (xy 357.240046 -232.057775)
			(xy 357.286062 -232.040323) (xy 357.334281 -232.030479) (xy 357.383456 -232.028498) (xy 357.432311 -232.03443)
			(xy 357.479582 -232.048122) (xy 357.524044 -232.06922) (xy 357.564547 -232.097176) (xy 357.60004 -232.131268)
			(xy 357.629605 -232.170612) (xy 357.652476 -232.214189) (xy 357.66806 -232.26087) (xy 357.675955 -232.309447)
			(xy 357.67645 -232.334054) (xy 357.675955 -232.358661) (xy 357.66806 -232.407238) (xy 357.652476 -232.453919)
			(xy 357.629605 -232.497496) (xy 357.60004 -232.53684) (xy 357.564547 -232.570932) (xy 357.524044 -232.598888)
			(xy 357.479582 -232.619986) (xy 357.432311 -232.633678) (xy 357.383456 -232.63961) (xy 357.334281 -232.637629)
			(xy 357.286062 -232.627785) (xy 357.240046 -232.610333) (xy 357.197425 -232.585726) (xy 357.159304 -232.554601)
			(xy 357.126669 -232.517764) (xy 357.100366 -232.476168) (xy 357.081075 -232.430892) (xy 357.069298 -232.383108)
			(xy 357.065338 -232.334054) (xy 356.736396 -232.334054) (xy 356.735901 -232.358661) (xy 356.728006 -232.407238)
			(xy 356.712422 -232.453919) (xy 356.689551 -232.497496) (xy 356.659986 -232.53684) (xy 356.624493 -232.570932)
			(xy 356.58399 -232.598888) (xy 356.539528 -232.619986) (xy 356.492257 -232.633678) (xy 356.443402 -232.63961)
			(xy 356.394227 -232.637629) (xy 356.346008 -232.627785) (xy 356.299992 -232.610333) (xy 356.257371 -232.585726)
			(xy 356.21925 -232.554601) (xy 356.186615 -232.517764) (xy 356.160312 -232.476168) (xy 356.141021 -232.430892)
			(xy 356.129244 -232.383108) (xy 356.125284 -232.334054) (xy 355.796342 -232.334054) (xy 355.795847 -232.358661)
			(xy 355.787952 -232.407238) (xy 355.772368 -232.453919) (xy 355.749497 -232.497496) (xy 355.719932 -232.53684)
			(xy 355.684439 -232.570932) (xy 355.643936 -232.598888) (xy 355.599474 -232.619986) (xy 355.552203 -232.633678)
			(xy 355.503348 -232.63961) (xy 355.454173 -232.637629) (xy 355.405954 -232.627785) (xy 355.359938 -232.610333)
			(xy 355.317317 -232.585726) (xy 355.279196 -232.554601) (xy 355.246561 -232.517764) (xy 355.220258 -232.476168)
			(xy 355.200967 -232.430892) (xy 355.18919 -232.383108) (xy 355.18523 -232.334054) (xy 354.856542 -232.334054)
			(xy 354.856047 -232.358661) (xy 354.848152 -232.407238) (xy 354.832568 -232.453919) (xy 354.809697 -232.497496)
			(xy 354.780132 -232.53684) (xy 354.744639 -232.570932) (xy 354.704136 -232.598888) (xy 354.659674 -232.619986)
			(xy 354.612403 -232.633678) (xy 354.563548 -232.63961) (xy 354.514373 -232.637629) (xy 354.466154 -232.627785)
			(xy 354.420138 -232.610333) (xy 354.377517 -232.585726) (xy 354.339396 -232.554601) (xy 354.306761 -232.517764)
			(xy 354.280458 -232.476168) (xy 354.261167 -232.430892) (xy 354.24939 -232.383108) (xy 354.24543 -232.334054)
			(xy 353.916488 -232.334054) (xy 353.915993 -232.358661) (xy 353.908098 -232.407238) (xy 353.892514 -232.453919)
			(xy 353.869643 -232.497496) (xy 353.840078 -232.53684) (xy 353.804585 -232.570932) (xy 353.764082 -232.598888)
			(xy 353.71962 -232.619986) (xy 353.672349 -232.633678) (xy 353.623494 -232.63961) (xy 353.574319 -232.637629)
			(xy 353.5261 -232.627785) (xy 353.480084 -232.610333) (xy 353.437463 -232.585726) (xy 353.399342 -232.554601)
			(xy 353.366707 -232.517764) (xy 353.340404 -232.476168) (xy 353.321113 -232.430892) (xy 353.309336 -232.383108)
			(xy 353.305376 -232.334054) (xy 352.976434 -232.334054) (xy 352.975939 -232.358661) (xy 352.968044 -232.407238)
			(xy 352.95246 -232.453919) (xy 352.929589 -232.497496) (xy 352.900024 -232.53684) (xy 352.864531 -232.570932)
			(xy 352.824028 -232.598888) (xy 352.779566 -232.619986) (xy 352.732295 -232.633678) (xy 352.68344 -232.63961)
			(xy 352.634265 -232.637629) (xy 352.586046 -232.627785) (xy 352.54003 -232.610333) (xy 352.497409 -232.585726)
			(xy 352.459288 -232.554601) (xy 352.426653 -232.517764) (xy 352.40035 -232.476168) (xy 352.381059 -232.430892)
			(xy 352.369282 -232.383108) (xy 352.365322 -232.334054) (xy 352.03638 -232.334054) (xy 352.035885 -232.358661)
			(xy 352.02799 -232.407238) (xy 352.012406 -232.453919) (xy 351.989535 -232.497496) (xy 351.95997 -232.53684)
			(xy 351.924477 -232.570932) (xy 351.883974 -232.598888) (xy 351.839512 -232.619986) (xy 351.792241 -232.633678)
			(xy 351.743386 -232.63961) (xy 351.694211 -232.637629) (xy 351.645992 -232.627785) (xy 351.599976 -232.610333)
			(xy 351.557355 -232.585726) (xy 351.519234 -232.554601) (xy 351.486599 -232.517764) (xy 351.460296 -232.476168)
			(xy 351.441005 -232.430892) (xy 351.429228 -232.383108) (xy 351.425268 -232.334054) (xy 351.096326 -232.334054)
			(xy 351.095831 -232.358661) (xy 351.087936 -232.407238) (xy 351.072352 -232.453919) (xy 351.049481 -232.497496)
			(xy 351.019916 -232.53684) (xy 350.984423 -232.570932) (xy 350.94392 -232.598888) (xy 350.899458 -232.619986)
			(xy 350.852187 -232.633678) (xy 350.803332 -232.63961) (xy 350.754157 -232.637629) (xy 350.705938 -232.627785)
			(xy 350.659922 -232.610333) (xy 350.617301 -232.585726) (xy 350.57918 -232.554601) (xy 350.546545 -232.517764)
			(xy 350.520242 -232.476168) (xy 350.500951 -232.430892) (xy 350.489174 -232.383108) (xy 350.485214 -232.334054)
			(xy 350.156526 -232.334054) (xy 350.156031 -232.358661) (xy 350.148136 -232.407238) (xy 350.132552 -232.453919)
			(xy 350.109681 -232.497496) (xy 350.080116 -232.53684) (xy 350.044623 -232.570932) (xy 350.00412 -232.598888)
			(xy 349.959658 -232.619986) (xy 349.912387 -232.633678) (xy 349.863532 -232.63961) (xy 349.814357 -232.637629)
			(xy 349.766138 -232.627785) (xy 349.720122 -232.610333) (xy 349.677501 -232.585726) (xy 349.63938 -232.554601)
			(xy 349.606745 -232.517764) (xy 349.580442 -232.476168) (xy 349.561151 -232.430892) (xy 349.549374 -232.383108)
			(xy 349.545414 -232.334054) (xy 349.216472 -232.334054) (xy 349.215977 -232.358661) (xy 349.208082 -232.407238)
			(xy 349.192498 -232.453919) (xy 349.169627 -232.497496) (xy 349.140062 -232.53684) (xy 349.104569 -232.570932)
			(xy 349.064066 -232.598888) (xy 349.019604 -232.619986) (xy 348.972333 -232.633678) (xy 348.923478 -232.63961)
			(xy 348.874303 -232.637629) (xy 348.826084 -232.627785) (xy 348.780068 -232.610333) (xy 348.737447 -232.585726)
			(xy 348.699326 -232.554601) (xy 348.666691 -232.517764) (xy 348.640388 -232.476168) (xy 348.621097 -232.430892)
			(xy 348.60932 -232.383108) (xy 348.60536 -232.334054) (xy 348.276418 -232.334054) (xy 348.275923 -232.358661)
			(xy 348.268028 -232.407238) (xy 348.252444 -232.453919) (xy 348.229573 -232.497496) (xy 348.200008 -232.53684)
			(xy 348.164515 -232.570932) (xy 348.124012 -232.598888) (xy 348.07955 -232.619986) (xy 348.032279 -232.633678)
			(xy 347.983424 -232.63961) (xy 347.934249 -232.637629) (xy 347.88603 -232.627785) (xy 347.840014 -232.610333)
			(xy 347.797393 -232.585726) (xy 347.759272 -232.554601) (xy 347.726637 -232.517764) (xy 347.700334 -232.476168)
			(xy 347.681043 -232.430892) (xy 347.669266 -232.383108) (xy 347.665306 -232.334054) (xy 347.336364 -232.334054)
			(xy 347.335869 -232.358661) (xy 347.327974 -232.407238) (xy 347.31239 -232.453919) (xy 347.289519 -232.497496)
			(xy 347.259954 -232.53684) (xy 347.224461 -232.570932) (xy 347.183958 -232.598888) (xy 347.139496 -232.619986)
			(xy 347.092225 -232.633678) (xy 347.04337 -232.63961) (xy 346.994195 -232.637629) (xy 346.945976 -232.627785)
			(xy 346.89996 -232.610333) (xy 346.857339 -232.585726) (xy 346.819218 -232.554601) (xy 346.786583 -232.517764)
			(xy 346.76028 -232.476168) (xy 346.740989 -232.430892) (xy 346.729212 -232.383108) (xy 346.725252 -232.334054)
			(xy 346.39631 -232.334054) (xy 346.395815 -232.358661) (xy 346.38792 -232.407238) (xy 346.372336 -232.453919)
			(xy 346.349465 -232.497496) (xy 346.3199 -232.53684) (xy 346.284407 -232.570932) (xy 346.243904 -232.598888)
			(xy 346.199442 -232.619986) (xy 346.152171 -232.633678) (xy 346.103316 -232.63961) (xy 346.054141 -232.637629)
			(xy 346.005922 -232.627785) (xy 345.959906 -232.610333) (xy 345.917285 -232.585726) (xy 345.879164 -232.554601)
			(xy 345.846529 -232.517764) (xy 345.820226 -232.476168) (xy 345.800935 -232.430892) (xy 345.789158 -232.383108)
			(xy 345.785198 -232.334054) (xy 345.45651 -232.334054) (xy 345.456015 -232.358661) (xy 345.44812 -232.407238)
			(xy 345.432536 -232.453919) (xy 345.409665 -232.497496) (xy 345.3801 -232.53684) (xy 345.344607 -232.570932)
			(xy 345.304104 -232.598888) (xy 345.259642 -232.619986) (xy 345.212371 -232.633678) (xy 345.163516 -232.63961)
			(xy 345.114341 -232.637629) (xy 345.066122 -232.627785) (xy 345.020106 -232.610333) (xy 344.977485 -232.585726)
			(xy 344.939364 -232.554601) (xy 344.906729 -232.517764) (xy 344.880426 -232.476168) (xy 344.861135 -232.430892)
			(xy 344.849358 -232.383108) (xy 344.845398 -232.334054) (xy 344.517018 -232.334054) (xy 344.512968 -232.383754)
			(xy 344.500865 -232.432213) (xy 344.481038 -232.478056) (xy 344.454016 -232.520062) (xy 344.420519 -232.557111)
			(xy 344.381439 -232.588216) (xy 344.337819 -232.612546) (xy 344.290821 -232.629455) (xy 344.241698 -232.638491)
			(xy 344.216736 -232.639362) (xy 344.215974 -232.639362) (xy 344.206223 -232.640094) (xy 344.188326 -232.647932)
			(xy 344.181176 -232.654602) (xy 344.131138 -232.705402) (xy 344.124564 -232.712786) (xy 344.117133 -232.731085)
			(xy 344.11666 -232.740962) (xy 344.11666 -233.14406) (xy 344.375244 -233.14406) (xy 344.379204 -233.095006)
			(xy 344.390981 -233.047222) (xy 344.410272 -233.001946) (xy 344.436575 -232.96035) (xy 344.46921 -232.923513)
			(xy 344.507331 -232.892388) (xy 344.549952 -232.867781) (xy 344.595968 -232.850329) (xy 344.644187 -232.840485)
			(xy 344.693362 -232.838504) (xy 344.742217 -232.844436) (xy 344.789488 -232.858128) (xy 344.83395 -232.879226)
			(xy 344.874453 -232.907182) (xy 344.909946 -232.941274) (xy 344.939511 -232.980618) (xy 344.962382 -233.024195)
			(xy 344.977966 -233.070876) (xy 344.985861 -233.119453) (xy 344.986356 -233.14406) (xy 345.315298 -233.14406)
			(xy 345.319258 -233.095006) (xy 345.331035 -233.047222) (xy 345.350326 -233.001946) (xy 345.376629 -232.96035)
			(xy 345.409264 -232.923513) (xy 345.447385 -232.892388) (xy 345.490006 -232.867781) (xy 345.536022 -232.850329)
			(xy 345.584241 -232.840485) (xy 345.633416 -232.838504) (xy 345.682271 -232.844436) (xy 345.729542 -232.858128)
			(xy 345.774004 -232.879226) (xy 345.814507 -232.907182) (xy 345.85 -232.941274) (xy 345.879565 -232.980618)
			(xy 345.902436 -233.024195) (xy 345.91802 -233.070876) (xy 345.925915 -233.119453) (xy 345.92641 -233.14406)
			(xy 346.255352 -233.14406) (xy 346.259312 -233.095006) (xy 346.271089 -233.047222) (xy 346.29038 -233.001946)
			(xy 346.316683 -232.96035) (xy 346.349318 -232.923513) (xy 346.387439 -232.892388) (xy 346.43006 -232.867781)
			(xy 346.476076 -232.850329) (xy 346.524295 -232.840485) (xy 346.57347 -232.838504) (xy 346.622325 -232.844436)
			(xy 346.669596 -232.858128) (xy 346.714058 -232.879226) (xy 346.754561 -232.907182) (xy 346.790054 -232.941274)
			(xy 346.819619 -232.980618) (xy 346.84249 -233.024195) (xy 346.858074 -233.070876) (xy 346.865969 -233.119453)
			(xy 346.866464 -233.14406) (xy 347.195406 -233.14406) (xy 347.199366 -233.095006) (xy 347.211143 -233.047222)
			(xy 347.230434 -233.001946) (xy 347.256737 -232.96035) (xy 347.289372 -232.923513) (xy 347.327493 -232.892388)
			(xy 347.370114 -232.867781) (xy 347.41613 -232.850329) (xy 347.464349 -232.840485) (xy 347.513524 -232.838504)
			(xy 347.562379 -232.844436) (xy 347.60965 -232.858128) (xy 347.654112 -232.879226) (xy 347.694615 -232.907182)
			(xy 347.730108 -232.941274) (xy 347.759673 -232.980618) (xy 347.782544 -233.024195) (xy 347.798128 -233.070876)
			(xy 347.806023 -233.119453) (xy 347.806518 -233.14406) (xy 348.135206 -233.14406) (xy 348.139166 -233.095006)
			(xy 348.150943 -233.047222) (xy 348.170234 -233.001946) (xy 348.196537 -232.96035) (xy 348.229172 -232.923513)
			(xy 348.267293 -232.892388) (xy 348.309914 -232.867781) (xy 348.35593 -232.850329) (xy 348.404149 -232.840485)
			(xy 348.453324 -232.838504) (xy 348.502179 -232.844436) (xy 348.54945 -232.858128) (xy 348.593912 -232.879226)
			(xy 348.634415 -232.907182) (xy 348.669908 -232.941274) (xy 348.699473 -232.980618) (xy 348.722344 -233.024195)
			(xy 348.737928 -233.070876) (xy 348.745823 -233.119453) (xy 348.746318 -233.14406) (xy 349.07526 -233.14406)
			(xy 349.07922 -233.095006) (xy 349.090997 -233.047222) (xy 349.110288 -233.001946) (xy 349.136591 -232.96035)
			(xy 349.169226 -232.923513) (xy 349.207347 -232.892388) (xy 349.249968 -232.867781) (xy 349.295984 -232.850329)
			(xy 349.344203 -232.840485) (xy 349.393378 -232.838504) (xy 349.442233 -232.844436) (xy 349.489504 -232.858128)
			(xy 349.533966 -232.879226) (xy 349.574469 -232.907182) (xy 349.609962 -232.941274) (xy 349.639527 -232.980618)
			(xy 349.662398 -233.024195) (xy 349.677982 -233.070876) (xy 349.685877 -233.119453) (xy 349.686372 -233.14406)
			(xy 350.015314 -233.14406) (xy 350.019274 -233.095006) (xy 350.031051 -233.047222) (xy 350.050342 -233.001946)
			(xy 350.076645 -232.96035) (xy 350.10928 -232.923513) (xy 350.147401 -232.892388) (xy 350.190022 -232.867781)
			(xy 350.236038 -232.850329) (xy 350.284257 -232.840485) (xy 350.333432 -232.838504) (xy 350.382287 -232.844436)
			(xy 350.429558 -232.858128) (xy 350.47402 -232.879226) (xy 350.514523 -232.907182) (xy 350.550016 -232.941274)
			(xy 350.579581 -232.980618) (xy 350.602452 -233.024195) (xy 350.618036 -233.070876) (xy 350.625931 -233.119453)
			(xy 350.626426 -233.14406) (xy 350.955368 -233.14406) (xy 350.959328 -233.095006) (xy 350.971105 -233.047222)
			(xy 350.990396 -233.001946) (xy 351.016699 -232.96035) (xy 351.049334 -232.923513) (xy 351.087455 -232.892388)
			(xy 351.130076 -232.867781) (xy 351.176092 -232.850329) (xy 351.224311 -232.840485) (xy 351.273486 -232.838504)
			(xy 351.322341 -232.844436) (xy 351.369612 -232.858128) (xy 351.414074 -232.879226) (xy 351.454577 -232.907182)
			(xy 351.49007 -232.941274) (xy 351.519635 -232.980618) (xy 351.542506 -233.024195) (xy 351.55809 -233.070876)
			(xy 351.565985 -233.119453) (xy 351.56648 -233.14406) (xy 351.895422 -233.14406) (xy 351.899382 -233.095006)
			(xy 351.911159 -233.047222) (xy 351.93045 -233.001946) (xy 351.956753 -232.96035) (xy 351.989388 -232.923513)
			(xy 352.027509 -232.892388) (xy 352.07013 -232.867781) (xy 352.116146 -232.850329) (xy 352.164365 -232.840485)
			(xy 352.21354 -232.838504) (xy 352.262395 -232.844436) (xy 352.309666 -232.858128) (xy 352.354128 -232.879226)
			(xy 352.394631 -232.907182) (xy 352.430124 -232.941274) (xy 352.459689 -232.980618) (xy 352.48256 -233.024195)
			(xy 352.498144 -233.070876) (xy 352.506039 -233.119453) (xy 352.506534 -233.14406) (xy 352.835222 -233.14406)
			(xy 352.839182 -233.095006) (xy 352.850959 -233.047222) (xy 352.87025 -233.001946) (xy 352.896553 -232.96035)
			(xy 352.929188 -232.923513) (xy 352.967309 -232.892388) (xy 353.00993 -232.867781) (xy 353.055946 -232.850329)
			(xy 353.104165 -232.840485) (xy 353.15334 -232.838504) (xy 353.202195 -232.844436) (xy 353.249466 -232.858128)
			(xy 353.293928 -232.879226) (xy 353.334431 -232.907182) (xy 353.369924 -232.941274) (xy 353.399489 -232.980618)
			(xy 353.42236 -233.024195) (xy 353.437944 -233.070876) (xy 353.445839 -233.119453) (xy 353.446334 -233.14406)
			(xy 353.775276 -233.14406) (xy 353.779236 -233.095006) (xy 353.791013 -233.047222) (xy 353.810304 -233.001946)
			(xy 353.836607 -232.96035) (xy 353.869242 -232.923513) (xy 353.907363 -232.892388) (xy 353.949984 -232.867781)
			(xy 353.996 -232.850329) (xy 354.044219 -232.840485) (xy 354.093394 -232.838504) (xy 354.142249 -232.844436)
			(xy 354.18952 -232.858128) (xy 354.233982 -232.879226) (xy 354.274485 -232.907182) (xy 354.309978 -232.941274)
			(xy 354.339543 -232.980618) (xy 354.362414 -233.024195) (xy 354.377998 -233.070876) (xy 354.385893 -233.119453)
			(xy 354.386388 -233.14406) (xy 354.71533 -233.14406) (xy 354.71929 -233.095006) (xy 354.731067 -233.047222)
			(xy 354.750358 -233.001946) (xy 354.776661 -232.96035) (xy 354.809296 -232.923513) (xy 354.847417 -232.892388)
			(xy 354.890038 -232.867781) (xy 354.936054 -232.850329) (xy 354.984273 -232.840485) (xy 355.033448 -232.838504)
			(xy 355.082303 -232.844436) (xy 355.129574 -232.858128) (xy 355.174036 -232.879226) (xy 355.214539 -232.907182)
			(xy 355.250032 -232.941274) (xy 355.279597 -232.980618) (xy 355.302468 -233.024195) (xy 355.318052 -233.070876)
			(xy 355.325947 -233.119453) (xy 355.326442 -233.14406) (xy 355.655384 -233.14406) (xy 355.659344 -233.095006)
			(xy 355.671121 -233.047222) (xy 355.690412 -233.001946) (xy 355.716715 -232.96035) (xy 355.74935 -232.923513)
			(xy 355.787471 -232.892388) (xy 355.830092 -232.867781) (xy 355.876108 -232.850329) (xy 355.924327 -232.840485)
			(xy 355.973502 -232.838504) (xy 356.022357 -232.844436) (xy 356.069628 -232.858128) (xy 356.11409 -232.879226)
			(xy 356.154593 -232.907182) (xy 356.190086 -232.941274) (xy 356.219651 -232.980618) (xy 356.242522 -233.024195)
			(xy 356.258106 -233.070876) (xy 356.266001 -233.119453) (xy 356.266496 -233.14406) (xy 356.595438 -233.14406)
			(xy 356.599398 -233.095006) (xy 356.611175 -233.047222) (xy 356.630466 -233.001946) (xy 356.656769 -232.96035)
			(xy 356.689404 -232.923513) (xy 356.727525 -232.892388) (xy 356.770146 -232.867781) (xy 356.816162 -232.850329)
			(xy 356.864381 -232.840485) (xy 356.913556 -232.838504) (xy 356.962411 -232.844436) (xy 357.009682 -232.858128)
			(xy 357.054144 -232.879226) (xy 357.094647 -232.907182) (xy 357.13014 -232.941274) (xy 357.159705 -232.980618)
			(xy 357.182576 -233.024195) (xy 357.19816 -233.070876) (xy 357.206055 -233.119453) (xy 357.20655 -233.14406)
			(xy 357.206055 -233.168667) (xy 357.19816 -233.217244) (xy 357.182576 -233.263925) (xy 357.159705 -233.307502)
			(xy 357.13014 -233.346846) (xy 357.094647 -233.380938) (xy 357.054144 -233.408894) (xy 357.009682 -233.429992)
			(xy 356.962411 -233.443684) (xy 356.913556 -233.449616) (xy 356.864381 -233.447635) (xy 356.816162 -233.437791)
			(xy 356.770146 -233.420339) (xy 356.727525 -233.395732) (xy 356.689404 -233.364607) (xy 356.656769 -233.32777)
			(xy 356.630466 -233.286174) (xy 356.611175 -233.240898) (xy 356.599398 -233.193114) (xy 356.595438 -233.14406)
			(xy 356.266496 -233.14406) (xy 356.266001 -233.168667) (xy 356.258106 -233.217244) (xy 356.242522 -233.263925)
			(xy 356.219651 -233.307502) (xy 356.190086 -233.346846) (xy 356.154593 -233.380938) (xy 356.11409 -233.408894)
			(xy 356.069628 -233.429992) (xy 356.022357 -233.443684) (xy 355.973502 -233.449616) (xy 355.924327 -233.447635)
			(xy 355.876108 -233.437791) (xy 355.830092 -233.420339) (xy 355.787471 -233.395732) (xy 355.74935 -233.364607)
			(xy 355.716715 -233.32777) (xy 355.690412 -233.286174) (xy 355.671121 -233.240898) (xy 355.659344 -233.193114)
			(xy 355.655384 -233.14406) (xy 355.326442 -233.14406) (xy 355.325947 -233.168667) (xy 355.318052 -233.217244)
			(xy 355.302468 -233.263925) (xy 355.279597 -233.307502) (xy 355.250032 -233.346846) (xy 355.214539 -233.380938)
			(xy 355.174036 -233.408894) (xy 355.129574 -233.429992) (xy 355.082303 -233.443684) (xy 355.033448 -233.449616)
			(xy 354.984273 -233.447635) (xy 354.936054 -233.437791) (xy 354.890038 -233.420339) (xy 354.847417 -233.395732)
			(xy 354.809296 -233.364607) (xy 354.776661 -233.32777) (xy 354.750358 -233.286174) (xy 354.731067 -233.240898)
			(xy 354.71929 -233.193114) (xy 354.71533 -233.14406) (xy 354.386388 -233.14406) (xy 354.385893 -233.168667)
			(xy 354.377998 -233.217244) (xy 354.362414 -233.263925) (xy 354.339543 -233.307502) (xy 354.309978 -233.346846)
			(xy 354.274485 -233.380938) (xy 354.233982 -233.408894) (xy 354.18952 -233.429992) (xy 354.142249 -233.443684)
			(xy 354.093394 -233.449616) (xy 354.044219 -233.447635) (xy 353.996 -233.437791) (xy 353.949984 -233.420339)
			(xy 353.907363 -233.395732) (xy 353.869242 -233.364607) (xy 353.836607 -233.32777) (xy 353.810304 -233.286174)
			(xy 353.791013 -233.240898) (xy 353.779236 -233.193114) (xy 353.775276 -233.14406) (xy 353.446334 -233.14406)
			(xy 353.445839 -233.168667) (xy 353.437944 -233.217244) (xy 353.42236 -233.263925) (xy 353.399489 -233.307502)
			(xy 353.369924 -233.346846) (xy 353.334431 -233.380938) (xy 353.293928 -233.408894) (xy 353.249466 -233.429992)
			(xy 353.202195 -233.443684) (xy 353.15334 -233.449616) (xy 353.104165 -233.447635) (xy 353.055946 -233.437791)
			(xy 353.00993 -233.420339) (xy 352.967309 -233.395732) (xy 352.929188 -233.364607) (xy 352.896553 -233.32777)
			(xy 352.87025 -233.286174) (xy 352.850959 -233.240898) (xy 352.839182 -233.193114) (xy 352.835222 -233.14406)
			(xy 352.506534 -233.14406) (xy 352.506039 -233.168667) (xy 352.498144 -233.217244) (xy 352.48256 -233.263925)
			(xy 352.459689 -233.307502) (xy 352.430124 -233.346846) (xy 352.394631 -233.380938) (xy 352.354128 -233.408894)
			(xy 352.309666 -233.429992) (xy 352.262395 -233.443684) (xy 352.21354 -233.449616) (xy 352.164365 -233.447635)
			(xy 352.116146 -233.437791) (xy 352.07013 -233.420339) (xy 352.027509 -233.395732) (xy 351.989388 -233.364607)
			(xy 351.956753 -233.32777) (xy 351.93045 -233.286174) (xy 351.911159 -233.240898) (xy 351.899382 -233.193114)
			(xy 351.895422 -233.14406) (xy 351.56648 -233.14406) (xy 351.565985 -233.168667) (xy 351.55809 -233.217244)
			(xy 351.542506 -233.263925) (xy 351.519635 -233.307502) (xy 351.49007 -233.346846) (xy 351.454577 -233.380938)
			(xy 351.414074 -233.408894) (xy 351.369612 -233.429992) (xy 351.322341 -233.443684) (xy 351.273486 -233.449616)
			(xy 351.224311 -233.447635) (xy 351.176092 -233.437791) (xy 351.130076 -233.420339) (xy 351.087455 -233.395732)
			(xy 351.049334 -233.364607) (xy 351.016699 -233.32777) (xy 350.990396 -233.286174) (xy 350.971105 -233.240898)
			(xy 350.959328 -233.193114) (xy 350.955368 -233.14406) (xy 350.626426 -233.14406) (xy 350.625931 -233.168667)
			(xy 350.618036 -233.217244) (xy 350.602452 -233.263925) (xy 350.579581 -233.307502) (xy 350.550016 -233.346846)
			(xy 350.514523 -233.380938) (xy 350.47402 -233.408894) (xy 350.429558 -233.429992) (xy 350.382287 -233.443684)
			(xy 350.333432 -233.449616) (xy 350.284257 -233.447635) (xy 350.236038 -233.437791) (xy 350.190022 -233.420339)
			(xy 350.147401 -233.395732) (xy 350.10928 -233.364607) (xy 350.076645 -233.32777) (xy 350.050342 -233.286174)
			(xy 350.031051 -233.240898) (xy 350.019274 -233.193114) (xy 350.015314 -233.14406) (xy 349.686372 -233.14406)
			(xy 349.685877 -233.168667) (xy 349.677982 -233.217244) (xy 349.662398 -233.263925) (xy 349.639527 -233.307502)
			(xy 349.609962 -233.346846) (xy 349.574469 -233.380938) (xy 349.533966 -233.408894) (xy 349.489504 -233.429992)
			(xy 349.442233 -233.443684) (xy 349.393378 -233.449616) (xy 349.344203 -233.447635) (xy 349.295984 -233.437791)
			(xy 349.249968 -233.420339) (xy 349.207347 -233.395732) (xy 349.169226 -233.364607) (xy 349.136591 -233.32777)
			(xy 349.110288 -233.286174) (xy 349.090997 -233.240898) (xy 349.07922 -233.193114) (xy 349.07526 -233.14406)
			(xy 348.746318 -233.14406) (xy 348.745823 -233.168667) (xy 348.737928 -233.217244) (xy 348.722344 -233.263925)
			(xy 348.699473 -233.307502) (xy 348.669908 -233.346846) (xy 348.634415 -233.380938) (xy 348.593912 -233.408894)
			(xy 348.54945 -233.429992) (xy 348.502179 -233.443684) (xy 348.453324 -233.449616) (xy 348.404149 -233.447635)
			(xy 348.35593 -233.437791) (xy 348.309914 -233.420339) (xy 348.267293 -233.395732) (xy 348.229172 -233.364607)
			(xy 348.196537 -233.32777) (xy 348.170234 -233.286174) (xy 348.150943 -233.240898) (xy 348.139166 -233.193114)
			(xy 348.135206 -233.14406) (xy 347.806518 -233.14406) (xy 347.806023 -233.168667) (xy 347.798128 -233.217244)
			(xy 347.782544 -233.263925) (xy 347.759673 -233.307502) (xy 347.730108 -233.346846) (xy 347.694615 -233.380938)
			(xy 347.654112 -233.408894) (xy 347.60965 -233.429992) (xy 347.562379 -233.443684) (xy 347.513524 -233.449616)
			(xy 347.464349 -233.447635) (xy 347.41613 -233.437791) (xy 347.370114 -233.420339) (xy 347.327493 -233.395732)
			(xy 347.289372 -233.364607) (xy 347.256737 -233.32777) (xy 347.230434 -233.286174) (xy 347.211143 -233.240898)
			(xy 347.199366 -233.193114) (xy 347.195406 -233.14406) (xy 346.866464 -233.14406) (xy 346.865969 -233.168667)
			(xy 346.858074 -233.217244) (xy 346.84249 -233.263925) (xy 346.819619 -233.307502) (xy 346.790054 -233.346846)
			(xy 346.754561 -233.380938) (xy 346.714058 -233.408894) (xy 346.669596 -233.429992) (xy 346.622325 -233.443684)
			(xy 346.57347 -233.449616) (xy 346.524295 -233.447635) (xy 346.476076 -233.437791) (xy 346.43006 -233.420339)
			(xy 346.387439 -233.395732) (xy 346.349318 -233.364607) (xy 346.316683 -233.32777) (xy 346.29038 -233.286174)
			(xy 346.271089 -233.240898) (xy 346.259312 -233.193114) (xy 346.255352 -233.14406) (xy 345.92641 -233.14406)
			(xy 345.925915 -233.168667) (xy 345.91802 -233.217244) (xy 345.902436 -233.263925) (xy 345.879565 -233.307502)
			(xy 345.85 -233.346846) (xy 345.814507 -233.380938) (xy 345.774004 -233.408894) (xy 345.729542 -233.429992)
			(xy 345.682271 -233.443684) (xy 345.633416 -233.449616) (xy 345.584241 -233.447635) (xy 345.536022 -233.437791)
			(xy 345.490006 -233.420339) (xy 345.447385 -233.395732) (xy 345.409264 -233.364607) (xy 345.376629 -233.32777)
			(xy 345.350326 -233.286174) (xy 345.331035 -233.240898) (xy 345.319258 -233.193114) (xy 345.315298 -233.14406)
			(xy 344.986356 -233.14406) (xy 344.985861 -233.168667) (xy 344.977966 -233.217244) (xy 344.962382 -233.263925)
			(xy 344.939511 -233.307502) (xy 344.909946 -233.346846) (xy 344.874453 -233.380938) (xy 344.83395 -233.408894)
			(xy 344.789488 -233.429992) (xy 344.742217 -233.443684) (xy 344.693362 -233.449616) (xy 344.644187 -233.447635)
			(xy 344.595968 -233.437791) (xy 344.549952 -233.420339) (xy 344.507331 -233.395732) (xy 344.46921 -233.364607)
			(xy 344.436575 -233.32777) (xy 344.410272 -233.286174) (xy 344.390981 -233.240898) (xy 344.379204 -233.193114)
			(xy 344.375244 -233.14406) (xy 344.11666 -233.14406) (xy 344.11666 -233.547158) (xy 344.117126 -233.557033)
			(xy 344.124575 -233.575325) (xy 344.131138 -233.582718) (xy 344.181176 -233.633518) (xy 344.188323 -233.640196)
			(xy 344.20622 -233.648045) (xy 344.215974 -233.648758) (xy 344.216482 -233.648758) (xy 344.241442 -233.649696)
			(xy 344.290571 -233.65869) (xy 344.337581 -233.675559) (xy 344.38122 -233.699852) (xy 344.420324 -233.730923)
			(xy 344.453851 -233.767942) (xy 344.480907 -233.809924) (xy 344.500772 -233.855749) (xy 344.512915 -233.904195)
			(xy 344.517013 -233.953972) (xy 344.517005 -233.954066) (xy 346.725252 -233.954066) (xy 346.729212 -233.905012)
			(xy 346.740989 -233.857228) (xy 346.76028 -233.811952) (xy 346.786583 -233.770356) (xy 346.819218 -233.733519)
			(xy 346.857339 -233.702394) (xy 346.89996 -233.677787) (xy 346.945976 -233.660335) (xy 346.994195 -233.650491)
			(xy 347.04337 -233.64851) (xy 347.092225 -233.654442) (xy 347.139496 -233.668134) (xy 347.183958 -233.689232)
			(xy 347.224461 -233.717188) (xy 347.259954 -233.75128) (xy 347.289519 -233.790624) (xy 347.31239 -233.834201)
			(xy 347.327974 -233.880882) (xy 347.335869 -233.929459) (xy 347.336364 -233.954066) (xy 349.545414 -233.954066)
			(xy 349.549374 -233.905012) (xy 349.561151 -233.857228) (xy 349.580442 -233.811952) (xy 349.606745 -233.770356)
			(xy 349.63938 -233.733519) (xy 349.677501 -233.702394) (xy 349.720122 -233.677787) (xy 349.766138 -233.660335)
			(xy 349.814357 -233.650491) (xy 349.863532 -233.64851) (xy 349.912387 -233.654442) (xy 349.959658 -233.668134)
			(xy 350.00412 -233.689232) (xy 350.044623 -233.717188) (xy 350.080116 -233.75128) (xy 350.109681 -233.790624)
			(xy 350.132552 -233.834201) (xy 350.148136 -233.880882) (xy 350.156031 -233.929459) (xy 350.156526 -233.954066)
			(xy 352.365322 -233.954066) (xy 352.369282 -233.905012) (xy 352.381059 -233.857228) (xy 352.40035 -233.811952)
			(xy 352.426653 -233.770356) (xy 352.459288 -233.733519) (xy 352.497409 -233.702394) (xy 352.54003 -233.677787)
			(xy 352.586046 -233.660335) (xy 352.634265 -233.650491) (xy 352.68344 -233.64851) (xy 352.732295 -233.654442)
			(xy 352.779566 -233.668134) (xy 352.824028 -233.689232) (xy 352.864531 -233.717188) (xy 352.900024 -233.75128)
			(xy 352.929589 -233.790624) (xy 352.95246 -233.834201) (xy 352.968044 -233.880882) (xy 352.975939 -233.929459)
			(xy 352.976434 -233.954066) (xy 355.18523 -233.954066) (xy 355.18919 -233.905012) (xy 355.200967 -233.857228)
			(xy 355.220258 -233.811952) (xy 355.246561 -233.770356) (xy 355.279196 -233.733519) (xy 355.317317 -233.702394)
			(xy 355.359938 -233.677787) (xy 355.405954 -233.660335) (xy 355.454173 -233.650491) (xy 355.503348 -233.64851)
			(xy 355.552203 -233.654442) (xy 355.599474 -233.668134) (xy 355.643936 -233.689232) (xy 355.684439 -233.717188)
			(xy 355.719932 -233.75128) (xy 355.749497 -233.790624) (xy 355.772368 -233.834201) (xy 355.787952 -233.880882)
			(xy 355.795847 -233.929459) (xy 355.796342 -233.954066) (xy 356.125284 -233.954066) (xy 356.129244 -233.905012)
			(xy 356.141021 -233.857228) (xy 356.160312 -233.811952) (xy 356.186615 -233.770356) (xy 356.21925 -233.733519)
			(xy 356.257371 -233.702394) (xy 356.299992 -233.677787) (xy 356.346008 -233.660335) (xy 356.394227 -233.650491)
			(xy 356.443402 -233.64851) (xy 356.492257 -233.654442) (xy 356.539528 -233.668134) (xy 356.58399 -233.689232)
			(xy 356.624493 -233.717188) (xy 356.659986 -233.75128) (xy 356.689551 -233.790624) (xy 356.712422 -233.834201)
			(xy 356.728006 -233.880882) (xy 356.735901 -233.929459) (xy 356.736396 -233.954066) (xy 357.065338 -233.954066)
			(xy 357.069298 -233.905012) (xy 357.081075 -233.857228) (xy 357.100366 -233.811952) (xy 357.126669 -233.770356)
			(xy 357.159304 -233.733519) (xy 357.197425 -233.702394) (xy 357.240046 -233.677787) (xy 357.286062 -233.660335)
			(xy 357.334281 -233.650491) (xy 357.383456 -233.64851) (xy 357.432311 -233.654442) (xy 357.479582 -233.668134)
			(xy 357.524044 -233.689232) (xy 357.564547 -233.717188) (xy 357.60004 -233.75128) (xy 357.629605 -233.790624)
			(xy 357.652476 -233.834201) (xy 357.66806 -233.880882) (xy 357.675955 -233.929459) (xy 357.67645 -233.954066)
			(xy 357.675955 -233.978673) (xy 357.66806 -234.02725) (xy 357.652476 -234.073931) (xy 357.629605 -234.117508)
			(xy 357.60004 -234.156852) (xy 357.564547 -234.190944) (xy 357.524044 -234.2189) (xy 357.479582 -234.239998)
			(xy 357.432311 -234.25369) (xy 357.383456 -234.259622) (xy 357.334281 -234.257641) (xy 357.286062 -234.247797)
			(xy 357.240046 -234.230345) (xy 357.197425 -234.205738) (xy 357.159304 -234.174613) (xy 357.126669 -234.137776)
			(xy 357.100366 -234.09618) (xy 357.081075 -234.050904) (xy 357.069298 -234.00312) (xy 357.065338 -233.954066)
			(xy 356.736396 -233.954066) (xy 356.735901 -233.978673) (xy 356.728006 -234.02725) (xy 356.712422 -234.073931)
			(xy 356.689551 -234.117508) (xy 356.659986 -234.156852) (xy 356.624493 -234.190944) (xy 356.58399 -234.2189)
			(xy 356.539528 -234.239998) (xy 356.492257 -234.25369) (xy 356.443402 -234.259622) (xy 356.394227 -234.257641)
			(xy 356.346008 -234.247797) (xy 356.299992 -234.230345) (xy 356.257371 -234.205738) (xy 356.21925 -234.174613)
			(xy 356.186615 -234.137776) (xy 356.160312 -234.09618) (xy 356.141021 -234.050904) (xy 356.129244 -234.00312)
			(xy 356.125284 -233.954066) (xy 355.796342 -233.954066) (xy 355.795847 -233.978673) (xy 355.787952 -234.02725)
			(xy 355.772368 -234.073931) (xy 355.749497 -234.117508) (xy 355.719932 -234.156852) (xy 355.684439 -234.190944)
			(xy 355.643936 -234.2189) (xy 355.599474 -234.239998) (xy 355.552203 -234.25369) (xy 355.503348 -234.259622)
			(xy 355.454173 -234.257641) (xy 355.405954 -234.247797) (xy 355.359938 -234.230345) (xy 355.317317 -234.205738)
			(xy 355.279196 -234.174613) (xy 355.246561 -234.137776) (xy 355.220258 -234.09618) (xy 355.200967 -234.050904)
			(xy 355.18919 -234.00312) (xy 355.18523 -233.954066) (xy 352.976434 -233.954066) (xy 352.975939 -233.978673)
			(xy 352.968044 -234.02725) (xy 352.95246 -234.073931) (xy 352.929589 -234.117508) (xy 352.900024 -234.156852)
			(xy 352.864531 -234.190944) (xy 352.824028 -234.2189) (xy 352.779566 -234.239998) (xy 352.732295 -234.25369)
			(xy 352.68344 -234.259622) (xy 352.634265 -234.257641) (xy 352.586046 -234.247797) (xy 352.54003 -234.230345)
			(xy 352.497409 -234.205738) (xy 352.459288 -234.174613) (xy 352.426653 -234.137776) (xy 352.40035 -234.09618)
			(xy 352.381059 -234.050904) (xy 352.369282 -234.00312) (xy 352.365322 -233.954066) (xy 350.156526 -233.954066)
			(xy 350.156031 -233.978673) (xy 350.148136 -234.02725) (xy 350.132552 -234.073931) (xy 350.109681 -234.117508)
			(xy 350.080116 -234.156852) (xy 350.044623 -234.190944) (xy 350.00412 -234.2189) (xy 349.959658 -234.239998)
			(xy 349.912387 -234.25369) (xy 349.863532 -234.259622) (xy 349.814357 -234.257641) (xy 349.766138 -234.247797)
			(xy 349.720122 -234.230345) (xy 349.677501 -234.205738) (xy 349.63938 -234.174613) (xy 349.606745 -234.137776)
			(xy 349.580442 -234.09618) (xy 349.561151 -234.050904) (xy 349.549374 -234.00312) (xy 349.545414 -233.954066)
			(xy 347.336364 -233.954066) (xy 347.335869 -233.978673) (xy 347.327974 -234.02725) (xy 347.31239 -234.073931)
			(xy 347.289519 -234.117508) (xy 347.259954 -234.156852) (xy 347.224461 -234.190944) (xy 347.183958 -234.2189)
			(xy 347.139496 -234.239998) (xy 347.092225 -234.25369) (xy 347.04337 -234.259622) (xy 346.994195 -234.257641)
			(xy 346.945976 -234.247797) (xy 346.89996 -234.230345) (xy 346.857339 -234.205738) (xy 346.819218 -234.174613)
			(xy 346.786583 -234.137776) (xy 346.76028 -234.09618) (xy 346.740989 -234.050904) (xy 346.729212 -234.00312)
			(xy 346.725252 -233.954066) (xy 344.517005 -233.954066) (xy 344.512957 -234.003752) (xy 344.500854 -234.052209)
			(xy 344.481028 -234.09805) (xy 344.454006 -234.140055) (xy 344.42051 -234.177102) (xy 344.381432 -234.208206)
			(xy 344.337814 -234.232536) (xy 344.290817 -234.249444) (xy 344.241696 -234.258479) (xy 344.216736 -234.259374)
			(xy 344.215974 -234.259374) (xy 344.206223 -234.260107) (xy 344.188328 -234.267945) (xy 344.181176 -234.274614)
			(xy 344.131138 -234.325414) (xy 344.12455 -234.332794) (xy 344.117087 -234.351092) (xy 344.11666 -234.360974)
			(xy 344.11666 -234.764072) (xy 344.375244 -234.764072) (xy 344.379204 -234.715018) (xy 344.390981 -234.667234)
			(xy 344.410272 -234.621958) (xy 344.436575 -234.580362) (xy 344.46921 -234.543525) (xy 344.507331 -234.5124)
			(xy 344.549952 -234.487793) (xy 344.595968 -234.470341) (xy 344.644187 -234.460497) (xy 344.693362 -234.458516)
			(xy 344.742217 -234.464448) (xy 344.789488 -234.47814) (xy 344.83395 -234.499238) (xy 344.874453 -234.527194)
			(xy 344.909946 -234.561286) (xy 344.939511 -234.60063) (xy 344.962382 -234.644207) (xy 344.977966 -234.690888)
			(xy 344.985861 -234.739465) (xy 344.986356 -234.764072) (xy 345.315298 -234.764072) (xy 345.319258 -234.715018)
			(xy 345.331035 -234.667234) (xy 345.350326 -234.621958) (xy 345.376629 -234.580362) (xy 345.409264 -234.543525)
			(xy 345.447385 -234.5124) (xy 345.490006 -234.487793) (xy 345.536022 -234.470341) (xy 345.584241 -234.460497)
			(xy 345.633416 -234.458516) (xy 345.682271 -234.464448) (xy 345.729542 -234.47814) (xy 345.774004 -234.499238)
			(xy 345.814507 -234.527194) (xy 345.85 -234.561286) (xy 345.879565 -234.60063) (xy 345.902436 -234.644207)
			(xy 345.91802 -234.690888) (xy 345.925915 -234.739465) (xy 345.92641 -234.764072) (xy 346.255352 -234.764072)
			(xy 346.259312 -234.715018) (xy 346.271089 -234.667234) (xy 346.29038 -234.621958) (xy 346.316683 -234.580362)
			(xy 346.349318 -234.543525) (xy 346.387439 -234.5124) (xy 346.43006 -234.487793) (xy 346.476076 -234.470341)
			(xy 346.524295 -234.460497) (xy 346.57347 -234.458516) (xy 346.622325 -234.464448) (xy 346.669596 -234.47814)
			(xy 346.714058 -234.499238) (xy 346.754561 -234.527194) (xy 346.790054 -234.561286) (xy 346.819619 -234.60063)
			(xy 346.84249 -234.644207) (xy 346.858074 -234.690888) (xy 346.865969 -234.739465) (xy 346.866464 -234.764072)
			(xy 347.195406 -234.764072) (xy 347.199366 -234.715018) (xy 347.211143 -234.667234) (xy 347.230434 -234.621958)
			(xy 347.256737 -234.580362) (xy 347.289372 -234.543525) (xy 347.327493 -234.5124) (xy 347.370114 -234.487793)
			(xy 347.41613 -234.470341) (xy 347.464349 -234.460497) (xy 347.513524 -234.458516) (xy 347.562379 -234.464448)
			(xy 347.60965 -234.47814) (xy 347.654112 -234.499238) (xy 347.694615 -234.527194) (xy 347.730108 -234.561286)
			(xy 347.759673 -234.60063) (xy 347.782544 -234.644207) (xy 347.798128 -234.690888) (xy 347.806023 -234.739465)
			(xy 347.806518 -234.764072) (xy 348.135206 -234.764072) (xy 348.139166 -234.715018) (xy 348.150943 -234.667234)
			(xy 348.170234 -234.621958) (xy 348.196537 -234.580362) (xy 348.229172 -234.543525) (xy 348.267293 -234.5124)
			(xy 348.309914 -234.487793) (xy 348.35593 -234.470341) (xy 348.404149 -234.460497) (xy 348.453324 -234.458516)
			(xy 348.502179 -234.464448) (xy 348.54945 -234.47814) (xy 348.593912 -234.499238) (xy 348.634415 -234.527194)
			(xy 348.669908 -234.561286) (xy 348.699473 -234.60063) (xy 348.722344 -234.644207) (xy 348.737928 -234.690888)
			(xy 348.745823 -234.739465) (xy 348.746318 -234.764072) (xy 349.07526 -234.764072) (xy 349.07922 -234.715018)
			(xy 349.090997 -234.667234) (xy 349.110288 -234.621958) (xy 349.136591 -234.580362) (xy 349.169226 -234.543525)
			(xy 349.207347 -234.5124) (xy 349.249968 -234.487793) (xy 349.295984 -234.470341) (xy 349.344203 -234.460497)
			(xy 349.393378 -234.458516) (xy 349.442233 -234.464448) (xy 349.489504 -234.47814) (xy 349.533966 -234.499238)
			(xy 349.574469 -234.527194) (xy 349.609962 -234.561286) (xy 349.639527 -234.60063) (xy 349.662398 -234.644207)
			(xy 349.677982 -234.690888) (xy 349.685877 -234.739465) (xy 349.686372 -234.764072) (xy 350.015314 -234.764072)
			(xy 350.019274 -234.715018) (xy 350.031051 -234.667234) (xy 350.050342 -234.621958) (xy 350.076645 -234.580362)
			(xy 350.10928 -234.543525) (xy 350.147401 -234.5124) (xy 350.190022 -234.487793) (xy 350.236038 -234.470341)
			(xy 350.284257 -234.460497) (xy 350.333432 -234.458516) (xy 350.382287 -234.464448) (xy 350.429558 -234.47814)
			(xy 350.47402 -234.499238) (xy 350.514523 -234.527194) (xy 350.550016 -234.561286) (xy 350.579581 -234.60063)
			(xy 350.602452 -234.644207) (xy 350.618036 -234.690888) (xy 350.625931 -234.739465) (xy 350.626426 -234.764072)
			(xy 350.955368 -234.764072) (xy 350.959328 -234.715018) (xy 350.971105 -234.667234) (xy 350.990396 -234.621958)
			(xy 351.016699 -234.580362) (xy 351.049334 -234.543525) (xy 351.087455 -234.5124) (xy 351.130076 -234.487793)
			(xy 351.176092 -234.470341) (xy 351.224311 -234.460497) (xy 351.273486 -234.458516) (xy 351.322341 -234.464448)
			(xy 351.369612 -234.47814) (xy 351.414074 -234.499238) (xy 351.454577 -234.527194) (xy 351.49007 -234.561286)
			(xy 351.519635 -234.60063) (xy 351.542506 -234.644207) (xy 351.55809 -234.690888) (xy 351.565985 -234.739465)
			(xy 351.56648 -234.764072) (xy 351.895422 -234.764072) (xy 351.899382 -234.715018) (xy 351.911159 -234.667234)
			(xy 351.93045 -234.621958) (xy 351.956753 -234.580362) (xy 351.989388 -234.543525) (xy 352.027509 -234.5124)
			(xy 352.07013 -234.487793) (xy 352.116146 -234.470341) (xy 352.164365 -234.460497) (xy 352.21354 -234.458516)
			(xy 352.262395 -234.464448) (xy 352.309666 -234.47814) (xy 352.354128 -234.499238) (xy 352.394631 -234.527194)
			(xy 352.430124 -234.561286) (xy 352.459689 -234.60063) (xy 352.48256 -234.644207) (xy 352.498144 -234.690888)
			(xy 352.506039 -234.739465) (xy 352.506534 -234.764072) (xy 352.835222 -234.764072) (xy 352.839182 -234.715018)
			(xy 352.850959 -234.667234) (xy 352.87025 -234.621958) (xy 352.896553 -234.580362) (xy 352.929188 -234.543525)
			(xy 352.967309 -234.5124) (xy 353.00993 -234.487793) (xy 353.055946 -234.470341) (xy 353.104165 -234.460497)
			(xy 353.15334 -234.458516) (xy 353.202195 -234.464448) (xy 353.249466 -234.47814) (xy 353.293928 -234.499238)
			(xy 353.334431 -234.527194) (xy 353.369924 -234.561286) (xy 353.399489 -234.60063) (xy 353.42236 -234.644207)
			(xy 353.437944 -234.690888) (xy 353.445839 -234.739465) (xy 353.446334 -234.764072) (xy 353.775276 -234.764072)
			(xy 353.779236 -234.715018) (xy 353.791013 -234.667234) (xy 353.810304 -234.621958) (xy 353.836607 -234.580362)
			(xy 353.869242 -234.543525) (xy 353.907363 -234.5124) (xy 353.949984 -234.487793) (xy 353.996 -234.470341)
			(xy 354.044219 -234.460497) (xy 354.093394 -234.458516) (xy 354.142249 -234.464448) (xy 354.18952 -234.47814)
			(xy 354.233982 -234.499238) (xy 354.274485 -234.527194) (xy 354.309978 -234.561286) (xy 354.339543 -234.60063)
			(xy 354.362414 -234.644207) (xy 354.377998 -234.690888) (xy 354.385893 -234.739465) (xy 354.386388 -234.764072)
			(xy 354.71533 -234.764072) (xy 354.71929 -234.715018) (xy 354.731067 -234.667234) (xy 354.750358 -234.621958)
			(xy 354.776661 -234.580362) (xy 354.809296 -234.543525) (xy 354.847417 -234.5124) (xy 354.890038 -234.487793)
			(xy 354.936054 -234.470341) (xy 354.984273 -234.460497) (xy 355.033448 -234.458516) (xy 355.082303 -234.464448)
			(xy 355.129574 -234.47814) (xy 355.174036 -234.499238) (xy 355.214539 -234.527194) (xy 355.250032 -234.561286)
			(xy 355.279597 -234.60063) (xy 355.302468 -234.644207) (xy 355.318052 -234.690888) (xy 355.325947 -234.739465)
			(xy 355.326442 -234.764072) (xy 355.655384 -234.764072) (xy 355.659344 -234.715018) (xy 355.671121 -234.667234)
			(xy 355.690412 -234.621958) (xy 355.716715 -234.580362) (xy 355.74935 -234.543525) (xy 355.787471 -234.5124)
			(xy 355.830092 -234.487793) (xy 355.876108 -234.470341) (xy 355.924327 -234.460497) (xy 355.973502 -234.458516)
			(xy 356.022357 -234.464448) (xy 356.069628 -234.47814) (xy 356.11409 -234.499238) (xy 356.154593 -234.527194)
			(xy 356.190086 -234.561286) (xy 356.219651 -234.60063) (xy 356.242522 -234.644207) (xy 356.258106 -234.690888)
			(xy 356.266001 -234.739465) (xy 356.266496 -234.764072) (xy 356.266001 -234.788679) (xy 356.258106 -234.837256)
			(xy 356.242522 -234.883937) (xy 356.219651 -234.927514) (xy 356.190086 -234.966858) (xy 356.154593 -235.00095)
			(xy 356.11409 -235.028906) (xy 356.069628 -235.050004) (xy 356.022357 -235.063696) (xy 355.973502 -235.069628)
			(xy 355.924327 -235.067647) (xy 355.876108 -235.057803) (xy 355.830092 -235.040351) (xy 355.787471 -235.015744)
			(xy 355.74935 -234.984619) (xy 355.716715 -234.947782) (xy 355.690412 -234.906186) (xy 355.671121 -234.86091)
			(xy 355.659344 -234.813126) (xy 355.655384 -234.764072) (xy 355.326442 -234.764072) (xy 355.325947 -234.788679)
			(xy 355.318052 -234.837256) (xy 355.302468 -234.883937) (xy 355.279597 -234.927514) (xy 355.250032 -234.966858)
			(xy 355.214539 -235.00095) (xy 355.174036 -235.028906) (xy 355.129574 -235.050004) (xy 355.082303 -235.063696)
			(xy 355.033448 -235.069628) (xy 354.984273 -235.067647) (xy 354.936054 -235.057803) (xy 354.890038 -235.040351)
			(xy 354.847417 -235.015744) (xy 354.809296 -234.984619) (xy 354.776661 -234.947782) (xy 354.750358 -234.906186)
			(xy 354.731067 -234.86091) (xy 354.71929 -234.813126) (xy 354.71533 -234.764072) (xy 354.386388 -234.764072)
			(xy 354.385893 -234.788679) (xy 354.377998 -234.837256) (xy 354.362414 -234.883937) (xy 354.339543 -234.927514)
			(xy 354.309978 -234.966858) (xy 354.274485 -235.00095) (xy 354.233982 -235.028906) (xy 354.18952 -235.050004)
			(xy 354.142249 -235.063696) (xy 354.093394 -235.069628) (xy 354.044219 -235.067647) (xy 353.996 -235.057803)
			(xy 353.949984 -235.040351) (xy 353.907363 -235.015744) (xy 353.869242 -234.984619) (xy 353.836607 -234.947782)
			(xy 353.810304 -234.906186) (xy 353.791013 -234.86091) (xy 353.779236 -234.813126) (xy 353.775276 -234.764072)
			(xy 353.446334 -234.764072) (xy 353.445839 -234.788679) (xy 353.437944 -234.837256) (xy 353.42236 -234.883937)
			(xy 353.399489 -234.927514) (xy 353.369924 -234.966858) (xy 353.334431 -235.00095) (xy 353.293928 -235.028906)
			(xy 353.249466 -235.050004) (xy 353.202195 -235.063696) (xy 353.15334 -235.069628) (xy 353.104165 -235.067647)
			(xy 353.055946 -235.057803) (xy 353.00993 -235.040351) (xy 352.967309 -235.015744) (xy 352.929188 -234.984619)
			(xy 352.896553 -234.947782) (xy 352.87025 -234.906186) (xy 352.850959 -234.86091) (xy 352.839182 -234.813126)
			(xy 352.835222 -234.764072) (xy 352.506534 -234.764072) (xy 352.506039 -234.788679) (xy 352.498144 -234.837256)
			(xy 352.48256 -234.883937) (xy 352.459689 -234.927514) (xy 352.430124 -234.966858) (xy 352.394631 -235.00095)
			(xy 352.354128 -235.028906) (xy 352.309666 -235.050004) (xy 352.262395 -235.063696) (xy 352.21354 -235.069628)
			(xy 352.164365 -235.067647) (xy 352.116146 -235.057803) (xy 352.07013 -235.040351) (xy 352.027509 -235.015744)
			(xy 351.989388 -234.984619) (xy 351.956753 -234.947782) (xy 351.93045 -234.906186) (xy 351.911159 -234.86091)
			(xy 351.899382 -234.813126) (xy 351.895422 -234.764072) (xy 351.56648 -234.764072) (xy 351.565985 -234.788679)
			(xy 351.55809 -234.837256) (xy 351.542506 -234.883937) (xy 351.519635 -234.927514) (xy 351.49007 -234.966858)
			(xy 351.454577 -235.00095) (xy 351.414074 -235.028906) (xy 351.369612 -235.050004) (xy 351.322341 -235.063696)
			(xy 351.273486 -235.069628) (xy 351.224311 -235.067647) (xy 351.176092 -235.057803) (xy 351.130076 -235.040351)
			(xy 351.087455 -235.015744) (xy 351.049334 -234.984619) (xy 351.016699 -234.947782) (xy 350.990396 -234.906186)
			(xy 350.971105 -234.86091) (xy 350.959328 -234.813126) (xy 350.955368 -234.764072) (xy 350.626426 -234.764072)
			(xy 350.625931 -234.788679) (xy 350.618036 -234.837256) (xy 350.602452 -234.883937) (xy 350.579581 -234.927514)
			(xy 350.550016 -234.966858) (xy 350.514523 -235.00095) (xy 350.47402 -235.028906) (xy 350.429558 -235.050004)
			(xy 350.382287 -235.063696) (xy 350.333432 -235.069628) (xy 350.284257 -235.067647) (xy 350.236038 -235.057803)
			(xy 350.190022 -235.040351) (xy 350.147401 -235.015744) (xy 350.10928 -234.984619) (xy 350.076645 -234.947782)
			(xy 350.050342 -234.906186) (xy 350.031051 -234.86091) (xy 350.019274 -234.813126) (xy 350.015314 -234.764072)
			(xy 349.686372 -234.764072) (xy 349.685877 -234.788679) (xy 349.677982 -234.837256) (xy 349.662398 -234.883937)
			(xy 349.639527 -234.927514) (xy 349.609962 -234.966858) (xy 349.574469 -235.00095) (xy 349.533966 -235.028906)
			(xy 349.489504 -235.050004) (xy 349.442233 -235.063696) (xy 349.393378 -235.069628) (xy 349.344203 -235.067647)
			(xy 349.295984 -235.057803) (xy 349.249968 -235.040351) (xy 349.207347 -235.015744) (xy 349.169226 -234.984619)
			(xy 349.136591 -234.947782) (xy 349.110288 -234.906186) (xy 349.090997 -234.86091) (xy 349.07922 -234.813126)
			(xy 349.07526 -234.764072) (xy 348.746318 -234.764072) (xy 348.745823 -234.788679) (xy 348.737928 -234.837256)
			(xy 348.722344 -234.883937) (xy 348.699473 -234.927514) (xy 348.669908 -234.966858) (xy 348.634415 -235.00095)
			(xy 348.593912 -235.028906) (xy 348.54945 -235.050004) (xy 348.502179 -235.063696) (xy 348.453324 -235.069628)
			(xy 348.404149 -235.067647) (xy 348.35593 -235.057803) (xy 348.309914 -235.040351) (xy 348.267293 -235.015744)
			(xy 348.229172 -234.984619) (xy 348.196537 -234.947782) (xy 348.170234 -234.906186) (xy 348.150943 -234.86091)
			(xy 348.139166 -234.813126) (xy 348.135206 -234.764072) (xy 347.806518 -234.764072) (xy 347.806023 -234.788679)
			(xy 347.798128 -234.837256) (xy 347.782544 -234.883937) (xy 347.759673 -234.927514) (xy 347.730108 -234.966858)
			(xy 347.694615 -235.00095) (xy 347.654112 -235.028906) (xy 347.60965 -235.050004) (xy 347.562379 -235.063696)
			(xy 347.513524 -235.069628) (xy 347.464349 -235.067647) (xy 347.41613 -235.057803) (xy 347.370114 -235.040351)
			(xy 347.327493 -235.015744) (xy 347.289372 -234.984619) (xy 347.256737 -234.947782) (xy 347.230434 -234.906186)
			(xy 347.211143 -234.86091) (xy 347.199366 -234.813126) (xy 347.195406 -234.764072) (xy 346.866464 -234.764072)
			(xy 346.865969 -234.788679) (xy 346.858074 -234.837256) (xy 346.84249 -234.883937) (xy 346.819619 -234.927514)
			(xy 346.790054 -234.966858) (xy 346.754561 -235.00095) (xy 346.714058 -235.028906) (xy 346.669596 -235.050004)
			(xy 346.622325 -235.063696) (xy 346.57347 -235.069628) (xy 346.524295 -235.067647) (xy 346.476076 -235.057803)
			(xy 346.43006 -235.040351) (xy 346.387439 -235.015744) (xy 346.349318 -234.984619) (xy 346.316683 -234.947782)
			(xy 346.29038 -234.906186) (xy 346.271089 -234.86091) (xy 346.259312 -234.813126) (xy 346.255352 -234.764072)
			(xy 345.92641 -234.764072) (xy 345.925915 -234.788679) (xy 345.91802 -234.837256) (xy 345.902436 -234.883937)
			(xy 345.879565 -234.927514) (xy 345.85 -234.966858) (xy 345.814507 -235.00095) (xy 345.774004 -235.028906)
			(xy 345.729542 -235.050004) (xy 345.682271 -235.063696) (xy 345.633416 -235.069628) (xy 345.584241 -235.067647)
			(xy 345.536022 -235.057803) (xy 345.490006 -235.040351) (xy 345.447385 -235.015744) (xy 345.409264 -234.984619)
			(xy 345.376629 -234.947782) (xy 345.350326 -234.906186) (xy 345.331035 -234.86091) (xy 345.319258 -234.813126)
			(xy 345.315298 -234.764072) (xy 344.986356 -234.764072) (xy 344.985861 -234.788679) (xy 344.977966 -234.837256)
			(xy 344.962382 -234.883937) (xy 344.939511 -234.927514) (xy 344.909946 -234.966858) (xy 344.874453 -235.00095)
			(xy 344.83395 -235.028906) (xy 344.789488 -235.050004) (xy 344.742217 -235.063696) (xy 344.693362 -235.069628)
			(xy 344.644187 -235.067647) (xy 344.595968 -235.057803) (xy 344.549952 -235.040351) (xy 344.507331 -235.015744)
			(xy 344.46921 -234.984619) (xy 344.436575 -234.947782) (xy 344.410272 -234.906186) (xy 344.390981 -234.86091)
			(xy 344.379204 -234.813126) (xy 344.375244 -234.764072) (xy 344.11666 -234.764072) (xy 344.11666 -235.16717)
			(xy 344.117128 -235.177044) (xy 344.12458 -235.195333) (xy 344.131138 -235.20273) (xy 344.181176 -235.25353)
			(xy 344.188324 -235.260206) (xy 344.20622 -235.268054) (xy 344.215974 -235.26877) (xy 344.216482 -235.26877)
			(xy 344.241441 -235.269707) (xy 344.290568 -235.278701) (xy 344.337576 -235.29557) (xy 344.381213 -235.319862)
			(xy 344.420316 -235.350932) (xy 344.453842 -235.38795) (xy 344.480897 -235.42993) (xy 344.500761 -235.475753)
			(xy 344.512903 -235.524198) (xy 344.517001 -235.573972) (xy 344.516992 -235.574078) (xy 344.845398 -235.574078)
			(xy 344.849358 -235.525024) (xy 344.861135 -235.47724) (xy 344.880426 -235.431964) (xy 344.906729 -235.390368)
			(xy 344.939364 -235.353531) (xy 344.977485 -235.322406) (xy 345.020106 -235.297799) (xy 345.066122 -235.280347)
			(xy 345.114341 -235.270503) (xy 345.163516 -235.268522) (xy 345.212371 -235.274454) (xy 345.259642 -235.288146)
			(xy 345.304104 -235.309244) (xy 345.344607 -235.3372) (xy 345.3801 -235.371292) (xy 345.409665 -235.410636)
			(xy 345.432536 -235.454213) (xy 345.44812 -235.500894) (xy 345.456015 -235.549471) (xy 345.45651 -235.574078)
			(xy 345.785198 -235.574078) (xy 345.789158 -235.525024) (xy 345.800935 -235.47724) (xy 345.820226 -235.431964)
			(xy 345.846529 -235.390368) (xy 345.879164 -235.353531) (xy 345.917285 -235.322406) (xy 345.959906 -235.297799)
			(xy 346.005922 -235.280347) (xy 346.054141 -235.270503) (xy 346.103316 -235.268522) (xy 346.152171 -235.274454)
			(xy 346.199442 -235.288146) (xy 346.243904 -235.309244) (xy 346.284407 -235.3372) (xy 346.3199 -235.371292)
			(xy 346.349465 -235.410636) (xy 346.372336 -235.454213) (xy 346.38792 -235.500894) (xy 346.395815 -235.549471)
			(xy 346.39631 -235.574078) (xy 346.725252 -235.574078) (xy 346.729212 -235.525024) (xy 346.740989 -235.47724)
			(xy 346.76028 -235.431964) (xy 346.786583 -235.390368) (xy 346.819218 -235.353531) (xy 346.857339 -235.322406)
			(xy 346.89996 -235.297799) (xy 346.945976 -235.280347) (xy 346.994195 -235.270503) (xy 347.04337 -235.268522)
			(xy 347.092225 -235.274454) (xy 347.139496 -235.288146) (xy 347.183958 -235.309244) (xy 347.224461 -235.3372)
			(xy 347.259954 -235.371292) (xy 347.289519 -235.410636) (xy 347.31239 -235.454213) (xy 347.327974 -235.500894)
			(xy 347.335869 -235.549471) (xy 347.336364 -235.574078) (xy 347.665306 -235.574078) (xy 347.669266 -235.525024)
			(xy 347.681043 -235.47724) (xy 347.700334 -235.431964) (xy 347.726637 -235.390368) (xy 347.759272 -235.353531)
			(xy 347.797393 -235.322406) (xy 347.840014 -235.297799) (xy 347.88603 -235.280347) (xy 347.934249 -235.270503)
			(xy 347.983424 -235.268522) (xy 348.032279 -235.274454) (xy 348.07955 -235.288146) (xy 348.124012 -235.309244)
			(xy 348.164515 -235.3372) (xy 348.200008 -235.371292) (xy 348.229573 -235.410636) (xy 348.252444 -235.454213)
			(xy 348.268028 -235.500894) (xy 348.275923 -235.549471) (xy 348.276418 -235.574078) (xy 348.60536 -235.574078)
			(xy 348.60932 -235.525024) (xy 348.621097 -235.47724) (xy 348.640388 -235.431964) (xy 348.666691 -235.390368)
			(xy 348.699326 -235.353531) (xy 348.737447 -235.322406) (xy 348.780068 -235.297799) (xy 348.826084 -235.280347)
			(xy 348.874303 -235.270503) (xy 348.923478 -235.268522) (xy 348.972333 -235.274454) (xy 349.019604 -235.288146)
			(xy 349.064066 -235.309244) (xy 349.104569 -235.3372) (xy 349.140062 -235.371292) (xy 349.169627 -235.410636)
			(xy 349.192498 -235.454213) (xy 349.208082 -235.500894) (xy 349.215977 -235.549471) (xy 349.216472 -235.574078)
			(xy 349.545414 -235.574078) (xy 349.549374 -235.525024) (xy 349.561151 -235.47724) (xy 349.580442 -235.431964)
			(xy 349.606745 -235.390368) (xy 349.63938 -235.353531) (xy 349.677501 -235.322406) (xy 349.720122 -235.297799)
			(xy 349.766138 -235.280347) (xy 349.814357 -235.270503) (xy 349.863532 -235.268522) (xy 349.912387 -235.274454)
			(xy 349.959658 -235.288146) (xy 350.00412 -235.309244) (xy 350.044623 -235.3372) (xy 350.080116 -235.371292)
			(xy 350.109681 -235.410636) (xy 350.132552 -235.454213) (xy 350.148136 -235.500894) (xy 350.156031 -235.549471)
			(xy 350.156526 -235.574078) (xy 350.485214 -235.574078) (xy 350.489174 -235.525024) (xy 350.500951 -235.47724)
			(xy 350.520242 -235.431964) (xy 350.546545 -235.390368) (xy 350.57918 -235.353531) (xy 350.617301 -235.322406)
			(xy 350.659922 -235.297799) (xy 350.705938 -235.280347) (xy 350.754157 -235.270503) (xy 350.803332 -235.268522)
			(xy 350.852187 -235.274454) (xy 350.899458 -235.288146) (xy 350.94392 -235.309244) (xy 350.984423 -235.3372)
			(xy 351.019916 -235.371292) (xy 351.049481 -235.410636) (xy 351.072352 -235.454213) (xy 351.087936 -235.500894)
			(xy 351.095831 -235.549471) (xy 351.096326 -235.574078) (xy 351.425268 -235.574078) (xy 351.429228 -235.525024)
			(xy 351.441005 -235.47724) (xy 351.460296 -235.431964) (xy 351.486599 -235.390368) (xy 351.519234 -235.353531)
			(xy 351.557355 -235.322406) (xy 351.599976 -235.297799) (xy 351.645992 -235.280347) (xy 351.694211 -235.270503)
			(xy 351.743386 -235.268522) (xy 351.792241 -235.274454) (xy 351.839512 -235.288146) (xy 351.883974 -235.309244)
			(xy 351.924477 -235.3372) (xy 351.95997 -235.371292) (xy 351.989535 -235.410636) (xy 352.012406 -235.454213)
			(xy 352.02799 -235.500894) (xy 352.035885 -235.549471) (xy 352.03638 -235.574078) (xy 352.365322 -235.574078)
			(xy 352.369282 -235.525024) (xy 352.381059 -235.47724) (xy 352.40035 -235.431964) (xy 352.426653 -235.390368)
			(xy 352.459288 -235.353531) (xy 352.497409 -235.322406) (xy 352.54003 -235.297799) (xy 352.586046 -235.280347)
			(xy 352.634265 -235.270503) (xy 352.68344 -235.268522) (xy 352.732295 -235.274454) (xy 352.779566 -235.288146)
			(xy 352.824028 -235.309244) (xy 352.864531 -235.3372) (xy 352.900024 -235.371292) (xy 352.929589 -235.410636)
			(xy 352.95246 -235.454213) (xy 352.968044 -235.500894) (xy 352.975939 -235.549471) (xy 352.976434 -235.574078)
			(xy 353.305376 -235.574078) (xy 353.309336 -235.525024) (xy 353.321113 -235.47724) (xy 353.340404 -235.431964)
			(xy 353.366707 -235.390368) (xy 353.399342 -235.353531) (xy 353.437463 -235.322406) (xy 353.480084 -235.297799)
			(xy 353.5261 -235.280347) (xy 353.574319 -235.270503) (xy 353.623494 -235.268522) (xy 353.672349 -235.274454)
			(xy 353.71962 -235.288146) (xy 353.764082 -235.309244) (xy 353.804585 -235.3372) (xy 353.840078 -235.371292)
			(xy 353.869643 -235.410636) (xy 353.892514 -235.454213) (xy 353.908098 -235.500894) (xy 353.915993 -235.549471)
			(xy 353.916488 -235.574078) (xy 354.24543 -235.574078) (xy 354.24939 -235.525024) (xy 354.261167 -235.47724)
			(xy 354.280458 -235.431964) (xy 354.306761 -235.390368) (xy 354.339396 -235.353531) (xy 354.377517 -235.322406)
			(xy 354.420138 -235.297799) (xy 354.466154 -235.280347) (xy 354.514373 -235.270503) (xy 354.563548 -235.268522)
			(xy 354.612403 -235.274454) (xy 354.659674 -235.288146) (xy 354.704136 -235.309244) (xy 354.744639 -235.3372)
			(xy 354.780132 -235.371292) (xy 354.809697 -235.410636) (xy 354.832568 -235.454213) (xy 354.848152 -235.500894)
			(xy 354.856047 -235.549471) (xy 354.856542 -235.574078) (xy 355.18523 -235.574078) (xy 355.18919 -235.525024)
			(xy 355.200967 -235.47724) (xy 355.220258 -235.431964) (xy 355.246561 -235.390368) (xy 355.279196 -235.353531)
			(xy 355.317317 -235.322406) (xy 355.359938 -235.297799) (xy 355.405954 -235.280347) (xy 355.454173 -235.270503)
			(xy 355.503348 -235.268522) (xy 355.552203 -235.274454) (xy 355.599474 -235.288146) (xy 355.643936 -235.309244)
			(xy 355.684439 -235.3372) (xy 355.719932 -235.371292) (xy 355.749497 -235.410636) (xy 355.772368 -235.454213)
			(xy 355.787952 -235.500894) (xy 355.795847 -235.549471) (xy 355.796342 -235.574078) (xy 356.125284 -235.574078)
			(xy 356.129244 -235.525024) (xy 356.141021 -235.47724) (xy 356.160312 -235.431964) (xy 356.186615 -235.390368)
			(xy 356.21925 -235.353531) (xy 356.257371 -235.322406) (xy 356.299992 -235.297799) (xy 356.346008 -235.280347)
			(xy 356.394227 -235.270503) (xy 356.443402 -235.268522) (xy 356.492257 -235.274454) (xy 356.539528 -235.288146)
			(xy 356.58399 -235.309244) (xy 356.624493 -235.3372) (xy 356.659986 -235.371292) (xy 356.689551 -235.410636)
			(xy 356.712422 -235.454213) (xy 356.728006 -235.500894) (xy 356.735901 -235.549471) (xy 356.736396 -235.574078)
			(xy 357.065338 -235.574078) (xy 357.069298 -235.525024) (xy 357.081075 -235.47724) (xy 357.100366 -235.431964)
			(xy 357.126669 -235.390368) (xy 357.159304 -235.353531) (xy 357.197425 -235.322406) (xy 357.240046 -235.297799)
			(xy 357.286062 -235.280347) (xy 357.334281 -235.270503) (xy 357.383456 -235.268522) (xy 357.432311 -235.274454)
			(xy 357.479582 -235.288146) (xy 357.524044 -235.309244) (xy 357.564547 -235.3372) (xy 357.60004 -235.371292)
			(xy 357.629605 -235.410636) (xy 357.652476 -235.454213) (xy 357.66806 -235.500894) (xy 357.675955 -235.549471)
			(xy 357.67645 -235.574078) (xy 357.675955 -235.598685) (xy 357.66806 -235.647262) (xy 357.652476 -235.693943)
			(xy 357.629605 -235.73752) (xy 357.60004 -235.776864) (xy 357.564547 -235.810956) (xy 357.524044 -235.838912)
			(xy 357.479582 -235.86001) (xy 357.432311 -235.873702) (xy 357.383456 -235.879634) (xy 357.334281 -235.877653)
			(xy 357.286062 -235.867809) (xy 357.240046 -235.850357) (xy 357.197425 -235.82575) (xy 357.159304 -235.794625)
			(xy 357.126669 -235.757788) (xy 357.100366 -235.716192) (xy 357.081075 -235.670916) (xy 357.069298 -235.623132)
			(xy 357.065338 -235.574078) (xy 356.736396 -235.574078) (xy 356.735901 -235.598685) (xy 356.728006 -235.647262)
			(xy 356.712422 -235.693943) (xy 356.689551 -235.73752) (xy 356.659986 -235.776864) (xy 356.624493 -235.810956)
			(xy 356.58399 -235.838912) (xy 356.539528 -235.86001) (xy 356.492257 -235.873702) (xy 356.443402 -235.879634)
			(xy 356.394227 -235.877653) (xy 356.346008 -235.867809) (xy 356.299992 -235.850357) (xy 356.257371 -235.82575)
			(xy 356.21925 -235.794625) (xy 356.186615 -235.757788) (xy 356.160312 -235.716192) (xy 356.141021 -235.670916)
			(xy 356.129244 -235.623132) (xy 356.125284 -235.574078) (xy 355.796342 -235.574078) (xy 355.795847 -235.598685)
			(xy 355.787952 -235.647262) (xy 355.772368 -235.693943) (xy 355.749497 -235.73752) (xy 355.719932 -235.776864)
			(xy 355.684439 -235.810956) (xy 355.643936 -235.838912) (xy 355.599474 -235.86001) (xy 355.552203 -235.873702)
			(xy 355.503348 -235.879634) (xy 355.454173 -235.877653) (xy 355.405954 -235.867809) (xy 355.359938 -235.850357)
			(xy 355.317317 -235.82575) (xy 355.279196 -235.794625) (xy 355.246561 -235.757788) (xy 355.220258 -235.716192)
			(xy 355.200967 -235.670916) (xy 355.18919 -235.623132) (xy 355.18523 -235.574078) (xy 354.856542 -235.574078)
			(xy 354.856047 -235.598685) (xy 354.848152 -235.647262) (xy 354.832568 -235.693943) (xy 354.809697 -235.73752)
			(xy 354.780132 -235.776864) (xy 354.744639 -235.810956) (xy 354.704136 -235.838912) (xy 354.659674 -235.86001)
			(xy 354.612403 -235.873702) (xy 354.563548 -235.879634) (xy 354.514373 -235.877653) (xy 354.466154 -235.867809)
			(xy 354.420138 -235.850357) (xy 354.377517 -235.82575) (xy 354.339396 -235.794625) (xy 354.306761 -235.757788)
			(xy 354.280458 -235.716192) (xy 354.261167 -235.670916) (xy 354.24939 -235.623132) (xy 354.24543 -235.574078)
			(xy 353.916488 -235.574078) (xy 353.915993 -235.598685) (xy 353.908098 -235.647262) (xy 353.892514 -235.693943)
			(xy 353.869643 -235.73752) (xy 353.840078 -235.776864) (xy 353.804585 -235.810956) (xy 353.764082 -235.838912)
			(xy 353.71962 -235.86001) (xy 353.672349 -235.873702) (xy 353.623494 -235.879634) (xy 353.574319 -235.877653)
			(xy 353.5261 -235.867809) (xy 353.480084 -235.850357) (xy 353.437463 -235.82575) (xy 353.399342 -235.794625)
			(xy 353.366707 -235.757788) (xy 353.340404 -235.716192) (xy 353.321113 -235.670916) (xy 353.309336 -235.623132)
			(xy 353.305376 -235.574078) (xy 352.976434 -235.574078) (xy 352.975939 -235.598685) (xy 352.968044 -235.647262)
			(xy 352.95246 -235.693943) (xy 352.929589 -235.73752) (xy 352.900024 -235.776864) (xy 352.864531 -235.810956)
			(xy 352.824028 -235.838912) (xy 352.779566 -235.86001) (xy 352.732295 -235.873702) (xy 352.68344 -235.879634)
			(xy 352.634265 -235.877653) (xy 352.586046 -235.867809) (xy 352.54003 -235.850357) (xy 352.497409 -235.82575)
			(xy 352.459288 -235.794625) (xy 352.426653 -235.757788) (xy 352.40035 -235.716192) (xy 352.381059 -235.670916)
			(xy 352.369282 -235.623132) (xy 352.365322 -235.574078) (xy 352.03638 -235.574078) (xy 352.035885 -235.598685)
			(xy 352.02799 -235.647262) (xy 352.012406 -235.693943) (xy 351.989535 -235.73752) (xy 351.95997 -235.776864)
			(xy 351.924477 -235.810956) (xy 351.883974 -235.838912) (xy 351.839512 -235.86001) (xy 351.792241 -235.873702)
			(xy 351.743386 -235.879634) (xy 351.694211 -235.877653) (xy 351.645992 -235.867809) (xy 351.599976 -235.850357)
			(xy 351.557355 -235.82575) (xy 351.519234 -235.794625) (xy 351.486599 -235.757788) (xy 351.460296 -235.716192)
			(xy 351.441005 -235.670916) (xy 351.429228 -235.623132) (xy 351.425268 -235.574078) (xy 351.096326 -235.574078)
			(xy 351.095831 -235.598685) (xy 351.087936 -235.647262) (xy 351.072352 -235.693943) (xy 351.049481 -235.73752)
			(xy 351.019916 -235.776864) (xy 350.984423 -235.810956) (xy 350.94392 -235.838912) (xy 350.899458 -235.86001)
			(xy 350.852187 -235.873702) (xy 350.803332 -235.879634) (xy 350.754157 -235.877653) (xy 350.705938 -235.867809)
			(xy 350.659922 -235.850357) (xy 350.617301 -235.82575) (xy 350.57918 -235.794625) (xy 350.546545 -235.757788)
			(xy 350.520242 -235.716192) (xy 350.500951 -235.670916) (xy 350.489174 -235.623132) (xy 350.485214 -235.574078)
			(xy 350.156526 -235.574078) (xy 350.156031 -235.598685) (xy 350.148136 -235.647262) (xy 350.132552 -235.693943)
			(xy 350.109681 -235.73752) (xy 350.080116 -235.776864) (xy 350.044623 -235.810956) (xy 350.00412 -235.838912)
			(xy 349.959658 -235.86001) (xy 349.912387 -235.873702) (xy 349.863532 -235.879634) (xy 349.814357 -235.877653)
			(xy 349.766138 -235.867809) (xy 349.720122 -235.850357) (xy 349.677501 -235.82575) (xy 349.63938 -235.794625)
			(xy 349.606745 -235.757788) (xy 349.580442 -235.716192) (xy 349.561151 -235.670916) (xy 349.549374 -235.623132)
			(xy 349.545414 -235.574078) (xy 349.216472 -235.574078) (xy 349.215977 -235.598685) (xy 349.208082 -235.647262)
			(xy 349.192498 -235.693943) (xy 349.169627 -235.73752) (xy 349.140062 -235.776864) (xy 349.104569 -235.810956)
			(xy 349.064066 -235.838912) (xy 349.019604 -235.86001) (xy 348.972333 -235.873702) (xy 348.923478 -235.879634)
			(xy 348.874303 -235.877653) (xy 348.826084 -235.867809) (xy 348.780068 -235.850357) (xy 348.737447 -235.82575)
			(xy 348.699326 -235.794625) (xy 348.666691 -235.757788) (xy 348.640388 -235.716192) (xy 348.621097 -235.670916)
			(xy 348.60932 -235.623132) (xy 348.60536 -235.574078) (xy 348.276418 -235.574078) (xy 348.275923 -235.598685)
			(xy 348.268028 -235.647262) (xy 348.252444 -235.693943) (xy 348.229573 -235.73752) (xy 348.200008 -235.776864)
			(xy 348.164515 -235.810956) (xy 348.124012 -235.838912) (xy 348.07955 -235.86001) (xy 348.032279 -235.873702)
			(xy 347.983424 -235.879634) (xy 347.934249 -235.877653) (xy 347.88603 -235.867809) (xy 347.840014 -235.850357)
			(xy 347.797393 -235.82575) (xy 347.759272 -235.794625) (xy 347.726637 -235.757788) (xy 347.700334 -235.716192)
			(xy 347.681043 -235.670916) (xy 347.669266 -235.623132) (xy 347.665306 -235.574078) (xy 347.336364 -235.574078)
			(xy 347.335869 -235.598685) (xy 347.327974 -235.647262) (xy 347.31239 -235.693943) (xy 347.289519 -235.73752)
			(xy 347.259954 -235.776864) (xy 347.224461 -235.810956) (xy 347.183958 -235.838912) (xy 347.139496 -235.86001)
			(xy 347.092225 -235.873702) (xy 347.04337 -235.879634) (xy 346.994195 -235.877653) (xy 346.945976 -235.867809)
			(xy 346.89996 -235.850357) (xy 346.857339 -235.82575) (xy 346.819218 -235.794625) (xy 346.786583 -235.757788)
			(xy 346.76028 -235.716192) (xy 346.740989 -235.670916) (xy 346.729212 -235.623132) (xy 346.725252 -235.574078)
			(xy 346.39631 -235.574078) (xy 346.395815 -235.598685) (xy 346.38792 -235.647262) (xy 346.372336 -235.693943)
			(xy 346.349465 -235.73752) (xy 346.3199 -235.776864) (xy 346.284407 -235.810956) (xy 346.243904 -235.838912)
			(xy 346.199442 -235.86001) (xy 346.152171 -235.873702) (xy 346.103316 -235.879634) (xy 346.054141 -235.877653)
			(xy 346.005922 -235.867809) (xy 345.959906 -235.850357) (xy 345.917285 -235.82575) (xy 345.879164 -235.794625)
			(xy 345.846529 -235.757788) (xy 345.820226 -235.716192) (xy 345.800935 -235.670916) (xy 345.789158 -235.623132)
			(xy 345.785198 -235.574078) (xy 345.45651 -235.574078) (xy 345.456015 -235.598685) (xy 345.44812 -235.647262)
			(xy 345.432536 -235.693943) (xy 345.409665 -235.73752) (xy 345.3801 -235.776864) (xy 345.344607 -235.810956)
			(xy 345.304104 -235.838912) (xy 345.259642 -235.86001) (xy 345.212371 -235.873702) (xy 345.163516 -235.879634)
			(xy 345.114341 -235.877653) (xy 345.066122 -235.867809) (xy 345.020106 -235.850357) (xy 344.977485 -235.82575)
			(xy 344.939364 -235.794625) (xy 344.906729 -235.757788) (xy 344.880426 -235.716192) (xy 344.861135 -235.670916)
			(xy 344.849358 -235.623132) (xy 344.845398 -235.574078) (xy 344.516992 -235.574078) (xy 344.512945 -235.623751)
			(xy 344.500843 -235.672205) (xy 344.481017 -235.718045) (xy 344.453997 -235.760048) (xy 344.420502 -235.797094)
			(xy 344.381425 -235.828196) (xy 344.337808 -235.852525) (xy 344.290814 -235.869432) (xy 344.241695 -235.878467)
			(xy 344.216736 -235.879386) (xy 344.215974 -235.879386) (xy 344.206223 -235.880119) (xy 344.188329 -235.887959)
			(xy 344.181176 -235.894626) (xy 344.131138 -235.945426) (xy 344.124553 -235.952806) (xy 344.117094 -235.971105)
			(xy 344.11666 -235.980986) (xy 344.11666 -236.384084) (xy 344.375244 -236.384084) (xy 344.379204 -236.33503)
			(xy 344.390981 -236.287246) (xy 344.410272 -236.24197) (xy 344.436575 -236.200374) (xy 344.46921 -236.163537)
			(xy 344.507331 -236.132412) (xy 344.549952 -236.107805) (xy 344.595968 -236.090353) (xy 344.644187 -236.080509)
			(xy 344.693362 -236.078528) (xy 344.742217 -236.08446) (xy 344.789488 -236.098152) (xy 344.83395 -236.11925)
			(xy 344.874453 -236.147206) (xy 344.909946 -236.181298) (xy 344.939511 -236.220642) (xy 344.962382 -236.264219)
			(xy 344.977966 -236.3109) (xy 344.985861 -236.359477) (xy 344.986356 -236.384084) (xy 345.315298 -236.384084)
			(xy 345.319258 -236.33503) (xy 345.331035 -236.287246) (xy 345.350326 -236.24197) (xy 345.376629 -236.200374)
			(xy 345.409264 -236.163537) (xy 345.447385 -236.132412) (xy 345.490006 -236.107805) (xy 345.536022 -236.090353)
			(xy 345.584241 -236.080509) (xy 345.633416 -236.078528) (xy 345.682271 -236.08446) (xy 345.729542 -236.098152)
			(xy 345.774004 -236.11925) (xy 345.814507 -236.147206) (xy 345.85 -236.181298) (xy 345.879565 -236.220642)
			(xy 345.902436 -236.264219) (xy 345.91802 -236.3109) (xy 345.925915 -236.359477) (xy 345.92641 -236.384084)
			(xy 346.255352 -236.384084) (xy 346.259312 -236.33503) (xy 346.271089 -236.287246) (xy 346.29038 -236.24197)
			(xy 346.316683 -236.200374) (xy 346.349318 -236.163537) (xy 346.387439 -236.132412) (xy 346.43006 -236.107805)
			(xy 346.476076 -236.090353) (xy 346.524295 -236.080509) (xy 346.57347 -236.078528) (xy 346.622325 -236.08446)
			(xy 346.669596 -236.098152) (xy 346.714058 -236.11925) (xy 346.754561 -236.147206) (xy 346.790054 -236.181298)
			(xy 346.819619 -236.220642) (xy 346.84249 -236.264219) (xy 346.858074 -236.3109) (xy 346.865969 -236.359477)
			(xy 346.866464 -236.384084) (xy 347.195406 -236.384084) (xy 347.199366 -236.33503) (xy 347.211143 -236.287246)
			(xy 347.230434 -236.24197) (xy 347.256737 -236.200374) (xy 347.289372 -236.163537) (xy 347.327493 -236.132412)
			(xy 347.370114 -236.107805) (xy 347.41613 -236.090353) (xy 347.464349 -236.080509) (xy 347.513524 -236.078528)
			(xy 347.562379 -236.08446) (xy 347.60965 -236.098152) (xy 347.654112 -236.11925) (xy 347.694615 -236.147206)
			(xy 347.730108 -236.181298) (xy 347.759673 -236.220642) (xy 347.782544 -236.264219) (xy 347.798128 -236.3109)
			(xy 347.806023 -236.359477) (xy 347.806518 -236.384084) (xy 348.135206 -236.384084) (xy 348.139166 -236.33503)
			(xy 348.150943 -236.287246) (xy 348.170234 -236.24197) (xy 348.196537 -236.200374) (xy 348.229172 -236.163537)
			(xy 348.267293 -236.132412) (xy 348.309914 -236.107805) (xy 348.35593 -236.090353) (xy 348.404149 -236.080509)
			(xy 348.453324 -236.078528) (xy 348.502179 -236.08446) (xy 348.54945 -236.098152) (xy 348.593912 -236.11925)
			(xy 348.634415 -236.147206) (xy 348.669908 -236.181298) (xy 348.699473 -236.220642) (xy 348.722344 -236.264219)
			(xy 348.737928 -236.3109) (xy 348.745823 -236.359477) (xy 348.746318 -236.384084) (xy 349.07526 -236.384084)
			(xy 349.07922 -236.33503) (xy 349.090997 -236.287246) (xy 349.110288 -236.24197) (xy 349.136591 -236.200374)
			(xy 349.169226 -236.163537) (xy 349.207347 -236.132412) (xy 349.249968 -236.107805) (xy 349.295984 -236.090353)
			(xy 349.344203 -236.080509) (xy 349.393378 -236.078528) (xy 349.442233 -236.08446) (xy 349.489504 -236.098152)
			(xy 349.533966 -236.11925) (xy 349.574469 -236.147206) (xy 349.609962 -236.181298) (xy 349.639527 -236.220642)
			(xy 349.662398 -236.264219) (xy 349.677982 -236.3109) (xy 349.685877 -236.359477) (xy 349.686372 -236.384084)
			(xy 350.015314 -236.384084) (xy 350.019274 -236.33503) (xy 350.031051 -236.287246) (xy 350.050342 -236.24197)
			(xy 350.076645 -236.200374) (xy 350.10928 -236.163537) (xy 350.147401 -236.132412) (xy 350.190022 -236.107805)
			(xy 350.236038 -236.090353) (xy 350.284257 -236.080509) (xy 350.333432 -236.078528) (xy 350.382287 -236.08446)
			(xy 350.429558 -236.098152) (xy 350.47402 -236.11925) (xy 350.514523 -236.147206) (xy 350.550016 -236.181298)
			(xy 350.579581 -236.220642) (xy 350.602452 -236.264219) (xy 350.618036 -236.3109) (xy 350.625931 -236.359477)
			(xy 350.626426 -236.384084) (xy 352.835222 -236.384084) (xy 352.839182 -236.33503) (xy 352.850959 -236.287246)
			(xy 352.87025 -236.24197) (xy 352.896553 -236.200374) (xy 352.929188 -236.163537) (xy 352.967309 -236.132412)
			(xy 353.00993 -236.107805) (xy 353.055946 -236.090353) (xy 353.104165 -236.080509) (xy 353.15334 -236.078528)
			(xy 353.202195 -236.08446) (xy 353.249466 -236.098152) (xy 353.293928 -236.11925) (xy 353.334431 -236.147206)
			(xy 353.369924 -236.181298) (xy 353.399489 -236.220642) (xy 353.42236 -236.264219) (xy 353.437944 -236.3109)
			(xy 353.445839 -236.359477) (xy 353.446334 -236.384084) (xy 355.655384 -236.384084) (xy 355.659344 -236.33503)
			(xy 355.671121 -236.287246) (xy 355.690412 -236.24197) (xy 355.716715 -236.200374) (xy 355.74935 -236.163537)
			(xy 355.787471 -236.132412) (xy 355.830092 -236.107805) (xy 355.876108 -236.090353) (xy 355.924327 -236.080509)
			(xy 355.973502 -236.078528) (xy 356.022357 -236.08446) (xy 356.069628 -236.098152) (xy 356.11409 -236.11925)
			(xy 356.154593 -236.147206) (xy 356.190086 -236.181298) (xy 356.219651 -236.220642) (xy 356.242522 -236.264219)
			(xy 356.258106 -236.3109) (xy 356.266001 -236.359477) (xy 356.266496 -236.384084) (xy 356.595438 -236.384084)
			(xy 356.599398 -236.33503) (xy 356.611175 -236.287246) (xy 356.630466 -236.24197) (xy 356.656769 -236.200374)
			(xy 356.689404 -236.163537) (xy 356.727525 -236.132412) (xy 356.770146 -236.107805) (xy 356.816162 -236.090353)
			(xy 356.864381 -236.080509) (xy 356.913556 -236.078528) (xy 356.962411 -236.08446) (xy 357.009682 -236.098152)
			(xy 357.054144 -236.11925) (xy 357.094647 -236.147206) (xy 357.13014 -236.181298) (xy 357.159705 -236.220642)
			(xy 357.182576 -236.264219) (xy 357.19816 -236.3109) (xy 357.206055 -236.359477) (xy 357.20655 -236.384084)
			(xy 357.206055 -236.408691) (xy 357.19816 -236.457268) (xy 357.182576 -236.503949) (xy 357.159705 -236.547526)
			(xy 357.13014 -236.58687) (xy 357.094647 -236.620962) (xy 357.054144 -236.648918) (xy 357.009682 -236.670016)
			(xy 356.962411 -236.683708) (xy 356.913556 -236.68964) (xy 356.864381 -236.687659) (xy 356.816162 -236.677815)
			(xy 356.770146 -236.660363) (xy 356.727525 -236.635756) (xy 356.689404 -236.604631) (xy 356.656769 -236.567794)
			(xy 356.630466 -236.526198) (xy 356.611175 -236.480922) (xy 356.599398 -236.433138) (xy 356.595438 -236.384084)
			(xy 356.266496 -236.384084) (xy 356.266001 -236.408691) (xy 356.258106 -236.457268) (xy 356.242522 -236.503949)
			(xy 356.219651 -236.547526) (xy 356.190086 -236.58687) (xy 356.154593 -236.620962) (xy 356.11409 -236.648918)
			(xy 356.069628 -236.670016) (xy 356.022357 -236.683708) (xy 355.973502 -236.68964) (xy 355.924327 -236.687659)
			(xy 355.876108 -236.677815) (xy 355.830092 -236.660363) (xy 355.787471 -236.635756) (xy 355.74935 -236.604631)
			(xy 355.716715 -236.567794) (xy 355.690412 -236.526198) (xy 355.671121 -236.480922) (xy 355.659344 -236.433138)
			(xy 355.655384 -236.384084) (xy 353.446334 -236.384084) (xy 353.445839 -236.408691) (xy 353.437944 -236.457268)
			(xy 353.42236 -236.503949) (xy 353.399489 -236.547526) (xy 353.369924 -236.58687) (xy 353.334431 -236.620962)
			(xy 353.293928 -236.648918) (xy 353.249466 -236.670016) (xy 353.202195 -236.683708) (xy 353.15334 -236.68964)
			(xy 353.104165 -236.687659) (xy 353.055946 -236.677815) (xy 353.00993 -236.660363) (xy 352.967309 -236.635756)
			(xy 352.929188 -236.604631) (xy 352.896553 -236.567794) (xy 352.87025 -236.526198) (xy 352.850959 -236.480922)
			(xy 352.839182 -236.433138) (xy 352.835222 -236.384084) (xy 350.626426 -236.384084) (xy 350.625931 -236.408691)
			(xy 350.618036 -236.457268) (xy 350.602452 -236.503949) (xy 350.579581 -236.547526) (xy 350.550016 -236.58687)
			(xy 350.514523 -236.620962) (xy 350.47402 -236.648918) (xy 350.429558 -236.670016) (xy 350.382287 -236.683708)
			(xy 350.333432 -236.68964) (xy 350.284257 -236.687659) (xy 350.236038 -236.677815) (xy 350.190022 -236.660363)
			(xy 350.147401 -236.635756) (xy 350.10928 -236.604631) (xy 350.076645 -236.567794) (xy 350.050342 -236.526198)
			(xy 350.031051 -236.480922) (xy 350.019274 -236.433138) (xy 350.015314 -236.384084) (xy 349.686372 -236.384084)
			(xy 349.685877 -236.408691) (xy 349.677982 -236.457268) (xy 349.662398 -236.503949) (xy 349.639527 -236.547526)
			(xy 349.609962 -236.58687) (xy 349.574469 -236.620962) (xy 349.533966 -236.648918) (xy 349.489504 -236.670016)
			(xy 349.442233 -236.683708) (xy 349.393378 -236.68964) (xy 349.344203 -236.687659) (xy 349.295984 -236.677815)
			(xy 349.249968 -236.660363) (xy 349.207347 -236.635756) (xy 349.169226 -236.604631) (xy 349.136591 -236.567794)
			(xy 349.110288 -236.526198) (xy 349.090997 -236.480922) (xy 349.07922 -236.433138) (xy 349.07526 -236.384084)
			(xy 348.746318 -236.384084) (xy 348.745823 -236.408691) (xy 348.737928 -236.457268) (xy 348.722344 -236.503949)
			(xy 348.699473 -236.547526) (xy 348.669908 -236.58687) (xy 348.634415 -236.620962) (xy 348.593912 -236.648918)
			(xy 348.54945 -236.670016) (xy 348.502179 -236.683708) (xy 348.453324 -236.68964) (xy 348.404149 -236.687659)
			(xy 348.35593 -236.677815) (xy 348.309914 -236.660363) (xy 348.267293 -236.635756) (xy 348.229172 -236.604631)
			(xy 348.196537 -236.567794) (xy 348.170234 -236.526198) (xy 348.150943 -236.480922) (xy 348.139166 -236.433138)
			(xy 348.135206 -236.384084) (xy 347.806518 -236.384084) (xy 347.806023 -236.408691) (xy 347.798128 -236.457268)
			(xy 347.782544 -236.503949) (xy 347.759673 -236.547526) (xy 347.730108 -236.58687) (xy 347.694615 -236.620962)
			(xy 347.654112 -236.648918) (xy 347.60965 -236.670016) (xy 347.562379 -236.683708) (xy 347.513524 -236.68964)
			(xy 347.464349 -236.687659) (xy 347.41613 -236.677815) (xy 347.370114 -236.660363) (xy 347.327493 -236.635756)
			(xy 347.289372 -236.604631) (xy 347.256737 -236.567794) (xy 347.230434 -236.526198) (xy 347.211143 -236.480922)
			(xy 347.199366 -236.433138) (xy 347.195406 -236.384084) (xy 346.866464 -236.384084) (xy 346.865969 -236.408691)
			(xy 346.858074 -236.457268) (xy 346.84249 -236.503949) (xy 346.819619 -236.547526) (xy 346.790054 -236.58687)
			(xy 346.754561 -236.620962) (xy 346.714058 -236.648918) (xy 346.669596 -236.670016) (xy 346.622325 -236.683708)
			(xy 346.57347 -236.68964) (xy 346.524295 -236.687659) (xy 346.476076 -236.677815) (xy 346.43006 -236.660363)
			(xy 346.387439 -236.635756) (xy 346.349318 -236.604631) (xy 346.316683 -236.567794) (xy 346.29038 -236.526198)
			(xy 346.271089 -236.480922) (xy 346.259312 -236.433138) (xy 346.255352 -236.384084) (xy 345.92641 -236.384084)
			(xy 345.925915 -236.408691) (xy 345.91802 -236.457268) (xy 345.902436 -236.503949) (xy 345.879565 -236.547526)
			(xy 345.85 -236.58687) (xy 345.814507 -236.620962) (xy 345.774004 -236.648918) (xy 345.729542 -236.670016)
			(xy 345.682271 -236.683708) (xy 345.633416 -236.68964) (xy 345.584241 -236.687659) (xy 345.536022 -236.677815)
			(xy 345.490006 -236.660363) (xy 345.447385 -236.635756) (xy 345.409264 -236.604631) (xy 345.376629 -236.567794)
			(xy 345.350326 -236.526198) (xy 345.331035 -236.480922) (xy 345.319258 -236.433138) (xy 345.315298 -236.384084)
			(xy 344.986356 -236.384084) (xy 344.985861 -236.408691) (xy 344.977966 -236.457268) (xy 344.962382 -236.503949)
			(xy 344.939511 -236.547526) (xy 344.909946 -236.58687) (xy 344.874453 -236.620962) (xy 344.83395 -236.648918)
			(xy 344.789488 -236.670016) (xy 344.742217 -236.683708) (xy 344.693362 -236.68964) (xy 344.644187 -236.687659)
			(xy 344.595968 -236.677815) (xy 344.549952 -236.660363) (xy 344.507331 -236.635756) (xy 344.46921 -236.604631)
			(xy 344.436575 -236.567794) (xy 344.410272 -236.526198) (xy 344.390981 -236.480922) (xy 344.379204 -236.433138)
			(xy 344.375244 -236.384084) (xy 344.11666 -236.384084) (xy 344.11666 -236.787182) (xy 344.11713 -236.797055)
			(xy 344.124586 -236.815341) (xy 344.131138 -236.822742) (xy 344.181176 -236.873542) (xy 344.188324 -236.880217)
			(xy 344.206221 -236.888063) (xy 344.215974 -236.888782) (xy 344.216482 -236.888782) (xy 344.24144 -236.889719)
			(xy 344.290565 -236.898713) (xy 344.337571 -236.915581) (xy 344.381207 -236.939872) (xy 344.420308 -236.97094)
			(xy 344.453832 -237.007957) (xy 344.480886 -237.049936) (xy 344.500749 -237.095757) (xy 344.512891 -237.1442)
			(xy 344.516989 -237.193973) (xy 344.516979 -237.19409) (xy 344.845398 -237.19409) (xy 344.849358 -237.145036)
			(xy 344.861135 -237.097252) (xy 344.880426 -237.051976) (xy 344.906729 -237.01038) (xy 344.939364 -236.973543)
			(xy 344.977485 -236.942418) (xy 345.020106 -236.917811) (xy 345.066122 -236.900359) (xy 345.114341 -236.890515)
			(xy 345.163516 -236.888534) (xy 345.212371 -236.894466) (xy 345.259642 -236.908158) (xy 345.304104 -236.929256)
			(xy 345.344607 -236.957212) (xy 345.3801 -236.991304) (xy 345.409665 -237.030648) (xy 345.432536 -237.074225)
			(xy 345.44812 -237.120906) (xy 345.456015 -237.169483) (xy 345.45651 -237.19409) (xy 345.785198 -237.19409)
			(xy 345.789158 -237.145036) (xy 345.800935 -237.097252) (xy 345.820226 -237.051976) (xy 345.846529 -237.01038)
			(xy 345.879164 -236.973543) (xy 345.917285 -236.942418) (xy 345.959906 -236.917811) (xy 346.005922 -236.900359)
			(xy 346.054141 -236.890515) (xy 346.103316 -236.888534) (xy 346.152171 -236.894466) (xy 346.199442 -236.908158)
			(xy 346.243904 -236.929256) (xy 346.284407 -236.957212) (xy 346.3199 -236.991304) (xy 346.349465 -237.030648)
			(xy 346.372336 -237.074225) (xy 346.38792 -237.120906) (xy 346.395815 -237.169483) (xy 346.39631 -237.19409)
			(xy 346.725252 -237.19409) (xy 346.729212 -237.145036) (xy 346.740989 -237.097252) (xy 346.76028 -237.051976)
			(xy 346.786583 -237.01038) (xy 346.819218 -236.973543) (xy 346.857339 -236.942418) (xy 346.89996 -236.917811)
			(xy 346.945976 -236.900359) (xy 346.994195 -236.890515) (xy 347.04337 -236.888534) (xy 347.092225 -236.894466)
			(xy 347.139496 -236.908158) (xy 347.183958 -236.929256) (xy 347.224461 -236.957212) (xy 347.259954 -236.991304)
			(xy 347.289519 -237.030648) (xy 347.31239 -237.074225) (xy 347.327974 -237.120906) (xy 347.335869 -237.169483)
			(xy 347.336364 -237.19409) (xy 347.665306 -237.19409) (xy 347.669266 -237.145036) (xy 347.681043 -237.097252)
			(xy 347.700334 -237.051976) (xy 347.726637 -237.01038) (xy 347.759272 -236.973543) (xy 347.797393 -236.942418)
			(xy 347.840014 -236.917811) (xy 347.88603 -236.900359) (xy 347.934249 -236.890515) (xy 347.983424 -236.888534)
			(xy 348.032279 -236.894466) (xy 348.07955 -236.908158) (xy 348.124012 -236.929256) (xy 348.164515 -236.957212)
			(xy 348.200008 -236.991304) (xy 348.229573 -237.030648) (xy 348.252444 -237.074225) (xy 348.268028 -237.120906)
			(xy 348.275923 -237.169483) (xy 348.276418 -237.19409) (xy 348.60536 -237.19409) (xy 348.60932 -237.145036)
			(xy 348.621097 -237.097252) (xy 348.640388 -237.051976) (xy 348.666691 -237.01038) (xy 348.699326 -236.973543)
			(xy 348.737447 -236.942418) (xy 348.780068 -236.917811) (xy 348.826084 -236.900359) (xy 348.874303 -236.890515)
			(xy 348.923478 -236.888534) (xy 348.972333 -236.894466) (xy 349.019604 -236.908158) (xy 349.064066 -236.929256)
			(xy 349.104569 -236.957212) (xy 349.140062 -236.991304) (xy 349.169627 -237.030648) (xy 349.192498 -237.074225)
			(xy 349.208082 -237.120906) (xy 349.215977 -237.169483) (xy 349.216472 -237.19409) (xy 349.545414 -237.19409)
			(xy 349.549374 -237.145036) (xy 349.561151 -237.097252) (xy 349.580442 -237.051976) (xy 349.606745 -237.01038)
			(xy 349.63938 -236.973543) (xy 349.677501 -236.942418) (xy 349.720122 -236.917811) (xy 349.766138 -236.900359)
			(xy 349.814357 -236.890515) (xy 349.863532 -236.888534) (xy 349.912387 -236.894466) (xy 349.959658 -236.908158)
			(xy 350.00412 -236.929256) (xy 350.044623 -236.957212) (xy 350.080116 -236.991304) (xy 350.109681 -237.030648)
			(xy 350.132552 -237.074225) (xy 350.148136 -237.120906) (xy 350.156031 -237.169483) (xy 350.156526 -237.19409)
			(xy 350.485214 -237.19409) (xy 350.489174 -237.145036) (xy 350.500951 -237.097252) (xy 350.520242 -237.051976)
			(xy 350.546545 -237.01038) (xy 350.57918 -236.973543) (xy 350.617301 -236.942418) (xy 350.659922 -236.917811)
			(xy 350.705938 -236.900359) (xy 350.754157 -236.890515) (xy 350.803332 -236.888534) (xy 350.852187 -236.894466)
			(xy 350.899458 -236.908158) (xy 350.94392 -236.929256) (xy 350.984423 -236.957212) (xy 351.019916 -236.991304)
			(xy 351.049481 -237.030648) (xy 351.072352 -237.074225) (xy 351.087936 -237.120906) (xy 351.095831 -237.169483)
			(xy 351.096326 -237.19409) (xy 351.425268 -237.19409) (xy 351.429228 -237.145036) (xy 351.441005 -237.097252)
			(xy 351.460296 -237.051976) (xy 351.486599 -237.01038) (xy 351.519234 -236.973543) (xy 351.557355 -236.942418)
			(xy 351.599976 -236.917811) (xy 351.645992 -236.900359) (xy 351.694211 -236.890515) (xy 351.743386 -236.888534)
			(xy 351.792241 -236.894466) (xy 351.839512 -236.908158) (xy 351.883974 -236.929256) (xy 351.924477 -236.957212)
			(xy 351.95997 -236.991304) (xy 351.989535 -237.030648) (xy 352.012406 -237.074225) (xy 352.02799 -237.120906)
			(xy 352.035885 -237.169483) (xy 352.03638 -237.19409) (xy 352.365322 -237.19409) (xy 352.369282 -237.145036)
			(xy 352.381059 -237.097252) (xy 352.40035 -237.051976) (xy 352.426653 -237.01038) (xy 352.459288 -236.973543)
			(xy 352.497409 -236.942418) (xy 352.54003 -236.917811) (xy 352.586046 -236.900359) (xy 352.634265 -236.890515)
			(xy 352.68344 -236.888534) (xy 352.732295 -236.894466) (xy 352.779566 -236.908158) (xy 352.824028 -236.929256)
			(xy 352.864531 -236.957212) (xy 352.900024 -236.991304) (xy 352.929589 -237.030648) (xy 352.95246 -237.074225)
			(xy 352.968044 -237.120906) (xy 352.975939 -237.169483) (xy 352.976434 -237.19409) (xy 353.305376 -237.19409)
			(xy 353.309336 -237.145036) (xy 353.321113 -237.097252) (xy 353.340404 -237.051976) (xy 353.366707 -237.01038)
			(xy 353.399342 -236.973543) (xy 353.437463 -236.942418) (xy 353.480084 -236.917811) (xy 353.5261 -236.900359)
			(xy 353.574319 -236.890515) (xy 353.623494 -236.888534) (xy 353.672349 -236.894466) (xy 353.71962 -236.908158)
			(xy 353.764082 -236.929256) (xy 353.804585 -236.957212) (xy 353.840078 -236.991304) (xy 353.869643 -237.030648)
			(xy 353.892514 -237.074225) (xy 353.908098 -237.120906) (xy 353.915993 -237.169483) (xy 353.916488 -237.19409)
			(xy 354.24543 -237.19409) (xy 354.24939 -237.145036) (xy 354.261167 -237.097252) (xy 354.280458 -237.051976)
			(xy 354.306761 -237.01038) (xy 354.339396 -236.973543) (xy 354.377517 -236.942418) (xy 354.420138 -236.917811)
			(xy 354.466154 -236.900359) (xy 354.514373 -236.890515) (xy 354.563548 -236.888534) (xy 354.612403 -236.894466)
			(xy 354.659674 -236.908158) (xy 354.704136 -236.929256) (xy 354.744639 -236.957212) (xy 354.780132 -236.991304)
			(xy 354.809697 -237.030648) (xy 354.832568 -237.074225) (xy 354.848152 -237.120906) (xy 354.856047 -237.169483)
			(xy 354.856542 -237.19409) (xy 355.18523 -237.19409) (xy 355.18919 -237.145036) (xy 355.200967 -237.097252)
			(xy 355.220258 -237.051976) (xy 355.246561 -237.01038) (xy 355.279196 -236.973543) (xy 355.317317 -236.942418)
			(xy 355.359938 -236.917811) (xy 355.405954 -236.900359) (xy 355.454173 -236.890515) (xy 355.503348 -236.888534)
			(xy 355.552203 -236.894466) (xy 355.599474 -236.908158) (xy 355.643936 -236.929256) (xy 355.684439 -236.957212)
			(xy 355.719932 -236.991304) (xy 355.749497 -237.030648) (xy 355.772368 -237.074225) (xy 355.787952 -237.120906)
			(xy 355.795847 -237.169483) (xy 355.796342 -237.19409) (xy 355.795847 -237.218697) (xy 355.787952 -237.267274)
			(xy 355.772368 -237.313955) (xy 355.749497 -237.357532) (xy 355.719932 -237.396876) (xy 355.684439 -237.430968)
			(xy 355.643936 -237.458924) (xy 355.599474 -237.480022) (xy 355.552203 -237.493714) (xy 355.503348 -237.499646)
			(xy 355.454173 -237.497665) (xy 355.405954 -237.487821) (xy 355.359938 -237.470369) (xy 355.317317 -237.445762)
			(xy 355.279196 -237.414637) (xy 355.246561 -237.3778) (xy 355.220258 -237.336204) (xy 355.200967 -237.290928)
			(xy 355.18919 -237.243144) (xy 355.18523 -237.19409) (xy 354.856542 -237.19409) (xy 354.856047 -237.218697)
			(xy 354.848152 -237.267274) (xy 354.832568 -237.313955) (xy 354.809697 -237.357532) (xy 354.780132 -237.396876)
			(xy 354.744639 -237.430968) (xy 354.704136 -237.458924) (xy 354.659674 -237.480022) (xy 354.612403 -237.493714)
			(xy 354.563548 -237.499646) (xy 354.514373 -237.497665) (xy 354.466154 -237.487821) (xy 354.420138 -237.470369)
			(xy 354.377517 -237.445762) (xy 354.339396 -237.414637) (xy 354.306761 -237.3778) (xy 354.280458 -237.336204)
			(xy 354.261167 -237.290928) (xy 354.24939 -237.243144) (xy 354.24543 -237.19409) (xy 353.916488 -237.19409)
			(xy 353.915993 -237.218697) (xy 353.908098 -237.267274) (xy 353.892514 -237.313955) (xy 353.869643 -237.357532)
			(xy 353.840078 -237.396876) (xy 353.804585 -237.430968) (xy 353.764082 -237.458924) (xy 353.71962 -237.480022)
			(xy 353.672349 -237.493714) (xy 353.623494 -237.499646) (xy 353.574319 -237.497665) (xy 353.5261 -237.487821)
			(xy 353.480084 -237.470369) (xy 353.437463 -237.445762) (xy 353.399342 -237.414637) (xy 353.366707 -237.3778)
			(xy 353.340404 -237.336204) (xy 353.321113 -237.290928) (xy 353.309336 -237.243144) (xy 353.305376 -237.19409)
			(xy 352.976434 -237.19409) (xy 352.975939 -237.218697) (xy 352.968044 -237.267274) (xy 352.95246 -237.313955)
			(xy 352.929589 -237.357532) (xy 352.900024 -237.396876) (xy 352.864531 -237.430968) (xy 352.824028 -237.458924)
			(xy 352.779566 -237.480022) (xy 352.732295 -237.493714) (xy 352.68344 -237.499646) (xy 352.634265 -237.497665)
			(xy 352.586046 -237.487821) (xy 352.54003 -237.470369) (xy 352.497409 -237.445762) (xy 352.459288 -237.414637)
			(xy 352.426653 -237.3778) (xy 352.40035 -237.336204) (xy 352.381059 -237.290928) (xy 352.369282 -237.243144)
			(xy 352.365322 -237.19409) (xy 352.03638 -237.19409) (xy 352.035885 -237.218697) (xy 352.02799 -237.267274)
			(xy 352.012406 -237.313955) (xy 351.989535 -237.357532) (xy 351.95997 -237.396876) (xy 351.924477 -237.430968)
			(xy 351.883974 -237.458924) (xy 351.839512 -237.480022) (xy 351.792241 -237.493714) (xy 351.743386 -237.499646)
			(xy 351.694211 -237.497665) (xy 351.645992 -237.487821) (xy 351.599976 -237.470369) (xy 351.557355 -237.445762)
			(xy 351.519234 -237.414637) (xy 351.486599 -237.3778) (xy 351.460296 -237.336204) (xy 351.441005 -237.290928)
			(xy 351.429228 -237.243144) (xy 351.425268 -237.19409) (xy 351.096326 -237.19409) (xy 351.095831 -237.218697)
			(xy 351.087936 -237.267274) (xy 351.072352 -237.313955) (xy 351.049481 -237.357532) (xy 351.019916 -237.396876)
			(xy 350.984423 -237.430968) (xy 350.94392 -237.458924) (xy 350.899458 -237.480022) (xy 350.852187 -237.493714)
			(xy 350.803332 -237.499646) (xy 350.754157 -237.497665) (xy 350.705938 -237.487821) (xy 350.659922 -237.470369)
			(xy 350.617301 -237.445762) (xy 350.57918 -237.414637) (xy 350.546545 -237.3778) (xy 350.520242 -237.336204)
			(xy 350.500951 -237.290928) (xy 350.489174 -237.243144) (xy 350.485214 -237.19409) (xy 350.156526 -237.19409)
			(xy 350.156031 -237.218697) (xy 350.148136 -237.267274) (xy 350.132552 -237.313955) (xy 350.109681 -237.357532)
			(xy 350.080116 -237.396876) (xy 350.044623 -237.430968) (xy 350.00412 -237.458924) (xy 349.959658 -237.480022)
			(xy 349.912387 -237.493714) (xy 349.863532 -237.499646) (xy 349.814357 -237.497665) (xy 349.766138 -237.487821)
			(xy 349.720122 -237.470369) (xy 349.677501 -237.445762) (xy 349.63938 -237.414637) (xy 349.606745 -237.3778)
			(xy 349.580442 -237.336204) (xy 349.561151 -237.290928) (xy 349.549374 -237.243144) (xy 349.545414 -237.19409)
			(xy 349.216472 -237.19409) (xy 349.215977 -237.218697) (xy 349.208082 -237.267274) (xy 349.192498 -237.313955)
			(xy 349.169627 -237.357532) (xy 349.140062 -237.396876) (xy 349.104569 -237.430968) (xy 349.064066 -237.458924)
			(xy 349.019604 -237.480022) (xy 348.972333 -237.493714) (xy 348.923478 -237.499646) (xy 348.874303 -237.497665)
			(xy 348.826084 -237.487821) (xy 348.780068 -237.470369) (xy 348.737447 -237.445762) (xy 348.699326 -237.414637)
			(xy 348.666691 -237.3778) (xy 348.640388 -237.336204) (xy 348.621097 -237.290928) (xy 348.60932 -237.243144)
			(xy 348.60536 -237.19409) (xy 348.276418 -237.19409) (xy 348.275923 -237.218697) (xy 348.268028 -237.267274)
			(xy 348.252444 -237.313955) (xy 348.229573 -237.357532) (xy 348.200008 -237.396876) (xy 348.164515 -237.430968)
			(xy 348.124012 -237.458924) (xy 348.07955 -237.480022) (xy 348.032279 -237.493714) (xy 347.983424 -237.499646)
			(xy 347.934249 -237.497665) (xy 347.88603 -237.487821) (xy 347.840014 -237.470369) (xy 347.797393 -237.445762)
			(xy 347.759272 -237.414637) (xy 347.726637 -237.3778) (xy 347.700334 -237.336204) (xy 347.681043 -237.290928)
			(xy 347.669266 -237.243144) (xy 347.665306 -237.19409) (xy 347.336364 -237.19409) (xy 347.335869 -237.218697)
			(xy 347.327974 -237.267274) (xy 347.31239 -237.313955) (xy 347.289519 -237.357532) (xy 347.259954 -237.396876)
			(xy 347.224461 -237.430968) (xy 347.183958 -237.458924) (xy 347.139496 -237.480022) (xy 347.092225 -237.493714)
			(xy 347.04337 -237.499646) (xy 346.994195 -237.497665) (xy 346.945976 -237.487821) (xy 346.89996 -237.470369)
			(xy 346.857339 -237.445762) (xy 346.819218 -237.414637) (xy 346.786583 -237.3778) (xy 346.76028 -237.336204)
			(xy 346.740989 -237.290928) (xy 346.729212 -237.243144) (xy 346.725252 -237.19409) (xy 346.39631 -237.19409)
			(xy 346.395815 -237.218697) (xy 346.38792 -237.267274) (xy 346.372336 -237.313955) (xy 346.349465 -237.357532)
			(xy 346.3199 -237.396876) (xy 346.284407 -237.430968) (xy 346.243904 -237.458924) (xy 346.199442 -237.480022)
			(xy 346.152171 -237.493714) (xy 346.103316 -237.499646) (xy 346.054141 -237.497665) (xy 346.005922 -237.487821)
			(xy 345.959906 -237.470369) (xy 345.917285 -237.445762) (xy 345.879164 -237.414637) (xy 345.846529 -237.3778)
			(xy 345.820226 -237.336204) (xy 345.800935 -237.290928) (xy 345.789158 -237.243144) (xy 345.785198 -237.19409)
			(xy 345.45651 -237.19409) (xy 345.456015 -237.218697) (xy 345.44812 -237.267274) (xy 345.432536 -237.313955)
			(xy 345.409665 -237.357532) (xy 345.3801 -237.396876) (xy 345.344607 -237.430968) (xy 345.304104 -237.458924)
			(xy 345.259642 -237.480022) (xy 345.212371 -237.493714) (xy 345.163516 -237.499646) (xy 345.114341 -237.497665)
			(xy 345.066122 -237.487821) (xy 345.020106 -237.470369) (xy 344.977485 -237.445762) (xy 344.939364 -237.414637)
			(xy 344.906729 -237.3778) (xy 344.880426 -237.336204) (xy 344.861135 -237.290928) (xy 344.849358 -237.243144)
			(xy 344.845398 -237.19409) (xy 344.516979 -237.19409) (xy 344.512933 -237.243749) (xy 344.500831 -237.292202)
			(xy 344.481006 -237.33804) (xy 344.453987 -237.380041) (xy 344.420493 -237.417085) (xy 344.381418 -237.448186)
			(xy 344.337803 -237.472514) (xy 344.290811 -237.489421) (xy 344.241693 -237.498455) (xy 344.216736 -237.499398)
			(xy 344.215974 -237.499398) (xy 344.206221 -237.500128) (xy 344.188318 -237.507958) (xy 344.181176 -237.514638)
			(xy 344.131138 -237.565438) (xy 344.124554 -237.572819) (xy 344.1171 -237.591118) (xy 344.11666 -237.600998)
			(xy 344.11666 -238.004096) (xy 344.375244 -238.004096) (xy 344.379204 -237.955042) (xy 344.390981 -237.907258)
			(xy 344.410272 -237.861982) (xy 344.436575 -237.820386) (xy 344.46921 -237.783549) (xy 344.507331 -237.752424)
			(xy 344.549952 -237.727817) (xy 344.595968 -237.710365) (xy 344.644187 -237.700521) (xy 344.693362 -237.69854)
			(xy 344.742217 -237.704472) (xy 344.789488 -237.718164) (xy 344.83395 -237.739262) (xy 344.874453 -237.767218)
			(xy 344.909946 -237.80131) (xy 344.939511 -237.840654) (xy 344.962382 -237.884231) (xy 344.977966 -237.930912)
			(xy 344.985861 -237.979489) (xy 344.986356 -238.004096) (xy 345.315298 -238.004096) (xy 345.319258 -237.955042)
			(xy 345.331035 -237.907258) (xy 345.350326 -237.861982) (xy 345.376629 -237.820386) (xy 345.409264 -237.783549)
			(xy 345.447385 -237.752424) (xy 345.490006 -237.727817) (xy 345.536022 -237.710365) (xy 345.584241 -237.700521)
			(xy 345.633416 -237.69854) (xy 345.682271 -237.704472) (xy 345.729542 -237.718164) (xy 345.774004 -237.739262)
			(xy 345.814507 -237.767218) (xy 345.85 -237.80131) (xy 345.879565 -237.840654) (xy 345.902436 -237.884231)
			(xy 345.91802 -237.930912) (xy 345.925915 -237.979489) (xy 345.92641 -238.004096) (xy 346.255352 -238.004096)
			(xy 346.259312 -237.955042) (xy 346.271089 -237.907258) (xy 346.29038 -237.861982) (xy 346.316683 -237.820386)
			(xy 346.349318 -237.783549) (xy 346.387439 -237.752424) (xy 346.43006 -237.727817) (xy 346.476076 -237.710365)
			(xy 346.524295 -237.700521) (xy 346.57347 -237.69854) (xy 346.622325 -237.704472) (xy 346.669596 -237.718164)
			(xy 346.714058 -237.739262) (xy 346.754561 -237.767218) (xy 346.790054 -237.80131) (xy 346.819619 -237.840654)
			(xy 346.84249 -237.884231) (xy 346.858074 -237.930912) (xy 346.865969 -237.979489) (xy 346.866464 -238.004096)
			(xy 347.195406 -238.004096) (xy 347.199366 -237.955042) (xy 347.211143 -237.907258) (xy 347.230434 -237.861982)
			(xy 347.256737 -237.820386) (xy 347.289372 -237.783549) (xy 347.327493 -237.752424) (xy 347.370114 -237.727817)
			(xy 347.41613 -237.710365) (xy 347.464349 -237.700521) (xy 347.513524 -237.69854) (xy 347.562379 -237.704472)
			(xy 347.60965 -237.718164) (xy 347.654112 -237.739262) (xy 347.694615 -237.767218) (xy 347.730108 -237.80131)
			(xy 347.759673 -237.840654) (xy 347.782544 -237.884231) (xy 347.798128 -237.930912) (xy 347.806023 -237.979489)
			(xy 347.806518 -238.004096) (xy 348.135206 -238.004096) (xy 348.139166 -237.955042) (xy 348.150943 -237.907258)
			(xy 348.170234 -237.861982) (xy 348.196537 -237.820386) (xy 348.229172 -237.783549) (xy 348.267293 -237.752424)
			(xy 348.309914 -237.727817) (xy 348.35593 -237.710365) (xy 348.404149 -237.700521) (xy 348.453324 -237.69854)
			(xy 348.502179 -237.704472) (xy 348.54945 -237.718164) (xy 348.593912 -237.739262) (xy 348.634415 -237.767218)
			(xy 348.669908 -237.80131) (xy 348.699473 -237.840654) (xy 348.722344 -237.884231) (xy 348.737928 -237.930912)
			(xy 348.745823 -237.979489) (xy 348.746318 -238.004096) (xy 349.07526 -238.004096) (xy 349.07922 -237.955042)
			(xy 349.090997 -237.907258) (xy 349.110288 -237.861982) (xy 349.136591 -237.820386) (xy 349.169226 -237.783549)
			(xy 349.207347 -237.752424) (xy 349.249968 -237.727817) (xy 349.295984 -237.710365) (xy 349.344203 -237.700521)
			(xy 349.393378 -237.69854) (xy 349.442233 -237.704472) (xy 349.489504 -237.718164) (xy 349.533966 -237.739262)
			(xy 349.574469 -237.767218) (xy 349.609962 -237.80131) (xy 349.639527 -237.840654) (xy 349.662398 -237.884231)
			(xy 349.677982 -237.930912) (xy 349.685877 -237.979489) (xy 349.686372 -238.004096) (xy 350.015314 -238.004096)
			(xy 350.019274 -237.955042) (xy 350.031051 -237.907258) (xy 350.050342 -237.861982) (xy 350.076645 -237.820386)
			(xy 350.10928 -237.783549) (xy 350.147401 -237.752424) (xy 350.190022 -237.727817) (xy 350.236038 -237.710365)
			(xy 350.284257 -237.700521) (xy 350.333432 -237.69854) (xy 350.382287 -237.704472) (xy 350.429558 -237.718164)
			(xy 350.47402 -237.739262) (xy 350.514523 -237.767218) (xy 350.550016 -237.80131) (xy 350.579581 -237.840654)
			(xy 350.602452 -237.884231) (xy 350.618036 -237.930912) (xy 350.625931 -237.979489) (xy 350.626426 -238.004096)
			(xy 350.955368 -238.004096) (xy 350.959328 -237.955042) (xy 350.971105 -237.907258) (xy 350.990396 -237.861982)
			(xy 351.016699 -237.820386) (xy 351.049334 -237.783549) (xy 351.087455 -237.752424) (xy 351.130076 -237.727817)
			(xy 351.176092 -237.710365) (xy 351.224311 -237.700521) (xy 351.273486 -237.69854) (xy 351.322341 -237.704472)
			(xy 351.369612 -237.718164) (xy 351.414074 -237.739262) (xy 351.454577 -237.767218) (xy 351.49007 -237.80131)
			(xy 351.519635 -237.840654) (xy 351.542506 -237.884231) (xy 351.55809 -237.930912) (xy 351.565985 -237.979489)
			(xy 351.56648 -238.004096) (xy 351.895422 -238.004096) (xy 351.899382 -237.955042) (xy 351.911159 -237.907258)
			(xy 351.93045 -237.861982) (xy 351.956753 -237.820386) (xy 351.989388 -237.783549) (xy 352.027509 -237.752424)
			(xy 352.07013 -237.727817) (xy 352.116146 -237.710365) (xy 352.164365 -237.700521) (xy 352.21354 -237.69854)
			(xy 352.262395 -237.704472) (xy 352.309666 -237.718164) (xy 352.354128 -237.739262) (xy 352.394631 -237.767218)
			(xy 352.430124 -237.80131) (xy 352.459689 -237.840654) (xy 352.48256 -237.884231) (xy 352.498144 -237.930912)
			(xy 352.506039 -237.979489) (xy 352.506534 -238.004096) (xy 352.835222 -238.004096) (xy 352.839182 -237.955042)
			(xy 352.850959 -237.907258) (xy 352.87025 -237.861982) (xy 352.896553 -237.820386) (xy 352.929188 -237.783549)
			(xy 352.967309 -237.752424) (xy 353.00993 -237.727817) (xy 353.055946 -237.710365) (xy 353.104165 -237.700521)
			(xy 353.15334 -237.69854) (xy 353.202195 -237.704472) (xy 353.249466 -237.718164) (xy 353.293928 -237.739262)
			(xy 353.334431 -237.767218) (xy 353.369924 -237.80131) (xy 353.399489 -237.840654) (xy 353.42236 -237.884231)
			(xy 353.437944 -237.930912) (xy 353.445839 -237.979489) (xy 353.446334 -238.004096) (xy 353.775276 -238.004096)
			(xy 353.779236 -237.955042) (xy 353.791013 -237.907258) (xy 353.810304 -237.861982) (xy 353.836607 -237.820386)
			(xy 353.869242 -237.783549) (xy 353.907363 -237.752424) (xy 353.949984 -237.727817) (xy 353.996 -237.710365)
			(xy 354.044219 -237.700521) (xy 354.093394 -237.69854) (xy 354.142249 -237.704472) (xy 354.18952 -237.718164)
			(xy 354.233982 -237.739262) (xy 354.274485 -237.767218) (xy 354.309978 -237.80131) (xy 354.339543 -237.840654)
			(xy 354.362414 -237.884231) (xy 354.377998 -237.930912) (xy 354.385893 -237.979489) (xy 354.386388 -238.004096)
			(xy 354.71533 -238.004096) (xy 354.71929 -237.955042) (xy 354.731067 -237.907258) (xy 354.750358 -237.861982)
			(xy 354.776661 -237.820386) (xy 354.809296 -237.783549) (xy 354.847417 -237.752424) (xy 354.890038 -237.727817)
			(xy 354.936054 -237.710365) (xy 354.984273 -237.700521) (xy 355.033448 -237.69854) (xy 355.082303 -237.704472)
			(xy 355.129574 -237.718164) (xy 355.174036 -237.739262) (xy 355.214539 -237.767218) (xy 355.250032 -237.80131)
			(xy 355.279597 -237.840654) (xy 355.302468 -237.884231) (xy 355.318052 -237.930912) (xy 355.325947 -237.979489)
			(xy 355.326442 -238.004096) (xy 355.655384 -238.004096) (xy 355.659344 -237.955042) (xy 355.671121 -237.907258)
			(xy 355.690412 -237.861982) (xy 355.716715 -237.820386) (xy 355.74935 -237.783549) (xy 355.787471 -237.752424)
			(xy 355.830092 -237.727817) (xy 355.876108 -237.710365) (xy 355.924327 -237.700521) (xy 355.973502 -237.69854)
			(xy 356.022357 -237.704472) (xy 356.069628 -237.718164) (xy 356.11409 -237.739262) (xy 356.154593 -237.767218)
			(xy 356.190086 -237.80131) (xy 356.219651 -237.840654) (xy 356.242522 -237.884231) (xy 356.258106 -237.930912)
			(xy 356.266001 -237.979489) (xy 356.266496 -238.004096) (xy 356.595438 -238.004096) (xy 356.599398 -237.955042)
			(xy 356.611175 -237.907258) (xy 356.630466 -237.861982) (xy 356.656769 -237.820386) (xy 356.689404 -237.783549)
			(xy 356.727525 -237.752424) (xy 356.770146 -237.727817) (xy 356.816162 -237.710365) (xy 356.864381 -237.700521)
			(xy 356.913556 -237.69854) (xy 356.962411 -237.704472) (xy 357.009682 -237.718164) (xy 357.054144 -237.739262)
			(xy 357.094647 -237.767218) (xy 357.13014 -237.80131) (xy 357.159705 -237.840654) (xy 357.182576 -237.884231)
			(xy 357.19816 -237.930912) (xy 357.206055 -237.979489) (xy 357.20655 -238.004096) (xy 357.206055 -238.028703)
			(xy 357.19816 -238.07728) (xy 357.182576 -238.123961) (xy 357.159705 -238.167538) (xy 357.13014 -238.206882)
			(xy 357.094647 -238.240974) (xy 357.054144 -238.26893) (xy 357.009682 -238.290028) (xy 356.962411 -238.30372)
			(xy 356.913556 -238.309652) (xy 356.864381 -238.307671) (xy 356.816162 -238.297827) (xy 356.770146 -238.280375)
			(xy 356.727525 -238.255768) (xy 356.689404 -238.224643) (xy 356.656769 -238.187806) (xy 356.630466 -238.14621)
			(xy 356.611175 -238.100934) (xy 356.599398 -238.05315) (xy 356.595438 -238.004096) (xy 356.266496 -238.004096)
			(xy 356.266001 -238.028703) (xy 356.258106 -238.07728) (xy 356.242522 -238.123961) (xy 356.219651 -238.167538)
			(xy 356.190086 -238.206882) (xy 356.154593 -238.240974) (xy 356.11409 -238.26893) (xy 356.069628 -238.290028)
			(xy 356.022357 -238.30372) (xy 355.973502 -238.309652) (xy 355.924327 -238.307671) (xy 355.876108 -238.297827)
			(xy 355.830092 -238.280375) (xy 355.787471 -238.255768) (xy 355.74935 -238.224643) (xy 355.716715 -238.187806)
			(xy 355.690412 -238.14621) (xy 355.671121 -238.100934) (xy 355.659344 -238.05315) (xy 355.655384 -238.004096)
			(xy 355.326442 -238.004096) (xy 355.325947 -238.028703) (xy 355.318052 -238.07728) (xy 355.302468 -238.123961)
			(xy 355.279597 -238.167538) (xy 355.250032 -238.206882) (xy 355.214539 -238.240974) (xy 355.174036 -238.26893)
			(xy 355.129574 -238.290028) (xy 355.082303 -238.30372) (xy 355.033448 -238.309652) (xy 354.984273 -238.307671)
			(xy 354.936054 -238.297827) (xy 354.890038 -238.280375) (xy 354.847417 -238.255768) (xy 354.809296 -238.224643)
			(xy 354.776661 -238.187806) (xy 354.750358 -238.14621) (xy 354.731067 -238.100934) (xy 354.71929 -238.05315)
			(xy 354.71533 -238.004096) (xy 354.386388 -238.004096) (xy 354.385893 -238.028703) (xy 354.377998 -238.07728)
			(xy 354.362414 -238.123961) (xy 354.339543 -238.167538) (xy 354.309978 -238.206882) (xy 354.274485 -238.240974)
			(xy 354.233982 -238.26893) (xy 354.18952 -238.290028) (xy 354.142249 -238.30372) (xy 354.093394 -238.309652)
			(xy 354.044219 -238.307671) (xy 353.996 -238.297827) (xy 353.949984 -238.280375) (xy 353.907363 -238.255768)
			(xy 353.869242 -238.224643) (xy 353.836607 -238.187806) (xy 353.810304 -238.14621) (xy 353.791013 -238.100934)
			(xy 353.779236 -238.05315) (xy 353.775276 -238.004096) (xy 353.446334 -238.004096) (xy 353.445839 -238.028703)
			(xy 353.437944 -238.07728) (xy 353.42236 -238.123961) (xy 353.399489 -238.167538) (xy 353.369924 -238.206882)
			(xy 353.334431 -238.240974) (xy 353.293928 -238.26893) (xy 353.249466 -238.290028) (xy 353.202195 -238.30372)
			(xy 353.15334 -238.309652) (xy 353.104165 -238.307671) (xy 353.055946 -238.297827) (xy 353.00993 -238.280375)
			(xy 352.967309 -238.255768) (xy 352.929188 -238.224643) (xy 352.896553 -238.187806) (xy 352.87025 -238.14621)
			(xy 352.850959 -238.100934) (xy 352.839182 -238.05315) (xy 352.835222 -238.004096) (xy 352.506534 -238.004096)
			(xy 352.506039 -238.028703) (xy 352.498144 -238.07728) (xy 352.48256 -238.123961) (xy 352.459689 -238.167538)
			(xy 352.430124 -238.206882) (xy 352.394631 -238.240974) (xy 352.354128 -238.26893) (xy 352.309666 -238.290028)
			(xy 352.262395 -238.30372) (xy 352.21354 -238.309652) (xy 352.164365 -238.307671) (xy 352.116146 -238.297827)
			(xy 352.07013 -238.280375) (xy 352.027509 -238.255768) (xy 351.989388 -238.224643) (xy 351.956753 -238.187806)
			(xy 351.93045 -238.14621) (xy 351.911159 -238.100934) (xy 351.899382 -238.05315) (xy 351.895422 -238.004096)
			(xy 351.56648 -238.004096) (xy 351.565985 -238.028703) (xy 351.55809 -238.07728) (xy 351.542506 -238.123961)
			(xy 351.519635 -238.167538) (xy 351.49007 -238.206882) (xy 351.454577 -238.240974) (xy 351.414074 -238.26893)
			(xy 351.369612 -238.290028) (xy 351.322341 -238.30372) (xy 351.273486 -238.309652) (xy 351.224311 -238.307671)
			(xy 351.176092 -238.297827) (xy 351.130076 -238.280375) (xy 351.087455 -238.255768) (xy 351.049334 -238.224643)
			(xy 351.016699 -238.187806) (xy 350.990396 -238.14621) (xy 350.971105 -238.100934) (xy 350.959328 -238.05315)
			(xy 350.955368 -238.004096) (xy 350.626426 -238.004096) (xy 350.625931 -238.028703) (xy 350.618036 -238.07728)
			(xy 350.602452 -238.123961) (xy 350.579581 -238.167538) (xy 350.550016 -238.206882) (xy 350.514523 -238.240974)
			(xy 350.47402 -238.26893) (xy 350.429558 -238.290028) (xy 350.382287 -238.30372) (xy 350.333432 -238.309652)
			(xy 350.284257 -238.307671) (xy 350.236038 -238.297827) (xy 350.190022 -238.280375) (xy 350.147401 -238.255768)
			(xy 350.10928 -238.224643) (xy 350.076645 -238.187806) (xy 350.050342 -238.14621) (xy 350.031051 -238.100934)
			(xy 350.019274 -238.05315) (xy 350.015314 -238.004096) (xy 349.686372 -238.004096) (xy 349.685877 -238.028703)
			(xy 349.677982 -238.07728) (xy 349.662398 -238.123961) (xy 349.639527 -238.167538) (xy 349.609962 -238.206882)
			(xy 349.574469 -238.240974) (xy 349.533966 -238.26893) (xy 349.489504 -238.290028) (xy 349.442233 -238.30372)
			(xy 349.393378 -238.309652) (xy 349.344203 -238.307671) (xy 349.295984 -238.297827) (xy 349.249968 -238.280375)
			(xy 349.207347 -238.255768) (xy 349.169226 -238.224643) (xy 349.136591 -238.187806) (xy 349.110288 -238.14621)
			(xy 349.090997 -238.100934) (xy 349.07922 -238.05315) (xy 349.07526 -238.004096) (xy 348.746318 -238.004096)
			(xy 348.745823 -238.028703) (xy 348.737928 -238.07728) (xy 348.722344 -238.123961) (xy 348.699473 -238.167538)
			(xy 348.669908 -238.206882) (xy 348.634415 -238.240974) (xy 348.593912 -238.26893) (xy 348.54945 -238.290028)
			(xy 348.502179 -238.30372) (xy 348.453324 -238.309652) (xy 348.404149 -238.307671) (xy 348.35593 -238.297827)
			(xy 348.309914 -238.280375) (xy 348.267293 -238.255768) (xy 348.229172 -238.224643) (xy 348.196537 -238.187806)
			(xy 348.170234 -238.14621) (xy 348.150943 -238.100934) (xy 348.139166 -238.05315) (xy 348.135206 -238.004096)
			(xy 347.806518 -238.004096) (xy 347.806023 -238.028703) (xy 347.798128 -238.07728) (xy 347.782544 -238.123961)
			(xy 347.759673 -238.167538) (xy 347.730108 -238.206882) (xy 347.694615 -238.240974) (xy 347.654112 -238.26893)
			(xy 347.60965 -238.290028) (xy 347.562379 -238.30372) (xy 347.513524 -238.309652) (xy 347.464349 -238.307671)
			(xy 347.41613 -238.297827) (xy 347.370114 -238.280375) (xy 347.327493 -238.255768) (xy 347.289372 -238.224643)
			(xy 347.256737 -238.187806) (xy 347.230434 -238.14621) (xy 347.211143 -238.100934) (xy 347.199366 -238.05315)
			(xy 347.195406 -238.004096) (xy 346.866464 -238.004096) (xy 346.865969 -238.028703) (xy 346.858074 -238.07728)
			(xy 346.84249 -238.123961) (xy 346.819619 -238.167538) (xy 346.790054 -238.206882) (xy 346.754561 -238.240974)
			(xy 346.714058 -238.26893) (xy 346.669596 -238.290028) (xy 346.622325 -238.30372) (xy 346.57347 -238.309652)
			(xy 346.524295 -238.307671) (xy 346.476076 -238.297827) (xy 346.43006 -238.280375) (xy 346.387439 -238.255768)
			(xy 346.349318 -238.224643) (xy 346.316683 -238.187806) (xy 346.29038 -238.14621) (xy 346.271089 -238.100934)
			(xy 346.259312 -238.05315) (xy 346.255352 -238.004096) (xy 345.92641 -238.004096) (xy 345.925915 -238.028703)
			(xy 345.91802 -238.07728) (xy 345.902436 -238.123961) (xy 345.879565 -238.167538) (xy 345.85 -238.206882)
			(xy 345.814507 -238.240974) (xy 345.774004 -238.26893) (xy 345.729542 -238.290028) (xy 345.682271 -238.30372)
			(xy 345.633416 -238.309652) (xy 345.584241 -238.307671) (xy 345.536022 -238.297827) (xy 345.490006 -238.280375)
			(xy 345.447385 -238.255768) (xy 345.409264 -238.224643) (xy 345.376629 -238.187806) (xy 345.350326 -238.14621)
			(xy 345.331035 -238.100934) (xy 345.319258 -238.05315) (xy 345.315298 -238.004096) (xy 344.986356 -238.004096)
			(xy 344.985861 -238.028703) (xy 344.977966 -238.07728) (xy 344.962382 -238.123961) (xy 344.939511 -238.167538)
			(xy 344.909946 -238.206882) (xy 344.874453 -238.240974) (xy 344.83395 -238.26893) (xy 344.789488 -238.290028)
			(xy 344.742217 -238.30372) (xy 344.693362 -238.309652) (xy 344.644187 -238.307671) (xy 344.595968 -238.297827)
			(xy 344.549952 -238.280375) (xy 344.507331 -238.255768) (xy 344.46921 -238.224643) (xy 344.436575 -238.187806)
			(xy 344.410272 -238.14621) (xy 344.390981 -238.100934) (xy 344.379204 -238.05315) (xy 344.375244 -238.004096)
			(xy 344.11666 -238.004096) (xy 344.11666 -238.407194) (xy 344.117133 -238.417066) (xy 344.124591 -238.435349)
			(xy 344.131138 -238.442754) (xy 344.181176 -238.493554) (xy 344.188325 -238.500228) (xy 344.206221 -238.508072)
			(xy 344.215974 -238.508794) (xy 344.216482 -238.508794) (xy 344.241439 -238.509731) (xy 344.290562 -238.518725)
			(xy 344.337567 -238.535592) (xy 344.3812 -238.559882) (xy 344.4203 -238.590949) (xy 344.453823 -238.627965)
			(xy 344.480876 -238.669942) (xy 344.500738 -238.715761) (xy 344.51288 -238.764202) (xy 344.516977 -238.813973)
			(xy 344.516966 -238.814102) (xy 346.725252 -238.814102) (xy 346.729212 -238.765048) (xy 346.740989 -238.717264)
			(xy 346.76028 -238.671988) (xy 346.786583 -238.630392) (xy 346.819218 -238.593555) (xy 346.857339 -238.56243)
			(xy 346.89996 -238.537823) (xy 346.945976 -238.520371) (xy 346.994195 -238.510527) (xy 347.04337 -238.508546)
			(xy 347.092225 -238.514478) (xy 347.139496 -238.52817) (xy 347.183958 -238.549268) (xy 347.224461 -238.577224)
			(xy 347.259954 -238.611316) (xy 347.289519 -238.65066) (xy 347.31239 -238.694237) (xy 347.327974 -238.740918)
			(xy 347.335869 -238.789495) (xy 347.336364 -238.814102) (xy 349.545414 -238.814102) (xy 349.549374 -238.765048)
			(xy 349.561151 -238.717264) (xy 349.580442 -238.671988) (xy 349.606745 -238.630392) (xy 349.63938 -238.593555)
			(xy 349.677501 -238.56243) (xy 349.720122 -238.537823) (xy 349.766138 -238.520371) (xy 349.814357 -238.510527)
			(xy 349.863532 -238.508546) (xy 349.912387 -238.514478) (xy 349.959658 -238.52817) (xy 350.00412 -238.549268)
			(xy 350.044623 -238.577224) (xy 350.080116 -238.611316) (xy 350.109681 -238.65066) (xy 350.132552 -238.694237)
			(xy 350.148136 -238.740918) (xy 350.156031 -238.789495) (xy 350.156526 -238.814102) (xy 352.365322 -238.814102)
			(xy 352.369282 -238.765048) (xy 352.381059 -238.717264) (xy 352.40035 -238.671988) (xy 352.426653 -238.630392)
			(xy 352.459288 -238.593555) (xy 352.497409 -238.56243) (xy 352.54003 -238.537823) (xy 352.586046 -238.520371)
			(xy 352.634265 -238.510527) (xy 352.68344 -238.508546) (xy 352.732295 -238.514478) (xy 352.779566 -238.52817)
			(xy 352.824028 -238.549268) (xy 352.864531 -238.577224) (xy 352.900024 -238.611316) (xy 352.929589 -238.65066)
			(xy 352.95246 -238.694237) (xy 352.968044 -238.740918) (xy 352.975939 -238.789495) (xy 352.976434 -238.814102)
			(xy 355.18523 -238.814102) (xy 355.18919 -238.765048) (xy 355.200967 -238.717264) (xy 355.220258 -238.671988)
			(xy 355.246561 -238.630392) (xy 355.279196 -238.593555) (xy 355.317317 -238.56243) (xy 355.359938 -238.537823)
			(xy 355.405954 -238.520371) (xy 355.454173 -238.510527) (xy 355.503348 -238.508546) (xy 355.552203 -238.514478)
			(xy 355.599474 -238.52817) (xy 355.643936 -238.549268) (xy 355.684439 -238.577224) (xy 355.719932 -238.611316)
			(xy 355.749497 -238.65066) (xy 355.772368 -238.694237) (xy 355.787952 -238.740918) (xy 355.795847 -238.789495)
			(xy 355.796342 -238.814102) (xy 356.125284 -238.814102) (xy 356.129244 -238.765048) (xy 356.141021 -238.717264)
			(xy 356.160312 -238.671988) (xy 356.186615 -238.630392) (xy 356.21925 -238.593555) (xy 356.257371 -238.56243)
			(xy 356.299992 -238.537823) (xy 356.346008 -238.520371) (xy 356.394227 -238.510527) (xy 356.443402 -238.508546)
			(xy 356.492257 -238.514478) (xy 356.539528 -238.52817) (xy 356.58399 -238.549268) (xy 356.624493 -238.577224)
			(xy 356.659986 -238.611316) (xy 356.689551 -238.65066) (xy 356.712422 -238.694237) (xy 356.728006 -238.740918)
			(xy 356.735901 -238.789495) (xy 356.736396 -238.814102) (xy 357.065338 -238.814102) (xy 357.069298 -238.765048)
			(xy 357.081075 -238.717264) (xy 357.100366 -238.671988) (xy 357.126669 -238.630392) (xy 357.159304 -238.593555)
			(xy 357.197425 -238.56243) (xy 357.240046 -238.537823) (xy 357.286062 -238.520371) (xy 357.334281 -238.510527)
			(xy 357.383456 -238.508546) (xy 357.432311 -238.514478) (xy 357.479582 -238.52817) (xy 357.524044 -238.549268)
			(xy 357.564547 -238.577224) (xy 357.60004 -238.611316) (xy 357.629605 -238.65066) (xy 357.652476 -238.694237)
			(xy 357.66806 -238.740918) (xy 357.675955 -238.789495) (xy 357.67645 -238.814102) (xy 357.675955 -238.838709)
			(xy 357.66806 -238.887286) (xy 357.652476 -238.933967) (xy 357.629605 -238.977544) (xy 357.60004 -239.016888)
			(xy 357.564547 -239.05098) (xy 357.524044 -239.078936) (xy 357.479582 -239.100034) (xy 357.432311 -239.113726)
			(xy 357.383456 -239.119658) (xy 357.334281 -239.117677) (xy 357.286062 -239.107833) (xy 357.240046 -239.090381)
			(xy 357.197425 -239.065774) (xy 357.159304 -239.034649) (xy 357.126669 -238.997812) (xy 357.100366 -238.956216)
			(xy 357.081075 -238.91094) (xy 357.069298 -238.863156) (xy 357.065338 -238.814102) (xy 356.736396 -238.814102)
			(xy 356.735901 -238.838709) (xy 356.728006 -238.887286) (xy 356.712422 -238.933967) (xy 356.689551 -238.977544)
			(xy 356.659986 -239.016888) (xy 356.624493 -239.05098) (xy 356.58399 -239.078936) (xy 356.539528 -239.100034)
			(xy 356.492257 -239.113726) (xy 356.443402 -239.119658) (xy 356.394227 -239.117677) (xy 356.346008 -239.107833)
			(xy 356.299992 -239.090381) (xy 356.257371 -239.065774) (xy 356.21925 -239.034649) (xy 356.186615 -238.997812)
			(xy 356.160312 -238.956216) (xy 356.141021 -238.91094) (xy 356.129244 -238.863156) (xy 356.125284 -238.814102)
			(xy 355.796342 -238.814102) (xy 355.795847 -238.838709) (xy 355.787952 -238.887286) (xy 355.772368 -238.933967)
			(xy 355.749497 -238.977544) (xy 355.719932 -239.016888) (xy 355.684439 -239.05098) (xy 355.643936 -239.078936)
			(xy 355.599474 -239.100034) (xy 355.552203 -239.113726) (xy 355.503348 -239.119658) (xy 355.454173 -239.117677)
			(xy 355.405954 -239.107833) (xy 355.359938 -239.090381) (xy 355.317317 -239.065774) (xy 355.279196 -239.034649)
			(xy 355.246561 -238.997812) (xy 355.220258 -238.956216) (xy 355.200967 -238.91094) (xy 355.18919 -238.863156)
			(xy 355.18523 -238.814102) (xy 352.976434 -238.814102) (xy 352.975939 -238.838709) (xy 352.968044 -238.887286)
			(xy 352.95246 -238.933967) (xy 352.929589 -238.977544) (xy 352.900024 -239.016888) (xy 352.864531 -239.05098)
			(xy 352.824028 -239.078936) (xy 352.779566 -239.100034) (xy 352.732295 -239.113726) (xy 352.68344 -239.119658)
			(xy 352.634265 -239.117677) (xy 352.586046 -239.107833) (xy 352.54003 -239.090381) (xy 352.497409 -239.065774)
			(xy 352.459288 -239.034649) (xy 352.426653 -238.997812) (xy 352.40035 -238.956216) (xy 352.381059 -238.91094)
			(xy 352.369282 -238.863156) (xy 352.365322 -238.814102) (xy 350.156526 -238.814102) (xy 350.156031 -238.838709)
			(xy 350.148136 -238.887286) (xy 350.132552 -238.933967) (xy 350.109681 -238.977544) (xy 350.080116 -239.016888)
			(xy 350.044623 -239.05098) (xy 350.00412 -239.078936) (xy 349.959658 -239.100034) (xy 349.912387 -239.113726)
			(xy 349.863532 -239.119658) (xy 349.814357 -239.117677) (xy 349.766138 -239.107833) (xy 349.720122 -239.090381)
			(xy 349.677501 -239.065774) (xy 349.63938 -239.034649) (xy 349.606745 -238.997812) (xy 349.580442 -238.956216)
			(xy 349.561151 -238.91094) (xy 349.549374 -238.863156) (xy 349.545414 -238.814102) (xy 347.336364 -238.814102)
			(xy 347.335869 -238.838709) (xy 347.327974 -238.887286) (xy 347.31239 -238.933967) (xy 347.289519 -238.977544)
			(xy 347.259954 -239.016888) (xy 347.224461 -239.05098) (xy 347.183958 -239.078936) (xy 347.139496 -239.100034)
			(xy 347.092225 -239.113726) (xy 347.04337 -239.119658) (xy 346.994195 -239.117677) (xy 346.945976 -239.107833)
			(xy 346.89996 -239.090381) (xy 346.857339 -239.065774) (xy 346.819218 -239.034649) (xy 346.786583 -238.997812)
			(xy 346.76028 -238.956216) (xy 346.740989 -238.91094) (xy 346.729212 -238.863156) (xy 346.725252 -238.814102)
			(xy 344.516966 -238.814102) (xy 344.512921 -238.863747) (xy 344.50082 -238.912198) (xy 344.480996 -238.958034)
			(xy 344.453977 -239.000033) (xy 344.420485 -239.037077) (xy 344.381411 -239.068176) (xy 344.337798 -239.092503)
			(xy 344.290807 -239.109409) (xy 344.241692 -239.118443) (xy 344.216736 -239.11941) (xy 344.215974 -239.11941)
			(xy 344.206222 -239.120141) (xy 344.18832 -239.127972) (xy 344.181176 -239.13465) (xy 344.131138 -239.18545)
			(xy 344.124556 -239.192831) (xy 344.117106 -239.21113) (xy 344.11666 -239.22101) (xy 344.11666 -239.419638)
			(xy 344.117092 -239.429704) (xy 344.124822 -239.448293) (xy 344.131646 -239.455706) (xy 344.22842 -239.55248)
			(xy 344.234654 -239.558253) (xy 344.249932 -239.565667) (xy 344.266792 -239.567691) (xy 344.275156 -239.566196)
			(xy 344.371422 -239.545368) (xy 344.390726 -239.528604) (xy 344.395298 -239.516412) (xy 344.405135 -239.491888)
			(xy 344.431993 -239.44639) (xy 344.466283 -239.406194) (xy 344.50698 -239.372501) (xy 344.552869 -239.346317)
			(xy 344.602581 -239.328423) (xy 344.654631 -239.319353) (xy 344.681048 -239.3188) (xy 344.705037 -239.319274)
			(xy 344.752422 -239.326786) (xy 344.798049 -239.341618) (xy 344.840794 -239.363404) (xy 344.879606 -239.391609)
			(xy 344.913528 -239.425537) (xy 344.941725 -239.464353) (xy 344.963503 -239.507103) (xy 344.978327 -239.552733)
			(xy 344.98583 -239.600119) (xy 344.986356 -239.624108) (xy 345.315298 -239.624108) (xy 345.319258 -239.575054)
			(xy 345.331035 -239.52727) (xy 345.350326 -239.481994) (xy 345.376629 -239.440398) (xy 345.409264 -239.403561)
			(xy 345.447385 -239.372436) (xy 345.490006 -239.347829) (xy 345.536022 -239.330377) (xy 345.584241 -239.320533)
			(xy 345.633416 -239.318552) (xy 345.682271 -239.324484) (xy 345.729542 -239.338176) (xy 345.774004 -239.359274)
			(xy 345.814507 -239.38723) (xy 345.85 -239.421322) (xy 345.879565 -239.460666) (xy 345.902436 -239.504243)
			(xy 345.91802 -239.550924) (xy 345.925915 -239.599501) (xy 345.92641 -239.624108) (xy 346.255352 -239.624108)
			(xy 346.259312 -239.575054) (xy 346.271089 -239.52727) (xy 346.29038 -239.481994) (xy 346.316683 -239.440398)
			(xy 346.349318 -239.403561) (xy 346.387439 -239.372436) (xy 346.43006 -239.347829) (xy 346.476076 -239.330377)
			(xy 346.524295 -239.320533) (xy 346.57347 -239.318552) (xy 346.622325 -239.324484) (xy 346.669596 -239.338176)
			(xy 346.714058 -239.359274) (xy 346.754561 -239.38723) (xy 346.790054 -239.421322) (xy 346.819619 -239.460666)
			(xy 346.84249 -239.504243) (xy 346.858074 -239.550924) (xy 346.865969 -239.599501) (xy 346.866464 -239.624108)
			(xy 347.195406 -239.624108) (xy 347.199366 -239.575054) (xy 347.211143 -239.52727) (xy 347.230434 -239.481994)
			(xy 347.256737 -239.440398) (xy 347.289372 -239.403561) (xy 347.327493 -239.372436) (xy 347.370114 -239.347829)
			(xy 347.41613 -239.330377) (xy 347.464349 -239.320533) (xy 347.513524 -239.318552) (xy 347.562379 -239.324484)
			(xy 347.60965 -239.338176) (xy 347.654112 -239.359274) (xy 347.694615 -239.38723) (xy 347.730108 -239.421322)
			(xy 347.759673 -239.460666) (xy 347.782544 -239.504243) (xy 347.798128 -239.550924) (xy 347.806023 -239.599501)
			(xy 347.806518 -239.624108) (xy 348.135206 -239.624108) (xy 348.139166 -239.575054) (xy 348.150943 -239.52727)
			(xy 348.170234 -239.481994) (xy 348.196537 -239.440398) (xy 348.229172 -239.403561) (xy 348.267293 -239.372436)
			(xy 348.309914 -239.347829) (xy 348.35593 -239.330377) (xy 348.404149 -239.320533) (xy 348.453324 -239.318552)
			(xy 348.502179 -239.324484) (xy 348.54945 -239.338176) (xy 348.593912 -239.359274) (xy 348.634415 -239.38723)
			(xy 348.669908 -239.421322) (xy 348.699473 -239.460666) (xy 348.722344 -239.504243) (xy 348.737928 -239.550924)
			(xy 348.745823 -239.599501) (xy 348.746318 -239.624108) (xy 349.07526 -239.624108) (xy 349.07922 -239.575054)
			(xy 349.090997 -239.52727) (xy 349.110288 -239.481994) (xy 349.136591 -239.440398) (xy 349.169226 -239.403561)
			(xy 349.207347 -239.372436) (xy 349.249968 -239.347829) (xy 349.295984 -239.330377) (xy 349.344203 -239.320533)
			(xy 349.393378 -239.318552) (xy 349.442233 -239.324484) (xy 349.489504 -239.338176) (xy 349.533966 -239.359274)
			(xy 349.574469 -239.38723) (xy 349.609962 -239.421322) (xy 349.639527 -239.460666) (xy 349.662398 -239.504243)
			(xy 349.677982 -239.550924) (xy 349.685877 -239.599501) (xy 349.686372 -239.624108) (xy 350.015314 -239.624108)
			(xy 350.019274 -239.575054) (xy 350.031051 -239.52727) (xy 350.050342 -239.481994) (xy 350.076645 -239.440398)
			(xy 350.10928 -239.403561) (xy 350.147401 -239.372436) (xy 350.190022 -239.347829) (xy 350.236038 -239.330377)
			(xy 350.284257 -239.320533) (xy 350.333432 -239.318552) (xy 350.382287 -239.324484) (xy 350.429558 -239.338176)
			(xy 350.47402 -239.359274) (xy 350.514523 -239.38723) (xy 350.550016 -239.421322) (xy 350.579581 -239.460666)
			(xy 350.602452 -239.504243) (xy 350.618036 -239.550924) (xy 350.625931 -239.599501) (xy 350.626426 -239.624108)
			(xy 350.955368 -239.624108) (xy 350.959328 -239.575054) (xy 350.971105 -239.52727) (xy 350.990396 -239.481994)
			(xy 351.016699 -239.440398) (xy 351.049334 -239.403561) (xy 351.087455 -239.372436) (xy 351.130076 -239.347829)
			(xy 351.176092 -239.330377) (xy 351.224311 -239.320533) (xy 351.273486 -239.318552) (xy 351.322341 -239.324484)
			(xy 351.369612 -239.338176) (xy 351.414074 -239.359274) (xy 351.454577 -239.38723) (xy 351.49007 -239.421322)
			(xy 351.519635 -239.460666) (xy 351.542506 -239.504243) (xy 351.55809 -239.550924) (xy 351.565985 -239.599501)
			(xy 351.56648 -239.624108) (xy 351.895422 -239.624108) (xy 351.899382 -239.575054) (xy 351.911159 -239.52727)
			(xy 351.93045 -239.481994) (xy 351.956753 -239.440398) (xy 351.989388 -239.403561) (xy 352.027509 -239.372436)
			(xy 352.07013 -239.347829) (xy 352.116146 -239.330377) (xy 352.164365 -239.320533) (xy 352.21354 -239.318552)
			(xy 352.262395 -239.324484) (xy 352.309666 -239.338176) (xy 352.354128 -239.359274) (xy 352.394631 -239.38723)
			(xy 352.430124 -239.421322) (xy 352.459689 -239.460666) (xy 352.48256 -239.504243) (xy 352.498144 -239.550924)
			(xy 352.506039 -239.599501) (xy 352.506534 -239.624108) (xy 352.835222 -239.624108) (xy 352.839182 -239.575054)
			(xy 352.850959 -239.52727) (xy 352.87025 -239.481994) (xy 352.896553 -239.440398) (xy 352.929188 -239.403561)
			(xy 352.967309 -239.372436) (xy 353.00993 -239.347829) (xy 353.055946 -239.330377) (xy 353.104165 -239.320533)
			(xy 353.15334 -239.318552) (xy 353.202195 -239.324484) (xy 353.249466 -239.338176) (xy 353.293928 -239.359274)
			(xy 353.334431 -239.38723) (xy 353.369924 -239.421322) (xy 353.399489 -239.460666) (xy 353.42236 -239.504243)
			(xy 353.437944 -239.550924) (xy 353.445839 -239.599501) (xy 353.446334 -239.624108) (xy 353.775276 -239.624108)
			(xy 353.779236 -239.575054) (xy 353.791013 -239.52727) (xy 353.810304 -239.481994) (xy 353.836607 -239.440398)
			(xy 353.869242 -239.403561) (xy 353.907363 -239.372436) (xy 353.949984 -239.347829) (xy 353.996 -239.330377)
			(xy 354.044219 -239.320533) (xy 354.093394 -239.318552) (xy 354.142249 -239.324484) (xy 354.18952 -239.338176)
			(xy 354.233982 -239.359274) (xy 354.274485 -239.38723) (xy 354.309978 -239.421322) (xy 354.339543 -239.460666)
			(xy 354.362414 -239.504243) (xy 354.377998 -239.550924) (xy 354.385893 -239.599501) (xy 354.386388 -239.624108)
			(xy 354.71533 -239.624108) (xy 354.71929 -239.575054) (xy 354.731067 -239.52727) (xy 354.750358 -239.481994)
			(xy 354.776661 -239.440398) (xy 354.809296 -239.403561) (xy 354.847417 -239.372436) (xy 354.890038 -239.347829)
			(xy 354.936054 -239.330377) (xy 354.984273 -239.320533) (xy 355.033448 -239.318552) (xy 355.082303 -239.324484)
			(xy 355.129574 -239.338176) (xy 355.174036 -239.359274) (xy 355.214539 -239.38723) (xy 355.250032 -239.421322)
			(xy 355.279597 -239.460666) (xy 355.302468 -239.504243) (xy 355.318052 -239.550924) (xy 355.325947 -239.599501)
			(xy 355.326442 -239.624108) (xy 355.655384 -239.624108) (xy 355.659344 -239.575054) (xy 355.671121 -239.52727)
			(xy 355.690412 -239.481994) (xy 355.716715 -239.440398) (xy 355.74935 -239.403561) (xy 355.787471 -239.372436)
			(xy 355.830092 -239.347829) (xy 355.876108 -239.330377) (xy 355.924327 -239.320533) (xy 355.973502 -239.318552)
			(xy 356.022357 -239.324484) (xy 356.069628 -239.338176) (xy 356.11409 -239.359274) (xy 356.154593 -239.38723)
			(xy 356.190086 -239.421322) (xy 356.219651 -239.460666) (xy 356.242522 -239.504243) (xy 356.258106 -239.550924)
			(xy 356.266001 -239.599501) (xy 356.266496 -239.624108) (xy 356.266001 -239.648715) (xy 356.258106 -239.697292)
			(xy 356.242522 -239.743973) (xy 356.219651 -239.78755) (xy 356.190086 -239.826894) (xy 356.154593 -239.860986)
			(xy 356.11409 -239.888942) (xy 356.069628 -239.91004) (xy 356.022357 -239.923732) (xy 355.973502 -239.929664)
			(xy 355.924327 -239.927683) (xy 355.876108 -239.917839) (xy 355.830092 -239.900387) (xy 355.787471 -239.87578)
			(xy 355.74935 -239.844655) (xy 355.716715 -239.807818) (xy 355.690412 -239.766222) (xy 355.671121 -239.720946)
			(xy 355.659344 -239.673162) (xy 355.655384 -239.624108) (xy 355.326442 -239.624108) (xy 355.325947 -239.648715)
			(xy 355.318052 -239.697292) (xy 355.302468 -239.743973) (xy 355.279597 -239.78755) (xy 355.250032 -239.826894)
			(xy 355.214539 -239.860986) (xy 355.174036 -239.888942) (xy 355.129574 -239.91004) (xy 355.082303 -239.923732)
			(xy 355.033448 -239.929664) (xy 354.984273 -239.927683) (xy 354.936054 -239.917839) (xy 354.890038 -239.900387)
			(xy 354.847417 -239.87578) (xy 354.809296 -239.844655) (xy 354.776661 -239.807818) (xy 354.750358 -239.766222)
			(xy 354.731067 -239.720946) (xy 354.71929 -239.673162) (xy 354.71533 -239.624108) (xy 354.386388 -239.624108)
			(xy 354.385893 -239.648715) (xy 354.377998 -239.697292) (xy 354.362414 -239.743973) (xy 354.339543 -239.78755)
			(xy 354.309978 -239.826894) (xy 354.274485 -239.860986) (xy 354.233982 -239.888942) (xy 354.18952 -239.91004)
			(xy 354.142249 -239.923732) (xy 354.093394 -239.929664) (xy 354.044219 -239.927683) (xy 353.996 -239.917839)
			(xy 353.949984 -239.900387) (xy 353.907363 -239.87578) (xy 353.869242 -239.844655) (xy 353.836607 -239.807818)
			(xy 353.810304 -239.766222) (xy 353.791013 -239.720946) (xy 353.779236 -239.673162) (xy 353.775276 -239.624108)
			(xy 353.446334 -239.624108) (xy 353.445839 -239.648715) (xy 353.437944 -239.697292) (xy 353.42236 -239.743973)
			(xy 353.399489 -239.78755) (xy 353.369924 -239.826894) (xy 353.334431 -239.860986) (xy 353.293928 -239.888942)
			(xy 353.249466 -239.91004) (xy 353.202195 -239.923732) (xy 353.15334 -239.929664) (xy 353.104165 -239.927683)
			(xy 353.055946 -239.917839) (xy 353.00993 -239.900387) (xy 352.967309 -239.87578) (xy 352.929188 -239.844655)
			(xy 352.896553 -239.807818) (xy 352.87025 -239.766222) (xy 352.850959 -239.720946) (xy 352.839182 -239.673162)
			(xy 352.835222 -239.624108) (xy 352.506534 -239.624108) (xy 352.506039 -239.648715) (xy 352.498144 -239.697292)
			(xy 352.48256 -239.743973) (xy 352.459689 -239.78755) (xy 352.430124 -239.826894) (xy 352.394631 -239.860986)
			(xy 352.354128 -239.888942) (xy 352.309666 -239.91004) (xy 352.262395 -239.923732) (xy 352.21354 -239.929664)
			(xy 352.164365 -239.927683) (xy 352.116146 -239.917839) (xy 352.07013 -239.900387) (xy 352.027509 -239.87578)
			(xy 351.989388 -239.844655) (xy 351.956753 -239.807818) (xy 351.93045 -239.766222) (xy 351.911159 -239.720946)
			(xy 351.899382 -239.673162) (xy 351.895422 -239.624108) (xy 351.56648 -239.624108) (xy 351.565985 -239.648715)
			(xy 351.55809 -239.697292) (xy 351.542506 -239.743973) (xy 351.519635 -239.78755) (xy 351.49007 -239.826894)
			(xy 351.454577 -239.860986) (xy 351.414074 -239.888942) (xy 351.369612 -239.91004) (xy 351.322341 -239.923732)
			(xy 351.273486 -239.929664) (xy 351.224311 -239.927683) (xy 351.176092 -239.917839) (xy 351.130076 -239.900387)
			(xy 351.087455 -239.87578) (xy 351.049334 -239.844655) (xy 351.016699 -239.807818) (xy 350.990396 -239.766222)
			(xy 350.971105 -239.720946) (xy 350.959328 -239.673162) (xy 350.955368 -239.624108) (xy 350.626426 -239.624108)
			(xy 350.625931 -239.648715) (xy 350.618036 -239.697292) (xy 350.602452 -239.743973) (xy 350.579581 -239.78755)
			(xy 350.550016 -239.826894) (xy 350.514523 -239.860986) (xy 350.47402 -239.888942) (xy 350.429558 -239.91004)
			(xy 350.382287 -239.923732) (xy 350.333432 -239.929664) (xy 350.284257 -239.927683) (xy 350.236038 -239.917839)
			(xy 350.190022 -239.900387) (xy 350.147401 -239.87578) (xy 350.10928 -239.844655) (xy 350.076645 -239.807818)
			(xy 350.050342 -239.766222) (xy 350.031051 -239.720946) (xy 350.019274 -239.673162) (xy 350.015314 -239.624108)
			(xy 349.686372 -239.624108) (xy 349.685877 -239.648715) (xy 349.677982 -239.697292) (xy 349.662398 -239.743973)
			(xy 349.639527 -239.78755) (xy 349.609962 -239.826894) (xy 349.574469 -239.860986) (xy 349.533966 -239.888942)
			(xy 349.489504 -239.91004) (xy 349.442233 -239.923732) (xy 349.393378 -239.929664) (xy 349.344203 -239.927683)
			(xy 349.295984 -239.917839) (xy 349.249968 -239.900387) (xy 349.207347 -239.87578) (xy 349.169226 -239.844655)
			(xy 349.136591 -239.807818) (xy 349.110288 -239.766222) (xy 349.090997 -239.720946) (xy 349.07922 -239.673162)
			(xy 349.07526 -239.624108) (xy 348.746318 -239.624108) (xy 348.745823 -239.648715) (xy 348.737928 -239.697292)
			(xy 348.722344 -239.743973) (xy 348.699473 -239.78755) (xy 348.669908 -239.826894) (xy 348.634415 -239.860986)
			(xy 348.593912 -239.888942) (xy 348.54945 -239.91004) (xy 348.502179 -239.923732) (xy 348.453324 -239.929664)
			(xy 348.404149 -239.927683) (xy 348.35593 -239.917839) (xy 348.309914 -239.900387) (xy 348.267293 -239.87578)
			(xy 348.229172 -239.844655) (xy 348.196537 -239.807818) (xy 348.170234 -239.766222) (xy 348.150943 -239.720946)
			(xy 348.139166 -239.673162) (xy 348.135206 -239.624108) (xy 347.806518 -239.624108) (xy 347.806023 -239.648715)
			(xy 347.798128 -239.697292) (xy 347.782544 -239.743973) (xy 347.759673 -239.78755) (xy 347.730108 -239.826894)
			(xy 347.694615 -239.860986) (xy 347.654112 -239.888942) (xy 347.60965 -239.91004) (xy 347.562379 -239.923732)
			(xy 347.513524 -239.929664) (xy 347.464349 -239.927683) (xy 347.41613 -239.917839) (xy 347.370114 -239.900387)
			(xy 347.327493 -239.87578) (xy 347.289372 -239.844655) (xy 347.256737 -239.807818) (xy 347.230434 -239.766222)
			(xy 347.211143 -239.720946) (xy 347.199366 -239.673162) (xy 347.195406 -239.624108) (xy 346.866464 -239.624108)
			(xy 346.865969 -239.648715) (xy 346.858074 -239.697292) (xy 346.84249 -239.743973) (xy 346.819619 -239.78755)
			(xy 346.790054 -239.826894) (xy 346.754561 -239.860986) (xy 346.714058 -239.888942) (xy 346.669596 -239.91004)
			(xy 346.622325 -239.923732) (xy 346.57347 -239.929664) (xy 346.524295 -239.927683) (xy 346.476076 -239.917839)
			(xy 346.43006 -239.900387) (xy 346.387439 -239.87578) (xy 346.349318 -239.844655) (xy 346.316683 -239.807818)
			(xy 346.29038 -239.766222) (xy 346.271089 -239.720946) (xy 346.259312 -239.673162) (xy 346.255352 -239.624108)
			(xy 345.92641 -239.624108) (xy 345.925915 -239.648715) (xy 345.91802 -239.697292) (xy 345.902436 -239.743973)
			(xy 345.879565 -239.78755) (xy 345.85 -239.826894) (xy 345.814507 -239.860986) (xy 345.774004 -239.888942)
			(xy 345.729542 -239.91004) (xy 345.682271 -239.923732) (xy 345.633416 -239.929664) (xy 345.584241 -239.927683)
			(xy 345.536022 -239.917839) (xy 345.490006 -239.900387) (xy 345.447385 -239.87578) (xy 345.409264 -239.844655)
			(xy 345.376629 -239.807818) (xy 345.350326 -239.766222) (xy 345.331035 -239.720946) (xy 345.319258 -239.673162)
			(xy 345.315298 -239.624108) (xy 344.986356 -239.624108) (xy 344.985797 -239.650523) (xy 344.976709 -239.702567)
			(xy 344.958807 -239.752272) (xy 344.932622 -239.798158) (xy 344.898936 -239.838856) (xy 344.858753 -239.873155)
			(xy 344.81327 -239.900032) (xy 344.788744 -239.909858) (xy 344.776552 -239.91443) (xy 344.759788 -239.933734)
			(xy 344.73896 -240.03) (xy 344.737442 -240.038364) (xy 344.739443 -240.055235) (xy 344.746892 -240.070505)
			(xy 344.752676 -240.076736) (xy 344.865198 -240.189258) (xy 344.87229 -240.195727) (xy 344.889914 -240.203299)
			(xy 344.899488 -240.20399) (xy 344.929206 -240.205006) (xy 344.933861 -240.205041) (xy 344.943063 -240.203639)
			(xy 344.947494 -240.202212) (xy 344.951512 -240.200725) (xy 344.95904 -240.196637) (xy 344.96248 -240.194084)
			(xy 344.982806 -240.17877) (xy 345.027482 -240.154406) (xy 345.075575 -240.137775) (xy 345.125758 -240.129334)
			(xy 345.151202 -240.128806) (xy 345.176456 -240.129328) (xy 345.226275 -240.137641) (xy 345.274047 -240.154042)
			(xy 345.318467 -240.178081) (xy 345.358325 -240.209104) (xy 345.392533 -240.246264) (xy 345.420158 -240.288548)
			(xy 345.440447 -240.334802) (xy 345.452846 -240.383764) (xy 345.457017 -240.4341) (xy 345.457016 -240.434114)
			(xy 345.785198 -240.434114) (xy 345.789158 -240.38506) (xy 345.800935 -240.337276) (xy 345.820226 -240.292)
			(xy 345.846529 -240.250404) (xy 345.879164 -240.213567) (xy 345.917285 -240.182442) (xy 345.959906 -240.157835)
			(xy 346.005922 -240.140383) (xy 346.054141 -240.130539) (xy 346.103316 -240.128558) (xy 346.152171 -240.13449)
			(xy 346.199442 -240.148182) (xy 346.243904 -240.16928) (xy 346.284407 -240.197236) (xy 346.3199 -240.231328)
			(xy 346.349465 -240.270672) (xy 346.372336 -240.314249) (xy 346.38792 -240.36093) (xy 346.395815 -240.409507)
			(xy 346.39631 -240.434114) (xy 346.725252 -240.434114) (xy 346.729212 -240.38506) (xy 346.740989 -240.337276)
			(xy 346.76028 -240.292) (xy 346.786583 -240.250404) (xy 346.819218 -240.213567) (xy 346.857339 -240.182442)
			(xy 346.89996 -240.157835) (xy 346.945976 -240.140383) (xy 346.994195 -240.130539) (xy 347.04337 -240.128558)
			(xy 347.092225 -240.13449) (xy 347.139496 -240.148182) (xy 347.183958 -240.16928) (xy 347.224461 -240.197236)
			(xy 347.259954 -240.231328) (xy 347.289519 -240.270672) (xy 347.31239 -240.314249) (xy 347.327974 -240.36093)
			(xy 347.335869 -240.409507) (xy 347.336364 -240.434114) (xy 347.665306 -240.434114) (xy 347.669266 -240.38506)
			(xy 347.681043 -240.337276) (xy 347.700334 -240.292) (xy 347.726637 -240.250404) (xy 347.759272 -240.213567)
			(xy 347.797393 -240.182442) (xy 347.840014 -240.157835) (xy 347.88603 -240.140383) (xy 347.934249 -240.130539)
			(xy 347.983424 -240.128558) (xy 348.032279 -240.13449) (xy 348.07955 -240.148182) (xy 348.124012 -240.16928)
			(xy 348.164515 -240.197236) (xy 348.200008 -240.231328) (xy 348.229573 -240.270672) (xy 348.252444 -240.314249)
			(xy 348.268028 -240.36093) (xy 348.275923 -240.409507) (xy 348.276418 -240.434114) (xy 348.60536 -240.434114)
			(xy 348.60932 -240.38506) (xy 348.621097 -240.337276) (xy 348.640388 -240.292) (xy 348.666691 -240.250404)
			(xy 348.699326 -240.213567) (xy 348.737447 -240.182442) (xy 348.780068 -240.157835) (xy 348.826084 -240.140383)
			(xy 348.874303 -240.130539) (xy 348.923478 -240.128558) (xy 348.972333 -240.13449) (xy 349.019604 -240.148182)
			(xy 349.064066 -240.16928) (xy 349.104569 -240.197236) (xy 349.140062 -240.231328) (xy 349.169627 -240.270672)
			(xy 349.192498 -240.314249) (xy 349.208082 -240.36093) (xy 349.215977 -240.409507) (xy 349.216472 -240.434114)
			(xy 349.545414 -240.434114) (xy 349.549374 -240.38506) (xy 349.561151 -240.337276) (xy 349.580442 -240.292)
			(xy 349.606745 -240.250404) (xy 349.63938 -240.213567) (xy 349.677501 -240.182442) (xy 349.720122 -240.157835)
			(xy 349.766138 -240.140383) (xy 349.814357 -240.130539) (xy 349.863532 -240.128558) (xy 349.912387 -240.13449)
			(xy 349.959658 -240.148182) (xy 350.00412 -240.16928) (xy 350.044623 -240.197236) (xy 350.080116 -240.231328)
			(xy 350.109681 -240.270672) (xy 350.132552 -240.314249) (xy 350.148136 -240.36093) (xy 350.156031 -240.409507)
			(xy 350.156526 -240.434114) (xy 350.485214 -240.434114) (xy 350.489174 -240.38506) (xy 350.500951 -240.337276)
			(xy 350.520242 -240.292) (xy 350.546545 -240.250404) (xy 350.57918 -240.213567) (xy 350.617301 -240.182442)
			(xy 350.659922 -240.157835) (xy 350.705938 -240.140383) (xy 350.754157 -240.130539) (xy 350.803332 -240.128558)
			(xy 350.852187 -240.13449) (xy 350.899458 -240.148182) (xy 350.94392 -240.16928) (xy 350.984423 -240.197236)
			(xy 351.019916 -240.231328) (xy 351.049481 -240.270672) (xy 351.072352 -240.314249) (xy 351.087936 -240.36093)
			(xy 351.095831 -240.409507) (xy 351.096326 -240.434114) (xy 351.425268 -240.434114) (xy 351.429228 -240.38506)
			(xy 351.441005 -240.337276) (xy 351.460296 -240.292) (xy 351.486599 -240.250404) (xy 351.519234 -240.213567)
			(xy 351.557355 -240.182442) (xy 351.599976 -240.157835) (xy 351.645992 -240.140383) (xy 351.694211 -240.130539)
			(xy 351.743386 -240.128558) (xy 351.792241 -240.13449) (xy 351.839512 -240.148182) (xy 351.883974 -240.16928)
			(xy 351.924477 -240.197236) (xy 351.95997 -240.231328) (xy 351.989535 -240.270672) (xy 352.012406 -240.314249)
			(xy 352.02799 -240.36093) (xy 352.035885 -240.409507) (xy 352.03638 -240.434114) (xy 352.365322 -240.434114)
			(xy 352.369282 -240.38506) (xy 352.381059 -240.337276) (xy 352.40035 -240.292) (xy 352.426653 -240.250404)
			(xy 352.459288 -240.213567) (xy 352.497409 -240.182442) (xy 352.54003 -240.157835) (xy 352.586046 -240.140383)
			(xy 352.634265 -240.130539) (xy 352.68344 -240.128558) (xy 352.732295 -240.13449) (xy 352.779566 -240.148182)
			(xy 352.824028 -240.16928) (xy 352.864531 -240.197236) (xy 352.900024 -240.231328) (xy 352.929589 -240.270672)
			(xy 352.95246 -240.314249) (xy 352.968044 -240.36093) (xy 352.975939 -240.409507) (xy 352.976434 -240.434114)
			(xy 353.305376 -240.434114) (xy 353.309336 -240.38506) (xy 353.321113 -240.337276) (xy 353.340404 -240.292)
			(xy 353.366707 -240.250404) (xy 353.399342 -240.213567) (xy 353.437463 -240.182442) (xy 353.480084 -240.157835)
			(xy 353.5261 -240.140383) (xy 353.574319 -240.130539) (xy 353.623494 -240.128558) (xy 353.672349 -240.13449)
			(xy 353.71962 -240.148182) (xy 353.764082 -240.16928) (xy 353.804585 -240.197236) (xy 353.840078 -240.231328)
			(xy 353.869643 -240.270672) (xy 353.892514 -240.314249) (xy 353.908098 -240.36093) (xy 353.915993 -240.409507)
			(xy 353.916488 -240.434114) (xy 354.24543 -240.434114) (xy 354.24939 -240.38506) (xy 354.261167 -240.337276)
			(xy 354.280458 -240.292) (xy 354.306761 -240.250404) (xy 354.339396 -240.213567) (xy 354.377517 -240.182442)
			(xy 354.420138 -240.157835) (xy 354.466154 -240.140383) (xy 354.514373 -240.130539) (xy 354.563548 -240.128558)
			(xy 354.612403 -240.13449) (xy 354.659674 -240.148182) (xy 354.704136 -240.16928) (xy 354.744639 -240.197236)
			(xy 354.780132 -240.231328) (xy 354.809697 -240.270672) (xy 354.832568 -240.314249) (xy 354.848152 -240.36093)
			(xy 354.856047 -240.409507) (xy 354.856542 -240.434114) (xy 355.18523 -240.434114) (xy 355.18919 -240.38506)
			(xy 355.200967 -240.337276) (xy 355.220258 -240.292) (xy 355.246561 -240.250404) (xy 355.279196 -240.213567)
			(xy 355.317317 -240.182442) (xy 355.359938 -240.157835) (xy 355.405954 -240.140383) (xy 355.454173 -240.130539)
			(xy 355.503348 -240.128558) (xy 355.552203 -240.13449) (xy 355.599474 -240.148182) (xy 355.643936 -240.16928)
			(xy 355.684439 -240.197236) (xy 355.719932 -240.231328) (xy 355.749497 -240.270672) (xy 355.772368 -240.314249)
			(xy 355.787952 -240.36093) (xy 355.795847 -240.409507) (xy 355.796342 -240.434114) (xy 356.125284 -240.434114)
			(xy 356.129244 -240.38506) (xy 356.141021 -240.337276) (xy 356.160312 -240.292) (xy 356.186615 -240.250404)
			(xy 356.21925 -240.213567) (xy 356.257371 -240.182442) (xy 356.299992 -240.157835) (xy 356.346008 -240.140383)
			(xy 356.394227 -240.130539) (xy 356.443402 -240.128558) (xy 356.492257 -240.13449) (xy 356.539528 -240.148182)
			(xy 356.58399 -240.16928) (xy 356.624493 -240.197236) (xy 356.659986 -240.231328) (xy 356.689551 -240.270672)
			(xy 356.712422 -240.314249) (xy 356.728006 -240.36093) (xy 356.735901 -240.409507) (xy 356.736396 -240.434114)
			(xy 357.065338 -240.434114) (xy 357.069298 -240.38506) (xy 357.081075 -240.337276) (xy 357.100366 -240.292)
			(xy 357.126669 -240.250404) (xy 357.159304 -240.213567) (xy 357.197425 -240.182442) (xy 357.240046 -240.157835)
			(xy 357.286062 -240.140383) (xy 357.334281 -240.130539) (xy 357.383456 -240.128558) (xy 357.432311 -240.13449)
			(xy 357.479582 -240.148182) (xy 357.524044 -240.16928) (xy 357.564547 -240.197236) (xy 357.60004 -240.231328)
			(xy 357.629605 -240.270672) (xy 357.652476 -240.314249) (xy 357.66806 -240.36093) (xy 357.675955 -240.409507)
			(xy 357.67645 -240.434114) (xy 357.675955 -240.458721) (xy 357.66806 -240.507298) (xy 357.652476 -240.553979)
			(xy 357.629605 -240.597556) (xy 357.60004 -240.6369) (xy 357.564547 -240.670992) (xy 357.524044 -240.698948)
			(xy 357.479582 -240.720046) (xy 357.432311 -240.733738) (xy 357.383456 -240.73967) (xy 357.334281 -240.737689)
			(xy 357.286062 -240.727845) (xy 357.240046 -240.710393) (xy 357.197425 -240.685786) (xy 357.159304 -240.654661)
			(xy 357.126669 -240.617824) (xy 357.100366 -240.576228) (xy 357.081075 -240.530952) (xy 357.069298 -240.483168)
			(xy 357.065338 -240.434114) (xy 356.736396 -240.434114) (xy 356.735901 -240.458721) (xy 356.728006 -240.507298)
			(xy 356.712422 -240.553979) (xy 356.689551 -240.597556) (xy 356.659986 -240.6369) (xy 356.624493 -240.670992)
			(xy 356.58399 -240.698948) (xy 356.539528 -240.720046) (xy 356.492257 -240.733738) (xy 356.443402 -240.73967)
			(xy 356.394227 -240.737689) (xy 356.346008 -240.727845) (xy 356.299992 -240.710393) (xy 356.257371 -240.685786)
			(xy 356.21925 -240.654661) (xy 356.186615 -240.617824) (xy 356.160312 -240.576228) (xy 356.141021 -240.530952)
			(xy 356.129244 -240.483168) (xy 356.125284 -240.434114) (xy 355.796342 -240.434114) (xy 355.795847 -240.458721)
			(xy 355.787952 -240.507298) (xy 355.772368 -240.553979) (xy 355.749497 -240.597556) (xy 355.719932 -240.6369)
			(xy 355.684439 -240.670992) (xy 355.643936 -240.698948) (xy 355.599474 -240.720046) (xy 355.552203 -240.733738)
			(xy 355.503348 -240.73967) (xy 355.454173 -240.737689) (xy 355.405954 -240.727845) (xy 355.359938 -240.710393)
			(xy 355.317317 -240.685786) (xy 355.279196 -240.654661) (xy 355.246561 -240.617824) (xy 355.220258 -240.576228)
			(xy 355.200967 -240.530952) (xy 355.18919 -240.483168) (xy 355.18523 -240.434114) (xy 354.856542 -240.434114)
			(xy 354.856047 -240.458721) (xy 354.848152 -240.507298) (xy 354.832568 -240.553979) (xy 354.809697 -240.597556)
			(xy 354.780132 -240.6369) (xy 354.744639 -240.670992) (xy 354.704136 -240.698948) (xy 354.659674 -240.720046)
			(xy 354.612403 -240.733738) (xy 354.563548 -240.73967) (xy 354.514373 -240.737689) (xy 354.466154 -240.727845)
			(xy 354.420138 -240.710393) (xy 354.377517 -240.685786) (xy 354.339396 -240.654661) (xy 354.306761 -240.617824)
			(xy 354.280458 -240.576228) (xy 354.261167 -240.530952) (xy 354.24939 -240.483168) (xy 354.24543 -240.434114)
			(xy 353.916488 -240.434114) (xy 353.915993 -240.458721) (xy 353.908098 -240.507298) (xy 353.892514 -240.553979)
			(xy 353.869643 -240.597556) (xy 353.840078 -240.6369) (xy 353.804585 -240.670992) (xy 353.764082 -240.698948)
			(xy 353.71962 -240.720046) (xy 353.672349 -240.733738) (xy 353.623494 -240.73967) (xy 353.574319 -240.737689)
			(xy 353.5261 -240.727845) (xy 353.480084 -240.710393) (xy 353.437463 -240.685786) (xy 353.399342 -240.654661)
			(xy 353.366707 -240.617824) (xy 353.340404 -240.576228) (xy 353.321113 -240.530952) (xy 353.309336 -240.483168)
			(xy 353.305376 -240.434114) (xy 352.976434 -240.434114) (xy 352.975939 -240.458721) (xy 352.968044 -240.507298)
			(xy 352.95246 -240.553979) (xy 352.929589 -240.597556) (xy 352.900024 -240.6369) (xy 352.864531 -240.670992)
			(xy 352.824028 -240.698948) (xy 352.779566 -240.720046) (xy 352.732295 -240.733738) (xy 352.68344 -240.73967)
			(xy 352.634265 -240.737689) (xy 352.586046 -240.727845) (xy 352.54003 -240.710393) (xy 352.497409 -240.685786)
			(xy 352.459288 -240.654661) (xy 352.426653 -240.617824) (xy 352.40035 -240.576228) (xy 352.381059 -240.530952)
			(xy 352.369282 -240.483168) (xy 352.365322 -240.434114) (xy 352.03638 -240.434114) (xy 352.035885 -240.458721)
			(xy 352.02799 -240.507298) (xy 352.012406 -240.553979) (xy 351.989535 -240.597556) (xy 351.95997 -240.6369)
			(xy 351.924477 -240.670992) (xy 351.883974 -240.698948) (xy 351.839512 -240.720046) (xy 351.792241 -240.733738)
			(xy 351.743386 -240.73967) (xy 351.694211 -240.737689) (xy 351.645992 -240.727845) (xy 351.599976 -240.710393)
			(xy 351.557355 -240.685786) (xy 351.519234 -240.654661) (xy 351.486599 -240.617824) (xy 351.460296 -240.576228)
			(xy 351.441005 -240.530952) (xy 351.429228 -240.483168) (xy 351.425268 -240.434114) (xy 351.096326 -240.434114)
			(xy 351.095831 -240.458721) (xy 351.087936 -240.507298) (xy 351.072352 -240.553979) (xy 351.049481 -240.597556)
			(xy 351.019916 -240.6369) (xy 350.984423 -240.670992) (xy 350.94392 -240.698948) (xy 350.899458 -240.720046)
			(xy 350.852187 -240.733738) (xy 350.803332 -240.73967) (xy 350.754157 -240.737689) (xy 350.705938 -240.727845)
			(xy 350.659922 -240.710393) (xy 350.617301 -240.685786) (xy 350.57918 -240.654661) (xy 350.546545 -240.617824)
			(xy 350.520242 -240.576228) (xy 350.500951 -240.530952) (xy 350.489174 -240.483168) (xy 350.485214 -240.434114)
			(xy 350.156526 -240.434114) (xy 350.156031 -240.458721) (xy 350.148136 -240.507298) (xy 350.132552 -240.553979)
			(xy 350.109681 -240.597556) (xy 350.080116 -240.6369) (xy 350.044623 -240.670992) (xy 350.00412 -240.698948)
			(xy 349.959658 -240.720046) (xy 349.912387 -240.733738) (xy 349.863532 -240.73967) (xy 349.814357 -240.737689)
			(xy 349.766138 -240.727845) (xy 349.720122 -240.710393) (xy 349.677501 -240.685786) (xy 349.63938 -240.654661)
			(xy 349.606745 -240.617824) (xy 349.580442 -240.576228) (xy 349.561151 -240.530952) (xy 349.549374 -240.483168)
			(xy 349.545414 -240.434114) (xy 349.216472 -240.434114) (xy 349.215977 -240.458721) (xy 349.208082 -240.507298)
			(xy 349.192498 -240.553979) (xy 349.169627 -240.597556) (xy 349.140062 -240.6369) (xy 349.104569 -240.670992)
			(xy 349.064066 -240.698948) (xy 349.019604 -240.720046) (xy 348.972333 -240.733738) (xy 348.923478 -240.73967)
			(xy 348.874303 -240.737689) (xy 348.826084 -240.727845) (xy 348.780068 -240.710393) (xy 348.737447 -240.685786)
			(xy 348.699326 -240.654661) (xy 348.666691 -240.617824) (xy 348.640388 -240.576228) (xy 348.621097 -240.530952)
			(xy 348.60932 -240.483168) (xy 348.60536 -240.434114) (xy 348.276418 -240.434114) (xy 348.275923 -240.458721)
			(xy 348.268028 -240.507298) (xy 348.252444 -240.553979) (xy 348.229573 -240.597556) (xy 348.200008 -240.6369)
			(xy 348.164515 -240.670992) (xy 348.124012 -240.698948) (xy 348.07955 -240.720046) (xy 348.032279 -240.733738)
			(xy 347.983424 -240.73967) (xy 347.934249 -240.737689) (xy 347.88603 -240.727845) (xy 347.840014 -240.710393)
			(xy 347.797393 -240.685786) (xy 347.759272 -240.654661) (xy 347.726637 -240.617824) (xy 347.700334 -240.576228)
			(xy 347.681043 -240.530952) (xy 347.669266 -240.483168) (xy 347.665306 -240.434114) (xy 347.336364 -240.434114)
			(xy 347.335869 -240.458721) (xy 347.327974 -240.507298) (xy 347.31239 -240.553979) (xy 347.289519 -240.597556)
			(xy 347.259954 -240.6369) (xy 347.224461 -240.670992) (xy 347.183958 -240.698948) (xy 347.139496 -240.720046)
			(xy 347.092225 -240.733738) (xy 347.04337 -240.73967) (xy 346.994195 -240.737689) (xy 346.945976 -240.727845)
			(xy 346.89996 -240.710393) (xy 346.857339 -240.685786) (xy 346.819218 -240.654661) (xy 346.786583 -240.617824)
			(xy 346.76028 -240.576228) (xy 346.740989 -240.530952) (xy 346.729212 -240.483168) (xy 346.725252 -240.434114)
			(xy 346.39631 -240.434114) (xy 346.395815 -240.458721) (xy 346.38792 -240.507298) (xy 346.372336 -240.553979)
			(xy 346.349465 -240.597556) (xy 346.3199 -240.6369) (xy 346.284407 -240.670992) (xy 346.243904 -240.698948)
			(xy 346.199442 -240.720046) (xy 346.152171 -240.733738) (xy 346.103316 -240.73967) (xy 346.054141 -240.737689)
			(xy 346.005922 -240.727845) (xy 345.959906 -240.710393) (xy 345.917285 -240.685786) (xy 345.879164 -240.654661)
			(xy 345.846529 -240.617824) (xy 345.820226 -240.576228) (xy 345.800935 -240.530952) (xy 345.789158 -240.483168)
			(xy 345.785198 -240.434114) (xy 345.457016 -240.434114) (xy 345.452846 -240.484436) (xy 345.440447 -240.533398)
			(xy 345.420158 -240.579652) (xy 345.392533 -240.621936) (xy 345.358325 -240.659096) (xy 345.318467 -240.690119)
			(xy 345.274047 -240.714158) (xy 345.226275 -240.730559) (xy 345.176456 -240.738872) (xy 345.151202 -240.739422)
			(xy 345.130062 -240.73906) (xy 345.088184 -240.733231) (xy 345.047507 -240.721699) (xy 345.028012 -240.713514)
			(xy 345.016118 -240.708998) (xy 344.990787 -240.710993) (xy 344.979752 -240.717324) (xy 344.908378 -240.763806)
			(xy 344.901449 -240.76867) (xy 344.891036 -240.782007) (xy 344.885558 -240.798017) (xy 344.885264 -240.806478)
			(xy 344.885264 -240.985548) (xy 344.885387 -240.990502) (xy 344.887313 -241.00022) (xy 344.889074 -241.004852)
			(xy 344.899488 -241.03076) (xy 344.905838 -241.037364) (xy 344.922535 -241.056306) (xy 344.950116 -241.098597)
			(xy 344.97037 -241.144847) (xy 344.982746 -241.193796) (xy 344.986908 -241.244115) (xy 344.986908 -241.24412)
			(xy 345.315298 -241.24412) (xy 345.319258 -241.195066) (xy 345.331035 -241.147282) (xy 345.350326 -241.102006)
			(xy 345.376629 -241.06041) (xy 345.409264 -241.023573) (xy 345.447385 -240.992448) (xy 345.490006 -240.967841)
			(xy 345.536022 -240.950389) (xy 345.584241 -240.940545) (xy 345.633416 -240.938564) (xy 345.682271 -240.944496)
			(xy 345.729542 -240.958188) (xy 345.774004 -240.979286) (xy 345.814507 -241.007242) (xy 345.85 -241.041334)
			(xy 345.879565 -241.080678) (xy 345.902436 -241.124255) (xy 345.91802 -241.170936) (xy 345.925915 -241.219513)
			(xy 345.92641 -241.24412) (xy 346.255352 -241.24412) (xy 346.259312 -241.195066) (xy 346.271089 -241.147282)
			(xy 346.29038 -241.102006) (xy 346.316683 -241.06041) (xy 346.349318 -241.023573) (xy 346.387439 -240.992448)
			(xy 346.43006 -240.967841) (xy 346.476076 -240.950389) (xy 346.524295 -240.940545) (xy 346.57347 -240.938564)
			(xy 346.622325 -240.944496) (xy 346.669596 -240.958188) (xy 346.714058 -240.979286) (xy 346.754561 -241.007242)
			(xy 346.790054 -241.041334) (xy 346.819619 -241.080678) (xy 346.84249 -241.124255) (xy 346.858074 -241.170936)
			(xy 346.865969 -241.219513) (xy 346.866464 -241.24412) (xy 347.195406 -241.24412) (xy 347.199366 -241.195066)
			(xy 347.211143 -241.147282) (xy 347.230434 -241.102006) (xy 347.256737 -241.06041) (xy 347.289372 -241.023573)
			(xy 347.327493 -240.992448) (xy 347.370114 -240.967841) (xy 347.41613 -240.950389) (xy 347.464349 -240.940545)
			(xy 347.513524 -240.938564) (xy 347.562379 -240.944496) (xy 347.60965 -240.958188) (xy 347.654112 -240.979286)
			(xy 347.694615 -241.007242) (xy 347.730108 -241.041334) (xy 347.759673 -241.080678) (xy 347.782544 -241.124255)
			(xy 347.798128 -241.170936) (xy 347.806023 -241.219513) (xy 347.806518 -241.24412) (xy 348.135206 -241.24412)
			(xy 348.139166 -241.195066) (xy 348.150943 -241.147282) (xy 348.170234 -241.102006) (xy 348.196537 -241.06041)
			(xy 348.229172 -241.023573) (xy 348.267293 -240.992448) (xy 348.309914 -240.967841) (xy 348.35593 -240.950389)
			(xy 348.404149 -240.940545) (xy 348.453324 -240.938564) (xy 348.502179 -240.944496) (xy 348.54945 -240.958188)
			(xy 348.593912 -240.979286) (xy 348.634415 -241.007242) (xy 348.669908 -241.041334) (xy 348.699473 -241.080678)
			(xy 348.722344 -241.124255) (xy 348.737928 -241.170936) (xy 348.745823 -241.219513) (xy 348.746318 -241.24412)
			(xy 349.07526 -241.24412) (xy 349.07922 -241.195066) (xy 349.090997 -241.147282) (xy 349.110288 -241.102006)
			(xy 349.136591 -241.06041) (xy 349.169226 -241.023573) (xy 349.207347 -240.992448) (xy 349.249968 -240.967841)
			(xy 349.295984 -240.950389) (xy 349.344203 -240.940545) (xy 349.393378 -240.938564) (xy 349.442233 -240.944496)
			(xy 349.489504 -240.958188) (xy 349.533966 -240.979286) (xy 349.574469 -241.007242) (xy 349.609962 -241.041334)
			(xy 349.639527 -241.080678) (xy 349.662398 -241.124255) (xy 349.677982 -241.170936) (xy 349.685877 -241.219513)
			(xy 349.686372 -241.24412) (xy 350.015314 -241.24412) (xy 350.019274 -241.195066) (xy 350.031051 -241.147282)
			(xy 350.050342 -241.102006) (xy 350.076645 -241.06041) (xy 350.10928 -241.023573) (xy 350.147401 -240.992448)
			(xy 350.190022 -240.967841) (xy 350.236038 -240.950389) (xy 350.284257 -240.940545) (xy 350.333432 -240.938564)
			(xy 350.382287 -240.944496) (xy 350.429558 -240.958188) (xy 350.47402 -240.979286) (xy 350.514523 -241.007242)
			(xy 350.550016 -241.041334) (xy 350.579581 -241.080678) (xy 350.602452 -241.124255) (xy 350.618036 -241.170936)
			(xy 350.625931 -241.219513) (xy 350.626426 -241.24412) (xy 350.955368 -241.24412) (xy 350.959328 -241.195066)
			(xy 350.971105 -241.147282) (xy 350.990396 -241.102006) (xy 351.016699 -241.06041) (xy 351.049334 -241.023573)
			(xy 351.087455 -240.992448) (xy 351.130076 -240.967841) (xy 351.176092 -240.950389) (xy 351.224311 -240.940545)
			(xy 351.273486 -240.938564) (xy 351.322341 -240.944496) (xy 351.369612 -240.958188) (xy 351.414074 -240.979286)
			(xy 351.454577 -241.007242) (xy 351.49007 -241.041334) (xy 351.519635 -241.080678) (xy 351.542506 -241.124255)
			(xy 351.55809 -241.170936) (xy 351.565985 -241.219513) (xy 351.56648 -241.24412) (xy 351.895422 -241.24412)
			(xy 351.899382 -241.195066) (xy 351.911159 -241.147282) (xy 351.93045 -241.102006) (xy 351.956753 -241.06041)
			(xy 351.989388 -241.023573) (xy 352.027509 -240.992448) (xy 352.07013 -240.967841) (xy 352.116146 -240.950389)
			(xy 352.164365 -240.940545) (xy 352.21354 -240.938564) (xy 352.262395 -240.944496) (xy 352.309666 -240.958188)
			(xy 352.354128 -240.979286) (xy 352.394631 -241.007242) (xy 352.430124 -241.041334) (xy 352.459689 -241.080678)
			(xy 352.48256 -241.124255) (xy 352.498144 -241.170936) (xy 352.506039 -241.219513) (xy 352.506534 -241.24412)
			(xy 352.835222 -241.24412) (xy 352.839182 -241.195066) (xy 352.850959 -241.147282) (xy 352.87025 -241.102006)
			(xy 352.896553 -241.06041) (xy 352.929188 -241.023573) (xy 352.967309 -240.992448) (xy 353.00993 -240.967841)
			(xy 353.055946 -240.950389) (xy 353.104165 -240.940545) (xy 353.15334 -240.938564) (xy 353.202195 -240.944496)
			(xy 353.249466 -240.958188) (xy 353.293928 -240.979286) (xy 353.334431 -241.007242) (xy 353.369924 -241.041334)
			(xy 353.399489 -241.080678) (xy 353.42236 -241.124255) (xy 353.437944 -241.170936) (xy 353.445839 -241.219513)
			(xy 353.446334 -241.24412) (xy 353.775276 -241.24412) (xy 353.779236 -241.195066) (xy 353.791013 -241.147282)
			(xy 353.810304 -241.102006) (xy 353.836607 -241.06041) (xy 353.869242 -241.023573) (xy 353.907363 -240.992448)
			(xy 353.949984 -240.967841) (xy 353.996 -240.950389) (xy 354.044219 -240.940545) (xy 354.093394 -240.938564)
			(xy 354.142249 -240.944496) (xy 354.18952 -240.958188) (xy 354.233982 -240.979286) (xy 354.274485 -241.007242)
			(xy 354.309978 -241.041334) (xy 354.339543 -241.080678) (xy 354.362414 -241.124255) (xy 354.377998 -241.170936)
			(xy 354.385893 -241.219513) (xy 354.386388 -241.24412) (xy 354.71533 -241.24412) (xy 354.71929 -241.195066)
			(xy 354.731067 -241.147282) (xy 354.750358 -241.102006) (xy 354.776661 -241.06041) (xy 354.809296 -241.023573)
			(xy 354.847417 -240.992448) (xy 354.890038 -240.967841) (xy 354.936054 -240.950389) (xy 354.984273 -240.940545)
			(xy 355.033448 -240.938564) (xy 355.082303 -240.944496) (xy 355.129574 -240.958188) (xy 355.174036 -240.979286)
			(xy 355.214539 -241.007242) (xy 355.250032 -241.041334) (xy 355.279597 -241.080678) (xy 355.302468 -241.124255)
			(xy 355.318052 -241.170936) (xy 355.325947 -241.219513) (xy 355.326442 -241.24412) (xy 355.655384 -241.24412)
			(xy 355.659344 -241.195066) (xy 355.671121 -241.147282) (xy 355.690412 -241.102006) (xy 355.716715 -241.06041)
			(xy 355.74935 -241.023573) (xy 355.787471 -240.992448) (xy 355.830092 -240.967841) (xy 355.876108 -240.950389)
			(xy 355.924327 -240.940545) (xy 355.973502 -240.938564) (xy 356.022357 -240.944496) (xy 356.069628 -240.958188)
			(xy 356.11409 -240.979286) (xy 356.154593 -241.007242) (xy 356.190086 -241.041334) (xy 356.219651 -241.080678)
			(xy 356.242522 -241.124255) (xy 356.258106 -241.170936) (xy 356.266001 -241.219513) (xy 356.266496 -241.24412)
			(xy 356.595438 -241.24412) (xy 356.599398 -241.195066) (xy 356.611175 -241.147282) (xy 356.630466 -241.102006)
			(xy 356.656769 -241.06041) (xy 356.689404 -241.023573) (xy 356.727525 -240.992448) (xy 356.770146 -240.967841)
			(xy 356.816162 -240.950389) (xy 356.864381 -240.940545) (xy 356.913556 -240.938564) (xy 356.962411 -240.944496)
			(xy 357.009682 -240.958188) (xy 357.054144 -240.979286) (xy 357.094647 -241.007242) (xy 357.13014 -241.041334)
			(xy 357.159705 -241.080678) (xy 357.182576 -241.124255) (xy 357.19816 -241.170936) (xy 357.206055 -241.219513)
			(xy 357.20655 -241.24412) (xy 357.535238 -241.24412) (xy 357.539198 -241.195066) (xy 357.550975 -241.147282)
			(xy 357.570266 -241.102006) (xy 357.596569 -241.06041) (xy 357.629204 -241.023573) (xy 357.667325 -240.992448)
			(xy 357.709946 -240.967841) (xy 357.755962 -240.950389) (xy 357.804181 -240.940545) (xy 357.853356 -240.938564)
			(xy 357.902211 -240.944496) (xy 357.949482 -240.958188) (xy 357.993944 -240.979286) (xy 358.034447 -241.007242)
			(xy 358.06994 -241.041334) (xy 358.099505 -241.080678) (xy 358.122376 -241.124255) (xy 358.13796 -241.170936)
			(xy 358.145855 -241.219513) (xy 358.14635 -241.24412) (xy 358.145855 -241.268727) (xy 358.13796 -241.317304)
			(xy 358.122376 -241.363985) (xy 358.099505 -241.407562) (xy 358.06994 -241.446906) (xy 358.034447 -241.480998)
			(xy 357.993944 -241.508954) (xy 357.949482 -241.530052) (xy 357.902211 -241.543744) (xy 357.853356 -241.549676)
			(xy 357.804181 -241.547695) (xy 357.755962 -241.537851) (xy 357.709946 -241.520399) (xy 357.667325 -241.495792)
			(xy 357.629204 -241.464667) (xy 357.596569 -241.42783) (xy 357.570266 -241.386234) (xy 357.550975 -241.340958)
			(xy 357.539198 -241.293174) (xy 357.535238 -241.24412) (xy 357.20655 -241.24412) (xy 357.206055 -241.268727)
			(xy 357.19816 -241.317304) (xy 357.182576 -241.363985) (xy 357.159705 -241.407562) (xy 357.13014 -241.446906)
			(xy 357.094647 -241.480998) (xy 357.054144 -241.508954) (xy 357.009682 -241.530052) (xy 356.962411 -241.543744)
			(xy 356.913556 -241.549676) (xy 356.864381 -241.547695) (xy 356.816162 -241.537851) (xy 356.770146 -241.520399)
			(xy 356.727525 -241.495792) (xy 356.689404 -241.464667) (xy 356.656769 -241.42783) (xy 356.630466 -241.386234)
			(xy 356.611175 -241.340958) (xy 356.599398 -241.293174) (xy 356.595438 -241.24412) (xy 356.266496 -241.24412)
			(xy 356.266001 -241.268727) (xy 356.258106 -241.317304) (xy 356.242522 -241.363985) (xy 356.219651 -241.407562)
			(xy 356.190086 -241.446906) (xy 356.154593 -241.480998) (xy 356.11409 -241.508954) (xy 356.069628 -241.530052)
			(xy 356.022357 -241.543744) (xy 355.973502 -241.549676) (xy 355.924327 -241.547695) (xy 355.876108 -241.537851)
			(xy 355.830092 -241.520399) (xy 355.787471 -241.495792) (xy 355.74935 -241.464667) (xy 355.716715 -241.42783)
			(xy 355.690412 -241.386234) (xy 355.671121 -241.340958) (xy 355.659344 -241.293174) (xy 355.655384 -241.24412)
			(xy 355.326442 -241.24412) (xy 355.325947 -241.268727) (xy 355.318052 -241.317304) (xy 355.302468 -241.363985)
			(xy 355.279597 -241.407562) (xy 355.250032 -241.446906) (xy 355.214539 -241.480998) (xy 355.174036 -241.508954)
			(xy 355.129574 -241.530052) (xy 355.082303 -241.543744) (xy 355.033448 -241.549676) (xy 354.984273 -241.547695)
			(xy 354.936054 -241.537851) (xy 354.890038 -241.520399) (xy 354.847417 -241.495792) (xy 354.809296 -241.464667)
			(xy 354.776661 -241.42783) (xy 354.750358 -241.386234) (xy 354.731067 -241.340958) (xy 354.71929 -241.293174)
			(xy 354.71533 -241.24412) (xy 354.386388 -241.24412) (xy 354.385893 -241.268727) (xy 354.377998 -241.317304)
			(xy 354.362414 -241.363985) (xy 354.339543 -241.407562) (xy 354.309978 -241.446906) (xy 354.274485 -241.480998)
			(xy 354.233982 -241.508954) (xy 354.18952 -241.530052) (xy 354.142249 -241.543744) (xy 354.093394 -241.549676)
			(xy 354.044219 -241.547695) (xy 353.996 -241.537851) (xy 353.949984 -241.520399) (xy 353.907363 -241.495792)
			(xy 353.869242 -241.464667) (xy 353.836607 -241.42783) (xy 353.810304 -241.386234) (xy 353.791013 -241.340958)
			(xy 353.779236 -241.293174) (xy 353.775276 -241.24412) (xy 353.446334 -241.24412) (xy 353.445839 -241.268727)
			(xy 353.437944 -241.317304) (xy 353.42236 -241.363985) (xy 353.399489 -241.407562) (xy 353.369924 -241.446906)
			(xy 353.334431 -241.480998) (xy 353.293928 -241.508954) (xy 353.249466 -241.530052) (xy 353.202195 -241.543744)
			(xy 353.15334 -241.549676) (xy 353.104165 -241.547695) (xy 353.055946 -241.537851) (xy 353.00993 -241.520399)
			(xy 352.967309 -241.495792) (xy 352.929188 -241.464667) (xy 352.896553 -241.42783) (xy 352.87025 -241.386234)
			(xy 352.850959 -241.340958) (xy 352.839182 -241.293174) (xy 352.835222 -241.24412) (xy 352.506534 -241.24412)
			(xy 352.506039 -241.268727) (xy 352.498144 -241.317304) (xy 352.48256 -241.363985) (xy 352.459689 -241.407562)
			(xy 352.430124 -241.446906) (xy 352.394631 -241.480998) (xy 352.354128 -241.508954) (xy 352.309666 -241.530052)
			(xy 352.262395 -241.543744) (xy 352.21354 -241.549676) (xy 352.164365 -241.547695) (xy 352.116146 -241.537851)
			(xy 352.07013 -241.520399) (xy 352.027509 -241.495792) (xy 351.989388 -241.464667) (xy 351.956753 -241.42783)
			(xy 351.93045 -241.386234) (xy 351.911159 -241.340958) (xy 351.899382 -241.293174) (xy 351.895422 -241.24412)
			(xy 351.56648 -241.24412) (xy 351.565985 -241.268727) (xy 351.55809 -241.317304) (xy 351.542506 -241.363985)
			(xy 351.519635 -241.407562) (xy 351.49007 -241.446906) (xy 351.454577 -241.480998) (xy 351.414074 -241.508954)
			(xy 351.369612 -241.530052) (xy 351.322341 -241.543744) (xy 351.273486 -241.549676) (xy 351.224311 -241.547695)
			(xy 351.176092 -241.537851) (xy 351.130076 -241.520399) (xy 351.087455 -241.495792) (xy 351.049334 -241.464667)
			(xy 351.016699 -241.42783) (xy 350.990396 -241.386234) (xy 350.971105 -241.340958) (xy 350.959328 -241.293174)
			(xy 350.955368 -241.24412) (xy 350.626426 -241.24412) (xy 350.625931 -241.268727) (xy 350.618036 -241.317304)
			(xy 350.602452 -241.363985) (xy 350.579581 -241.407562) (xy 350.550016 -241.446906) (xy 350.514523 -241.480998)
			(xy 350.47402 -241.508954) (xy 350.429558 -241.530052) (xy 350.382287 -241.543744) (xy 350.333432 -241.549676)
			(xy 350.284257 -241.547695) (xy 350.236038 -241.537851) (xy 350.190022 -241.520399) (xy 350.147401 -241.495792)
			(xy 350.10928 -241.464667) (xy 350.076645 -241.42783) (xy 350.050342 -241.386234) (xy 350.031051 -241.340958)
			(xy 350.019274 -241.293174) (xy 350.015314 -241.24412) (xy 349.686372 -241.24412) (xy 349.685877 -241.268727)
			(xy 349.677982 -241.317304) (xy 349.662398 -241.363985) (xy 349.639527 -241.407562) (xy 349.609962 -241.446906)
			(xy 349.574469 -241.480998) (xy 349.533966 -241.508954) (xy 349.489504 -241.530052) (xy 349.442233 -241.543744)
			(xy 349.393378 -241.549676) (xy 349.344203 -241.547695) (xy 349.295984 -241.537851) (xy 349.249968 -241.520399)
			(xy 349.207347 -241.495792) (xy 349.169226 -241.464667) (xy 349.136591 -241.42783) (xy 349.110288 -241.386234)
			(xy 349.090997 -241.340958) (xy 349.07922 -241.293174) (xy 349.07526 -241.24412) (xy 348.746318 -241.24412)
			(xy 348.745823 -241.268727) (xy 348.737928 -241.317304) (xy 348.722344 -241.363985) (xy 348.699473 -241.407562)
			(xy 348.669908 -241.446906) (xy 348.634415 -241.480998) (xy 348.593912 -241.508954) (xy 348.54945 -241.530052)
			(xy 348.502179 -241.543744) (xy 348.453324 -241.549676) (xy 348.404149 -241.547695) (xy 348.35593 -241.537851)
			(xy 348.309914 -241.520399) (xy 348.267293 -241.495792) (xy 348.229172 -241.464667) (xy 348.196537 -241.42783)
			(xy 348.170234 -241.386234) (xy 348.150943 -241.340958) (xy 348.139166 -241.293174) (xy 348.135206 -241.24412)
			(xy 347.806518 -241.24412) (xy 347.806023 -241.268727) (xy 347.798128 -241.317304) (xy 347.782544 -241.363985)
			(xy 347.759673 -241.407562) (xy 347.730108 -241.446906) (xy 347.694615 -241.480998) (xy 347.654112 -241.508954)
			(xy 347.60965 -241.530052) (xy 347.562379 -241.543744) (xy 347.513524 -241.549676) (xy 347.464349 -241.547695)
			(xy 347.41613 -241.537851) (xy 347.370114 -241.520399) (xy 347.327493 -241.495792) (xy 347.289372 -241.464667)
			(xy 347.256737 -241.42783) (xy 347.230434 -241.386234) (xy 347.211143 -241.340958) (xy 347.199366 -241.293174)
			(xy 347.195406 -241.24412) (xy 346.866464 -241.24412) (xy 346.865969 -241.268727) (xy 346.858074 -241.317304)
			(xy 346.84249 -241.363985) (xy 346.819619 -241.407562) (xy 346.790054 -241.446906) (xy 346.754561 -241.480998)
			(xy 346.714058 -241.508954) (xy 346.669596 -241.530052) (xy 346.622325 -241.543744) (xy 346.57347 -241.549676)
			(xy 346.524295 -241.547695) (xy 346.476076 -241.537851) (xy 346.43006 -241.520399) (xy 346.387439 -241.495792)
			(xy 346.349318 -241.464667) (xy 346.316683 -241.42783) (xy 346.29038 -241.386234) (xy 346.271089 -241.340958)
			(xy 346.259312 -241.293174) (xy 346.255352 -241.24412) (xy 345.92641 -241.24412) (xy 345.925915 -241.268727)
			(xy 345.91802 -241.317304) (xy 345.902436 -241.363985) (xy 345.879565 -241.407562) (xy 345.85 -241.446906)
			(xy 345.814507 -241.480998) (xy 345.774004 -241.508954) (xy 345.729542 -241.530052) (xy 345.682271 -241.543744)
			(xy 345.633416 -241.549676) (xy 345.584241 -241.547695) (xy 345.536022 -241.537851) (xy 345.490006 -241.520399)
			(xy 345.447385 -241.495792) (xy 345.409264 -241.464667) (xy 345.376629 -241.42783) (xy 345.350326 -241.386234)
			(xy 345.331035 -241.340958) (xy 345.319258 -241.293174) (xy 345.315298 -241.24412) (xy 344.986908 -241.24412)
			(xy 344.982742 -241.294433) (xy 344.970361 -241.343381) (xy 344.950102 -241.389629) (xy 344.922516 -241.431917)
			(xy 344.905838 -241.450876) (xy 344.899488 -241.45748) (xy 344.889074 -241.483388) (xy 344.887298 -241.488015)
			(xy 344.885375 -241.497737) (xy 344.885264 -241.502692) (xy 344.885264 -242.054126) (xy 346.725252 -242.054126)
			(xy 346.729212 -242.005072) (xy 346.740989 -241.957288) (xy 346.76028 -241.912012) (xy 346.786583 -241.870416)
			(xy 346.819218 -241.833579) (xy 346.857339 -241.802454) (xy 346.89996 -241.777847) (xy 346.945976 -241.760395)
			(xy 346.994195 -241.750551) (xy 347.04337 -241.74857) (xy 347.092225 -241.754502) (xy 347.139496 -241.768194)
			(xy 347.183958 -241.789292) (xy 347.224461 -241.817248) (xy 347.259954 -241.85134) (xy 347.289519 -241.890684)
			(xy 347.31239 -241.934261) (xy 347.327974 -241.980942) (xy 347.335869 -242.029519) (xy 347.336364 -242.054126)
			(xy 349.545414 -242.054126) (xy 349.549374 -242.005072) (xy 349.561151 -241.957288) (xy 349.580442 -241.912012)
			(xy 349.606745 -241.870416) (xy 349.63938 -241.833579) (xy 349.677501 -241.802454) (xy 349.720122 -241.777847)
			(xy 349.766138 -241.760395) (xy 349.814357 -241.750551) (xy 349.863532 -241.74857) (xy 349.912387 -241.754502)
			(xy 349.959658 -241.768194) (xy 350.00412 -241.789292) (xy 350.044623 -241.817248) (xy 350.080116 -241.85134)
			(xy 350.109681 -241.890684) (xy 350.132552 -241.934261) (xy 350.148136 -241.980942) (xy 350.156031 -242.029519)
			(xy 350.156526 -242.054126) (xy 352.365322 -242.054126) (xy 352.369282 -242.005072) (xy 352.381059 -241.957288)
			(xy 352.40035 -241.912012) (xy 352.426653 -241.870416) (xy 352.459288 -241.833579) (xy 352.497409 -241.802454)
			(xy 352.54003 -241.777847) (xy 352.586046 -241.760395) (xy 352.634265 -241.750551) (xy 352.68344 -241.74857)
			(xy 352.732295 -241.754502) (xy 352.779566 -241.768194) (xy 352.824028 -241.789292) (xy 352.864531 -241.817248)
			(xy 352.900024 -241.85134) (xy 352.929589 -241.890684) (xy 352.95246 -241.934261) (xy 352.968044 -241.980942)
			(xy 352.975939 -242.029519) (xy 352.976434 -242.054126) (xy 355.18523 -242.054126) (xy 355.18919 -242.005072)
			(xy 355.200967 -241.957288) (xy 355.220258 -241.912012) (xy 355.246561 -241.870416) (xy 355.279196 -241.833579)
			(xy 355.317317 -241.802454) (xy 355.359938 -241.777847) (xy 355.405954 -241.760395) (xy 355.454173 -241.750551)
			(xy 355.503348 -241.74857) (xy 355.552203 -241.754502) (xy 355.599474 -241.768194) (xy 355.643936 -241.789292)
			(xy 355.684439 -241.817248) (xy 355.719932 -241.85134) (xy 355.749497 -241.890684) (xy 355.772368 -241.934261)
			(xy 355.787952 -241.980942) (xy 355.795847 -242.029519) (xy 355.796342 -242.054126) (xy 356.125284 -242.054126)
			(xy 356.129244 -242.005072) (xy 356.141021 -241.957288) (xy 356.160312 -241.912012) (xy 356.186615 -241.870416)
			(xy 356.21925 -241.833579) (xy 356.257371 -241.802454) (xy 356.299992 -241.777847) (xy 356.346008 -241.760395)
			(xy 356.394227 -241.750551) (xy 356.443402 -241.74857) (xy 356.492257 -241.754502) (xy 356.539528 -241.768194)
			(xy 356.58399 -241.789292) (xy 356.624493 -241.817248) (xy 356.659986 -241.85134) (xy 356.689551 -241.890684)
			(xy 356.712422 -241.934261) (xy 356.728006 -241.980942) (xy 356.735901 -242.029519) (xy 356.736396 -242.054126)
			(xy 357.065338 -242.054126) (xy 357.069298 -242.005072) (xy 357.081075 -241.957288) (xy 357.100366 -241.912012)
			(xy 357.126669 -241.870416) (xy 357.159304 -241.833579) (xy 357.197425 -241.802454) (xy 357.240046 -241.777847)
			(xy 357.286062 -241.760395) (xy 357.334281 -241.750551) (xy 357.383456 -241.74857) (xy 357.432311 -241.754502)
			(xy 357.479582 -241.768194) (xy 357.524044 -241.789292) (xy 357.564547 -241.817248) (xy 357.60004 -241.85134)
			(xy 357.629605 -241.890684) (xy 357.652476 -241.934261) (xy 357.66806 -241.980942) (xy 357.675955 -242.029519)
			(xy 357.67645 -242.054126) (xy 358.005392 -242.054126) (xy 358.009352 -242.005072) (xy 358.021129 -241.957288)
			(xy 358.04042 -241.912012) (xy 358.066723 -241.870416) (xy 358.099358 -241.833579) (xy 358.137479 -241.802454)
			(xy 358.1801 -241.777847) (xy 358.226116 -241.760395) (xy 358.274335 -241.750551) (xy 358.32351 -241.74857)
			(xy 358.372365 -241.754502) (xy 358.419636 -241.768194) (xy 358.464098 -241.789292) (xy 358.504601 -241.817248)
			(xy 358.540094 -241.85134) (xy 358.569659 -241.890684) (xy 358.59253 -241.934261) (xy 358.608114 -241.980942)
			(xy 358.616009 -242.029519) (xy 358.616504 -242.054126) (xy 358.616009 -242.078733) (xy 358.608114 -242.12731)
			(xy 358.59253 -242.173991) (xy 358.569659 -242.217568) (xy 358.540094 -242.256912) (xy 358.504601 -242.291004)
			(xy 358.464098 -242.31896) (xy 358.419636 -242.340058) (xy 358.372365 -242.35375) (xy 358.32351 -242.359682)
			(xy 358.274335 -242.357701) (xy 358.226116 -242.347857) (xy 358.1801 -242.330405) (xy 358.137479 -242.305798)
			(xy 358.099358 -242.274673) (xy 358.066723 -242.237836) (xy 358.04042 -242.19624) (xy 358.021129 -242.150964)
			(xy 358.009352 -242.10318) (xy 358.005392 -242.054126) (xy 357.67645 -242.054126) (xy 357.675955 -242.078733)
			(xy 357.66806 -242.12731) (xy 357.652476 -242.173991) (xy 357.629605 -242.217568) (xy 357.60004 -242.256912)
			(xy 357.564547 -242.291004) (xy 357.524044 -242.31896) (xy 357.479582 -242.340058) (xy 357.432311 -242.35375)
			(xy 357.383456 -242.359682) (xy 357.334281 -242.357701) (xy 357.286062 -242.347857) (xy 357.240046 -242.330405)
			(xy 357.197425 -242.305798) (xy 357.159304 -242.274673) (xy 357.126669 -242.237836) (xy 357.100366 -242.19624)
			(xy 357.081075 -242.150964) (xy 357.069298 -242.10318) (xy 357.065338 -242.054126) (xy 356.736396 -242.054126)
			(xy 356.735901 -242.078733) (xy 356.728006 -242.12731) (xy 356.712422 -242.173991) (xy 356.689551 -242.217568)
			(xy 356.659986 -242.256912) (xy 356.624493 -242.291004) (xy 356.58399 -242.31896) (xy 356.539528 -242.340058)
			(xy 356.492257 -242.35375) (xy 356.443402 -242.359682) (xy 356.394227 -242.357701) (xy 356.346008 -242.347857)
			(xy 356.299992 -242.330405) (xy 356.257371 -242.305798) (xy 356.21925 -242.274673) (xy 356.186615 -242.237836)
			(xy 356.160312 -242.19624) (xy 356.141021 -242.150964) (xy 356.129244 -242.10318) (xy 356.125284 -242.054126)
			(xy 355.796342 -242.054126) (xy 355.795847 -242.078733) (xy 355.787952 -242.12731) (xy 355.772368 -242.173991)
			(xy 355.749497 -242.217568) (xy 355.719932 -242.256912) (xy 355.684439 -242.291004) (xy 355.643936 -242.31896)
			(xy 355.599474 -242.340058) (xy 355.552203 -242.35375) (xy 355.503348 -242.359682) (xy 355.454173 -242.357701)
			(xy 355.405954 -242.347857) (xy 355.359938 -242.330405) (xy 355.317317 -242.305798) (xy 355.279196 -242.274673)
			(xy 355.246561 -242.237836) (xy 355.220258 -242.19624) (xy 355.200967 -242.150964) (xy 355.18919 -242.10318)
			(xy 355.18523 -242.054126) (xy 352.976434 -242.054126) (xy 352.975939 -242.078733) (xy 352.968044 -242.12731)
			(xy 352.95246 -242.173991) (xy 352.929589 -242.217568) (xy 352.900024 -242.256912) (xy 352.864531 -242.291004)
			(xy 352.824028 -242.31896) (xy 352.779566 -242.340058) (xy 352.732295 -242.35375) (xy 352.68344 -242.359682)
			(xy 352.634265 -242.357701) (xy 352.586046 -242.347857) (xy 352.54003 -242.330405) (xy 352.497409 -242.305798)
			(xy 352.459288 -242.274673) (xy 352.426653 -242.237836) (xy 352.40035 -242.19624) (xy 352.381059 -242.150964)
			(xy 352.369282 -242.10318) (xy 352.365322 -242.054126) (xy 350.156526 -242.054126) (xy 350.156031 -242.078733)
			(xy 350.148136 -242.12731) (xy 350.132552 -242.173991) (xy 350.109681 -242.217568) (xy 350.080116 -242.256912)
			(xy 350.044623 -242.291004) (xy 350.00412 -242.31896) (xy 349.959658 -242.340058) (xy 349.912387 -242.35375)
			(xy 349.863532 -242.359682) (xy 349.814357 -242.357701) (xy 349.766138 -242.347857) (xy 349.720122 -242.330405)
			(xy 349.677501 -242.305798) (xy 349.63938 -242.274673) (xy 349.606745 -242.237836) (xy 349.580442 -242.19624)
			(xy 349.561151 -242.150964) (xy 349.549374 -242.10318) (xy 349.545414 -242.054126) (xy 347.336364 -242.054126)
			(xy 347.335869 -242.078733) (xy 347.327974 -242.12731) (xy 347.31239 -242.173991) (xy 347.289519 -242.217568)
			(xy 347.259954 -242.256912) (xy 347.224461 -242.291004) (xy 347.183958 -242.31896) (xy 347.139496 -242.340058)
			(xy 347.092225 -242.35375) (xy 347.04337 -242.359682) (xy 346.994195 -242.357701) (xy 346.945976 -242.347857)
			(xy 346.89996 -242.330405) (xy 346.857339 -242.305798) (xy 346.819218 -242.274673) (xy 346.786583 -242.237836)
			(xy 346.76028 -242.19624) (xy 346.740989 -242.150964) (xy 346.729212 -242.10318) (xy 346.725252 -242.054126)
			(xy 344.885264 -242.054126) (xy 344.885264 -242.60556) (xy 344.885379 -242.610515) (xy 344.887289 -242.62024)
			(xy 344.889074 -242.624864) (xy 344.899488 -242.650772) (xy 344.905838 -242.657376) (xy 344.922534 -242.676318)
			(xy 344.950113 -242.718609) (xy 344.970365 -242.764858) (xy 344.98274 -242.813806) (xy 344.9869 -242.864124)
			(xy 344.986899 -242.864132) (xy 345.315298 -242.864132) (xy 345.319258 -242.815078) (xy 345.331035 -242.767294)
			(xy 345.350326 -242.722018) (xy 345.376629 -242.680422) (xy 345.409264 -242.643585) (xy 345.447385 -242.61246)
			(xy 345.490006 -242.587853) (xy 345.536022 -242.570401) (xy 345.584241 -242.560557) (xy 345.633416 -242.558576)
			(xy 345.682271 -242.564508) (xy 345.729542 -242.5782) (xy 345.774004 -242.599298) (xy 345.814507 -242.627254)
			(xy 345.85 -242.661346) (xy 345.879565 -242.70069) (xy 345.902436 -242.744267) (xy 345.91802 -242.790948)
			(xy 345.925915 -242.839525) (xy 345.92641 -242.864132) (xy 346.255352 -242.864132) (xy 346.259312 -242.815078)
			(xy 346.271089 -242.767294) (xy 346.29038 -242.722018) (xy 346.316683 -242.680422) (xy 346.349318 -242.643585)
			(xy 346.387439 -242.61246) (xy 346.43006 -242.587853) (xy 346.476076 -242.570401) (xy 346.524295 -242.560557)
			(xy 346.57347 -242.558576) (xy 346.622325 -242.564508) (xy 346.669596 -242.5782) (xy 346.714058 -242.599298)
			(xy 346.754561 -242.627254) (xy 346.790054 -242.661346) (xy 346.819619 -242.70069) (xy 346.84249 -242.744267)
			(xy 346.858074 -242.790948) (xy 346.865969 -242.839525) (xy 346.866464 -242.864132) (xy 347.195406 -242.864132)
			(xy 347.199366 -242.815078) (xy 347.211143 -242.767294) (xy 347.230434 -242.722018) (xy 347.256737 -242.680422)
			(xy 347.289372 -242.643585) (xy 347.327493 -242.61246) (xy 347.370114 -242.587853) (xy 347.41613 -242.570401)
			(xy 347.464349 -242.560557) (xy 347.513524 -242.558576) (xy 347.562379 -242.564508) (xy 347.60965 -242.5782)
			(xy 347.654112 -242.599298) (xy 347.694615 -242.627254) (xy 347.730108 -242.661346) (xy 347.759673 -242.70069)
			(xy 347.782544 -242.744267) (xy 347.798128 -242.790948) (xy 347.806023 -242.839525) (xy 347.806518 -242.864132)
			(xy 348.135206 -242.864132) (xy 348.139166 -242.815078) (xy 348.150943 -242.767294) (xy 348.170234 -242.722018)
			(xy 348.196537 -242.680422) (xy 348.229172 -242.643585) (xy 348.267293 -242.61246) (xy 348.309914 -242.587853)
			(xy 348.35593 -242.570401) (xy 348.404149 -242.560557) (xy 348.453324 -242.558576) (xy 348.502179 -242.564508)
			(xy 348.54945 -242.5782) (xy 348.593912 -242.599298) (xy 348.634415 -242.627254) (xy 348.669908 -242.661346)
			(xy 348.699473 -242.70069) (xy 348.722344 -242.744267) (xy 348.737928 -242.790948) (xy 348.745823 -242.839525)
			(xy 348.746318 -242.864132) (xy 349.07526 -242.864132) (xy 349.07922 -242.815078) (xy 349.090997 -242.767294)
			(xy 349.110288 -242.722018) (xy 349.136591 -242.680422) (xy 349.169226 -242.643585) (xy 349.207347 -242.61246)
			(xy 349.249968 -242.587853) (xy 349.295984 -242.570401) (xy 349.344203 -242.560557) (xy 349.393378 -242.558576)
			(xy 349.442233 -242.564508) (xy 349.489504 -242.5782) (xy 349.533966 -242.599298) (xy 349.574469 -242.627254)
			(xy 349.609962 -242.661346) (xy 349.639527 -242.70069) (xy 349.662398 -242.744267) (xy 349.677982 -242.790948)
			(xy 349.685877 -242.839525) (xy 349.686372 -242.864132) (xy 350.015314 -242.864132) (xy 350.019274 -242.815078)
			(xy 350.031051 -242.767294) (xy 350.050342 -242.722018) (xy 350.076645 -242.680422) (xy 350.10928 -242.643585)
			(xy 350.147401 -242.61246) (xy 350.190022 -242.587853) (xy 350.236038 -242.570401) (xy 350.284257 -242.560557)
			(xy 350.333432 -242.558576) (xy 350.382287 -242.564508) (xy 350.429558 -242.5782) (xy 350.47402 -242.599298)
			(xy 350.514523 -242.627254) (xy 350.550016 -242.661346) (xy 350.579581 -242.70069) (xy 350.602452 -242.744267)
			(xy 350.618036 -242.790948) (xy 350.625931 -242.839525) (xy 350.626426 -242.864132) (xy 350.955368 -242.864132)
			(xy 350.959328 -242.815078) (xy 350.971105 -242.767294) (xy 350.990396 -242.722018) (xy 351.016699 -242.680422)
			(xy 351.049334 -242.643585) (xy 351.087455 -242.61246) (xy 351.130076 -242.587853) (xy 351.176092 -242.570401)
			(xy 351.224311 -242.560557) (xy 351.273486 -242.558576) (xy 351.322341 -242.564508) (xy 351.369612 -242.5782)
			(xy 351.414074 -242.599298) (xy 351.454577 -242.627254) (xy 351.49007 -242.661346) (xy 351.519635 -242.70069)
			(xy 351.542506 -242.744267) (xy 351.55809 -242.790948) (xy 351.565985 -242.839525) (xy 351.56648 -242.864132)
			(xy 351.895422 -242.864132) (xy 351.899382 -242.815078) (xy 351.911159 -242.767294) (xy 351.93045 -242.722018)
			(xy 351.956753 -242.680422) (xy 351.989388 -242.643585) (xy 352.027509 -242.61246) (xy 352.07013 -242.587853)
			(xy 352.116146 -242.570401) (xy 352.164365 -242.560557) (xy 352.21354 -242.558576) (xy 352.262395 -242.564508)
			(xy 352.309666 -242.5782) (xy 352.354128 -242.599298) (xy 352.394631 -242.627254) (xy 352.430124 -242.661346)
			(xy 352.459689 -242.70069) (xy 352.48256 -242.744267) (xy 352.498144 -242.790948) (xy 352.506039 -242.839525)
			(xy 352.506534 -242.864132) (xy 352.835222 -242.864132) (xy 352.839182 -242.815078) (xy 352.850959 -242.767294)
			(xy 352.87025 -242.722018) (xy 352.896553 -242.680422) (xy 352.929188 -242.643585) (xy 352.967309 -242.61246)
			(xy 353.00993 -242.587853) (xy 353.055946 -242.570401) (xy 353.104165 -242.560557) (xy 353.15334 -242.558576)
			(xy 353.202195 -242.564508) (xy 353.249466 -242.5782) (xy 353.293928 -242.599298) (xy 353.334431 -242.627254)
			(xy 353.369924 -242.661346) (xy 353.399489 -242.70069) (xy 353.42236 -242.744267) (xy 353.437944 -242.790948)
			(xy 353.445839 -242.839525) (xy 353.446334 -242.864132) (xy 353.775276 -242.864132) (xy 353.779236 -242.815078)
			(xy 353.791013 -242.767294) (xy 353.810304 -242.722018) (xy 353.836607 -242.680422) (xy 353.869242 -242.643585)
			(xy 353.907363 -242.61246) (xy 353.949984 -242.587853) (xy 353.996 -242.570401) (xy 354.044219 -242.560557)
			(xy 354.093394 -242.558576) (xy 354.142249 -242.564508) (xy 354.18952 -242.5782) (xy 354.233982 -242.599298)
			(xy 354.274485 -242.627254) (xy 354.309978 -242.661346) (xy 354.339543 -242.70069) (xy 354.362414 -242.744267)
			(xy 354.377998 -242.790948) (xy 354.385893 -242.839525) (xy 354.386388 -242.864132) (xy 354.71533 -242.864132)
			(xy 354.71929 -242.815078) (xy 354.731067 -242.767294) (xy 354.750358 -242.722018) (xy 354.776661 -242.680422)
			(xy 354.809296 -242.643585) (xy 354.847417 -242.61246) (xy 354.890038 -242.587853) (xy 354.936054 -242.570401)
			(xy 354.984273 -242.560557) (xy 355.033448 -242.558576) (xy 355.082303 -242.564508) (xy 355.129574 -242.5782)
			(xy 355.174036 -242.599298) (xy 355.214539 -242.627254) (xy 355.250032 -242.661346) (xy 355.279597 -242.70069)
			(xy 355.302468 -242.744267) (xy 355.318052 -242.790948) (xy 355.325947 -242.839525) (xy 355.326442 -242.864132)
			(xy 355.655384 -242.864132) (xy 355.659344 -242.815078) (xy 355.671121 -242.767294) (xy 355.690412 -242.722018)
			(xy 355.716715 -242.680422) (xy 355.74935 -242.643585) (xy 355.787471 -242.61246) (xy 355.830092 -242.587853)
			(xy 355.876108 -242.570401) (xy 355.924327 -242.560557) (xy 355.973502 -242.558576) (xy 356.022357 -242.564508)
			(xy 356.069628 -242.5782) (xy 356.11409 -242.599298) (xy 356.154593 -242.627254) (xy 356.190086 -242.661346)
			(xy 356.219651 -242.70069) (xy 356.242522 -242.744267) (xy 356.258106 -242.790948) (xy 356.266001 -242.839525)
			(xy 356.266496 -242.864132) (xy 356.266001 -242.888739) (xy 356.258106 -242.937316) (xy 356.242522 -242.983997)
			(xy 356.219651 -243.027574) (xy 356.190086 -243.066918) (xy 356.154593 -243.10101) (xy 356.11409 -243.128966)
			(xy 356.069628 -243.150064) (xy 356.022357 -243.163756) (xy 355.973502 -243.169688) (xy 355.924327 -243.167707)
			(xy 355.876108 -243.157863) (xy 355.830092 -243.140411) (xy 355.787471 -243.115804) (xy 355.74935 -243.084679)
			(xy 355.716715 -243.047842) (xy 355.690412 -243.006246) (xy 355.671121 -242.96097) (xy 355.659344 -242.913186)
			(xy 355.655384 -242.864132) (xy 355.326442 -242.864132) (xy 355.325947 -242.888739) (xy 355.318052 -242.937316)
			(xy 355.302468 -242.983997) (xy 355.279597 -243.027574) (xy 355.250032 -243.066918) (xy 355.214539 -243.10101)
			(xy 355.174036 -243.128966) (xy 355.129574 -243.150064) (xy 355.082303 -243.163756) (xy 355.033448 -243.169688)
			(xy 354.984273 -243.167707) (xy 354.936054 -243.157863) (xy 354.890038 -243.140411) (xy 354.847417 -243.115804)
			(xy 354.809296 -243.084679) (xy 354.776661 -243.047842) (xy 354.750358 -243.006246) (xy 354.731067 -242.96097)
			(xy 354.71929 -242.913186) (xy 354.71533 -242.864132) (xy 354.386388 -242.864132) (xy 354.385893 -242.888739)
			(xy 354.377998 -242.937316) (xy 354.362414 -242.983997) (xy 354.339543 -243.027574) (xy 354.309978 -243.066918)
			(xy 354.274485 -243.10101) (xy 354.233982 -243.128966) (xy 354.18952 -243.150064) (xy 354.142249 -243.163756)
			(xy 354.093394 -243.169688) (xy 354.044219 -243.167707) (xy 353.996 -243.157863) (xy 353.949984 -243.140411)
			(xy 353.907363 -243.115804) (xy 353.869242 -243.084679) (xy 353.836607 -243.047842) (xy 353.810304 -243.006246)
			(xy 353.791013 -242.96097) (xy 353.779236 -242.913186) (xy 353.775276 -242.864132) (xy 353.446334 -242.864132)
			(xy 353.445839 -242.888739) (xy 353.437944 -242.937316) (xy 353.42236 -242.983997) (xy 353.399489 -243.027574)
			(xy 353.369924 -243.066918) (xy 353.334431 -243.10101) (xy 353.293928 -243.128966) (xy 353.249466 -243.150064)
			(xy 353.202195 -243.163756) (xy 353.15334 -243.169688) (xy 353.104165 -243.167707) (xy 353.055946 -243.157863)
			(xy 353.00993 -243.140411) (xy 352.967309 -243.115804) (xy 352.929188 -243.084679) (xy 352.896553 -243.047842)
			(xy 352.87025 -243.006246) (xy 352.850959 -242.96097) (xy 352.839182 -242.913186) (xy 352.835222 -242.864132)
			(xy 352.506534 -242.864132) (xy 352.506039 -242.888739) (xy 352.498144 -242.937316) (xy 352.48256 -242.983997)
			(xy 352.459689 -243.027574) (xy 352.430124 -243.066918) (xy 352.394631 -243.10101) (xy 352.354128 -243.128966)
			(xy 352.309666 -243.150064) (xy 352.262395 -243.163756) (xy 352.21354 -243.169688) (xy 352.164365 -243.167707)
			(xy 352.116146 -243.157863) (xy 352.07013 -243.140411) (xy 352.027509 -243.115804) (xy 351.989388 -243.084679)
			(xy 351.956753 -243.047842) (xy 351.93045 -243.006246) (xy 351.911159 -242.96097) (xy 351.899382 -242.913186)
			(xy 351.895422 -242.864132) (xy 351.56648 -242.864132) (xy 351.565985 -242.888739) (xy 351.55809 -242.937316)
			(xy 351.542506 -242.983997) (xy 351.519635 -243.027574) (xy 351.49007 -243.066918) (xy 351.454577 -243.10101)
			(xy 351.414074 -243.128966) (xy 351.369612 -243.150064) (xy 351.322341 -243.163756) (xy 351.273486 -243.169688)
			(xy 351.224311 -243.167707) (xy 351.176092 -243.157863) (xy 351.130076 -243.140411) (xy 351.087455 -243.115804)
			(xy 351.049334 -243.084679) (xy 351.016699 -243.047842) (xy 350.990396 -243.006246) (xy 350.971105 -242.96097)
			(xy 350.959328 -242.913186) (xy 350.955368 -242.864132) (xy 350.626426 -242.864132) (xy 350.625931 -242.888739)
			(xy 350.618036 -242.937316) (xy 350.602452 -242.983997) (xy 350.579581 -243.027574) (xy 350.550016 -243.066918)
			(xy 350.514523 -243.10101) (xy 350.47402 -243.128966) (xy 350.429558 -243.150064) (xy 350.382287 -243.163756)
			(xy 350.333432 -243.169688) (xy 350.284257 -243.167707) (xy 350.236038 -243.157863) (xy 350.190022 -243.140411)
			(xy 350.147401 -243.115804) (xy 350.10928 -243.084679) (xy 350.076645 -243.047842) (xy 350.050342 -243.006246)
			(xy 350.031051 -242.96097) (xy 350.019274 -242.913186) (xy 350.015314 -242.864132) (xy 349.686372 -242.864132)
			(xy 349.685877 -242.888739) (xy 349.677982 -242.937316) (xy 349.662398 -242.983997) (xy 349.639527 -243.027574)
			(xy 349.609962 -243.066918) (xy 349.574469 -243.10101) (xy 349.533966 -243.128966) (xy 349.489504 -243.150064)
			(xy 349.442233 -243.163756) (xy 349.393378 -243.169688) (xy 349.344203 -243.167707) (xy 349.295984 -243.157863)
			(xy 349.249968 -243.140411) (xy 349.207347 -243.115804) (xy 349.169226 -243.084679) (xy 349.136591 -243.047842)
			(xy 349.110288 -243.006246) (xy 349.090997 -242.96097) (xy 349.07922 -242.913186) (xy 349.07526 -242.864132)
			(xy 348.746318 -242.864132) (xy 348.745823 -242.888739) (xy 348.737928 -242.937316) (xy 348.722344 -242.983997)
			(xy 348.699473 -243.027574) (xy 348.669908 -243.066918) (xy 348.634415 -243.10101) (xy 348.593912 -243.128966)
			(xy 348.54945 -243.150064) (xy 348.502179 -243.163756) (xy 348.453324 -243.169688) (xy 348.404149 -243.167707)
			(xy 348.35593 -243.157863) (xy 348.309914 -243.140411) (xy 348.267293 -243.115804) (xy 348.229172 -243.084679)
			(xy 348.196537 -243.047842) (xy 348.170234 -243.006246) (xy 348.150943 -242.96097) (xy 348.139166 -242.913186)
			(xy 348.135206 -242.864132) (xy 347.806518 -242.864132) (xy 347.806023 -242.888739) (xy 347.798128 -242.937316)
			(xy 347.782544 -242.983997) (xy 347.759673 -243.027574) (xy 347.730108 -243.066918) (xy 347.694615 -243.10101)
			(xy 347.654112 -243.128966) (xy 347.60965 -243.150064) (xy 347.562379 -243.163756) (xy 347.513524 -243.169688)
			(xy 347.464349 -243.167707) (xy 347.41613 -243.157863) (xy 347.370114 -243.140411) (xy 347.327493 -243.115804)
			(xy 347.289372 -243.084679) (xy 347.256737 -243.047842) (xy 347.230434 -243.006246) (xy 347.211143 -242.96097)
			(xy 347.199366 -242.913186) (xy 347.195406 -242.864132) (xy 346.866464 -242.864132) (xy 346.865969 -242.888739)
			(xy 346.858074 -242.937316) (xy 346.84249 -242.983997) (xy 346.819619 -243.027574) (xy 346.790054 -243.066918)
			(xy 346.754561 -243.10101) (xy 346.714058 -243.128966) (xy 346.669596 -243.150064) (xy 346.622325 -243.163756)
			(xy 346.57347 -243.169688) (xy 346.524295 -243.167707) (xy 346.476076 -243.157863) (xy 346.43006 -243.140411)
			(xy 346.387439 -243.115804) (xy 346.349318 -243.084679) (xy 346.316683 -243.047842) (xy 346.29038 -243.006246)
			(xy 346.271089 -242.96097) (xy 346.259312 -242.913186) (xy 346.255352 -242.864132) (xy 345.92641 -242.864132)
			(xy 345.925915 -242.888739) (xy 345.91802 -242.937316) (xy 345.902436 -242.983997) (xy 345.879565 -243.027574)
			(xy 345.85 -243.066918) (xy 345.814507 -243.10101) (xy 345.774004 -243.128966) (xy 345.729542 -243.150064)
			(xy 345.682271 -243.163756) (xy 345.633416 -243.169688) (xy 345.584241 -243.167707) (xy 345.536022 -243.157863)
			(xy 345.490006 -243.140411) (xy 345.447385 -243.115804) (xy 345.409264 -243.084679) (xy 345.376629 -243.047842)
			(xy 345.350326 -243.006246) (xy 345.331035 -242.96097) (xy 345.319258 -242.913186) (xy 345.315298 -242.864132)
			(xy 344.986899 -242.864132) (xy 344.982732 -242.91444) (xy 344.97035 -242.963387) (xy 344.95009 -243.009633)
			(xy 344.922505 -243.051919) (xy 344.905838 -243.070888) (xy 344.899488 -243.077492) (xy 344.889074 -243.1034)
			(xy 344.887299 -243.108028) (xy 344.885379 -243.117749) (xy 344.885264 -243.122704) (xy 344.885264 -243.301774)
			(xy 344.885967 -243.314505) (xy 344.898104 -243.336892) (xy 344.908378 -243.344446) (xy 344.979752 -243.390928)
			(xy 344.986995 -243.395267) (xy 345.003368 -243.399357) (xy 345.02018 -243.397893) (xy 345.028012 -243.394738)
			(xy 345.0475 -243.386531) (xy 345.088175 -243.374975) (xy 345.130059 -243.369161) (xy 345.151202 -243.36883)
			(xy 345.156028 -243.36883) (xy 345.17977 -243.369657) (xy 345.226579 -243.377756) (xy 345.271568 -243.393007)
			(xy 345.313653 -243.415043) (xy 345.351816 -243.44333) (xy 345.385138 -243.477187) (xy 345.412814 -243.515797)
			(xy 345.434175 -243.558227) (xy 345.448707 -243.603454) (xy 345.456059 -243.650386) (xy 345.45651 -243.674138)
			(xy 345.785198 -243.674138) (xy 345.789158 -243.625084) (xy 345.800935 -243.5773) (xy 345.820226 -243.532024)
			(xy 345.846529 -243.490428) (xy 345.879164 -243.453591) (xy 345.917285 -243.422466) (xy 345.959906 -243.397859)
			(xy 346.005922 -243.380407) (xy 346.054141 -243.370563) (xy 346.103316 -243.368582) (xy 346.152171 -243.374514)
			(xy 346.199442 -243.388206) (xy 346.243904 -243.409304) (xy 346.284407 -243.43726) (xy 346.3199 -243.471352)
			(xy 346.349465 -243.510696) (xy 346.372336 -243.554273) (xy 346.38792 -243.600954) (xy 346.395815 -243.649531)
			(xy 346.39631 -243.674138) (xy 346.725252 -243.674138) (xy 346.729212 -243.625084) (xy 346.740989 -243.5773)
			(xy 346.76028 -243.532024) (xy 346.786583 -243.490428) (xy 346.819218 -243.453591) (xy 346.857339 -243.422466)
			(xy 346.89996 -243.397859) (xy 346.945976 -243.380407) (xy 346.994195 -243.370563) (xy 347.04337 -243.368582)
			(xy 347.092225 -243.374514) (xy 347.139496 -243.388206) (xy 347.183958 -243.409304) (xy 347.224461 -243.43726)
			(xy 347.259954 -243.471352) (xy 347.289519 -243.510696) (xy 347.31239 -243.554273) (xy 347.327974 -243.600954)
			(xy 347.335869 -243.649531) (xy 347.336364 -243.674138) (xy 347.665306 -243.674138) (xy 347.669266 -243.625084)
			(xy 347.681043 -243.5773) (xy 347.700334 -243.532024) (xy 347.726637 -243.490428) (xy 347.759272 -243.453591)
			(xy 347.797393 -243.422466) (xy 347.840014 -243.397859) (xy 347.88603 -243.380407) (xy 347.934249 -243.370563)
			(xy 347.983424 -243.368582) (xy 348.032279 -243.374514) (xy 348.07955 -243.388206) (xy 348.124012 -243.409304)
			(xy 348.164515 -243.43726) (xy 348.200008 -243.471352) (xy 348.229573 -243.510696) (xy 348.252444 -243.554273)
			(xy 348.268028 -243.600954) (xy 348.275923 -243.649531) (xy 348.276418 -243.674138) (xy 348.60536 -243.674138)
			(xy 348.60932 -243.625084) (xy 348.621097 -243.5773) (xy 348.640388 -243.532024) (xy 348.666691 -243.490428)
			(xy 348.699326 -243.453591) (xy 348.737447 -243.422466) (xy 348.780068 -243.397859) (xy 348.826084 -243.380407)
			(xy 348.874303 -243.370563) (xy 348.923478 -243.368582) (xy 348.972333 -243.374514) (xy 349.019604 -243.388206)
			(xy 349.064066 -243.409304) (xy 349.104569 -243.43726) (xy 349.140062 -243.471352) (xy 349.169627 -243.510696)
			(xy 349.192498 -243.554273) (xy 349.208082 -243.600954) (xy 349.215977 -243.649531) (xy 349.216472 -243.674138)
			(xy 349.545414 -243.674138) (xy 349.549374 -243.625084) (xy 349.561151 -243.5773) (xy 349.580442 -243.532024)
			(xy 349.606745 -243.490428) (xy 349.63938 -243.453591) (xy 349.677501 -243.422466) (xy 349.720122 -243.397859)
			(xy 349.766138 -243.380407) (xy 349.814357 -243.370563) (xy 349.863532 -243.368582) (xy 349.912387 -243.374514)
			(xy 349.959658 -243.388206) (xy 350.00412 -243.409304) (xy 350.044623 -243.43726) (xy 350.080116 -243.471352)
			(xy 350.109681 -243.510696) (xy 350.132552 -243.554273) (xy 350.148136 -243.600954) (xy 350.156031 -243.649531)
			(xy 350.156526 -243.674138) (xy 350.485214 -243.674138) (xy 350.489174 -243.625084) (xy 350.500951 -243.5773)
			(xy 350.520242 -243.532024) (xy 350.546545 -243.490428) (xy 350.57918 -243.453591) (xy 350.617301 -243.422466)
			(xy 350.659922 -243.397859) (xy 350.705938 -243.380407) (xy 350.754157 -243.370563) (xy 350.803332 -243.368582)
			(xy 350.852187 -243.374514) (xy 350.899458 -243.388206) (xy 350.94392 -243.409304) (xy 350.984423 -243.43726)
			(xy 351.019916 -243.471352) (xy 351.049481 -243.510696) (xy 351.072352 -243.554273) (xy 351.087936 -243.600954)
			(xy 351.095831 -243.649531) (xy 351.096326 -243.674138) (xy 351.425268 -243.674138) (xy 351.429228 -243.625084)
			(xy 351.441005 -243.5773) (xy 351.460296 -243.532024) (xy 351.486599 -243.490428) (xy 351.519234 -243.453591)
			(xy 351.557355 -243.422466) (xy 351.599976 -243.397859) (xy 351.645992 -243.380407) (xy 351.694211 -243.370563)
			(xy 351.743386 -243.368582) (xy 351.792241 -243.374514) (xy 351.839512 -243.388206) (xy 351.883974 -243.409304)
			(xy 351.924477 -243.43726) (xy 351.95997 -243.471352) (xy 351.989535 -243.510696) (xy 352.012406 -243.554273)
			(xy 352.02799 -243.600954) (xy 352.035885 -243.649531) (xy 352.03638 -243.674138) (xy 352.365322 -243.674138)
			(xy 352.369282 -243.625084) (xy 352.381059 -243.5773) (xy 352.40035 -243.532024) (xy 352.426653 -243.490428)
			(xy 352.459288 -243.453591) (xy 352.497409 -243.422466) (xy 352.54003 -243.397859) (xy 352.586046 -243.380407)
			(xy 352.634265 -243.370563) (xy 352.68344 -243.368582) (xy 352.732295 -243.374514) (xy 352.779566 -243.388206)
			(xy 352.824028 -243.409304) (xy 352.864531 -243.43726) (xy 352.900024 -243.471352) (xy 352.929589 -243.510696)
			(xy 352.95246 -243.554273) (xy 352.968044 -243.600954) (xy 352.975939 -243.649531) (xy 352.976434 -243.674138)
			(xy 353.305376 -243.674138) (xy 353.309336 -243.625084) (xy 353.321113 -243.5773) (xy 353.340404 -243.532024)
			(xy 353.366707 -243.490428) (xy 353.399342 -243.453591) (xy 353.437463 -243.422466) (xy 353.480084 -243.397859)
			(xy 353.5261 -243.380407) (xy 353.574319 -243.370563) (xy 353.623494 -243.368582) (xy 353.672349 -243.374514)
			(xy 353.71962 -243.388206) (xy 353.764082 -243.409304) (xy 353.804585 -243.43726) (xy 353.840078 -243.471352)
			(xy 353.869643 -243.510696) (xy 353.892514 -243.554273) (xy 353.908098 -243.600954) (xy 353.915993 -243.649531)
			(xy 353.916488 -243.674138) (xy 354.24543 -243.674138) (xy 354.24939 -243.625084) (xy 354.261167 -243.5773)
			(xy 354.280458 -243.532024) (xy 354.306761 -243.490428) (xy 354.339396 -243.453591) (xy 354.377517 -243.422466)
			(xy 354.420138 -243.397859) (xy 354.466154 -243.380407) (xy 354.514373 -243.370563) (xy 354.563548 -243.368582)
			(xy 354.612403 -243.374514) (xy 354.659674 -243.388206) (xy 354.704136 -243.409304) (xy 354.744639 -243.43726)
			(xy 354.780132 -243.471352) (xy 354.809697 -243.510696) (xy 354.832568 -243.554273) (xy 354.848152 -243.600954)
			(xy 354.856047 -243.649531) (xy 354.856542 -243.674138) (xy 355.18523 -243.674138) (xy 355.18919 -243.625084)
			(xy 355.200967 -243.5773) (xy 355.220258 -243.532024) (xy 355.246561 -243.490428) (xy 355.279196 -243.453591)
			(xy 355.317317 -243.422466) (xy 355.359938 -243.397859) (xy 355.405954 -243.380407) (xy 355.454173 -243.370563)
			(xy 355.503348 -243.368582) (xy 355.552203 -243.374514) (xy 355.599474 -243.388206) (xy 355.643936 -243.409304)
			(xy 355.684439 -243.43726) (xy 355.719932 -243.471352) (xy 355.749497 -243.510696) (xy 355.772368 -243.554273)
			(xy 355.787952 -243.600954) (xy 355.795847 -243.649531) (xy 355.796342 -243.674138) (xy 356.125284 -243.674138)
			(xy 356.129244 -243.625084) (xy 356.141021 -243.5773) (xy 356.160312 -243.532024) (xy 356.186615 -243.490428)
			(xy 356.21925 -243.453591) (xy 356.257371 -243.422466) (xy 356.299992 -243.397859) (xy 356.346008 -243.380407)
			(xy 356.394227 -243.370563) (xy 356.443402 -243.368582) (xy 356.492257 -243.374514) (xy 356.539528 -243.388206)
			(xy 356.58399 -243.409304) (xy 356.624493 -243.43726) (xy 356.659986 -243.471352) (xy 356.689551 -243.510696)
			(xy 356.712422 -243.554273) (xy 356.728006 -243.600954) (xy 356.735901 -243.649531) (xy 356.736396 -243.674138)
			(xy 357.065338 -243.674138) (xy 357.069298 -243.625084) (xy 357.081075 -243.5773) (xy 357.100366 -243.532024)
			(xy 357.126669 -243.490428) (xy 357.159304 -243.453591) (xy 357.197425 -243.422466) (xy 357.240046 -243.397859)
			(xy 357.286062 -243.380407) (xy 357.334281 -243.370563) (xy 357.383456 -243.368582) (xy 357.432311 -243.374514)
			(xy 357.479582 -243.388206) (xy 357.524044 -243.409304) (xy 357.564547 -243.43726) (xy 357.60004 -243.471352)
			(xy 357.629605 -243.510696) (xy 357.652476 -243.554273) (xy 357.66806 -243.600954) (xy 357.675955 -243.649531)
			(xy 357.67645 -243.674138) (xy 358.005392 -243.674138) (xy 358.009352 -243.625084) (xy 358.021129 -243.5773)
			(xy 358.04042 -243.532024) (xy 358.066723 -243.490428) (xy 358.099358 -243.453591) (xy 358.137479 -243.422466)
			(xy 358.1801 -243.397859) (xy 358.226116 -243.380407) (xy 358.274335 -243.370563) (xy 358.32351 -243.368582)
			(xy 358.372365 -243.374514) (xy 358.419636 -243.388206) (xy 358.464098 -243.409304) (xy 358.504601 -243.43726)
			(xy 358.540094 -243.471352) (xy 358.569659 -243.510696) (xy 358.59253 -243.554273) (xy 358.608114 -243.600954)
			(xy 358.616009 -243.649531) (xy 358.616504 -243.674138) (xy 360.81895 -243.674138) (xy 360.82291 -243.625084)
			(xy 360.834687 -243.5773) (xy 360.853978 -243.532024) (xy 360.880281 -243.490428) (xy 360.912916 -243.453591)
			(xy 360.951037 -243.422466) (xy 360.993658 -243.397859) (xy 361.039674 -243.380407) (xy 361.087893 -243.370563)
			(xy 361.137068 -243.368582) (xy 361.185923 -243.374514) (xy 361.233194 -243.388206) (xy 361.277656 -243.409304)
			(xy 361.318159 -243.43726) (xy 361.353652 -243.471352) (xy 361.383217 -243.510696) (xy 361.406088 -243.554273)
			(xy 361.421672 -243.600954) (xy 361.429567 -243.649531) (xy 361.430061 -243.6741) (xy 361.758723 -243.6741)
			(xy 361.762898 -243.623721) (xy 361.775308 -243.574716) (xy 361.795615 -243.528421) (xy 361.823265 -243.486101)
			(xy 361.857503 -243.448909) (xy 361.897396 -243.41786) (xy 361.941856 -243.393801) (xy 361.989669 -243.377388)
			(xy 362.039532 -243.369068) (xy 362.064808 -243.368576) (xy 363.004862 -243.368576) (xy 363.030146 -243.36899)
			(xy 363.080025 -243.377308) (xy 363.127854 -243.393722) (xy 363.172329 -243.417786) (xy 363.212237 -243.448843)
			(xy 363.246487 -243.486045) (xy 363.274147 -243.528377) (xy 363.294462 -243.574685) (xy 363.306876 -243.623705)
			(xy 363.311053 -243.6741) (xy 363.306876 -243.724495) (xy 363.294462 -243.773515) (xy 363.274147 -243.819823)
			(xy 363.246487 -243.862155) (xy 363.212237 -243.899357) (xy 363.172329 -243.930414) (xy 363.127854 -243.954478)
			(xy 363.080025 -243.970892) (xy 363.030146 -243.97921) (xy 363.004862 -243.9797) (xy 362.064808 -243.9797)
			(xy 362.039532 -243.979132) (xy 361.989669 -243.970812) (xy 361.941856 -243.954399) (xy 361.897396 -243.93034)
			(xy 361.857503 -243.899291) (xy 361.823265 -243.862099) (xy 361.795615 -243.819779) (xy 361.775308 -243.773484)
			(xy 361.762898 -243.724479) (xy 361.758723 -243.6741) (xy 361.430061 -243.6741) (xy 361.430062 -243.674138)
			(xy 361.429567 -243.698745) (xy 361.421672 -243.747322) (xy 361.406088 -243.794003) (xy 361.383217 -243.83758)
			(xy 361.353652 -243.876924) (xy 361.318159 -243.911016) (xy 361.277656 -243.938972) (xy 361.233194 -243.96007)
			(xy 361.185923 -243.973762) (xy 361.137068 -243.979694) (xy 361.087893 -243.977713) (xy 361.039674 -243.967869)
			(xy 360.993658 -243.950417) (xy 360.951037 -243.92581) (xy 360.912916 -243.894685) (xy 360.880281 -243.857848)
			(xy 360.853978 -243.816252) (xy 360.834687 -243.770976) (xy 360.82291 -243.723192) (xy 360.81895 -243.674138)
			(xy 358.616504 -243.674138) (xy 358.616009 -243.698745) (xy 358.608114 -243.747322) (xy 358.59253 -243.794003)
			(xy 358.569659 -243.83758) (xy 358.540094 -243.876924) (xy 358.504601 -243.911016) (xy 358.464098 -243.938972)
			(xy 358.419636 -243.96007) (xy 358.372365 -243.973762) (xy 358.32351 -243.979694) (xy 358.274335 -243.977713)
			(xy 358.226116 -243.967869) (xy 358.1801 -243.950417) (xy 358.137479 -243.92581) (xy 358.099358 -243.894685)
			(xy 358.066723 -243.857848) (xy 358.04042 -243.816252) (xy 358.021129 -243.770976) (xy 358.009352 -243.723192)
			(xy 358.005392 -243.674138) (xy 357.67645 -243.674138) (xy 357.675955 -243.698745) (xy 357.66806 -243.747322)
			(xy 357.652476 -243.794003) (xy 357.629605 -243.83758) (xy 357.60004 -243.876924) (xy 357.564547 -243.911016)
			(xy 357.524044 -243.938972) (xy 357.479582 -243.96007) (xy 357.432311 -243.973762) (xy 357.383456 -243.979694)
			(xy 357.334281 -243.977713) (xy 357.286062 -243.967869) (xy 357.240046 -243.950417) (xy 357.197425 -243.92581)
			(xy 357.159304 -243.894685) (xy 357.126669 -243.857848) (xy 357.100366 -243.816252) (xy 357.081075 -243.770976)
			(xy 357.069298 -243.723192) (xy 357.065338 -243.674138) (xy 356.736396 -243.674138) (xy 356.735901 -243.698745)
			(xy 356.728006 -243.747322) (xy 356.712422 -243.794003) (xy 356.689551 -243.83758) (xy 356.659986 -243.876924)
			(xy 356.624493 -243.911016) (xy 356.58399 -243.938972) (xy 356.539528 -243.96007) (xy 356.492257 -243.973762)
			(xy 356.443402 -243.979694) (xy 356.394227 -243.977713) (xy 356.346008 -243.967869) (xy 356.299992 -243.950417)
			(xy 356.257371 -243.92581) (xy 356.21925 -243.894685) (xy 356.186615 -243.857848) (xy 356.160312 -243.816252)
			(xy 356.141021 -243.770976) (xy 356.129244 -243.723192) (xy 356.125284 -243.674138) (xy 355.796342 -243.674138)
			(xy 355.795847 -243.698745) (xy 355.787952 -243.747322) (xy 355.772368 -243.794003) (xy 355.749497 -243.83758)
			(xy 355.719932 -243.876924) (xy 355.684439 -243.911016) (xy 355.643936 -243.938972) (xy 355.599474 -243.96007)
			(xy 355.552203 -243.973762) (xy 355.503348 -243.979694) (xy 355.454173 -243.977713) (xy 355.405954 -243.967869)
			(xy 355.359938 -243.950417) (xy 355.317317 -243.92581) (xy 355.279196 -243.894685) (xy 355.246561 -243.857848)
			(xy 355.220258 -243.816252) (xy 355.200967 -243.770976) (xy 355.18919 -243.723192) (xy 355.18523 -243.674138)
			(xy 354.856542 -243.674138) (xy 354.856047 -243.698745) (xy 354.848152 -243.747322) (xy 354.832568 -243.794003)
			(xy 354.809697 -243.83758) (xy 354.780132 -243.876924) (xy 354.744639 -243.911016) (xy 354.704136 -243.938972)
			(xy 354.659674 -243.96007) (xy 354.612403 -243.973762) (xy 354.563548 -243.979694) (xy 354.514373 -243.977713)
			(xy 354.466154 -243.967869) (xy 354.420138 -243.950417) (xy 354.377517 -243.92581) (xy 354.339396 -243.894685)
			(xy 354.306761 -243.857848) (xy 354.280458 -243.816252) (xy 354.261167 -243.770976) (xy 354.24939 -243.723192)
			(xy 354.24543 -243.674138) (xy 353.916488 -243.674138) (xy 353.915993 -243.698745) (xy 353.908098 -243.747322)
			(xy 353.892514 -243.794003) (xy 353.869643 -243.83758) (xy 353.840078 -243.876924) (xy 353.804585 -243.911016)
			(xy 353.764082 -243.938972) (xy 353.71962 -243.96007) (xy 353.672349 -243.973762) (xy 353.623494 -243.979694)
			(xy 353.574319 -243.977713) (xy 353.5261 -243.967869) (xy 353.480084 -243.950417) (xy 353.437463 -243.92581)
			(xy 353.399342 -243.894685) (xy 353.366707 -243.857848) (xy 353.340404 -243.816252) (xy 353.321113 -243.770976)
			(xy 353.309336 -243.723192) (xy 353.305376 -243.674138) (xy 352.976434 -243.674138) (xy 352.975939 -243.698745)
			(xy 352.968044 -243.747322) (xy 352.95246 -243.794003) (xy 352.929589 -243.83758) (xy 352.900024 -243.876924)
			(xy 352.864531 -243.911016) (xy 352.824028 -243.938972) (xy 352.779566 -243.96007) (xy 352.732295 -243.973762)
			(xy 352.68344 -243.979694) (xy 352.634265 -243.977713) (xy 352.586046 -243.967869) (xy 352.54003 -243.950417)
			(xy 352.497409 -243.92581) (xy 352.459288 -243.894685) (xy 352.426653 -243.857848) (xy 352.40035 -243.816252)
			(xy 352.381059 -243.770976) (xy 352.369282 -243.723192) (xy 352.365322 -243.674138) (xy 352.03638 -243.674138)
			(xy 352.035885 -243.698745) (xy 352.02799 -243.747322) (xy 352.012406 -243.794003) (xy 351.989535 -243.83758)
			(xy 351.95997 -243.876924) (xy 351.924477 -243.911016) (xy 351.883974 -243.938972) (xy 351.839512 -243.96007)
			(xy 351.792241 -243.973762) (xy 351.743386 -243.979694) (xy 351.694211 -243.977713) (xy 351.645992 -243.967869)
			(xy 351.599976 -243.950417) (xy 351.557355 -243.92581) (xy 351.519234 -243.894685) (xy 351.486599 -243.857848)
			(xy 351.460296 -243.816252) (xy 351.441005 -243.770976) (xy 351.429228 -243.723192) (xy 351.425268 -243.674138)
			(xy 351.096326 -243.674138) (xy 351.095831 -243.698745) (xy 351.087936 -243.747322) (xy 351.072352 -243.794003)
			(xy 351.049481 -243.83758) (xy 351.019916 -243.876924) (xy 350.984423 -243.911016) (xy 350.94392 -243.938972)
			(xy 350.899458 -243.96007) (xy 350.852187 -243.973762) (xy 350.803332 -243.979694) (xy 350.754157 -243.977713)
			(xy 350.705938 -243.967869) (xy 350.659922 -243.950417) (xy 350.617301 -243.92581) (xy 350.57918 -243.894685)
			(xy 350.546545 -243.857848) (xy 350.520242 -243.816252) (xy 350.500951 -243.770976) (xy 350.489174 -243.723192)
			(xy 350.485214 -243.674138) (xy 350.156526 -243.674138) (xy 350.156031 -243.698745) (xy 350.148136 -243.747322)
			(xy 350.132552 -243.794003) (xy 350.109681 -243.83758) (xy 350.080116 -243.876924) (xy 350.044623 -243.911016)
			(xy 350.00412 -243.938972) (xy 349.959658 -243.96007) (xy 349.912387 -243.973762) (xy 349.863532 -243.979694)
			(xy 349.814357 -243.977713) (xy 349.766138 -243.967869) (xy 349.720122 -243.950417) (xy 349.677501 -243.92581)
			(xy 349.63938 -243.894685) (xy 349.606745 -243.857848) (xy 349.580442 -243.816252) (xy 349.561151 -243.770976)
			(xy 349.549374 -243.723192) (xy 349.545414 -243.674138) (xy 349.216472 -243.674138) (xy 349.215977 -243.698745)
			(xy 349.208082 -243.747322) (xy 349.192498 -243.794003) (xy 349.169627 -243.83758) (xy 349.140062 -243.876924)
			(xy 349.104569 -243.911016) (xy 349.064066 -243.938972) (xy 349.019604 -243.96007) (xy 348.972333 -243.973762)
			(xy 348.923478 -243.979694) (xy 348.874303 -243.977713) (xy 348.826084 -243.967869) (xy 348.780068 -243.950417)
			(xy 348.737447 -243.92581) (xy 348.699326 -243.894685) (xy 348.666691 -243.857848) (xy 348.640388 -243.816252)
			(xy 348.621097 -243.770976) (xy 348.60932 -243.723192) (xy 348.60536 -243.674138) (xy 348.276418 -243.674138)
			(xy 348.275923 -243.698745) (xy 348.268028 -243.747322) (xy 348.252444 -243.794003) (xy 348.229573 -243.83758)
			(xy 348.200008 -243.876924) (xy 348.164515 -243.911016) (xy 348.124012 -243.938972) (xy 348.07955 -243.96007)
			(xy 348.032279 -243.973762) (xy 347.983424 -243.979694) (xy 347.934249 -243.977713) (xy 347.88603 -243.967869)
			(xy 347.840014 -243.950417) (xy 347.797393 -243.92581) (xy 347.759272 -243.894685) (xy 347.726637 -243.857848)
			(xy 347.700334 -243.816252) (xy 347.681043 -243.770976) (xy 347.669266 -243.723192) (xy 347.665306 -243.674138)
			(xy 347.336364 -243.674138) (xy 347.335869 -243.698745) (xy 347.327974 -243.747322) (xy 347.31239 -243.794003)
			(xy 347.289519 -243.83758) (xy 347.259954 -243.876924) (xy 347.224461 -243.911016) (xy 347.183958 -243.938972)
			(xy 347.139496 -243.96007) (xy 347.092225 -243.973762) (xy 347.04337 -243.979694) (xy 346.994195 -243.977713)
			(xy 346.945976 -243.967869) (xy 346.89996 -243.950417) (xy 346.857339 -243.92581) (xy 346.819218 -243.894685)
			(xy 346.786583 -243.857848) (xy 346.76028 -243.816252) (xy 346.740989 -243.770976) (xy 346.729212 -243.723192)
			(xy 346.725252 -243.674138) (xy 346.39631 -243.674138) (xy 346.395815 -243.698745) (xy 346.38792 -243.747322)
			(xy 346.372336 -243.794003) (xy 346.349465 -243.83758) (xy 346.3199 -243.876924) (xy 346.284407 -243.911016)
			(xy 346.243904 -243.938972) (xy 346.199442 -243.96007) (xy 346.152171 -243.973762) (xy 346.103316 -243.979694)
			(xy 346.054141 -243.977713) (xy 346.005922 -243.967869) (xy 345.959906 -243.950417) (xy 345.917285 -243.92581)
			(xy 345.879164 -243.894685) (xy 345.846529 -243.857848) (xy 345.820226 -243.816252) (xy 345.800935 -243.770976)
			(xy 345.789158 -243.723192) (xy 345.785198 -243.674138) (xy 345.45651 -243.674138) (xy 345.456037 -243.698127)
			(xy 345.448526 -243.745515) (xy 345.433695 -243.791144) (xy 345.411909 -243.833891) (xy 345.383705 -243.872705)
			(xy 345.349777 -243.906629) (xy 345.31096 -243.934828) (xy 345.26821 -243.956609) (xy 345.222579 -243.971434)
			(xy 345.175191 -243.978939) (xy 345.151202 -243.979446) (xy 345.130062 -243.979084) (xy 345.088184 -243.973256)
			(xy 345.047506 -243.961724) (xy 345.028012 -243.953538) (xy 345.016117 -243.949026) (xy 344.990787 -243.951019)
			(xy 344.979752 -243.957348) (xy 344.908378 -244.00383) (xy 344.901451 -244.008695) (xy 344.891045 -244.022033)
			(xy 344.885575 -244.038042) (xy 344.885264 -244.046502) (xy 344.885264 -244.126258) (xy 344.885264 -244.126512)
			(xy 344.885145 -244.131466) (xy 344.883226 -244.141188) (xy 344.881454 -244.145816) (xy 344.870532 -244.171216)
			(xy 344.870532 -244.221254) (xy 344.870668 -244.226552) (xy 344.872839 -244.236925) (xy 344.87485 -244.241828)
			(xy 344.879168 -244.251734) (xy 344.887042 -244.258846) (xy 344.905421 -244.276328) (xy 344.936686 -244.316266)
			(xy 344.960926 -244.360819) (xy 344.977474 -244.408764) (xy 344.985877 -244.458784) (xy 344.986356 -244.484144)
			(xy 345.315298 -244.484144) (xy 345.319258 -244.43509) (xy 345.331035 -244.387306) (xy 345.350326 -244.34203)
			(xy 345.376629 -244.300434) (xy 345.409264 -244.263597) (xy 345.447385 -244.232472) (xy 345.490006 -244.207865)
			(xy 345.536022 -244.190413) (xy 345.584241 -244.180569) (xy 345.633416 -244.178588) (xy 345.682271 -244.18452)
			(xy 345.729542 -244.198212) (xy 345.774004 -244.21931) (xy 345.814507 -244.247266) (xy 345.85 -244.281358)
			(xy 345.879565 -244.320702) (xy 345.902436 -244.364279) (xy 345.91802 -244.41096) (xy 345.925915 -244.459537)
			(xy 345.92641 -244.484144) (xy 346.255352 -244.484144) (xy 346.259312 -244.43509) (xy 346.271089 -244.387306)
			(xy 346.29038 -244.34203) (xy 346.316683 -244.300434) (xy 346.349318 -244.263597) (xy 346.387439 -244.232472)
			(xy 346.43006 -244.207865) (xy 346.476076 -244.190413) (xy 346.524295 -244.180569) (xy 346.57347 -244.178588)
			(xy 346.622325 -244.18452) (xy 346.669596 -244.198212) (xy 346.714058 -244.21931) (xy 346.754561 -244.247266)
			(xy 346.790054 -244.281358) (xy 346.819619 -244.320702) (xy 346.84249 -244.364279) (xy 346.858074 -244.41096)
			(xy 346.865969 -244.459537) (xy 346.866464 -244.484144) (xy 347.195406 -244.484144) (xy 347.199366 -244.43509)
			(xy 347.211143 -244.387306) (xy 347.230434 -244.34203) (xy 347.256737 -244.300434) (xy 347.289372 -244.263597)
			(xy 347.327493 -244.232472) (xy 347.370114 -244.207865) (xy 347.41613 -244.190413) (xy 347.464349 -244.180569)
			(xy 347.513524 -244.178588) (xy 347.562379 -244.18452) (xy 347.60965 -244.198212) (xy 347.654112 -244.21931)
			(xy 347.694615 -244.247266) (xy 347.730108 -244.281358) (xy 347.759673 -244.320702) (xy 347.782544 -244.364279)
			(xy 347.798128 -244.41096) (xy 347.806023 -244.459537) (xy 347.806518 -244.484144) (xy 348.135206 -244.484144)
			(xy 348.139166 -244.43509) (xy 348.150943 -244.387306) (xy 348.170234 -244.34203) (xy 348.196537 -244.300434)
			(xy 348.229172 -244.263597) (xy 348.267293 -244.232472) (xy 348.309914 -244.207865) (xy 348.35593 -244.190413)
			(xy 348.404149 -244.180569) (xy 348.453324 -244.178588) (xy 348.502179 -244.18452) (xy 348.54945 -244.198212)
			(xy 348.593912 -244.21931) (xy 348.634415 -244.247266) (xy 348.669908 -244.281358) (xy 348.699473 -244.320702)
			(xy 348.722344 -244.364279) (xy 348.737928 -244.41096) (xy 348.745823 -244.459537) (xy 348.746318 -244.484144)
			(xy 349.07526 -244.484144) (xy 349.07922 -244.43509) (xy 349.090997 -244.387306) (xy 349.110288 -244.34203)
			(xy 349.136591 -244.300434) (xy 349.169226 -244.263597) (xy 349.207347 -244.232472) (xy 349.249968 -244.207865)
			(xy 349.295984 -244.190413) (xy 349.344203 -244.180569) (xy 349.393378 -244.178588) (xy 349.442233 -244.18452)
			(xy 349.489504 -244.198212) (xy 349.533966 -244.21931) (xy 349.574469 -244.247266) (xy 349.609962 -244.281358)
			(xy 349.639527 -244.320702) (xy 349.662398 -244.364279) (xy 349.677982 -244.41096) (xy 349.685877 -244.459537)
			(xy 349.686372 -244.484144) (xy 350.015314 -244.484144) (xy 350.019274 -244.43509) (xy 350.031051 -244.387306)
			(xy 350.050342 -244.34203) (xy 350.076645 -244.300434) (xy 350.10928 -244.263597) (xy 350.147401 -244.232472)
			(xy 350.190022 -244.207865) (xy 350.236038 -244.190413) (xy 350.284257 -244.180569) (xy 350.333432 -244.178588)
			(xy 350.382287 -244.18452) (xy 350.429558 -244.198212) (xy 350.47402 -244.21931) (xy 350.514523 -244.247266)
			(xy 350.550016 -244.281358) (xy 350.579581 -244.320702) (xy 350.602452 -244.364279) (xy 350.618036 -244.41096)
			(xy 350.625931 -244.459537) (xy 350.626426 -244.484144) (xy 350.955368 -244.484144) (xy 350.959328 -244.43509)
			(xy 350.971105 -244.387306) (xy 350.990396 -244.34203) (xy 351.016699 -244.300434) (xy 351.049334 -244.263597)
			(xy 351.087455 -244.232472) (xy 351.130076 -244.207865) (xy 351.176092 -244.190413) (xy 351.224311 -244.180569)
			(xy 351.273486 -244.178588) (xy 351.322341 -244.18452) (xy 351.369612 -244.198212) (xy 351.414074 -244.21931)
			(xy 351.454577 -244.247266) (xy 351.49007 -244.281358) (xy 351.519635 -244.320702) (xy 351.542506 -244.364279)
			(xy 351.55809 -244.41096) (xy 351.565985 -244.459537) (xy 351.56648 -244.484144) (xy 351.895422 -244.484144)
			(xy 351.899382 -244.43509) (xy 351.911159 -244.387306) (xy 351.93045 -244.34203) (xy 351.956753 -244.300434)
			(xy 351.989388 -244.263597) (xy 352.027509 -244.232472) (xy 352.07013 -244.207865) (xy 352.116146 -244.190413)
			(xy 352.164365 -244.180569) (xy 352.21354 -244.178588) (xy 352.262395 -244.18452) (xy 352.309666 -244.198212)
			(xy 352.354128 -244.21931) (xy 352.394631 -244.247266) (xy 352.430124 -244.281358) (xy 352.459689 -244.320702)
			(xy 352.48256 -244.364279) (xy 352.498144 -244.41096) (xy 352.506039 -244.459537) (xy 352.506534 -244.484144)
			(xy 352.835222 -244.484144) (xy 352.839182 -244.43509) (xy 352.850959 -244.387306) (xy 352.87025 -244.34203)
			(xy 352.896553 -244.300434) (xy 352.929188 -244.263597) (xy 352.967309 -244.232472) (xy 353.00993 -244.207865)
			(xy 353.055946 -244.190413) (xy 353.104165 -244.180569) (xy 353.15334 -244.178588) (xy 353.202195 -244.18452)
			(xy 353.249466 -244.198212) (xy 353.293928 -244.21931) (xy 353.334431 -244.247266) (xy 353.369924 -244.281358)
			(xy 353.399489 -244.320702) (xy 353.42236 -244.364279) (xy 353.437944 -244.41096) (xy 353.445839 -244.459537)
			(xy 353.446334 -244.484144) (xy 353.775276 -244.484144) (xy 353.779236 -244.43509) (xy 353.791013 -244.387306)
			(xy 353.810304 -244.34203) (xy 353.836607 -244.300434) (xy 353.869242 -244.263597) (xy 353.907363 -244.232472)
			(xy 353.949984 -244.207865) (xy 353.996 -244.190413) (xy 354.044219 -244.180569) (xy 354.093394 -244.178588)
			(xy 354.142249 -244.18452) (xy 354.18952 -244.198212) (xy 354.233982 -244.21931) (xy 354.274485 -244.247266)
			(xy 354.309978 -244.281358) (xy 354.339543 -244.320702) (xy 354.362414 -244.364279) (xy 354.377998 -244.41096)
			(xy 354.385893 -244.459537) (xy 354.386388 -244.484144) (xy 354.71533 -244.484144) (xy 354.71929 -244.43509)
			(xy 354.731067 -244.387306) (xy 354.750358 -244.34203) (xy 354.776661 -244.300434) (xy 354.809296 -244.263597)
			(xy 354.847417 -244.232472) (xy 354.890038 -244.207865) (xy 354.936054 -244.190413) (xy 354.984273 -244.180569)
			(xy 355.033448 -244.178588) (xy 355.082303 -244.18452) (xy 355.129574 -244.198212) (xy 355.174036 -244.21931)
			(xy 355.214539 -244.247266) (xy 355.250032 -244.281358) (xy 355.279597 -244.320702) (xy 355.302468 -244.364279)
			(xy 355.318052 -244.41096) (xy 355.325947 -244.459537) (xy 355.326442 -244.484144) (xy 355.655384 -244.484144)
			(xy 355.659344 -244.43509) (xy 355.671121 -244.387306) (xy 355.690412 -244.34203) (xy 355.716715 -244.300434)
			(xy 355.74935 -244.263597) (xy 355.787471 -244.232472) (xy 355.830092 -244.207865) (xy 355.876108 -244.190413)
			(xy 355.924327 -244.180569) (xy 355.973502 -244.178588) (xy 356.022357 -244.18452) (xy 356.069628 -244.198212)
			(xy 356.11409 -244.21931) (xy 356.154593 -244.247266) (xy 356.190086 -244.281358) (xy 356.219651 -244.320702)
			(xy 356.242522 -244.364279) (xy 356.258106 -244.41096) (xy 356.266001 -244.459537) (xy 356.266496 -244.484144)
			(xy 356.595438 -244.484144) (xy 356.599398 -244.43509) (xy 356.611175 -244.387306) (xy 356.630466 -244.34203)
			(xy 356.656769 -244.300434) (xy 356.689404 -244.263597) (xy 356.727525 -244.232472) (xy 356.770146 -244.207865)
			(xy 356.816162 -244.190413) (xy 356.864381 -244.180569) (xy 356.913556 -244.178588) (xy 356.962411 -244.18452)
			(xy 357.009682 -244.198212) (xy 357.054144 -244.21931) (xy 357.094647 -244.247266) (xy 357.13014 -244.281358)
			(xy 357.159705 -244.320702) (xy 357.182576 -244.364279) (xy 357.19816 -244.41096) (xy 357.206055 -244.459537)
			(xy 357.20655 -244.484144) (xy 357.535238 -244.484144) (xy 357.539198 -244.43509) (xy 357.550975 -244.387306)
			(xy 357.570266 -244.34203) (xy 357.596569 -244.300434) (xy 357.629204 -244.263597) (xy 357.667325 -244.232472)
			(xy 357.709946 -244.207865) (xy 357.755962 -244.190413) (xy 357.804181 -244.180569) (xy 357.853356 -244.178588)
			(xy 357.902211 -244.18452) (xy 357.949482 -244.198212) (xy 357.993944 -244.21931) (xy 358.034447 -244.247266)
			(xy 358.06994 -244.281358) (xy 358.099505 -244.320702) (xy 358.122376 -244.364279) (xy 358.13796 -244.41096)
			(xy 358.145855 -244.459537) (xy 358.14635 -244.484144) (xy 361.289104 -244.484144) (xy 361.293064 -244.43509)
			(xy 361.304841 -244.387306) (xy 361.324132 -244.34203) (xy 361.350435 -244.300434) (xy 361.38307 -244.263597)
			(xy 361.421191 -244.232472) (xy 361.463812 -244.207865) (xy 361.509828 -244.190413) (xy 361.558047 -244.180569)
			(xy 361.607222 -244.178588) (xy 361.656077 -244.18452) (xy 361.703348 -244.198212) (xy 361.74781 -244.21931)
			(xy 361.788313 -244.247266) (xy 361.823806 -244.281358) (xy 361.853371 -244.320702) (xy 361.876242 -244.364279)
			(xy 361.891826 -244.41096) (xy 361.899721 -244.459537) (xy 361.900216 -244.484144) (xy 362.228904 -244.484144)
			(xy 362.232864 -244.43509) (xy 362.244641 -244.387306) (xy 362.263932 -244.34203) (xy 362.290235 -244.300434)
			(xy 362.32287 -244.263597) (xy 362.360991 -244.232472) (xy 362.403612 -244.207865) (xy 362.449628 -244.190413)
			(xy 362.497847 -244.180569) (xy 362.547022 -244.178588) (xy 362.595877 -244.18452) (xy 362.643148 -244.198212)
			(xy 362.68761 -244.21931) (xy 362.728113 -244.247266) (xy 362.763606 -244.281358) (xy 362.793171 -244.320702)
			(xy 362.816042 -244.364279) (xy 362.831626 -244.41096) (xy 362.839521 -244.459537) (xy 362.840016 -244.484144)
			(xy 363.168958 -244.484144) (xy 363.172918 -244.43509) (xy 363.184695 -244.387306) (xy 363.203986 -244.34203)
			(xy 363.230289 -244.300434) (xy 363.262924 -244.263597) (xy 363.301045 -244.232472) (xy 363.343666 -244.207865)
			(xy 363.389682 -244.190413) (xy 363.437901 -244.180569) (xy 363.487076 -244.178588) (xy 363.535931 -244.18452)
			(xy 363.583202 -244.198212) (xy 363.627664 -244.21931) (xy 363.668167 -244.247266) (xy 363.70366 -244.281358)
			(xy 363.733225 -244.320702) (xy 363.756096 -244.364279) (xy 363.77168 -244.41096) (xy 363.779575 -244.459537)
			(xy 363.780069 -244.4841) (xy 364.108984 -244.4841) (xy 364.113155 -244.433763) (xy 364.125555 -244.384799)
			(xy 364.145845 -244.338543) (xy 364.173472 -244.296259) (xy 364.207683 -244.259098) (xy 364.247543 -244.228076)
			(xy 364.291966 -244.204037) (xy 364.33974 -244.187639) (xy 364.389561 -244.179327) (xy 364.414816 -244.178836)
			(xy 365.35487 -244.178836) (xy 365.380133 -244.179238) (xy 365.42997 -244.18755) (xy 365.47776 -244.203952)
			(xy 365.522198 -244.227997) (xy 365.562072 -244.259028) (xy 365.596293 -244.2962) (xy 365.62393 -244.338497)
			(xy 365.644227 -244.384767) (xy 365.656631 -244.433747) (xy 365.660804 -244.4841) (xy 365.6608 -244.484144)
			(xy 365.98912 -244.484144) (xy 365.99308 -244.43509) (xy 366.004857 -244.387306) (xy 366.024148 -244.34203)
			(xy 366.050451 -244.300434) (xy 366.083086 -244.263597) (xy 366.121207 -244.232472) (xy 366.163828 -244.207865)
			(xy 366.209844 -244.190413) (xy 366.258063 -244.180569) (xy 366.307238 -244.178588) (xy 366.356093 -244.18452)
			(xy 366.403364 -244.198212) (xy 366.447826 -244.21931) (xy 366.488329 -244.247266) (xy 366.523822 -244.281358)
			(xy 366.553387 -244.320702) (xy 366.576258 -244.364279) (xy 366.591842 -244.41096) (xy 366.599737 -244.459537)
			(xy 366.600231 -244.4841) (xy 366.928884 -244.4841) (xy 366.933055 -244.433762) (xy 366.945456 -244.384797)
			(xy 366.965746 -244.338541) (xy 366.993374 -244.296256) (xy 367.027586 -244.259095) (xy 367.067447 -244.228073)
			(xy 367.111871 -244.204035) (xy 367.159646 -244.187637) (xy 367.209469 -244.179327) (xy 367.234724 -244.178836)
			(xy 368.174778 -244.178836) (xy 368.200041 -244.179239) (xy 368.249877 -244.187552) (xy 368.297665 -244.203955)
			(xy 368.342102 -244.228) (xy 368.381975 -244.259031) (xy 368.416196 -244.296203) (xy 368.443831 -244.3385)
			(xy 368.464128 -244.384769) (xy 368.476531 -244.433748) (xy 368.480704 -244.4841) (xy 368.4807 -244.484144)
			(xy 368.809028 -244.484144) (xy 368.812988 -244.43509) (xy 368.824765 -244.387306) (xy 368.844056 -244.34203)
			(xy 368.870359 -244.300434) (xy 368.902994 -244.263597) (xy 368.941115 -244.232472) (xy 368.983736 -244.207865)
			(xy 369.029752 -244.190413) (xy 369.077971 -244.180569) (xy 369.127146 -244.178588) (xy 369.176001 -244.18452)
			(xy 369.223272 -244.198212) (xy 369.267734 -244.21931) (xy 369.308237 -244.247266) (xy 369.34373 -244.281358)
			(xy 369.373295 -244.320702) (xy 369.396166 -244.364279) (xy 369.41175 -244.41096) (xy 369.419645 -244.459537)
			(xy 369.420139 -244.4841) (xy 369.749113 -244.4841) (xy 369.753283 -244.433771) (xy 369.76568 -244.384814)
			(xy 369.785966 -244.338565) (xy 369.813587 -244.296286) (xy 369.847791 -244.25913) (xy 369.887643 -244.22811)
			(xy 369.932057 -244.204073) (xy 369.979822 -244.187673) (xy 370.029635 -244.179359) (xy 370.054886 -244.178836)
			(xy 370.99494 -244.178836) (xy 371.020197 -244.179272) (xy 371.070021 -244.187592) (xy 371.117796 -244.203999)
			(xy 371.162219 -244.228045) (xy 371.202079 -244.259074) (xy 371.236289 -244.296241) (xy 371.263916 -244.33853)
			(xy 371.284205 -244.38479) (xy 371.296604 -244.433759) (xy 371.300776 -244.4841) (xy 371.300772 -244.484144)
			(xy 371.628936 -244.484144) (xy 371.632896 -244.43509) (xy 371.644673 -244.387306) (xy 371.663964 -244.34203)
			(xy 371.690267 -244.300434) (xy 371.722902 -244.263597) (xy 371.761023 -244.232472) (xy 371.803644 -244.207865)
			(xy 371.84966 -244.190413) (xy 371.897879 -244.180569) (xy 371.947054 -244.178588) (xy 371.995909 -244.18452)
			(xy 372.04318 -244.198212) (xy 372.087642 -244.21931) (xy 372.128145 -244.247266) (xy 372.163638 -244.281358)
			(xy 372.193203 -244.320702) (xy 372.216074 -244.364279) (xy 372.231658 -244.41096) (xy 372.239553 -244.459537)
			(xy 372.240047 -244.4841) (xy 372.569013 -244.4841) (xy 372.573183 -244.43377) (xy 372.585581 -244.384812)
			(xy 372.605867 -244.338563) (xy 372.63349 -244.296284) (xy 372.667694 -244.259127) (xy 372.707547 -244.228107)
			(xy 372.751963 -244.20407) (xy 372.799729 -244.187671) (xy 372.849543 -244.179358) (xy 372.874794 -244.178836)
			(xy 373.814848 -244.178836) (xy 373.840104 -244.179273) (xy 373.889927 -244.187594) (xy 373.937701 -244.204002)
			(xy 373.982123 -244.228048) (xy 374.021982 -244.259077) (xy 374.056191 -244.296243) (xy 374.083817 -244.338533)
			(xy 374.104106 -244.384792) (xy 374.116505 -244.43376) (xy 374.120676 -244.4841) (xy 374.116505 -244.53444)
			(xy 374.104106 -244.583408) (xy 374.083817 -244.629667) (xy 374.056191 -244.671957) (xy 374.021982 -244.709123)
			(xy 373.982123 -244.740152) (xy 373.937701 -244.764198) (xy 373.889927 -244.780606) (xy 373.840104 -244.788927)
			(xy 373.814848 -244.789452) (xy 372.874794 -244.789452) (xy 372.849543 -244.788842) (xy 372.799729 -244.780529)
			(xy 372.751963 -244.76413) (xy 372.707547 -244.740093) (xy 372.667694 -244.709073) (xy 372.63349 -244.671916)
			(xy 372.605867 -244.629637) (xy 372.585581 -244.583388) (xy 372.573183 -244.53443) (xy 372.569013 -244.4841)
			(xy 372.240047 -244.4841) (xy 372.240048 -244.484144) (xy 372.239553 -244.508751) (xy 372.231658 -244.557328)
			(xy 372.216074 -244.604009) (xy 372.193203 -244.647586) (xy 372.163638 -244.68693) (xy 372.128145 -244.721022)
			(xy 372.087642 -244.748978) (xy 372.04318 -244.770076) (xy 371.995909 -244.783768) (xy 371.947054 -244.7897)
			(xy 371.897879 -244.787719) (xy 371.84966 -244.777875) (xy 371.803644 -244.760423) (xy 371.761023 -244.735816)
			(xy 371.722902 -244.704691) (xy 371.690267 -244.667854) (xy 371.663964 -244.626258) (xy 371.644673 -244.580982)
			(xy 371.632896 -244.533198) (xy 371.628936 -244.484144) (xy 371.300772 -244.484144) (xy 371.296604 -244.534441)
			(xy 371.284205 -244.58341) (xy 371.263915 -244.62967) (xy 371.236289 -244.671959) (xy 371.202079 -244.709126)
			(xy 371.162219 -244.740155) (xy 371.117796 -244.764201) (xy 371.070021 -244.780608) (xy 371.020197 -244.788928)
			(xy 370.99494 -244.789452) (xy 370.054886 -244.789452) (xy 370.029635 -244.788841) (xy 369.979822 -244.780527)
			(xy 369.932057 -244.764127) (xy 369.887643 -244.74009) (xy 369.847791 -244.70907) (xy 369.813587 -244.671914)
			(xy 369.785966 -244.629635) (xy 369.76568 -244.583386) (xy 369.753283 -244.534429) (xy 369.749113 -244.4841)
			(xy 369.420139 -244.4841) (xy 369.42014 -244.484144) (xy 369.419645 -244.508751) (xy 369.41175 -244.557328)
			(xy 369.396166 -244.604009) (xy 369.373295 -244.647586) (xy 369.34373 -244.68693) (xy 369.308237 -244.721022)
			(xy 369.267734 -244.748978) (xy 369.223272 -244.770076) (xy 369.176001 -244.783768) (xy 369.127146 -244.7897)
			(xy 369.077971 -244.787719) (xy 369.029752 -244.777875) (xy 368.983736 -244.760423) (xy 368.941115 -244.735816)
			(xy 368.902994 -244.704691) (xy 368.870359 -244.667854) (xy 368.844056 -244.626258) (xy 368.824765 -244.580982)
			(xy 368.812988 -244.533198) (xy 368.809028 -244.484144) (xy 368.4807 -244.484144) (xy 368.476531 -244.534452)
			(xy 368.464128 -244.583431) (xy 368.443831 -244.6297) (xy 368.416196 -244.671997) (xy 368.381975 -244.709169)
			(xy 368.342102 -244.7402) (xy 368.297665 -244.764245) (xy 368.249877 -244.780648) (xy 368.200041 -244.788961)
			(xy 368.174778 -244.789452) (xy 367.234724 -244.789452) (xy 367.209469 -244.788873) (xy 367.159646 -244.780563)
			(xy 367.111871 -244.764165) (xy 367.067447 -244.740127) (xy 367.027586 -244.709105) (xy 366.993374 -244.671944)
			(xy 366.965746 -244.629659) (xy 366.945456 -244.583403) (xy 366.933055 -244.534438) (xy 366.928884 -244.4841)
			(xy 366.600231 -244.4841) (xy 366.600232 -244.484144) (xy 366.599737 -244.508751) (xy 366.591842 -244.557328)
			(xy 366.576258 -244.604009) (xy 366.553387 -244.647586) (xy 366.523822 -244.68693) (xy 366.488329 -244.721022)
			(xy 366.447826 -244.748978) (xy 366.403364 -244.770076) (xy 366.356093 -244.783768) (xy 366.307238 -244.7897)
			(xy 366.258063 -244.787719) (xy 366.209844 -244.777875) (xy 366.163828 -244.760423) (xy 366.121207 -244.735816)
			(xy 366.083086 -244.704691) (xy 366.050451 -244.667854) (xy 366.024148 -244.626258) (xy 366.004857 -244.580982)
			(xy 365.99308 -244.533198) (xy 365.98912 -244.484144) (xy 365.6608 -244.484144) (xy 365.656631 -244.534453)
			(xy 365.644227 -244.583433) (xy 365.62393 -244.629703) (xy 365.596293 -244.672) (xy 365.562072 -244.709172)
			(xy 365.522198 -244.740203) (xy 365.47776 -244.764248) (xy 365.42997 -244.78065) (xy 365.380133 -244.788962)
			(xy 365.35487 -244.789452) (xy 364.414816 -244.789452) (xy 364.389561 -244.788873) (xy 364.33974 -244.780561)
			(xy 364.291966 -244.764163) (xy 364.247543 -244.740124) (xy 364.207683 -244.709102) (xy 364.173472 -244.671941)
			(xy 364.145845 -244.629657) (xy 364.125555 -244.583401) (xy 364.113155 -244.534437) (xy 364.108984 -244.4841)
			(xy 363.780069 -244.4841) (xy 363.78007 -244.484144) (xy 363.779575 -244.508751) (xy 363.77168 -244.557328)
			(xy 363.756096 -244.604009) (xy 363.733225 -244.647586) (xy 363.70366 -244.68693) (xy 363.668167 -244.721022)
			(xy 363.627664 -244.748978) (xy 363.583202 -244.770076) (xy 363.535931 -244.783768) (xy 363.487076 -244.7897)
			(xy 363.437901 -244.787719) (xy 363.389682 -244.777875) (xy 363.343666 -244.760423) (xy 363.301045 -244.735816)
			(xy 363.262924 -244.704691) (xy 363.230289 -244.667854) (xy 363.203986 -244.626258) (xy 363.184695 -244.580982)
			(xy 363.172918 -244.533198) (xy 363.168958 -244.484144) (xy 362.840016 -244.484144) (xy 362.839521 -244.508751)
			(xy 362.831626 -244.557328) (xy 362.816042 -244.604009) (xy 362.793171 -244.647586) (xy 362.763606 -244.68693)
			(xy 362.728113 -244.721022) (xy 362.68761 -244.748978) (xy 362.643148 -244.770076) (xy 362.595877 -244.783768)
			(xy 362.547022 -244.7897) (xy 362.497847 -244.787719) (xy 362.449628 -244.777875) (xy 362.403612 -244.760423)
			(xy 362.360991 -244.735816) (xy 362.32287 -244.704691) (xy 362.290235 -244.667854) (xy 362.263932 -244.626258)
			(xy 362.244641 -244.580982) (xy 362.232864 -244.533198) (xy 362.228904 -244.484144) (xy 361.900216 -244.484144)
			(xy 361.899721 -244.508751) (xy 361.891826 -244.557328) (xy 361.876242 -244.604009) (xy 361.853371 -244.647586)
			(xy 361.823806 -244.68693) (xy 361.788313 -244.721022) (xy 361.74781 -244.748978) (xy 361.703348 -244.770076)
			(xy 361.656077 -244.783768) (xy 361.607222 -244.7897) (xy 361.558047 -244.787719) (xy 361.509828 -244.777875)
			(xy 361.463812 -244.760423) (xy 361.421191 -244.735816) (xy 361.38307 -244.704691) (xy 361.350435 -244.667854)
			(xy 361.324132 -244.626258) (xy 361.304841 -244.580982) (xy 361.293064 -244.533198) (xy 361.289104 -244.484144)
			(xy 358.14635 -244.484144) (xy 358.145855 -244.508751) (xy 358.13796 -244.557328) (xy 358.122376 -244.604009)
			(xy 358.099505 -244.647586) (xy 358.06994 -244.68693) (xy 358.034447 -244.721022) (xy 357.993944 -244.748978)
			(xy 357.949482 -244.770076) (xy 357.902211 -244.783768) (xy 357.853356 -244.7897) (xy 357.804181 -244.787719)
			(xy 357.755962 -244.777875) (xy 357.709946 -244.760423) (xy 357.667325 -244.735816) (xy 357.629204 -244.704691)
			(xy 357.596569 -244.667854) (xy 357.570266 -244.626258) (xy 357.550975 -244.580982) (xy 357.539198 -244.533198)
			(xy 357.535238 -244.484144) (xy 357.20655 -244.484144) (xy 357.206055 -244.508751) (xy 357.19816 -244.557328)
			(xy 357.182576 -244.604009) (xy 357.159705 -244.647586) (xy 357.13014 -244.68693) (xy 357.094647 -244.721022)
			(xy 357.054144 -244.748978) (xy 357.009682 -244.770076) (xy 356.962411 -244.783768) (xy 356.913556 -244.7897)
			(xy 356.864381 -244.787719) (xy 356.816162 -244.777875) (xy 356.770146 -244.760423) (xy 356.727525 -244.735816)
			(xy 356.689404 -244.704691) (xy 356.656769 -244.667854) (xy 356.630466 -244.626258) (xy 356.611175 -244.580982)
			(xy 356.599398 -244.533198) (xy 356.595438 -244.484144) (xy 356.266496 -244.484144) (xy 356.266001 -244.508751)
			(xy 356.258106 -244.557328) (xy 356.242522 -244.604009) (xy 356.219651 -244.647586) (xy 356.190086 -244.68693)
			(xy 356.154593 -244.721022) (xy 356.11409 -244.748978) (xy 356.069628 -244.770076) (xy 356.022357 -244.783768)
			(xy 355.973502 -244.7897) (xy 355.924327 -244.787719) (xy 355.876108 -244.777875) (xy 355.830092 -244.760423)
			(xy 355.787471 -244.735816) (xy 355.74935 -244.704691) (xy 355.716715 -244.667854) (xy 355.690412 -244.626258)
			(xy 355.671121 -244.580982) (xy 355.659344 -244.533198) (xy 355.655384 -244.484144) (xy 355.326442 -244.484144)
			(xy 355.325947 -244.508751) (xy 355.318052 -244.557328) (xy 355.302468 -244.604009) (xy 355.279597 -244.647586)
			(xy 355.250032 -244.68693) (xy 355.214539 -244.721022) (xy 355.174036 -244.748978) (xy 355.129574 -244.770076)
			(xy 355.082303 -244.783768) (xy 355.033448 -244.7897) (xy 354.984273 -244.787719) (xy 354.936054 -244.777875)
			(xy 354.890038 -244.760423) (xy 354.847417 -244.735816) (xy 354.809296 -244.704691) (xy 354.776661 -244.667854)
			(xy 354.750358 -244.626258) (xy 354.731067 -244.580982) (xy 354.71929 -244.533198) (xy 354.71533 -244.484144)
			(xy 354.386388 -244.484144) (xy 354.385893 -244.508751) (xy 354.377998 -244.557328) (xy 354.362414 -244.604009)
			(xy 354.339543 -244.647586) (xy 354.309978 -244.68693) (xy 354.274485 -244.721022) (xy 354.233982 -244.748978)
			(xy 354.18952 -244.770076) (xy 354.142249 -244.783768) (xy 354.093394 -244.7897) (xy 354.044219 -244.787719)
			(xy 353.996 -244.777875) (xy 353.949984 -244.760423) (xy 353.907363 -244.735816) (xy 353.869242 -244.704691)
			(xy 353.836607 -244.667854) (xy 353.810304 -244.626258) (xy 353.791013 -244.580982) (xy 353.779236 -244.533198)
			(xy 353.775276 -244.484144) (xy 353.446334 -244.484144) (xy 353.445839 -244.508751) (xy 353.437944 -244.557328)
			(xy 353.42236 -244.604009) (xy 353.399489 -244.647586) (xy 353.369924 -244.68693) (xy 353.334431 -244.721022)
			(xy 353.293928 -244.748978) (xy 353.249466 -244.770076) (xy 353.202195 -244.783768) (xy 353.15334 -244.7897)
			(xy 353.104165 -244.787719) (xy 353.055946 -244.777875) (xy 353.00993 -244.760423) (xy 352.967309 -244.735816)
			(xy 352.929188 -244.704691) (xy 352.896553 -244.667854) (xy 352.87025 -244.626258) (xy 352.850959 -244.580982)
			(xy 352.839182 -244.533198) (xy 352.835222 -244.484144) (xy 352.506534 -244.484144) (xy 352.506039 -244.508751)
			(xy 352.498144 -244.557328) (xy 352.48256 -244.604009) (xy 352.459689 -244.647586) (xy 352.430124 -244.68693)
			(xy 352.394631 -244.721022) (xy 352.354128 -244.748978) (xy 352.309666 -244.770076) (xy 352.262395 -244.783768)
			(xy 352.21354 -244.7897) (xy 352.164365 -244.787719) (xy 352.116146 -244.777875) (xy 352.07013 -244.760423)
			(xy 352.027509 -244.735816) (xy 351.989388 -244.704691) (xy 351.956753 -244.667854) (xy 351.93045 -244.626258)
			(xy 351.911159 -244.580982) (xy 351.899382 -244.533198) (xy 351.895422 -244.484144) (xy 351.56648 -244.484144)
			(xy 351.565985 -244.508751) (xy 351.55809 -244.557328) (xy 351.542506 -244.604009) (xy 351.519635 -244.647586)
			(xy 351.49007 -244.68693) (xy 351.454577 -244.721022) (xy 351.414074 -244.748978) (xy 351.369612 -244.770076)
			(xy 351.322341 -244.783768) (xy 351.273486 -244.7897) (xy 351.224311 -244.787719) (xy 351.176092 -244.777875)
			(xy 351.130076 -244.760423) (xy 351.087455 -244.735816) (xy 351.049334 -244.704691) (xy 351.016699 -244.667854)
			(xy 350.990396 -244.626258) (xy 350.971105 -244.580982) (xy 350.959328 -244.533198) (xy 350.955368 -244.484144)
			(xy 350.626426 -244.484144) (xy 350.625931 -244.508751) (xy 350.618036 -244.557328) (xy 350.602452 -244.604009)
			(xy 350.579581 -244.647586) (xy 350.550016 -244.68693) (xy 350.514523 -244.721022) (xy 350.47402 -244.748978)
			(xy 350.429558 -244.770076) (xy 350.382287 -244.783768) (xy 350.333432 -244.7897) (xy 350.284257 -244.787719)
			(xy 350.236038 -244.777875) (xy 350.190022 -244.760423) (xy 350.147401 -244.735816) (xy 350.10928 -244.704691)
			(xy 350.076645 -244.667854) (xy 350.050342 -244.626258) (xy 350.031051 -244.580982) (xy 350.019274 -244.533198)
			(xy 350.015314 -244.484144) (xy 349.686372 -244.484144) (xy 349.685877 -244.508751) (xy 349.677982 -244.557328)
			(xy 349.662398 -244.604009) (xy 349.639527 -244.647586) (xy 349.609962 -244.68693) (xy 349.574469 -244.721022)
			(xy 349.533966 -244.748978) (xy 349.489504 -244.770076) (xy 349.442233 -244.783768) (xy 349.393378 -244.7897)
			(xy 349.344203 -244.787719) (xy 349.295984 -244.777875) (xy 349.249968 -244.760423) (xy 349.207347 -244.735816)
			(xy 349.169226 -244.704691) (xy 349.136591 -244.667854) (xy 349.110288 -244.626258) (xy 349.090997 -244.580982)
			(xy 349.07922 -244.533198) (xy 349.07526 -244.484144) (xy 348.746318 -244.484144) (xy 348.745823 -244.508751)
			(xy 348.737928 -244.557328) (xy 348.722344 -244.604009) (xy 348.699473 -244.647586) (xy 348.669908 -244.68693)
			(xy 348.634415 -244.721022) (xy 348.593912 -244.748978) (xy 348.54945 -244.770076) (xy 348.502179 -244.783768)
			(xy 348.453324 -244.7897) (xy 348.404149 -244.787719) (xy 348.35593 -244.777875) (xy 348.309914 -244.760423)
			(xy 348.267293 -244.735816) (xy 348.229172 -244.704691) (xy 348.196537 -244.667854) (xy 348.170234 -244.626258)
			(xy 348.150943 -244.580982) (xy 348.139166 -244.533198) (xy 348.135206 -244.484144) (xy 347.806518 -244.484144)
			(xy 347.806023 -244.508751) (xy 347.798128 -244.557328) (xy 347.782544 -244.604009) (xy 347.759673 -244.647586)
			(xy 347.730108 -244.68693) (xy 347.694615 -244.721022) (xy 347.654112 -244.748978) (xy 347.60965 -244.770076)
			(xy 347.562379 -244.783768) (xy 347.513524 -244.7897) (xy 347.464349 -244.787719) (xy 347.41613 -244.777875)
			(xy 347.370114 -244.760423) (xy 347.327493 -244.735816) (xy 347.289372 -244.704691) (xy 347.256737 -244.667854)
			(xy 347.230434 -244.626258) (xy 347.211143 -244.580982) (xy 347.199366 -244.533198) (xy 347.195406 -244.484144)
			(xy 346.866464 -244.484144) (xy 346.865969 -244.508751) (xy 346.858074 -244.557328) (xy 346.84249 -244.604009)
			(xy 346.819619 -244.647586) (xy 346.790054 -244.68693) (xy 346.754561 -244.721022) (xy 346.714058 -244.748978)
			(xy 346.669596 -244.770076) (xy 346.622325 -244.783768) (xy 346.57347 -244.7897) (xy 346.524295 -244.787719)
			(xy 346.476076 -244.777875) (xy 346.43006 -244.760423) (xy 346.387439 -244.735816) (xy 346.349318 -244.704691)
			(xy 346.316683 -244.667854) (xy 346.29038 -244.626258) (xy 346.271089 -244.580982) (xy 346.259312 -244.533198)
			(xy 346.255352 -244.484144) (xy 345.92641 -244.484144) (xy 345.925915 -244.508751) (xy 345.91802 -244.557328)
			(xy 345.902436 -244.604009) (xy 345.879565 -244.647586) (xy 345.85 -244.68693) (xy 345.814507 -244.721022)
			(xy 345.774004 -244.748978) (xy 345.729542 -244.770076) (xy 345.682271 -244.783768) (xy 345.633416 -244.7897)
			(xy 345.584241 -244.787719) (xy 345.536022 -244.777875) (xy 345.490006 -244.760423) (xy 345.447385 -244.735816)
			(xy 345.409264 -244.704691) (xy 345.376629 -244.667854) (xy 345.350326 -244.626258) (xy 345.331035 -244.580982)
			(xy 345.319258 -244.533198) (xy 345.315298 -244.484144) (xy 344.986356 -244.484144) (xy 344.985878 -244.508606)
			(xy 344.978088 -244.556907) (xy 344.962699 -244.603348) (xy 344.940105 -244.646743) (xy 344.910882 -244.685981)
			(xy 344.893646 -244.703346) (xy 344.886534 -244.710204) (xy 344.87485 -244.73662) (xy 344.872817 -244.741518)
			(xy 344.870636 -244.751893) (xy 344.870532 -244.757194) (xy 344.870532 -245.29415) (xy 346.725252 -245.29415)
			(xy 346.729212 -245.245096) (xy 346.740989 -245.197312) (xy 346.76028 -245.152036) (xy 346.786583 -245.11044)
			(xy 346.819218 -245.073603) (xy 346.857339 -245.042478) (xy 346.89996 -245.017871) (xy 346.945976 -245.000419)
			(xy 346.994195 -244.990575) (xy 347.04337 -244.988594) (xy 347.092225 -244.994526) (xy 347.139496 -245.008218)
			(xy 347.183958 -245.029316) (xy 347.224461 -245.057272) (xy 347.259954 -245.091364) (xy 347.289519 -245.130708)
			(xy 347.31239 -245.174285) (xy 347.327974 -245.220966) (xy 347.335869 -245.269543) (xy 347.336364 -245.29415)
			(xy 349.545414 -245.29415) (xy 349.549374 -245.245096) (xy 349.561151 -245.197312) (xy 349.580442 -245.152036)
			(xy 349.606745 -245.11044) (xy 349.63938 -245.073603) (xy 349.677501 -245.042478) (xy 349.720122 -245.017871)
			(xy 349.766138 -245.000419) (xy 349.814357 -244.990575) (xy 349.863532 -244.988594) (xy 349.912387 -244.994526)
			(xy 349.959658 -245.008218) (xy 350.00412 -245.029316) (xy 350.044623 -245.057272) (xy 350.080116 -245.091364)
			(xy 350.109681 -245.130708) (xy 350.132552 -245.174285) (xy 350.148136 -245.220966) (xy 350.156031 -245.269543)
			(xy 350.156526 -245.29415) (xy 352.365322 -245.29415) (xy 352.369282 -245.245096) (xy 352.381059 -245.197312)
			(xy 352.40035 -245.152036) (xy 352.426653 -245.11044) (xy 352.459288 -245.073603) (xy 352.497409 -245.042478)
			(xy 352.54003 -245.017871) (xy 352.586046 -245.000419) (xy 352.634265 -244.990575) (xy 352.68344 -244.988594)
			(xy 352.732295 -244.994526) (xy 352.779566 -245.008218) (xy 352.824028 -245.029316) (xy 352.864531 -245.057272)
			(xy 352.900024 -245.091364) (xy 352.929589 -245.130708) (xy 352.95246 -245.174285) (xy 352.968044 -245.220966)
			(xy 352.975939 -245.269543) (xy 352.976434 -245.29415) (xy 355.18523 -245.29415) (xy 355.18919 -245.245096)
			(xy 355.200967 -245.197312) (xy 355.220258 -245.152036) (xy 355.246561 -245.11044) (xy 355.279196 -245.073603)
			(xy 355.317317 -245.042478) (xy 355.359938 -245.017871) (xy 355.405954 -245.000419) (xy 355.454173 -244.990575)
			(xy 355.503348 -244.988594) (xy 355.552203 -244.994526) (xy 355.599474 -245.008218) (xy 355.643936 -245.029316)
			(xy 355.684439 -245.057272) (xy 355.719932 -245.091364) (xy 355.749497 -245.130708) (xy 355.772368 -245.174285)
			(xy 355.787952 -245.220966) (xy 355.795847 -245.269543) (xy 355.796342 -245.29415) (xy 356.125284 -245.29415)
			(xy 356.129244 -245.245096) (xy 356.141021 -245.197312) (xy 356.160312 -245.152036) (xy 356.186615 -245.11044)
			(xy 356.21925 -245.073603) (xy 356.257371 -245.042478) (xy 356.299992 -245.017871) (xy 356.346008 -245.000419)
			(xy 356.394227 -244.990575) (xy 356.443402 -244.988594) (xy 356.492257 -244.994526) (xy 356.539528 -245.008218)
			(xy 356.58399 -245.029316) (xy 356.624493 -245.057272) (xy 356.659986 -245.091364) (xy 356.689551 -245.130708)
			(xy 356.712422 -245.174285) (xy 356.728006 -245.220966) (xy 356.735901 -245.269543) (xy 356.736396 -245.29415)
			(xy 357.065338 -245.29415) (xy 357.069298 -245.245096) (xy 357.081075 -245.197312) (xy 357.100366 -245.152036)
			(xy 357.126669 -245.11044) (xy 357.159304 -245.073603) (xy 357.197425 -245.042478) (xy 357.240046 -245.017871)
			(xy 357.286062 -245.000419) (xy 357.334281 -244.990575) (xy 357.383456 -244.988594) (xy 357.432311 -244.994526)
			(xy 357.479582 -245.008218) (xy 357.524044 -245.029316) (xy 357.564547 -245.057272) (xy 357.60004 -245.091364)
			(xy 357.629605 -245.130708) (xy 357.652476 -245.174285) (xy 357.66806 -245.220966) (xy 357.675955 -245.269543)
			(xy 357.67645 -245.29415) (xy 358.005392 -245.29415) (xy 358.009352 -245.245096) (xy 358.021129 -245.197312)
			(xy 358.04042 -245.152036) (xy 358.066723 -245.11044) (xy 358.099358 -245.073603) (xy 358.137479 -245.042478)
			(xy 358.1801 -245.017871) (xy 358.226116 -245.000419) (xy 358.274335 -244.990575) (xy 358.32351 -244.988594)
			(xy 358.372365 -244.994526) (xy 358.419636 -245.008218) (xy 358.464098 -245.029316) (xy 358.504601 -245.057272)
			(xy 358.540094 -245.091364) (xy 358.569659 -245.130708) (xy 358.59253 -245.174285) (xy 358.608114 -245.220966)
			(xy 358.616009 -245.269543) (xy 358.616504 -245.29415) (xy 358.616009 -245.318757) (xy 358.608114 -245.367334)
			(xy 358.59253 -245.414015) (xy 358.569659 -245.457592) (xy 358.540094 -245.496936) (xy 358.504601 -245.531028)
			(xy 358.474274 -245.55196) (xy 359.396541 -245.55196) (xy 359.400571 -245.499462) (xy 359.412568 -245.448194)
			(xy 359.432251 -245.399359) (xy 359.459157 -245.3541) (xy 359.492657 -245.313479) (xy 359.531965 -245.278448)
			(xy 359.57616 -245.249828) (xy 359.624205 -245.228289) (xy 359.674976 -245.214337) (xy 359.727281 -245.208299)
			(xy 359.779895 -245.210316) (xy 359.831585 -245.22034) (xy 359.881138 -245.238138) (xy 359.927394 -245.263291)
			(xy 359.967877 -245.29415) (xy 360.81895 -245.29415) (xy 360.82291 -245.245096) (xy 360.834687 -245.197312)
			(xy 360.853978 -245.152036) (xy 360.880281 -245.11044) (xy 360.912916 -245.073603) (xy 360.951037 -245.042478)
			(xy 360.993658 -245.017871) (xy 361.039674 -245.000419) (xy 361.087893 -244.990575) (xy 361.137068 -244.988594)
			(xy 361.185923 -244.994526) (xy 361.233194 -245.008218) (xy 361.277656 -245.029316) (xy 361.318159 -245.057272)
			(xy 361.353652 -245.091364) (xy 361.383217 -245.130708) (xy 361.406088 -245.174285) (xy 361.421672 -245.220966)
			(xy 361.429567 -245.269543) (xy 361.430061 -245.2941) (xy 361.758735 -245.2941) (xy 361.76291 -245.243723)
			(xy 361.775319 -245.194719) (xy 361.795626 -245.148427) (xy 361.823274 -245.106109) (xy 361.857511 -245.068918)
			(xy 361.897403 -245.03787) (xy 361.941861 -245.013812) (xy 361.989672 -244.997399) (xy 362.039533 -244.98908)
			(xy 362.064808 -244.988588) (xy 363.004862 -244.988588) (xy 363.030147 -244.988978) (xy 363.080028 -244.997296)
			(xy 363.127859 -245.013711) (xy 363.172336 -245.037776) (xy 363.212245 -245.068834) (xy 363.246497 -245.106037)
			(xy 363.274158 -245.148371) (xy 363.294473 -245.194681) (xy 363.306888 -245.243703) (xy 363.311065 -245.2941)
			(xy 363.311061 -245.29415) (xy 363.639112 -245.29415) (xy 363.643072 -245.245096) (xy 363.654849 -245.197312)
			(xy 363.67414 -245.152036) (xy 363.700443 -245.11044) (xy 363.733078 -245.073603) (xy 363.771199 -245.042478)
			(xy 363.81382 -245.017871) (xy 363.859836 -245.000419) (xy 363.908055 -244.990575) (xy 363.95723 -244.988594)
			(xy 364.006085 -244.994526) (xy 364.053356 -245.008218) (xy 364.097818 -245.029316) (xy 364.138321 -245.057272)
			(xy 364.173814 -245.091364) (xy 364.203379 -245.130708) (xy 364.22625 -245.174285) (xy 364.241834 -245.220966)
			(xy 364.249729 -245.269543) (xy 364.250224 -245.29415) (xy 366.45902 -245.29415) (xy 366.46298 -245.245096)
			(xy 366.474757 -245.197312) (xy 366.494048 -245.152036) (xy 366.520351 -245.11044) (xy 366.552986 -245.073603)
			(xy 366.591107 -245.042478) (xy 366.633728 -245.017871) (xy 366.679744 -245.000419) (xy 366.727963 -244.990575)
			(xy 366.777138 -244.988594) (xy 366.825993 -244.994526) (xy 366.873264 -245.008218) (xy 366.917726 -245.029316)
			(xy 366.958229 -245.057272) (xy 366.993722 -245.091364) (xy 367.023287 -245.130708) (xy 367.046158 -245.174285)
			(xy 367.061742 -245.220966) (xy 367.069637 -245.269543) (xy 367.070132 -245.29415) (xy 369.278928 -245.29415)
			(xy 369.282888 -245.245096) (xy 369.294665 -245.197312) (xy 369.313956 -245.152036) (xy 369.340259 -245.11044)
			(xy 369.372894 -245.073603) (xy 369.411015 -245.042478) (xy 369.453636 -245.017871) (xy 369.499652 -245.000419)
			(xy 369.547871 -244.990575) (xy 369.597046 -244.988594) (xy 369.645901 -244.994526) (xy 369.693172 -245.008218)
			(xy 369.737634 -245.029316) (xy 369.778137 -245.057272) (xy 369.81363 -245.091364) (xy 369.843195 -245.130708)
			(xy 369.866066 -245.174285) (xy 369.88165 -245.220966) (xy 369.889545 -245.269543) (xy 369.89004 -245.29415)
			(xy 372.09909 -245.29415) (xy 372.10305 -245.245096) (xy 372.114827 -245.197312) (xy 372.134118 -245.152036)
			(xy 372.160421 -245.11044) (xy 372.193056 -245.073603) (xy 372.231177 -245.042478) (xy 372.273798 -245.017871)
			(xy 372.319814 -245.000419) (xy 372.368033 -244.990575) (xy 372.417208 -244.988594) (xy 372.466063 -244.994526)
			(xy 372.513334 -245.008218) (xy 372.557796 -245.029316) (xy 372.598299 -245.057272) (xy 372.633792 -245.091364)
			(xy 372.663357 -245.130708) (xy 372.686228 -245.174285) (xy 372.701812 -245.220966) (xy 372.709707 -245.269543)
			(xy 372.710202 -245.29415) (xy 372.709707 -245.318757) (xy 372.701812 -245.367334) (xy 372.686228 -245.414015)
			(xy 372.663357 -245.457592) (xy 372.633792 -245.496936) (xy 372.598299 -245.531028) (xy 372.557796 -245.558984)
			(xy 372.513334 -245.580082) (xy 372.466063 -245.593774) (xy 372.417208 -245.599706) (xy 372.368033 -245.597725)
			(xy 372.319814 -245.587881) (xy 372.273798 -245.570429) (xy 372.231177 -245.545822) (xy 372.193056 -245.514697)
			(xy 372.160421 -245.47786) (xy 372.134118 -245.436264) (xy 372.114827 -245.390988) (xy 372.10305 -245.343204)
			(xy 372.09909 -245.29415) (xy 369.89004 -245.29415) (xy 369.889545 -245.318757) (xy 369.88165 -245.367334)
			(xy 369.866066 -245.414015) (xy 369.843195 -245.457592) (xy 369.81363 -245.496936) (xy 369.778137 -245.531028)
			(xy 369.737634 -245.558984) (xy 369.693172 -245.580082) (xy 369.645901 -245.593774) (xy 369.597046 -245.599706)
			(xy 369.547871 -245.597725) (xy 369.499652 -245.587881) (xy 369.453636 -245.570429) (xy 369.411015 -245.545822)
			(xy 369.372894 -245.514697) (xy 369.340259 -245.47786) (xy 369.313956 -245.436264) (xy 369.294665 -245.390988)
			(xy 369.282888 -245.343204) (xy 369.278928 -245.29415) (xy 367.070132 -245.29415) (xy 367.069637 -245.318757)
			(xy 367.061742 -245.367334) (xy 367.046158 -245.414015) (xy 367.023287 -245.457592) (xy 366.993722 -245.496936)
			(xy 366.958229 -245.531028) (xy 366.917726 -245.558984) (xy 366.873264 -245.580082) (xy 366.825993 -245.593774)
			(xy 366.777138 -245.599706) (xy 366.727963 -245.597725) (xy 366.679744 -245.587881) (xy 366.633728 -245.570429)
			(xy 366.591107 -245.545822) (xy 366.552986 -245.514697) (xy 366.520351 -245.47786) (xy 366.494048 -245.436264)
			(xy 366.474757 -245.390988) (xy 366.46298 -245.343204) (xy 366.45902 -245.29415) (xy 364.250224 -245.29415)
			(xy 364.249729 -245.318757) (xy 364.241834 -245.367334) (xy 364.22625 -245.414015) (xy 364.203379 -245.457592)
			(xy 364.173814 -245.496936) (xy 364.138321 -245.531028) (xy 364.097818 -245.558984) (xy 364.053356 -245.580082)
			(xy 364.006085 -245.593774) (xy 363.95723 -245.599706) (xy 363.908055 -245.597725) (xy 363.859836 -245.587881)
			(xy 363.81382 -245.570429) (xy 363.771199 -245.545822) (xy 363.733078 -245.514697) (xy 363.700443 -245.47786)
			(xy 363.67414 -245.436264) (xy 363.654849 -245.390988) (xy 363.643072 -245.343204) (xy 363.639112 -245.29415)
			(xy 363.311061 -245.29415) (xy 363.306888 -245.344497) (xy 363.294473 -245.393519) (xy 363.274158 -245.439829)
			(xy 363.246497 -245.482163) (xy 363.212245 -245.519366) (xy 363.172336 -245.550424) (xy 363.127859 -245.574489)
			(xy 363.080028 -245.590904) (xy 363.030147 -245.599222) (xy 363.004862 -245.599712) (xy 362.064808 -245.599712)
			(xy 362.039533 -245.59912) (xy 361.989672 -245.590801) (xy 361.941861 -245.574388) (xy 361.897403 -245.55033)
			(xy 361.857511 -245.519282) (xy 361.823274 -245.482091) (xy 361.795626 -245.439773) (xy 361.775319 -245.393481)
			(xy 361.76291 -245.344477) (xy 361.758735 -245.2941) (xy 361.430061 -245.2941) (xy 361.430062 -245.29415)
			(xy 361.429567 -245.318757) (xy 361.421672 -245.367334) (xy 361.406088 -245.414015) (xy 361.383217 -245.457592)
			(xy 361.353652 -245.496936) (xy 361.318159 -245.531028) (xy 361.277656 -245.558984) (xy 361.233194 -245.580082)
			(xy 361.185923 -245.593774) (xy 361.137068 -245.599706) (xy 361.087893 -245.597725) (xy 361.039674 -245.587881)
			(xy 360.993658 -245.570429) (xy 360.951037 -245.545822) (xy 360.912916 -245.514697) (xy 360.880281 -245.47786)
			(xy 360.853978 -245.436264) (xy 360.834687 -245.390988) (xy 360.82291 -245.343204) (xy 360.81895 -245.29415)
			(xy 359.967877 -245.29415) (xy 359.969268 -245.29521) (xy 360.00578 -245.333148) (xy 360.036072 -245.376214)
			(xy 360.059435 -245.423399) (xy 360.075321 -245.473598) (xy 360.083358 -245.525634) (xy 360.083862 -245.55196)
			(xy 360.083358 -245.578286) (xy 360.075321 -245.630322) (xy 360.059435 -245.680521) (xy 360.036072 -245.727706)
			(xy 360.00578 -245.770772) (xy 359.969268 -245.80871) (xy 359.927394 -245.840629) (xy 359.881138 -245.865782)
			(xy 359.831585 -245.88358) (xy 359.779895 -245.893604) (xy 359.727281 -245.895621) (xy 359.674976 -245.889583)
			(xy 359.624205 -245.875631) (xy 359.57616 -245.854092) (xy 359.531965 -245.825472) (xy 359.492657 -245.790441)
			(xy 359.459157 -245.74982) (xy 359.432251 -245.704561) (xy 359.412568 -245.655726) (xy 359.400571 -245.604458)
			(xy 359.396541 -245.55196) (xy 358.474274 -245.55196) (xy 358.464098 -245.558984) (xy 358.419636 -245.580082)
			(xy 358.372365 -245.593774) (xy 358.32351 -245.599706) (xy 358.274335 -245.597725) (xy 358.226116 -245.587881)
			(xy 358.1801 -245.570429) (xy 358.137479 -245.545822) (xy 358.099358 -245.514697) (xy 358.066723 -245.47786)
			(xy 358.04042 -245.436264) (xy 358.021129 -245.390988) (xy 358.009352 -245.343204) (xy 358.005392 -245.29415)
			(xy 357.67645 -245.29415) (xy 357.675955 -245.318757) (xy 357.66806 -245.367334) (xy 357.652476 -245.414015)
			(xy 357.629605 -245.457592) (xy 357.60004 -245.496936) (xy 357.564547 -245.531028) (xy 357.524044 -245.558984)
			(xy 357.479582 -245.580082) (xy 357.432311 -245.593774) (xy 357.383456 -245.599706) (xy 357.334281 -245.597725)
			(xy 357.286062 -245.587881) (xy 357.240046 -245.570429) (xy 357.197425 -245.545822) (xy 357.159304 -245.514697)
			(xy 357.126669 -245.47786) (xy 357.100366 -245.436264) (xy 357.081075 -245.390988) (xy 357.069298 -245.343204)
			(xy 357.065338 -245.29415) (xy 356.736396 -245.29415) (xy 356.735901 -245.318757) (xy 356.728006 -245.367334)
			(xy 356.712422 -245.414015) (xy 356.689551 -245.457592) (xy 356.659986 -245.496936) (xy 356.624493 -245.531028)
			(xy 356.58399 -245.558984) (xy 356.539528 -245.580082) (xy 356.492257 -245.593774) (xy 356.443402 -245.599706)
			(xy 356.394227 -245.597725) (xy 356.346008 -245.587881) (xy 356.299992 -245.570429) (xy 356.257371 -245.545822)
			(xy 356.21925 -245.514697) (xy 356.186615 -245.47786) (xy 356.160312 -245.436264) (xy 356.141021 -245.390988)
			(xy 356.129244 -245.343204) (xy 356.125284 -245.29415) (xy 355.796342 -245.29415) (xy 355.795847 -245.318757)
			(xy 355.787952 -245.367334) (xy 355.772368 -245.414015) (xy 355.749497 -245.457592) (xy 355.719932 -245.496936)
			(xy 355.684439 -245.531028) (xy 355.643936 -245.558984) (xy 355.599474 -245.580082) (xy 355.552203 -245.593774)
			(xy 355.503348 -245.599706) (xy 355.454173 -245.597725) (xy 355.405954 -245.587881) (xy 355.359938 -245.570429)
			(xy 355.317317 -245.545822) (xy 355.279196 -245.514697) (xy 355.246561 -245.47786) (xy 355.220258 -245.436264)
			(xy 355.200967 -245.390988) (xy 355.18919 -245.343204) (xy 355.18523 -245.29415) (xy 352.976434 -245.29415)
			(xy 352.975939 -245.318757) (xy 352.968044 -245.367334) (xy 352.95246 -245.414015) (xy 352.929589 -245.457592)
			(xy 352.900024 -245.496936) (xy 352.864531 -245.531028) (xy 352.824028 -245.558984) (xy 352.779566 -245.580082)
			(xy 352.732295 -245.593774) (xy 352.68344 -245.599706) (xy 352.634265 -245.597725) (xy 352.586046 -245.587881)
			(xy 352.54003 -245.570429) (xy 352.497409 -245.545822) (xy 352.459288 -245.514697) (xy 352.426653 -245.47786)
			(xy 352.40035 -245.436264) (xy 352.381059 -245.390988) (xy 352.369282 -245.343204) (xy 352.365322 -245.29415)
			(xy 350.156526 -245.29415) (xy 350.156031 -245.318757) (xy 350.148136 -245.367334) (xy 350.132552 -245.414015)
			(xy 350.109681 -245.457592) (xy 350.080116 -245.496936) (xy 350.044623 -245.531028) (xy 350.00412 -245.558984)
			(xy 349.959658 -245.580082) (xy 349.912387 -245.593774) (xy 349.863532 -245.599706) (xy 349.814357 -245.597725)
			(xy 349.766138 -245.587881) (xy 349.720122 -245.570429) (xy 349.677501 -245.545822) (xy 349.63938 -245.514697)
			(xy 349.606745 -245.47786) (xy 349.580442 -245.436264) (xy 349.561151 -245.390988) (xy 349.549374 -245.343204)
			(xy 349.545414 -245.29415) (xy 347.336364 -245.29415) (xy 347.335869 -245.318757) (xy 347.327974 -245.367334)
			(xy 347.31239 -245.414015) (xy 347.289519 -245.457592) (xy 347.259954 -245.496936) (xy 347.224461 -245.531028)
			(xy 347.183958 -245.558984) (xy 347.139496 -245.580082) (xy 347.092225 -245.593774) (xy 347.04337 -245.599706)
			(xy 346.994195 -245.597725) (xy 346.945976 -245.587881) (xy 346.89996 -245.570429) (xy 346.857339 -245.545822)
			(xy 346.819218 -245.514697) (xy 346.786583 -245.47786) (xy 346.76028 -245.436264) (xy 346.740989 -245.390988)
			(xy 346.729212 -245.343204) (xy 346.725252 -245.29415) (xy 344.870532 -245.29415) (xy 344.870532 -245.831106)
			(xy 344.870673 -245.836403) (xy 344.872854 -245.846771) (xy 344.87485 -245.85168) (xy 344.886534 -245.878096)
			(xy 344.893646 -245.884954) (xy 344.910862 -245.902339) (xy 344.940087 -245.941576) (xy 344.962687 -245.984969)
			(xy 344.978084 -246.031408) (xy 344.985884 -246.079707) (xy 344.985886 -246.104156) (xy 345.315298 -246.104156)
			(xy 345.319258 -246.055102) (xy 345.331035 -246.007318) (xy 345.350326 -245.962042) (xy 345.376629 -245.920446)
			(xy 345.409264 -245.883609) (xy 345.447385 -245.852484) (xy 345.490006 -245.827877) (xy 345.536022 -245.810425)
			(xy 345.584241 -245.800581) (xy 345.633416 -245.7986) (xy 345.682271 -245.804532) (xy 345.729542 -245.818224)
			(xy 345.774004 -245.839322) (xy 345.814507 -245.867278) (xy 345.85 -245.90137) (xy 345.879565 -245.940714)
			(xy 345.902436 -245.984291) (xy 345.91802 -246.030972) (xy 345.925915 -246.079549) (xy 345.92641 -246.104156)
			(xy 346.255352 -246.104156) (xy 346.259312 -246.055102) (xy 346.271089 -246.007318) (xy 346.29038 -245.962042)
			(xy 346.316683 -245.920446) (xy 346.349318 -245.883609) (xy 346.387439 -245.852484) (xy 346.43006 -245.827877)
			(xy 346.476076 -245.810425) (xy 346.524295 -245.800581) (xy 346.57347 -245.7986) (xy 346.622325 -245.804532)
			(xy 346.669596 -245.818224) (xy 346.714058 -245.839322) (xy 346.754561 -245.867278) (xy 346.790054 -245.90137)
			(xy 346.819619 -245.940714) (xy 346.84249 -245.984291) (xy 346.858074 -246.030972) (xy 346.865969 -246.079549)
			(xy 346.866464 -246.104156) (xy 347.195406 -246.104156) (xy 347.199366 -246.055102) (xy 347.211143 -246.007318)
			(xy 347.230434 -245.962042) (xy 347.256737 -245.920446) (xy 347.289372 -245.883609) (xy 347.327493 -245.852484)
			(xy 347.370114 -245.827877) (xy 347.41613 -245.810425) (xy 347.464349 -245.800581) (xy 347.513524 -245.7986)
			(xy 347.562379 -245.804532) (xy 347.60965 -245.818224) (xy 347.654112 -245.839322) (xy 347.694615 -245.867278)
			(xy 347.730108 -245.90137) (xy 347.759673 -245.940714) (xy 347.782544 -245.984291) (xy 347.798128 -246.030972)
			(xy 347.806023 -246.079549) (xy 347.806518 -246.104156) (xy 348.135206 -246.104156) (xy 348.139166 -246.055102)
			(xy 348.150943 -246.007318) (xy 348.170234 -245.962042) (xy 348.196537 -245.920446) (xy 348.229172 -245.883609)
			(xy 348.267293 -245.852484) (xy 348.309914 -245.827877) (xy 348.35593 -245.810425) (xy 348.404149 -245.800581)
			(xy 348.453324 -245.7986) (xy 348.502179 -245.804532) (xy 348.54945 -245.818224) (xy 348.593912 -245.839322)
			(xy 348.634415 -245.867278) (xy 348.669908 -245.90137) (xy 348.699473 -245.940714) (xy 348.722344 -245.984291)
			(xy 348.737928 -246.030972) (xy 348.745823 -246.079549) (xy 348.746318 -246.104156) (xy 349.07526 -246.104156)
			(xy 349.07922 -246.055102) (xy 349.090997 -246.007318) (xy 349.110288 -245.962042) (xy 349.136591 -245.920446)
			(xy 349.169226 -245.883609) (xy 349.207347 -245.852484) (xy 349.249968 -245.827877) (xy 349.295984 -245.810425)
			(xy 349.344203 -245.800581) (xy 349.393378 -245.7986) (xy 349.442233 -245.804532) (xy 349.489504 -245.818224)
			(xy 349.533966 -245.839322) (xy 349.574469 -245.867278) (xy 349.609962 -245.90137) (xy 349.639527 -245.940714)
			(xy 349.662398 -245.984291) (xy 349.677982 -246.030972) (xy 349.685877 -246.079549) (xy 349.686372 -246.104156)
			(xy 350.015314 -246.104156) (xy 350.019274 -246.055102) (xy 350.031051 -246.007318) (xy 350.050342 -245.962042)
			(xy 350.076645 -245.920446) (xy 350.10928 -245.883609) (xy 350.147401 -245.852484) (xy 350.190022 -245.827877)
			(xy 350.236038 -245.810425) (xy 350.284257 -245.800581) (xy 350.333432 -245.7986) (xy 350.382287 -245.804532)
			(xy 350.429558 -245.818224) (xy 350.47402 -245.839322) (xy 350.514523 -245.867278) (xy 350.550016 -245.90137)
			(xy 350.579581 -245.940714) (xy 350.602452 -245.984291) (xy 350.618036 -246.030972) (xy 350.625931 -246.079549)
			(xy 350.626426 -246.104156) (xy 350.955368 -246.104156) (xy 350.959328 -246.055102) (xy 350.971105 -246.007318)
			(xy 350.990396 -245.962042) (xy 351.016699 -245.920446) (xy 351.049334 -245.883609) (xy 351.087455 -245.852484)
			(xy 351.130076 -245.827877) (xy 351.176092 -245.810425) (xy 351.224311 -245.800581) (xy 351.273486 -245.7986)
			(xy 351.322341 -245.804532) (xy 351.369612 -245.818224) (xy 351.414074 -245.839322) (xy 351.454577 -245.867278)
			(xy 351.49007 -245.90137) (xy 351.519635 -245.940714) (xy 351.542506 -245.984291) (xy 351.55809 -246.030972)
			(xy 351.565985 -246.079549) (xy 351.56648 -246.104156) (xy 351.895422 -246.104156) (xy 351.899382 -246.055102)
			(xy 351.911159 -246.007318) (xy 351.93045 -245.962042) (xy 351.956753 -245.920446) (xy 351.989388 -245.883609)
			(xy 352.027509 -245.852484) (xy 352.07013 -245.827877) (xy 352.116146 -245.810425) (xy 352.164365 -245.800581)
			(xy 352.21354 -245.7986) (xy 352.262395 -245.804532) (xy 352.309666 -245.818224) (xy 352.354128 -245.839322)
			(xy 352.394631 -245.867278) (xy 352.430124 -245.90137) (xy 352.459689 -245.940714) (xy 352.48256 -245.984291)
			(xy 352.498144 -246.030972) (xy 352.506039 -246.079549) (xy 352.506534 -246.104156) (xy 352.835222 -246.104156)
			(xy 352.839182 -246.055102) (xy 352.850959 -246.007318) (xy 352.87025 -245.962042) (xy 352.896553 -245.920446)
			(xy 352.929188 -245.883609) (xy 352.967309 -245.852484) (xy 353.00993 -245.827877) (xy 353.055946 -245.810425)
			(xy 353.104165 -245.800581) (xy 353.15334 -245.7986) (xy 353.202195 -245.804532) (xy 353.249466 -245.818224)
			(xy 353.293928 -245.839322) (xy 353.334431 -245.867278) (xy 353.369924 -245.90137) (xy 353.399489 -245.940714)
			(xy 353.42236 -245.984291) (xy 353.437944 -246.030972) (xy 353.445839 -246.079549) (xy 353.446334 -246.104156)
			(xy 353.775276 -246.104156) (xy 353.779236 -246.055102) (xy 353.791013 -246.007318) (xy 353.810304 -245.962042)
			(xy 353.836607 -245.920446) (xy 353.869242 -245.883609) (xy 353.907363 -245.852484) (xy 353.949984 -245.827877)
			(xy 353.996 -245.810425) (xy 354.044219 -245.800581) (xy 354.093394 -245.7986) (xy 354.142249 -245.804532)
			(xy 354.18952 -245.818224) (xy 354.233982 -245.839322) (xy 354.274485 -245.867278) (xy 354.309978 -245.90137)
			(xy 354.339543 -245.940714) (xy 354.362414 -245.984291) (xy 354.377998 -246.030972) (xy 354.385893 -246.079549)
			(xy 354.386388 -246.104156) (xy 354.71533 -246.104156) (xy 354.71929 -246.055102) (xy 354.731067 -246.007318)
			(xy 354.750358 -245.962042) (xy 354.776661 -245.920446) (xy 354.809296 -245.883609) (xy 354.847417 -245.852484)
			(xy 354.890038 -245.827877) (xy 354.936054 -245.810425) (xy 354.984273 -245.800581) (xy 355.033448 -245.7986)
			(xy 355.082303 -245.804532) (xy 355.129574 -245.818224) (xy 355.174036 -245.839322) (xy 355.214539 -245.867278)
			(xy 355.250032 -245.90137) (xy 355.279597 -245.940714) (xy 355.302468 -245.984291) (xy 355.318052 -246.030972)
			(xy 355.325947 -246.079549) (xy 355.326442 -246.104156) (xy 355.655384 -246.104156) (xy 355.659344 -246.055102)
			(xy 355.671121 -246.007318) (xy 355.690412 -245.962042) (xy 355.716715 -245.920446) (xy 355.74935 -245.883609)
			(xy 355.787471 -245.852484) (xy 355.830092 -245.827877) (xy 355.876108 -245.810425) (xy 355.924327 -245.800581)
			(xy 355.973502 -245.7986) (xy 356.022357 -245.804532) (xy 356.069628 -245.818224) (xy 356.11409 -245.839322)
			(xy 356.154593 -245.867278) (xy 356.190086 -245.90137) (xy 356.219651 -245.940714) (xy 356.242522 -245.984291)
			(xy 356.258106 -246.030972) (xy 356.266001 -246.079549) (xy 356.266496 -246.104156) (xy 363.168958 -246.104156)
			(xy 363.172918 -246.055102) (xy 363.184695 -246.007318) (xy 363.203986 -245.962042) (xy 363.230289 -245.920446)
			(xy 363.262924 -245.883609) (xy 363.301045 -245.852484) (xy 363.343666 -245.827877) (xy 363.389682 -245.810425)
			(xy 363.437901 -245.800581) (xy 363.487076 -245.7986) (xy 363.535931 -245.804532) (xy 363.583202 -245.818224)
			(xy 363.627664 -245.839322) (xy 363.668167 -245.867278) (xy 363.70366 -245.90137) (xy 363.733225 -245.940714)
			(xy 363.756096 -245.984291) (xy 363.77168 -246.030972) (xy 363.779575 -246.079549) (xy 363.78007 -246.104156)
			(xy 363.780069 -246.1042) (xy 364.108896 -246.1042) (xy 364.113068 -246.053848) (xy 364.125472 -246.00487)
			(xy 364.145768 -245.958601) (xy 364.173403 -245.916305) (xy 364.207623 -245.879133) (xy 364.247495 -245.848102)
			(xy 364.291931 -245.824057) (xy 364.339718 -245.807653) (xy 364.389554 -245.79934) (xy 364.414816 -245.798848)
			(xy 365.35487 -245.798848) (xy 365.380126 -245.799426) (xy 365.429949 -245.807736) (xy 365.477725 -245.824133)
			(xy 365.52215 -245.848171) (xy 365.562012 -245.879193) (xy 365.596224 -245.916354) (xy 365.623853 -245.958639)
			(xy 365.644144 -246.004896) (xy 365.656545 -246.053861) (xy 365.660712 -246.104156) (xy 365.98912 -246.104156)
			(xy 365.99308 -246.055102) (xy 366.004857 -246.007318) (xy 366.024148 -245.962042) (xy 366.050451 -245.920446)
			(xy 366.083086 -245.883609) (xy 366.121207 -245.852484) (xy 366.163828 -245.827877) (xy 366.209844 -245.810425)
			(xy 366.258063 -245.800581) (xy 366.307238 -245.7986) (xy 366.356093 -245.804532) (xy 366.403364 -245.818224)
			(xy 366.447826 -245.839322) (xy 366.488329 -245.867278) (xy 366.523822 -245.90137) (xy 366.553387 -245.940714)
			(xy 366.576258 -245.984291) (xy 366.591842 -246.030972) (xy 366.599737 -246.079549) (xy 366.600232 -246.104156)
			(xy 366.600231 -246.1042) (xy 366.928796 -246.1042) (xy 366.932969 -246.053847) (xy 366.945372 -246.004868)
			(xy 366.965669 -245.958599) (xy 366.993305 -245.916302) (xy 367.027526 -245.879131) (xy 367.067399 -245.848099)
			(xy 367.111836 -245.824054) (xy 367.159625 -245.807652) (xy 367.209461 -245.799339) (xy 367.234724 -245.798848)
			(xy 368.174778 -245.798848) (xy 368.200033 -245.799427) (xy 368.249855 -245.807737) (xy 368.29763 -245.824135)
			(xy 368.342054 -245.848173) (xy 368.381915 -245.879196) (xy 368.416126 -245.916357) (xy 368.443754 -245.958642)
			(xy 368.464045 -246.004897) (xy 368.476445 -246.053862) (xy 368.480612 -246.104156) (xy 368.809028 -246.104156)
			(xy 368.812988 -246.055102) (xy 368.824765 -246.007318) (xy 368.844056 -245.962042) (xy 368.870359 -245.920446)
			(xy 368.902994 -245.883609) (xy 368.941115 -245.852484) (xy 368.983736 -245.827877) (xy 369.029752 -245.810425)
			(xy 369.077971 -245.800581) (xy 369.127146 -245.7986) (xy 369.176001 -245.804532) (xy 369.223272 -245.818224)
			(xy 369.267734 -245.839322) (xy 369.308237 -245.867278) (xy 369.34373 -245.90137) (xy 369.373295 -245.940714)
			(xy 369.396166 -245.984291) (xy 369.41175 -246.030972) (xy 369.419645 -246.079549) (xy 369.42014 -246.104156)
			(xy 369.420139 -246.1042) (xy 369.749024 -246.1042) (xy 369.753196 -246.053856) (xy 369.765597 -246.004885)
			(xy 369.785888 -245.958623) (xy 369.813518 -245.916332) (xy 369.847731 -245.879165) (xy 369.887595 -245.848136)
			(xy 369.932022 -245.824092) (xy 369.979801 -245.807687) (xy 370.029628 -245.79937) (xy 370.054886 -245.798848)
			(xy 370.99494 -245.798848) (xy 371.02019 -245.799461) (xy 371.069999 -245.807778) (xy 371.11776 -245.82418)
			(xy 371.162171 -245.848219) (xy 371.202019 -245.879239) (xy 371.236219 -245.916395) (xy 371.263838 -245.958673)
			(xy 371.284121 -246.004919) (xy 371.296517 -246.053873) (xy 371.300683 -246.104156) (xy 371.628936 -246.104156)
			(xy 371.632896 -246.055102) (xy 371.644673 -246.007318) (xy 371.663964 -245.962042) (xy 371.690267 -245.920446)
			(xy 371.722902 -245.883609) (xy 371.761023 -245.852484) (xy 371.803644 -245.827877) (xy 371.84966 -245.810425)
			(xy 371.897879 -245.800581) (xy 371.947054 -245.7986) (xy 371.995909 -245.804532) (xy 372.04318 -245.818224)
			(xy 372.087642 -245.839322) (xy 372.128145 -245.867278) (xy 372.163638 -245.90137) (xy 372.193203 -245.940714)
			(xy 372.216074 -245.984291) (xy 372.231658 -246.030972) (xy 372.239553 -246.079549) (xy 372.240048 -246.104156)
			(xy 372.240047 -246.1042) (xy 372.568924 -246.1042) (xy 372.573096 -246.053855) (xy 372.585497 -246.004884)
			(xy 372.60579 -245.958621) (xy 372.63342 -245.916329) (xy 372.667634 -245.879162) (xy 372.707499 -245.848133)
			(xy 372.751927 -245.824089) (xy 372.799707 -245.807685) (xy 372.849535 -245.79937) (xy 372.874794 -245.798848)
			(xy 373.814848 -245.798848) (xy 373.840097 -245.799461) (xy 373.889906 -245.80778) (xy 373.937666 -245.824183)
			(xy 373.982075 -245.848222) (xy 374.021923 -245.879242) (xy 374.056121 -245.916398) (xy 374.083739 -245.958675)
			(xy 374.104022 -246.004921) (xy 374.116417 -246.053874) (xy 374.120587 -246.1042) (xy 374.116417 -246.154526)
			(xy 374.104022 -246.203479) (xy 374.083739 -246.249725) (xy 374.056121 -246.292002) (xy 374.021923 -246.329158)
			(xy 373.982075 -246.360178) (xy 373.937666 -246.384217) (xy 373.889906 -246.40062) (xy 373.840097 -246.408939)
			(xy 373.814848 -246.409464) (xy 372.874794 -246.409464) (xy 372.849535 -246.40903) (xy 372.799707 -246.400715)
			(xy 372.751927 -246.384311) (xy 372.707499 -246.360267) (xy 372.667634 -246.329238) (xy 372.63342 -246.292071)
			(xy 372.60579 -246.249779) (xy 372.585497 -246.203516) (xy 372.573096 -246.154545) (xy 372.568924 -246.1042)
			(xy 372.240047 -246.1042) (xy 372.239553 -246.128763) (xy 372.231658 -246.17734) (xy 372.216074 -246.224021)
			(xy 372.193203 -246.267598) (xy 372.163638 -246.306942) (xy 372.128145 -246.341034) (xy 372.087642 -246.36899)
			(xy 372.04318 -246.390088) (xy 371.995909 -246.40378) (xy 371.947054 -246.409712) (xy 371.897879 -246.407731)
			(xy 371.84966 -246.397887) (xy 371.803644 -246.380435) (xy 371.761023 -246.355828) (xy 371.722902 -246.324703)
			(xy 371.690267 -246.287866) (xy 371.663964 -246.24627) (xy 371.644673 -246.200994) (xy 371.632896 -246.15321)
			(xy 371.628936 -246.104156) (xy 371.300683 -246.104156) (xy 371.300687 -246.1042) (xy 371.296517 -246.154527)
			(xy 371.284121 -246.203481) (xy 371.263838 -246.249727) (xy 371.236219 -246.292005) (xy 371.202019 -246.329161)
			(xy 371.162171 -246.360181) (xy 371.11776 -246.38422) (xy 371.069999 -246.400622) (xy 371.02019 -246.408939)
			(xy 370.99494 -246.409464) (xy 370.054886 -246.409464) (xy 370.029628 -246.40903) (xy 369.979801 -246.400713)
			(xy 369.932022 -246.384308) (xy 369.887595 -246.360264) (xy 369.847731 -246.329235) (xy 369.813518 -246.292068)
			(xy 369.785888 -246.249777) (xy 369.765597 -246.203515) (xy 369.753196 -246.154544) (xy 369.749024 -246.1042)
			(xy 369.420139 -246.1042) (xy 369.419645 -246.128763) (xy 369.41175 -246.17734) (xy 369.396166 -246.224021)
			(xy 369.373295 -246.267598) (xy 369.34373 -246.306942) (xy 369.308237 -246.341034) (xy 369.267734 -246.36899)
			(xy 369.223272 -246.390088) (xy 369.176001 -246.40378) (xy 369.127146 -246.409712) (xy 369.077971 -246.407731)
			(xy 369.029752 -246.397887) (xy 368.983736 -246.380435) (xy 368.941115 -246.355828) (xy 368.902994 -246.324703)
			(xy 368.870359 -246.287866) (xy 368.844056 -246.24627) (xy 368.824765 -246.200994) (xy 368.812988 -246.15321)
			(xy 368.809028 -246.104156) (xy 368.480612 -246.104156) (xy 368.480616 -246.1042) (xy 368.476445 -246.154538)
			(xy 368.464045 -246.203503) (xy 368.443754 -246.249758) (xy 368.416126 -246.292043) (xy 368.381915 -246.329204)
			(xy 368.342054 -246.360227) (xy 368.29763 -246.384265) (xy 368.249855 -246.400663) (xy 368.200033 -246.408973)
			(xy 368.174778 -246.409464) (xy 367.234724 -246.409464) (xy 367.209461 -246.409061) (xy 367.159625 -246.400748)
			(xy 367.111836 -246.384346) (xy 367.067399 -246.360301) (xy 367.027526 -246.329269) (xy 366.993305 -246.292098)
			(xy 366.965669 -246.249801) (xy 366.945372 -246.203532) (xy 366.932969 -246.154553) (xy 366.928796 -246.1042)
			(xy 366.600231 -246.1042) (xy 366.599737 -246.128763) (xy 366.591842 -246.17734) (xy 366.576258 -246.224021)
			(xy 366.553387 -246.267598) (xy 366.523822 -246.306942) (xy 366.488329 -246.341034) (xy 366.447826 -246.36899)
			(xy 366.403364 -246.390088) (xy 366.356093 -246.40378) (xy 366.307238 -246.409712) (xy 366.258063 -246.407731)
			(xy 366.209844 -246.397887) (xy 366.163828 -246.380435) (xy 366.121207 -246.355828) (xy 366.083086 -246.324703)
			(xy 366.050451 -246.287866) (xy 366.024148 -246.24627) (xy 366.004857 -246.200994) (xy 365.99308 -246.15321)
			(xy 365.98912 -246.104156) (xy 365.660712 -246.104156) (xy 365.660716 -246.1042) (xy 365.656545 -246.154539)
			(xy 365.644144 -246.203504) (xy 365.623853 -246.249761) (xy 365.596224 -246.292046) (xy 365.562012 -246.329207)
			(xy 365.52215 -246.360229) (xy 365.477725 -246.384267) (xy 365.429949 -246.400664) (xy 365.380126 -246.408974)
			(xy 365.35487 -246.409464) (xy 364.414816 -246.409464) (xy 364.389554 -246.40906) (xy 364.339718 -246.400747)
			(xy 364.291931 -246.384343) (xy 364.247495 -246.360298) (xy 364.207623 -246.329267) (xy 364.173403 -246.292095)
			(xy 364.145768 -246.249799) (xy 364.125472 -246.20353) (xy 364.113068 -246.154552) (xy 364.108896 -246.1042)
			(xy 363.780069 -246.1042) (xy 363.779575 -246.128763) (xy 363.77168 -246.17734) (xy 363.756096 -246.224021)
			(xy 363.733225 -246.267598) (xy 363.70366 -246.306942) (xy 363.668167 -246.341034) (xy 363.627664 -246.36899)
			(xy 363.583202 -246.390088) (xy 363.535931 -246.40378) (xy 363.487076 -246.409712) (xy 363.437901 -246.407731)
			(xy 363.389682 -246.397887) (xy 363.343666 -246.380435) (xy 363.301045 -246.355828) (xy 363.262924 -246.324703)
			(xy 363.230289 -246.287866) (xy 363.203986 -246.24627) (xy 363.184695 -246.200994) (xy 363.172918 -246.15321)
			(xy 363.168958 -246.104156) (xy 356.266496 -246.104156) (xy 356.266001 -246.128763) (xy 356.258106 -246.17734)
			(xy 356.242522 -246.224021) (xy 356.219651 -246.267598) (xy 356.190086 -246.306942) (xy 356.154593 -246.341034)
			(xy 356.11409 -246.36899) (xy 356.069628 -246.390088) (xy 356.022357 -246.40378) (xy 355.973502 -246.409712)
			(xy 355.924327 -246.407731) (xy 355.876108 -246.397887) (xy 355.830092 -246.380435) (xy 355.787471 -246.355828)
			(xy 355.74935 -246.324703) (xy 355.716715 -246.287866) (xy 355.690412 -246.24627) (xy 355.671121 -246.200994)
			(xy 355.659344 -246.15321) (xy 355.655384 -246.104156) (xy 355.326442 -246.104156) (xy 355.325947 -246.128763)
			(xy 355.318052 -246.17734) (xy 355.302468 -246.224021) (xy 355.279597 -246.267598) (xy 355.250032 -246.306942)
			(xy 355.214539 -246.341034) (xy 355.174036 -246.36899) (xy 355.129574 -246.390088) (xy 355.082303 -246.40378)
			(xy 355.033448 -246.409712) (xy 354.984273 -246.407731) (xy 354.936054 -246.397887) (xy 354.890038 -246.380435)
			(xy 354.847417 -246.355828) (xy 354.809296 -246.324703) (xy 354.776661 -246.287866) (xy 354.750358 -246.24627)
			(xy 354.731067 -246.200994) (xy 354.71929 -246.15321) (xy 354.71533 -246.104156) (xy 354.386388 -246.104156)
			(xy 354.385893 -246.128763) (xy 354.377998 -246.17734) (xy 354.362414 -246.224021) (xy 354.339543 -246.267598)
			(xy 354.309978 -246.306942) (xy 354.274485 -246.341034) (xy 354.233982 -246.36899) (xy 354.18952 -246.390088)
			(xy 354.142249 -246.40378) (xy 354.093394 -246.409712) (xy 354.044219 -246.407731) (xy 353.996 -246.397887)
			(xy 353.949984 -246.380435) (xy 353.907363 -246.355828) (xy 353.869242 -246.324703) (xy 353.836607 -246.287866)
			(xy 353.810304 -246.24627) (xy 353.791013 -246.200994) (xy 353.779236 -246.15321) (xy 353.775276 -246.104156)
			(xy 353.446334 -246.104156) (xy 353.445839 -246.128763) (xy 353.437944 -246.17734) (xy 353.42236 -246.224021)
			(xy 353.399489 -246.267598) (xy 353.369924 -246.306942) (xy 353.334431 -246.341034) (xy 353.293928 -246.36899)
			(xy 353.249466 -246.390088) (xy 353.202195 -246.40378) (xy 353.15334 -246.409712) (xy 353.104165 -246.407731)
			(xy 353.055946 -246.397887) (xy 353.00993 -246.380435) (xy 352.967309 -246.355828) (xy 352.929188 -246.324703)
			(xy 352.896553 -246.287866) (xy 352.87025 -246.24627) (xy 352.850959 -246.200994) (xy 352.839182 -246.15321)
			(xy 352.835222 -246.104156) (xy 352.506534 -246.104156) (xy 352.506039 -246.128763) (xy 352.498144 -246.17734)
			(xy 352.48256 -246.224021) (xy 352.459689 -246.267598) (xy 352.430124 -246.306942) (xy 352.394631 -246.341034)
			(xy 352.354128 -246.36899) (xy 352.309666 -246.390088) (xy 352.262395 -246.40378) (xy 352.21354 -246.409712)
			(xy 352.164365 -246.407731) (xy 352.116146 -246.397887) (xy 352.07013 -246.380435) (xy 352.027509 -246.355828)
			(xy 351.989388 -246.324703) (xy 351.956753 -246.287866) (xy 351.93045 -246.24627) (xy 351.911159 -246.200994)
			(xy 351.899382 -246.15321) (xy 351.895422 -246.104156) (xy 351.56648 -246.104156) (xy 351.565985 -246.128763)
			(xy 351.55809 -246.17734) (xy 351.542506 -246.224021) (xy 351.519635 -246.267598) (xy 351.49007 -246.306942)
			(xy 351.454577 -246.341034) (xy 351.414074 -246.36899) (xy 351.369612 -246.390088) (xy 351.322341 -246.40378)
			(xy 351.273486 -246.409712) (xy 351.224311 -246.407731) (xy 351.176092 -246.397887) (xy 351.130076 -246.380435)
			(xy 351.087455 -246.355828) (xy 351.049334 -246.324703) (xy 351.016699 -246.287866) (xy 350.990396 -246.24627)
			(xy 350.971105 -246.200994) (xy 350.959328 -246.15321) (xy 350.955368 -246.104156) (xy 350.626426 -246.104156)
			(xy 350.625931 -246.128763) (xy 350.618036 -246.17734) (xy 350.602452 -246.224021) (xy 350.579581 -246.267598)
			(xy 350.550016 -246.306942) (xy 350.514523 -246.341034) (xy 350.47402 -246.36899) (xy 350.429558 -246.390088)
			(xy 350.382287 -246.40378) (xy 350.333432 -246.409712) (xy 350.284257 -246.407731) (xy 350.236038 -246.397887)
			(xy 350.190022 -246.380435) (xy 350.147401 -246.355828) (xy 350.10928 -246.324703) (xy 350.076645 -246.287866)
			(xy 350.050342 -246.24627) (xy 350.031051 -246.200994) (xy 350.019274 -246.15321) (xy 350.015314 -246.104156)
			(xy 349.686372 -246.104156) (xy 349.685877 -246.128763) (xy 349.677982 -246.17734) (xy 349.662398 -246.224021)
			(xy 349.639527 -246.267598) (xy 349.609962 -246.306942) (xy 349.574469 -246.341034) (xy 349.533966 -246.36899)
			(xy 349.489504 -246.390088) (xy 349.442233 -246.40378) (xy 349.393378 -246.409712) (xy 349.344203 -246.407731)
			(xy 349.295984 -246.397887) (xy 349.249968 -246.380435) (xy 349.207347 -246.355828) (xy 349.169226 -246.324703)
			(xy 349.136591 -246.287866) (xy 349.110288 -246.24627) (xy 349.090997 -246.200994) (xy 349.07922 -246.15321)
			(xy 349.07526 -246.104156) (xy 348.746318 -246.104156) (xy 348.745823 -246.128763) (xy 348.737928 -246.17734)
			(xy 348.722344 -246.224021) (xy 348.699473 -246.267598) (xy 348.669908 -246.306942) (xy 348.634415 -246.341034)
			(xy 348.593912 -246.36899) (xy 348.54945 -246.390088) (xy 348.502179 -246.40378) (xy 348.453324 -246.409712)
			(xy 348.404149 -246.407731) (xy 348.35593 -246.397887) (xy 348.309914 -246.380435) (xy 348.267293 -246.355828)
			(xy 348.229172 -246.324703) (xy 348.196537 -246.287866) (xy 348.170234 -246.24627) (xy 348.150943 -246.200994)
			(xy 348.139166 -246.15321) (xy 348.135206 -246.104156) (xy 347.806518 -246.104156) (xy 347.806023 -246.128763)
			(xy 347.798128 -246.17734) (xy 347.782544 -246.224021) (xy 347.759673 -246.267598) (xy 347.730108 -246.306942)
			(xy 347.694615 -246.341034) (xy 347.654112 -246.36899) (xy 347.60965 -246.390088) (xy 347.562379 -246.40378)
			(xy 347.513524 -246.409712) (xy 347.464349 -246.407731) (xy 347.41613 -246.397887) (xy 347.370114 -246.380435)
			(xy 347.327493 -246.355828) (xy 347.289372 -246.324703) (xy 347.256737 -246.287866) (xy 347.230434 -246.24627)
			(xy 347.211143 -246.200994) (xy 347.199366 -246.15321) (xy 347.195406 -246.104156) (xy 346.866464 -246.104156)
			(xy 346.865969 -246.128763) (xy 346.858074 -246.17734) (xy 346.84249 -246.224021) (xy 346.819619 -246.267598)
			(xy 346.790054 -246.306942) (xy 346.754561 -246.341034) (xy 346.714058 -246.36899) (xy 346.669596 -246.390088)
			(xy 346.622325 -246.40378) (xy 346.57347 -246.409712) (xy 346.524295 -246.407731) (xy 346.476076 -246.397887)
			(xy 346.43006 -246.380435) (xy 346.387439 -246.355828) (xy 346.349318 -246.324703) (xy 346.316683 -246.287866)
			(xy 346.29038 -246.24627) (xy 346.271089 -246.200994) (xy 346.259312 -246.15321) (xy 346.255352 -246.104156)
			(xy 345.92641 -246.104156) (xy 345.925915 -246.128763) (xy 345.91802 -246.17734) (xy 345.902436 -246.224021)
			(xy 345.879565 -246.267598) (xy 345.85 -246.306942) (xy 345.814507 -246.341034) (xy 345.774004 -246.36899)
			(xy 345.729542 -246.390088) (xy 345.682271 -246.40378) (xy 345.633416 -246.409712) (xy 345.584241 -246.407731)
			(xy 345.536022 -246.397887) (xy 345.490006 -246.380435) (xy 345.447385 -246.355828) (xy 345.409264 -246.324703)
			(xy 345.376629 -246.287866) (xy 345.350326 -246.24627) (xy 345.331035 -246.200994) (xy 345.319258 -246.15321)
			(xy 345.315298 -246.104156) (xy 344.985886 -246.104156) (xy 344.985889 -246.128632) (xy 344.978098 -246.176932)
			(xy 344.962711 -246.223375) (xy 344.94012 -246.266772) (xy 344.910902 -246.306014) (xy 344.893646 -246.323358)
			(xy 344.886534 -246.330216) (xy 344.87485 -246.356632) (xy 344.872819 -246.36153) (xy 344.87064 -246.371905)
			(xy 344.870532 -246.377206) (xy 344.870532 -246.550942) (xy 344.870869 -246.55958) (xy 344.876622 -246.575869)
			(xy 344.887487 -246.5893) (xy 344.894662 -246.594122) (xy 344.96629 -246.638318) (xy 344.971846 -246.641465)
			(xy 344.984054 -246.645193) (xy 344.99042 -246.645684) (xy 345.003628 -246.646446) (xy 345.015566 -246.640604)
			(xy 345.036756 -246.630582) (xy 345.081443 -246.616434) (xy 345.127766 -246.609276) (xy 345.151202 -246.608854)
			(xy 345.175194 -246.609325) (xy 345.222588 -246.616831) (xy 345.268224 -246.631658) (xy 345.310979 -246.653441)
			(xy 345.349801 -246.681644) (xy 345.383733 -246.715572) (xy 345.41194 -246.75439) (xy 345.433728 -246.797143)
			(xy 345.448561 -246.842777) (xy 345.456072 -246.89017) (xy 345.45651 -246.914162) (xy 345.785198 -246.914162)
			(xy 345.789158 -246.865108) (xy 345.800935 -246.817324) (xy 345.820226 -246.772048) (xy 345.846529 -246.730452)
			(xy 345.879164 -246.693615) (xy 345.917285 -246.66249) (xy 345.959906 -246.637883) (xy 346.005922 -246.620431)
			(xy 346.054141 -246.610587) (xy 346.103316 -246.608606) (xy 346.152171 -246.614538) (xy 346.199442 -246.62823)
			(xy 346.243904 -246.649328) (xy 346.284407 -246.677284) (xy 346.3199 -246.711376) (xy 346.349465 -246.75072)
			(xy 346.372336 -246.794297) (xy 346.38792 -246.840978) (xy 346.395815 -246.889555) (xy 346.39631 -246.914162)
			(xy 346.725252 -246.914162) (xy 346.729212 -246.865108) (xy 346.740989 -246.817324) (xy 346.76028 -246.772048)
			(xy 346.786583 -246.730452) (xy 346.819218 -246.693615) (xy 346.857339 -246.66249) (xy 346.89996 -246.637883)
			(xy 346.945976 -246.620431) (xy 346.994195 -246.610587) (xy 347.04337 -246.608606) (xy 347.092225 -246.614538)
			(xy 347.139496 -246.62823) (xy 347.183958 -246.649328) (xy 347.224461 -246.677284) (xy 347.259954 -246.711376)
			(xy 347.289519 -246.75072) (xy 347.31239 -246.794297) (xy 347.327974 -246.840978) (xy 347.335869 -246.889555)
			(xy 347.336364 -246.914162) (xy 347.665306 -246.914162) (xy 347.669266 -246.865108) (xy 347.681043 -246.817324)
			(xy 347.700334 -246.772048) (xy 347.726637 -246.730452) (xy 347.759272 -246.693615) (xy 347.797393 -246.66249)
			(xy 347.840014 -246.637883) (xy 347.88603 -246.620431) (xy 347.934249 -246.610587) (xy 347.983424 -246.608606)
			(xy 348.032279 -246.614538) (xy 348.07955 -246.62823) (xy 348.124012 -246.649328) (xy 348.164515 -246.677284)
			(xy 348.200008 -246.711376) (xy 348.229573 -246.75072) (xy 348.252444 -246.794297) (xy 348.268028 -246.840978)
			(xy 348.275923 -246.889555) (xy 348.276418 -246.914162) (xy 348.60536 -246.914162) (xy 348.60932 -246.865108)
			(xy 348.621097 -246.817324) (xy 348.640388 -246.772048) (xy 348.666691 -246.730452) (xy 348.699326 -246.693615)
			(xy 348.737447 -246.66249) (xy 348.780068 -246.637883) (xy 348.826084 -246.620431) (xy 348.874303 -246.610587)
			(xy 348.923478 -246.608606) (xy 348.972333 -246.614538) (xy 349.019604 -246.62823) (xy 349.064066 -246.649328)
			(xy 349.104569 -246.677284) (xy 349.140062 -246.711376) (xy 349.169627 -246.75072) (xy 349.192498 -246.794297)
			(xy 349.208082 -246.840978) (xy 349.215977 -246.889555) (xy 349.216472 -246.914162) (xy 349.545414 -246.914162)
			(xy 349.549374 -246.865108) (xy 349.561151 -246.817324) (xy 349.580442 -246.772048) (xy 349.606745 -246.730452)
			(xy 349.63938 -246.693615) (xy 349.677501 -246.66249) (xy 349.720122 -246.637883) (xy 349.766138 -246.620431)
			(xy 349.814357 -246.610587) (xy 349.863532 -246.608606) (xy 349.912387 -246.614538) (xy 349.959658 -246.62823)
			(xy 350.00412 -246.649328) (xy 350.044623 -246.677284) (xy 350.080116 -246.711376) (xy 350.109681 -246.75072)
			(xy 350.132552 -246.794297) (xy 350.148136 -246.840978) (xy 350.156031 -246.889555) (xy 350.156526 -246.914162)
			(xy 350.485214 -246.914162) (xy 350.489174 -246.865108) (xy 350.500951 -246.817324) (xy 350.520242 -246.772048)
			(xy 350.546545 -246.730452) (xy 350.57918 -246.693615) (xy 350.617301 -246.66249) (xy 350.659922 -246.637883)
			(xy 350.705938 -246.620431) (xy 350.754157 -246.610587) (xy 350.803332 -246.608606) (xy 350.852187 -246.614538)
			(xy 350.899458 -246.62823) (xy 350.94392 -246.649328) (xy 350.984423 -246.677284) (xy 351.019916 -246.711376)
			(xy 351.049481 -246.75072) (xy 351.072352 -246.794297) (xy 351.087936 -246.840978) (xy 351.095831 -246.889555)
			(xy 351.096326 -246.914162) (xy 351.425268 -246.914162) (xy 351.429228 -246.865108) (xy 351.441005 -246.817324)
			(xy 351.460296 -246.772048) (xy 351.486599 -246.730452) (xy 351.519234 -246.693615) (xy 351.557355 -246.66249)
			(xy 351.599976 -246.637883) (xy 351.645992 -246.620431) (xy 351.694211 -246.610587) (xy 351.743386 -246.608606)
			(xy 351.792241 -246.614538) (xy 351.839512 -246.62823) (xy 351.883974 -246.649328) (xy 351.924477 -246.677284)
			(xy 351.95997 -246.711376) (xy 351.989535 -246.75072) (xy 352.012406 -246.794297) (xy 352.02799 -246.840978)
			(xy 352.035885 -246.889555) (xy 352.03638 -246.914162) (xy 352.365322 -246.914162) (xy 352.369282 -246.865108)
			(xy 352.381059 -246.817324) (xy 352.40035 -246.772048) (xy 352.426653 -246.730452) (xy 352.459288 -246.693615)
			(xy 352.497409 -246.66249) (xy 352.54003 -246.637883) (xy 352.586046 -246.620431) (xy 352.634265 -246.610587)
			(xy 352.68344 -246.608606) (xy 352.732295 -246.614538) (xy 352.779566 -246.62823) (xy 352.824028 -246.649328)
			(xy 352.864531 -246.677284) (xy 352.900024 -246.711376) (xy 352.929589 -246.75072) (xy 352.95246 -246.794297)
			(xy 352.968044 -246.840978) (xy 352.975939 -246.889555) (xy 352.976434 -246.914162) (xy 353.305376 -246.914162)
			(xy 353.309336 -246.865108) (xy 353.321113 -246.817324) (xy 353.340404 -246.772048) (xy 353.366707 -246.730452)
			(xy 353.399342 -246.693615) (xy 353.437463 -246.66249) (xy 353.480084 -246.637883) (xy 353.5261 -246.620431)
			(xy 353.574319 -246.610587) (xy 353.623494 -246.608606) (xy 353.672349 -246.614538) (xy 353.71962 -246.62823)
			(xy 353.764082 -246.649328) (xy 353.804585 -246.677284) (xy 353.840078 -246.711376) (xy 353.869643 -246.75072)
			(xy 353.892514 -246.794297) (xy 353.908098 -246.840978) (xy 353.915993 -246.889555) (xy 353.916488 -246.914162)
			(xy 354.24543 -246.914162) (xy 354.24939 -246.865108) (xy 354.261167 -246.817324) (xy 354.280458 -246.772048)
			(xy 354.306761 -246.730452) (xy 354.339396 -246.693615) (xy 354.377517 -246.66249) (xy 354.420138 -246.637883)
			(xy 354.466154 -246.620431) (xy 354.514373 -246.610587) (xy 354.563548 -246.608606) (xy 354.612403 -246.614538)
			(xy 354.659674 -246.62823) (xy 354.704136 -246.649328) (xy 354.744639 -246.677284) (xy 354.780132 -246.711376)
			(xy 354.809697 -246.75072) (xy 354.832568 -246.794297) (xy 354.848152 -246.840978) (xy 354.856047 -246.889555)
			(xy 354.856542 -246.914162) (xy 355.18523 -246.914162) (xy 355.18919 -246.865108) (xy 355.200967 -246.817324)
			(xy 355.220258 -246.772048) (xy 355.246561 -246.730452) (xy 355.279196 -246.693615) (xy 355.317317 -246.66249)
			(xy 355.359938 -246.637883) (xy 355.405954 -246.620431) (xy 355.454173 -246.610587) (xy 355.503348 -246.608606)
			(xy 355.552203 -246.614538) (xy 355.599474 -246.62823) (xy 355.643936 -246.649328) (xy 355.684439 -246.677284)
			(xy 355.719932 -246.711376) (xy 355.749497 -246.75072) (xy 355.772368 -246.794297) (xy 355.787952 -246.840978)
			(xy 355.795847 -246.889555) (xy 355.796342 -246.914162) (xy 356.125284 -246.914162) (xy 356.129244 -246.865108)
			(xy 356.141021 -246.817324) (xy 356.160312 -246.772048) (xy 356.186615 -246.730452) (xy 356.21925 -246.693615)
			(xy 356.257371 -246.66249) (xy 356.299992 -246.637883) (xy 356.346008 -246.620431) (xy 356.394227 -246.610587)
			(xy 356.443402 -246.608606) (xy 356.492257 -246.614538) (xy 356.539528 -246.62823) (xy 356.58399 -246.649328)
			(xy 356.624493 -246.677284) (xy 356.659986 -246.711376) (xy 356.689551 -246.75072) (xy 356.712422 -246.794297)
			(xy 356.728006 -246.840978) (xy 356.735901 -246.889555) (xy 356.736396 -246.914162) (xy 357.065338 -246.914162)
			(xy 357.069298 -246.865108) (xy 357.081075 -246.817324) (xy 357.100366 -246.772048) (xy 357.126669 -246.730452)
			(xy 357.159304 -246.693615) (xy 357.197425 -246.66249) (xy 357.240046 -246.637883) (xy 357.286062 -246.620431)
			(xy 357.334281 -246.610587) (xy 357.383456 -246.608606) (xy 357.432311 -246.614538) (xy 357.479582 -246.62823)
			(xy 357.524044 -246.649328) (xy 357.564547 -246.677284) (xy 357.60004 -246.711376) (xy 357.629605 -246.75072)
			(xy 357.652476 -246.794297) (xy 357.66806 -246.840978) (xy 357.675955 -246.889555) (xy 357.67645 -246.914162)
			(xy 358.005392 -246.914162) (xy 358.009352 -246.865108) (xy 358.021129 -246.817324) (xy 358.04042 -246.772048)
			(xy 358.066723 -246.730452) (xy 358.099358 -246.693615) (xy 358.137479 -246.66249) (xy 358.1801 -246.637883)
			(xy 358.226116 -246.620431) (xy 358.274335 -246.610587) (xy 358.32351 -246.608606) (xy 358.372365 -246.614538)
			(xy 358.419636 -246.62823) (xy 358.464098 -246.649328) (xy 358.504601 -246.677284) (xy 358.540094 -246.711376)
			(xy 358.569659 -246.75072) (xy 358.59253 -246.794297) (xy 358.608114 -246.840978) (xy 358.616009 -246.889555)
			(xy 358.616504 -246.914162) (xy 360.81895 -246.914162) (xy 360.82291 -246.865108) (xy 360.834687 -246.817324)
			(xy 360.853978 -246.772048) (xy 360.880281 -246.730452) (xy 360.912916 -246.693615) (xy 360.951037 -246.66249)
			(xy 360.993658 -246.637883) (xy 361.039674 -246.620431) (xy 361.087893 -246.610587) (xy 361.137068 -246.608606)
			(xy 361.185923 -246.614538) (xy 361.233194 -246.62823) (xy 361.277656 -246.649328) (xy 361.318159 -246.677284)
			(xy 361.353652 -246.711376) (xy 361.383217 -246.75072) (xy 361.406088 -246.794297) (xy 361.421672 -246.840978)
			(xy 361.429567 -246.889555) (xy 361.430062 -246.914162) (xy 361.430061 -246.9142) (xy 361.758647 -246.9142)
			(xy 361.762823 -246.863808) (xy 361.775236 -246.814791) (xy 361.795548 -246.768485) (xy 361.823205 -246.726155)
			(xy 361.857452 -246.688953) (xy 361.897355 -246.657897) (xy 361.941825 -246.633831) (xy 361.989651 -246.617414)
			(xy 362.039526 -246.609093) (xy 362.064808 -246.6086) (xy 363.004862 -246.6086) (xy 363.03014 -246.609166)
			(xy 363.080006 -246.617481) (xy 363.127824 -246.633892) (xy 363.172288 -246.65795) (xy 363.212185 -246.688999)
			(xy 363.246428 -246.726191) (xy 363.274081 -246.768513) (xy 363.29439 -246.81481) (xy 363.306801 -246.863818)
			(xy 363.310974 -246.914162) (xy 363.639112 -246.914162) (xy 363.643072 -246.865108) (xy 363.654849 -246.817324)
			(xy 363.67414 -246.772048) (xy 363.700443 -246.730452) (xy 363.733078 -246.693615) (xy 363.771199 -246.66249)
			(xy 363.81382 -246.637883) (xy 363.859836 -246.620431) (xy 363.908055 -246.610587) (xy 363.95723 -246.608606)
			(xy 364.006085 -246.614538) (xy 364.053356 -246.62823) (xy 364.097818 -246.649328) (xy 364.138321 -246.677284)
			(xy 364.173814 -246.711376) (xy 364.203379 -246.75072) (xy 364.22625 -246.794297) (xy 364.241834 -246.840978)
			(xy 364.249729 -246.889555) (xy 364.250224 -246.914162) (xy 364.578912 -246.914162) (xy 364.582872 -246.865108)
			(xy 364.594649 -246.817324) (xy 364.61394 -246.772048) (xy 364.640243 -246.730452) (xy 364.672878 -246.693615)
			(xy 364.710999 -246.66249) (xy 364.75362 -246.637883) (xy 364.799636 -246.620431) (xy 364.847855 -246.610587)
			(xy 364.89703 -246.608606) (xy 364.945885 -246.614538) (xy 364.993156 -246.62823) (xy 365.037618 -246.649328)
			(xy 365.078121 -246.677284) (xy 365.113614 -246.711376) (xy 365.143179 -246.75072) (xy 365.16605 -246.794297)
			(xy 365.181634 -246.840978) (xy 365.189529 -246.889555) (xy 365.190024 -246.914162) (xy 365.518966 -246.914162)
			(xy 365.522926 -246.865108) (xy 365.534703 -246.817324) (xy 365.553994 -246.772048) (xy 365.580297 -246.730452)
			(xy 365.612932 -246.693615) (xy 365.651053 -246.66249) (xy 365.693674 -246.637883) (xy 365.73969 -246.620431)
			(xy 365.787909 -246.610587) (xy 365.837084 -246.608606) (xy 365.885939 -246.614538) (xy 365.93321 -246.62823)
			(xy 365.977672 -246.649328) (xy 366.018175 -246.677284) (xy 366.053668 -246.711376) (xy 366.083233 -246.75072)
			(xy 366.106104 -246.794297) (xy 366.121688 -246.840978) (xy 366.129583 -246.889555) (xy 366.130078 -246.914162)
			(xy 366.45902 -246.914162) (xy 366.46298 -246.865108) (xy 366.474757 -246.817324) (xy 366.494048 -246.772048)
			(xy 366.520351 -246.730452) (xy 366.552986 -246.693615) (xy 366.591107 -246.66249) (xy 366.633728 -246.637883)
			(xy 366.679744 -246.620431) (xy 366.727963 -246.610587) (xy 366.777138 -246.608606) (xy 366.825993 -246.614538)
			(xy 366.873264 -246.62823) (xy 366.917726 -246.649328) (xy 366.958229 -246.677284) (xy 366.993722 -246.711376)
			(xy 367.023287 -246.75072) (xy 367.046158 -246.794297) (xy 367.061742 -246.840978) (xy 367.069637 -246.889555)
			(xy 367.070132 -246.914162) (xy 367.399074 -246.914162) (xy 367.403034 -246.865108) (xy 367.414811 -246.817324)
			(xy 367.434102 -246.772048) (xy 367.460405 -246.730452) (xy 367.49304 -246.693615) (xy 367.531161 -246.66249)
			(xy 367.573782 -246.637883) (xy 367.619798 -246.620431) (xy 367.668017 -246.610587) (xy 367.717192 -246.608606)
			(xy 367.766047 -246.614538) (xy 367.813318 -246.62823) (xy 367.85778 -246.649328) (xy 367.898283 -246.677284)
			(xy 367.933776 -246.711376) (xy 367.963341 -246.75072) (xy 367.986212 -246.794297) (xy 368.001796 -246.840978)
			(xy 368.009691 -246.889555) (xy 368.010186 -246.914162) (xy 368.338874 -246.914162) (xy 368.342834 -246.865108)
			(xy 368.354611 -246.817324) (xy 368.373902 -246.772048) (xy 368.400205 -246.730452) (xy 368.43284 -246.693615)
			(xy 368.470961 -246.66249) (xy 368.513582 -246.637883) (xy 368.559598 -246.620431) (xy 368.607817 -246.610587)
			(xy 368.656992 -246.608606) (xy 368.705847 -246.614538) (xy 368.753118 -246.62823) (xy 368.79758 -246.649328)
			(xy 368.838083 -246.677284) (xy 368.873576 -246.711376) (xy 368.903141 -246.75072) (xy 368.926012 -246.794297)
			(xy 368.941596 -246.840978) (xy 368.949491 -246.889555) (xy 368.949986 -246.914162) (xy 369.278928 -246.914162)
			(xy 369.282888 -246.865108) (xy 369.294665 -246.817324) (xy 369.313956 -246.772048) (xy 369.340259 -246.730452)
			(xy 369.372894 -246.693615) (xy 369.411015 -246.66249) (xy 369.453636 -246.637883) (xy 369.499652 -246.620431)
			(xy 369.547871 -246.610587) (xy 369.597046 -246.608606) (xy 369.645901 -246.614538) (xy 369.693172 -246.62823)
			(xy 369.737634 -246.649328) (xy 369.778137 -246.677284) (xy 369.81363 -246.711376) (xy 369.843195 -246.75072)
			(xy 369.866066 -246.794297) (xy 369.88165 -246.840978) (xy 369.889545 -246.889555) (xy 369.89004 -246.914162)
			(xy 370.218982 -246.914162) (xy 370.222942 -246.865108) (xy 370.234719 -246.817324) (xy 370.25401 -246.772048)
			(xy 370.280313 -246.730452) (xy 370.312948 -246.693615) (xy 370.351069 -246.66249) (xy 370.39369 -246.637883)
			(xy 370.439706 -246.620431) (xy 370.487925 -246.610587) (xy 370.5371 -246.608606) (xy 370.585955 -246.614538)
			(xy 370.633226 -246.62823) (xy 370.677688 -246.649328) (xy 370.718191 -246.677284) (xy 370.753684 -246.711376)
			(xy 370.783249 -246.75072) (xy 370.80612 -246.794297) (xy 370.821704 -246.840978) (xy 370.829599 -246.889555)
			(xy 370.830094 -246.914162) (xy 371.159036 -246.914162) (xy 371.162996 -246.865108) (xy 371.174773 -246.817324)
			(xy 371.194064 -246.772048) (xy 371.220367 -246.730452) (xy 371.253002 -246.693615) (xy 371.291123 -246.66249)
			(xy 371.333744 -246.637883) (xy 371.37976 -246.620431) (xy 371.427979 -246.610587) (xy 371.477154 -246.608606)
			(xy 371.526009 -246.614538) (xy 371.57328 -246.62823) (xy 371.617742 -246.649328) (xy 371.658245 -246.677284)
			(xy 371.693738 -246.711376) (xy 371.723303 -246.75072) (xy 371.746174 -246.794297) (xy 371.761758 -246.840978)
			(xy 371.769653 -246.889555) (xy 371.770148 -246.914162) (xy 372.09909 -246.914162) (xy 372.10305 -246.865108)
			(xy 372.114827 -246.817324) (xy 372.134118 -246.772048) (xy 372.160421 -246.730452) (xy 372.193056 -246.693615)
			(xy 372.231177 -246.66249) (xy 372.273798 -246.637883) (xy 372.319814 -246.620431) (xy 372.368033 -246.610587)
			(xy 372.417208 -246.608606) (xy 372.466063 -246.614538) (xy 372.513334 -246.62823) (xy 372.557796 -246.649328)
			(xy 372.598299 -246.677284) (xy 372.633792 -246.711376) (xy 372.663357 -246.75072) (xy 372.686228 -246.794297)
			(xy 372.701812 -246.840978) (xy 372.709707 -246.889555) (xy 372.710202 -246.914162) (xy 373.03889 -246.914162)
			(xy 373.04285 -246.865108) (xy 373.054627 -246.817324) (xy 373.073918 -246.772048) (xy 373.100221 -246.730452)
			(xy 373.132856 -246.693615) (xy 373.170977 -246.66249) (xy 373.213598 -246.637883) (xy 373.259614 -246.620431)
			(xy 373.307833 -246.610587) (xy 373.357008 -246.608606) (xy 373.405863 -246.614538) (xy 373.453134 -246.62823)
			(xy 373.497596 -246.649328) (xy 373.538099 -246.677284) (xy 373.573592 -246.711376) (xy 373.603157 -246.75072)
			(xy 373.626028 -246.794297) (xy 373.641612 -246.840978) (xy 373.649507 -246.889555) (xy 373.650002 -246.914162)
			(xy 373.649507 -246.938769) (xy 373.641612 -246.987346) (xy 373.626028 -247.034027) (xy 373.603157 -247.077604)
			(xy 373.573592 -247.116948) (xy 373.538099 -247.15104) (xy 373.497596 -247.178996) (xy 373.453134 -247.200094)
			(xy 373.405863 -247.213786) (xy 373.357008 -247.219718) (xy 373.307833 -247.217737) (xy 373.259614 -247.207893)
			(xy 373.213598 -247.190441) (xy 373.170977 -247.165834) (xy 373.132856 -247.134709) (xy 373.100221 -247.097872)
			(xy 373.073918 -247.056276) (xy 373.054627 -247.011) (xy 373.04285 -246.963216) (xy 373.03889 -246.914162)
			(xy 372.710202 -246.914162) (xy 372.709707 -246.938769) (xy 372.701812 -246.987346) (xy 372.686228 -247.034027)
			(xy 372.663357 -247.077604) (xy 372.633792 -247.116948) (xy 372.598299 -247.15104) (xy 372.557796 -247.178996)
			(xy 372.513334 -247.200094) (xy 372.466063 -247.213786) (xy 372.417208 -247.219718) (xy 372.368033 -247.217737)
			(xy 372.319814 -247.207893) (xy 372.273798 -247.190441) (xy 372.231177 -247.165834) (xy 372.193056 -247.134709)
			(xy 372.160421 -247.097872) (xy 372.134118 -247.056276) (xy 372.114827 -247.011) (xy 372.10305 -246.963216)
			(xy 372.09909 -246.914162) (xy 371.770148 -246.914162) (xy 371.769653 -246.938769) (xy 371.761758 -246.987346)
			(xy 371.746174 -247.034027) (xy 371.723303 -247.077604) (xy 371.693738 -247.116948) (xy 371.658245 -247.15104)
			(xy 371.617742 -247.178996) (xy 371.57328 -247.200094) (xy 371.526009 -247.213786) (xy 371.477154 -247.219718)
			(xy 371.427979 -247.217737) (xy 371.37976 -247.207893) (xy 371.333744 -247.190441) (xy 371.291123 -247.165834)
			(xy 371.253002 -247.134709) (xy 371.220367 -247.097872) (xy 371.194064 -247.056276) (xy 371.174773 -247.011)
			(xy 371.162996 -246.963216) (xy 371.159036 -246.914162) (xy 370.830094 -246.914162) (xy 370.829599 -246.938769)
			(xy 370.821704 -246.987346) (xy 370.80612 -247.034027) (xy 370.783249 -247.077604) (xy 370.753684 -247.116948)
			(xy 370.718191 -247.15104) (xy 370.677688 -247.178996) (xy 370.633226 -247.200094) (xy 370.585955 -247.213786)
			(xy 370.5371 -247.219718) (xy 370.487925 -247.217737) (xy 370.439706 -247.207893) (xy 370.39369 -247.190441)
			(xy 370.351069 -247.165834) (xy 370.312948 -247.134709) (xy 370.280313 -247.097872) (xy 370.25401 -247.056276)
			(xy 370.234719 -247.011) (xy 370.222942 -246.963216) (xy 370.218982 -246.914162) (xy 369.89004 -246.914162)
			(xy 369.889545 -246.938769) (xy 369.88165 -246.987346) (xy 369.866066 -247.034027) (xy 369.843195 -247.077604)
			(xy 369.81363 -247.116948) (xy 369.778137 -247.15104) (xy 369.737634 -247.178996) (xy 369.693172 -247.200094)
			(xy 369.645901 -247.213786) (xy 369.597046 -247.219718) (xy 369.547871 -247.217737) (xy 369.499652 -247.207893)
			(xy 369.453636 -247.190441) (xy 369.411015 -247.165834) (xy 369.372894 -247.134709) (xy 369.340259 -247.097872)
			(xy 369.313956 -247.056276) (xy 369.294665 -247.011) (xy 369.282888 -246.963216) (xy 369.278928 -246.914162)
			(xy 368.949986 -246.914162) (xy 368.949491 -246.938769) (xy 368.941596 -246.987346) (xy 368.926012 -247.034027)
			(xy 368.903141 -247.077604) (xy 368.873576 -247.116948) (xy 368.838083 -247.15104) (xy 368.79758 -247.178996)
			(xy 368.753118 -247.200094) (xy 368.705847 -247.213786) (xy 368.656992 -247.219718) (xy 368.607817 -247.217737)
			(xy 368.559598 -247.207893) (xy 368.513582 -247.190441) (xy 368.470961 -247.165834) (xy 368.43284 -247.134709)
			(xy 368.400205 -247.097872) (xy 368.373902 -247.056276) (xy 368.354611 -247.011) (xy 368.342834 -246.963216)
			(xy 368.338874 -246.914162) (xy 368.010186 -246.914162) (xy 368.009691 -246.938769) (xy 368.001796 -246.987346)
			(xy 367.986212 -247.034027) (xy 367.963341 -247.077604) (xy 367.933776 -247.116948) (xy 367.898283 -247.15104)
			(xy 367.85778 -247.178996) (xy 367.813318 -247.200094) (xy 367.766047 -247.213786) (xy 367.717192 -247.219718)
			(xy 367.668017 -247.217737) (xy 367.619798 -247.207893) (xy 367.573782 -247.190441) (xy 367.531161 -247.165834)
			(xy 367.49304 -247.134709) (xy 367.460405 -247.097872) (xy 367.434102 -247.056276) (xy 367.414811 -247.011)
			(xy 367.403034 -246.963216) (xy 367.399074 -246.914162) (xy 367.070132 -246.914162) (xy 367.069637 -246.938769)
			(xy 367.061742 -246.987346) (xy 367.046158 -247.034027) (xy 367.023287 -247.077604) (xy 366.993722 -247.116948)
			(xy 366.958229 -247.15104) (xy 366.917726 -247.178996) (xy 366.873264 -247.200094) (xy 366.825993 -247.213786)
			(xy 366.777138 -247.219718) (xy 366.727963 -247.217737) (xy 366.679744 -247.207893) (xy 366.633728 -247.190441)
			(xy 366.591107 -247.165834) (xy 366.552986 -247.134709) (xy 366.520351 -247.097872) (xy 366.494048 -247.056276)
			(xy 366.474757 -247.011) (xy 366.46298 -246.963216) (xy 366.45902 -246.914162) (xy 366.130078 -246.914162)
			(xy 366.129583 -246.938769) (xy 366.121688 -246.987346) (xy 366.106104 -247.034027) (xy 366.083233 -247.077604)
			(xy 366.053668 -247.116948) (xy 366.018175 -247.15104) (xy 365.977672 -247.178996) (xy 365.93321 -247.200094)
			(xy 365.885939 -247.213786) (xy 365.837084 -247.219718) (xy 365.787909 -247.217737) (xy 365.73969 -247.207893)
			(xy 365.693674 -247.190441) (xy 365.651053 -247.165834) (xy 365.612932 -247.134709) (xy 365.580297 -247.097872)
			(xy 365.553994 -247.056276) (xy 365.534703 -247.011) (xy 365.522926 -246.963216) (xy 365.518966 -246.914162)
			(xy 365.190024 -246.914162) (xy 365.189529 -246.938769) (xy 365.181634 -246.987346) (xy 365.16605 -247.034027)
			(xy 365.143179 -247.077604) (xy 365.113614 -247.116948) (xy 365.078121 -247.15104) (xy 365.037618 -247.178996)
			(xy 364.993156 -247.200094) (xy 364.945885 -247.213786) (xy 364.89703 -247.219718) (xy 364.847855 -247.217737)
			(xy 364.799636 -247.207893) (xy 364.75362 -247.190441) (xy 364.710999 -247.165834) (xy 364.672878 -247.134709)
			(xy 364.640243 -247.097872) (xy 364.61394 -247.056276) (xy 364.594649 -247.011) (xy 364.582872 -246.963216)
			(xy 364.578912 -246.914162) (xy 364.250224 -246.914162) (xy 364.249729 -246.938769) (xy 364.241834 -246.987346)
			(xy 364.22625 -247.034027) (xy 364.203379 -247.077604) (xy 364.173814 -247.116948) (xy 364.138321 -247.15104)
			(xy 364.097818 -247.178996) (xy 364.053356 -247.200094) (xy 364.006085 -247.213786) (xy 363.95723 -247.219718)
			(xy 363.908055 -247.217737) (xy 363.859836 -247.207893) (xy 363.81382 -247.190441) (xy 363.771199 -247.165834)
			(xy 363.733078 -247.134709) (xy 363.700443 -247.097872) (xy 363.67414 -247.056276) (xy 363.654849 -247.011)
			(xy 363.643072 -246.963216) (xy 363.639112 -246.914162) (xy 363.310974 -246.914162) (xy 363.310977 -246.9142)
			(xy 363.306801 -246.964582) (xy 363.29439 -247.01359) (xy 363.274081 -247.059887) (xy 363.246428 -247.102209)
			(xy 363.212185 -247.139401) (xy 363.172288 -247.17045) (xy 363.127824 -247.194508) (xy 363.080006 -247.210919)
			(xy 363.03014 -247.219234) (xy 363.004862 -247.219724) (xy 362.064808 -247.219724) (xy 362.039526 -247.219307)
			(xy 361.989651 -247.210986) (xy 361.941825 -247.194569) (xy 361.897355 -247.170503) (xy 361.857452 -247.139447)
			(xy 361.823205 -247.102245) (xy 361.795548 -247.059915) (xy 361.775236 -247.013609) (xy 361.762823 -246.964592)
			(xy 361.758647 -246.9142) (xy 361.430061 -246.9142) (xy 361.429567 -246.938769) (xy 361.421672 -246.987346)
			(xy 361.406088 -247.034027) (xy 361.383217 -247.077604) (xy 361.353652 -247.116948) (xy 361.318159 -247.15104)
			(xy 361.277656 -247.178996) (xy 361.233194 -247.200094) (xy 361.185923 -247.213786) (xy 361.137068 -247.219718)
			(xy 361.087893 -247.217737) (xy 361.039674 -247.207893) (xy 360.993658 -247.190441) (xy 360.951037 -247.165834)
			(xy 360.912916 -247.134709) (xy 360.880281 -247.097872) (xy 360.853978 -247.056276) (xy 360.834687 -247.011)
			(xy 360.82291 -246.963216) (xy 360.81895 -246.914162) (xy 358.616504 -246.914162) (xy 358.616009 -246.938769)
			(xy 358.608114 -246.987346) (xy 358.59253 -247.034027) (xy 358.569659 -247.077604) (xy 358.540094 -247.116948)
			(xy 358.504601 -247.15104) (xy 358.464098 -247.178996) (xy 358.419636 -247.200094) (xy 358.372365 -247.213786)
			(xy 358.32351 -247.219718) (xy 358.274335 -247.217737) (xy 358.226116 -247.207893) (xy 358.1801 -247.190441)
			(xy 358.137479 -247.165834) (xy 358.099358 -247.134709) (xy 358.066723 -247.097872) (xy 358.04042 -247.056276)
			(xy 358.021129 -247.011) (xy 358.009352 -246.963216) (xy 358.005392 -246.914162) (xy 357.67645 -246.914162)
			(xy 357.675955 -246.938769) (xy 357.66806 -246.987346) (xy 357.652476 -247.034027) (xy 357.629605 -247.077604)
			(xy 357.60004 -247.116948) (xy 357.564547 -247.15104) (xy 357.524044 -247.178996) (xy 357.479582 -247.200094)
			(xy 357.432311 -247.213786) (xy 357.383456 -247.219718) (xy 357.334281 -247.217737) (xy 357.286062 -247.207893)
			(xy 357.240046 -247.190441) (xy 357.197425 -247.165834) (xy 357.159304 -247.134709) (xy 357.126669 -247.097872)
			(xy 357.100366 -247.056276) (xy 357.081075 -247.011) (xy 357.069298 -246.963216) (xy 357.065338 -246.914162)
			(xy 356.736396 -246.914162) (xy 356.735901 -246.938769) (xy 356.728006 -246.987346) (xy 356.712422 -247.034027)
			(xy 356.689551 -247.077604) (xy 356.659986 -247.116948) (xy 356.624493 -247.15104) (xy 356.58399 -247.178996)
			(xy 356.539528 -247.200094) (xy 356.492257 -247.213786) (xy 356.443402 -247.219718) (xy 356.394227 -247.217737)
			(xy 356.346008 -247.207893) (xy 356.299992 -247.190441) (xy 356.257371 -247.165834) (xy 356.21925 -247.134709)
			(xy 356.186615 -247.097872) (xy 356.160312 -247.056276) (xy 356.141021 -247.011) (xy 356.129244 -246.963216)
			(xy 356.125284 -246.914162) (xy 355.796342 -246.914162) (xy 355.795847 -246.938769) (xy 355.787952 -246.987346)
			(xy 355.772368 -247.034027) (xy 355.749497 -247.077604) (xy 355.719932 -247.116948) (xy 355.684439 -247.15104)
			(xy 355.643936 -247.178996) (xy 355.599474 -247.200094) (xy 355.552203 -247.213786) (xy 355.503348 -247.219718)
			(xy 355.454173 -247.217737) (xy 355.405954 -247.207893) (xy 355.359938 -247.190441) (xy 355.317317 -247.165834)
			(xy 355.279196 -247.134709) (xy 355.246561 -247.097872) (xy 355.220258 -247.056276) (xy 355.200967 -247.011)
			(xy 355.18919 -246.963216) (xy 355.18523 -246.914162) (xy 354.856542 -246.914162) (xy 354.856047 -246.938769)
			(xy 354.848152 -246.987346) (xy 354.832568 -247.034027) (xy 354.809697 -247.077604) (xy 354.780132 -247.116948)
			(xy 354.744639 -247.15104) (xy 354.704136 -247.178996) (xy 354.659674 -247.200094) (xy 354.612403 -247.213786)
			(xy 354.563548 -247.219718) (xy 354.514373 -247.217737) (xy 354.466154 -247.207893) (xy 354.420138 -247.190441)
			(xy 354.377517 -247.165834) (xy 354.339396 -247.134709) (xy 354.306761 -247.097872) (xy 354.280458 -247.056276)
			(xy 354.261167 -247.011) (xy 354.24939 -246.963216) (xy 354.24543 -246.914162) (xy 353.916488 -246.914162)
			(xy 353.915993 -246.938769) (xy 353.908098 -246.987346) (xy 353.892514 -247.034027) (xy 353.869643 -247.077604)
			(xy 353.840078 -247.116948) (xy 353.804585 -247.15104) (xy 353.764082 -247.178996) (xy 353.71962 -247.200094)
			(xy 353.672349 -247.213786) (xy 353.623494 -247.219718) (xy 353.574319 -247.217737) (xy 353.5261 -247.207893)
			(xy 353.480084 -247.190441) (xy 353.437463 -247.165834) (xy 353.399342 -247.134709) (xy 353.366707 -247.097872)
			(xy 353.340404 -247.056276) (xy 353.321113 -247.011) (xy 353.309336 -246.963216) (xy 353.305376 -246.914162)
			(xy 352.976434 -246.914162) (xy 352.975939 -246.938769) (xy 352.968044 -246.987346) (xy 352.95246 -247.034027)
			(xy 352.929589 -247.077604) (xy 352.900024 -247.116948) (xy 352.864531 -247.15104) (xy 352.824028 -247.178996)
			(xy 352.779566 -247.200094) (xy 352.732295 -247.213786) (xy 352.68344 -247.219718) (xy 352.634265 -247.217737)
			(xy 352.586046 -247.207893) (xy 352.54003 -247.190441) (xy 352.497409 -247.165834) (xy 352.459288 -247.134709)
			(xy 352.426653 -247.097872) (xy 352.40035 -247.056276) (xy 352.381059 -247.011) (xy 352.369282 -246.963216)
			(xy 352.365322 -246.914162) (xy 352.03638 -246.914162) (xy 352.035885 -246.938769) (xy 352.02799 -246.987346)
			(xy 352.012406 -247.034027) (xy 351.989535 -247.077604) (xy 351.95997 -247.116948) (xy 351.924477 -247.15104)
			(xy 351.883974 -247.178996) (xy 351.839512 -247.200094) (xy 351.792241 -247.213786) (xy 351.743386 -247.219718)
			(xy 351.694211 -247.217737) (xy 351.645992 -247.207893) (xy 351.599976 -247.190441) (xy 351.557355 -247.165834)
			(xy 351.519234 -247.134709) (xy 351.486599 -247.097872) (xy 351.460296 -247.056276) (xy 351.441005 -247.011)
			(xy 351.429228 -246.963216) (xy 351.425268 -246.914162) (xy 351.096326 -246.914162) (xy 351.095831 -246.938769)
			(xy 351.087936 -246.987346) (xy 351.072352 -247.034027) (xy 351.049481 -247.077604) (xy 351.019916 -247.116948)
			(xy 350.984423 -247.15104) (xy 350.94392 -247.178996) (xy 350.899458 -247.200094) (xy 350.852187 -247.213786)
			(xy 350.803332 -247.219718) (xy 350.754157 -247.217737) (xy 350.705938 -247.207893) (xy 350.659922 -247.190441)
			(xy 350.617301 -247.165834) (xy 350.57918 -247.134709) (xy 350.546545 -247.097872) (xy 350.520242 -247.056276)
			(xy 350.500951 -247.011) (xy 350.489174 -246.963216) (xy 350.485214 -246.914162) (xy 350.156526 -246.914162)
			(xy 350.156031 -246.938769) (xy 350.148136 -246.987346) (xy 350.132552 -247.034027) (xy 350.109681 -247.077604)
			(xy 350.080116 -247.116948) (xy 350.044623 -247.15104) (xy 350.00412 -247.178996) (xy 349.959658 -247.200094)
			(xy 349.912387 -247.213786) (xy 349.863532 -247.219718) (xy 349.814357 -247.217737) (xy 349.766138 -247.207893)
			(xy 349.720122 -247.190441) (xy 349.677501 -247.165834) (xy 349.63938 -247.134709) (xy 349.606745 -247.097872)
			(xy 349.580442 -247.056276) (xy 349.561151 -247.011) (xy 349.549374 -246.963216) (xy 349.545414 -246.914162)
			(xy 349.216472 -246.914162) (xy 349.215977 -246.938769) (xy 349.208082 -246.987346) (xy 349.192498 -247.034027)
			(xy 349.169627 -247.077604) (xy 349.140062 -247.116948) (xy 349.104569 -247.15104) (xy 349.064066 -247.178996)
			(xy 349.019604 -247.200094) (xy 348.972333 -247.213786) (xy 348.923478 -247.219718) (xy 348.874303 -247.217737)
			(xy 348.826084 -247.207893) (xy 348.780068 -247.190441) (xy 348.737447 -247.165834) (xy 348.699326 -247.134709)
			(xy 348.666691 -247.097872) (xy 348.640388 -247.056276) (xy 348.621097 -247.011) (xy 348.60932 -246.963216)
			(xy 348.60536 -246.914162) (xy 348.276418 -246.914162) (xy 348.275923 -246.938769) (xy 348.268028 -246.987346)
			(xy 348.252444 -247.034027) (xy 348.229573 -247.077604) (xy 348.200008 -247.116948) (xy 348.164515 -247.15104)
			(xy 348.124012 -247.178996) (xy 348.07955 -247.200094) (xy 348.032279 -247.213786) (xy 347.983424 -247.219718)
			(xy 347.934249 -247.217737) (xy 347.88603 -247.207893) (xy 347.840014 -247.190441) (xy 347.797393 -247.165834)
			(xy 347.759272 -247.134709) (xy 347.726637 -247.097872) (xy 347.700334 -247.056276) (xy 347.681043 -247.011)
			(xy 347.669266 -246.963216) (xy 347.665306 -246.914162) (xy 347.336364 -246.914162) (xy 347.335869 -246.938769)
			(xy 347.327974 -246.987346) (xy 347.31239 -247.034027) (xy 347.289519 -247.077604) (xy 347.259954 -247.116948)
			(xy 347.224461 -247.15104) (xy 347.183958 -247.178996) (xy 347.139496 -247.200094) (xy 347.092225 -247.213786)
			(xy 347.04337 -247.219718) (xy 346.994195 -247.217737) (xy 346.945976 -247.207893) (xy 346.89996 -247.190441)
			(xy 346.857339 -247.165834) (xy 346.819218 -247.134709) (xy 346.786583 -247.097872) (xy 346.76028 -247.056276)
			(xy 346.740989 -247.011) (xy 346.729212 -246.963216) (xy 346.725252 -246.914162) (xy 346.39631 -246.914162)
			(xy 346.395815 -246.938769) (xy 346.38792 -246.987346) (xy 346.372336 -247.034027) (xy 346.349465 -247.077604)
			(xy 346.3199 -247.116948) (xy 346.284407 -247.15104) (xy 346.243904 -247.178996) (xy 346.199442 -247.200094)
			(xy 346.152171 -247.213786) (xy 346.103316 -247.219718) (xy 346.054141 -247.217737) (xy 346.005922 -247.207893)
			(xy 345.959906 -247.190441) (xy 345.917285 -247.165834) (xy 345.879164 -247.134709) (xy 345.846529 -247.097872)
			(xy 345.820226 -247.056276) (xy 345.800935 -247.011) (xy 345.789158 -246.963216) (xy 345.785198 -246.914162)
			(xy 345.45651 -246.914162) (xy 345.45637 -246.926925) (xy 345.454206 -246.952358) (xy 345.452192 -246.964962)
			(xy 345.452446 -246.964962) (xy 345.447999 -246.988641) (xy 345.432636 -247.034304) (xy 345.410289 -247.076986)
			(xy 345.381513 -247.115627) (xy 345.347023 -247.149266) (xy 345.307677 -247.177068) (xy 345.26445 -247.198343)
			(xy 345.218418 -247.212562) (xy 345.194636 -247.216422) (xy 345.181936 -247.2182) (xy 345.151456 -247.219724)
			(xy 345.150948 -247.219724) (xy 345.127469 -247.219314) (xy 345.081059 -247.212169) (xy 345.036288 -247.19801)
			(xy 345.015058 -247.187974) (xy 345.003374 -247.181878) (xy 344.977212 -247.183148) (xy 344.894662 -247.234202)
			(xy 344.887504 -247.239036) (xy 344.876676 -247.25248) (xy 344.870917 -247.268752) (xy 344.870532 -247.277382)
			(xy 344.870532 -247.451118) (xy 344.870674 -247.456415) (xy 344.872857 -247.466782) (xy 344.87485 -247.471692)
			(xy 344.886534 -247.498108) (xy 344.893646 -247.504966) (xy 344.910861 -247.522351) (xy 344.940084 -247.561588)
			(xy 344.962682 -247.60498) (xy 344.978077 -247.651418) (xy 344.985876 -247.699716) (xy 344.985878 -247.724168)
			(xy 345.315298 -247.724168) (xy 345.319258 -247.675114) (xy 345.331035 -247.62733) (xy 345.350326 -247.582054)
			(xy 345.376629 -247.540458) (xy 345.409264 -247.503621) (xy 345.447385 -247.472496) (xy 345.490006 -247.447889)
			(xy 345.536022 -247.430437) (xy 345.584241 -247.420593) (xy 345.633416 -247.418612) (xy 345.682271 -247.424544)
			(xy 345.729542 -247.438236) (xy 345.774004 -247.459334) (xy 345.814507 -247.48729) (xy 345.85 -247.521382)
			(xy 345.879565 -247.560726) (xy 345.902436 -247.604303) (xy 345.91802 -247.650984) (xy 345.925915 -247.699561)
			(xy 345.92641 -247.724168) (xy 346.255352 -247.724168) (xy 346.259312 -247.675114) (xy 346.271089 -247.62733)
			(xy 346.29038 -247.582054) (xy 346.316683 -247.540458) (xy 346.349318 -247.503621) (xy 346.387439 -247.472496)
			(xy 346.43006 -247.447889) (xy 346.476076 -247.430437) (xy 346.524295 -247.420593) (xy 346.57347 -247.418612)
			(xy 346.622325 -247.424544) (xy 346.669596 -247.438236) (xy 346.714058 -247.459334) (xy 346.754561 -247.48729)
			(xy 346.790054 -247.521382) (xy 346.819619 -247.560726) (xy 346.84249 -247.604303) (xy 346.858074 -247.650984)
			(xy 346.865969 -247.699561) (xy 346.866464 -247.724168) (xy 347.195406 -247.724168) (xy 347.199366 -247.675114)
			(xy 347.211143 -247.62733) (xy 347.230434 -247.582054) (xy 347.256737 -247.540458) (xy 347.289372 -247.503621)
			(xy 347.327493 -247.472496) (xy 347.370114 -247.447889) (xy 347.41613 -247.430437) (xy 347.464349 -247.420593)
			(xy 347.513524 -247.418612) (xy 347.562379 -247.424544) (xy 347.60965 -247.438236) (xy 347.654112 -247.459334)
			(xy 347.694615 -247.48729) (xy 347.730108 -247.521382) (xy 347.759673 -247.560726) (xy 347.782544 -247.604303)
			(xy 347.798128 -247.650984) (xy 347.806023 -247.699561) (xy 347.806518 -247.724168) (xy 348.135206 -247.724168)
			(xy 348.139166 -247.675114) (xy 348.150943 -247.62733) (xy 348.170234 -247.582054) (xy 348.196537 -247.540458)
			(xy 348.229172 -247.503621) (xy 348.267293 -247.472496) (xy 348.309914 -247.447889) (xy 348.35593 -247.430437)
			(xy 348.404149 -247.420593) (xy 348.453324 -247.418612) (xy 348.502179 -247.424544) (xy 348.54945 -247.438236)
			(xy 348.593912 -247.459334) (xy 348.634415 -247.48729) (xy 348.669908 -247.521382) (xy 348.699473 -247.560726)
			(xy 348.722344 -247.604303) (xy 348.737928 -247.650984) (xy 348.745823 -247.699561) (xy 348.746318 -247.724168)
			(xy 349.07526 -247.724168) (xy 349.07922 -247.675114) (xy 349.090997 -247.62733) (xy 349.110288 -247.582054)
			(xy 349.136591 -247.540458) (xy 349.169226 -247.503621) (xy 349.207347 -247.472496) (xy 349.249968 -247.447889)
			(xy 349.295984 -247.430437) (xy 349.344203 -247.420593) (xy 349.393378 -247.418612) (xy 349.442233 -247.424544)
			(xy 349.489504 -247.438236) (xy 349.533966 -247.459334) (xy 349.574469 -247.48729) (xy 349.609962 -247.521382)
			(xy 349.639527 -247.560726) (xy 349.662398 -247.604303) (xy 349.677982 -247.650984) (xy 349.685877 -247.699561)
			(xy 349.686372 -247.724168) (xy 350.015314 -247.724168) (xy 350.019274 -247.675114) (xy 350.031051 -247.62733)
			(xy 350.050342 -247.582054) (xy 350.076645 -247.540458) (xy 350.10928 -247.503621) (xy 350.147401 -247.472496)
			(xy 350.190022 -247.447889) (xy 350.236038 -247.430437) (xy 350.284257 -247.420593) (xy 350.333432 -247.418612)
			(xy 350.382287 -247.424544) (xy 350.429558 -247.438236) (xy 350.47402 -247.459334) (xy 350.514523 -247.48729)
			(xy 350.550016 -247.521382) (xy 350.579581 -247.560726) (xy 350.602452 -247.604303) (xy 350.618036 -247.650984)
			(xy 350.625931 -247.699561) (xy 350.626426 -247.724168) (xy 350.955368 -247.724168) (xy 350.959328 -247.675114)
			(xy 350.971105 -247.62733) (xy 350.990396 -247.582054) (xy 351.016699 -247.540458) (xy 351.049334 -247.503621)
			(xy 351.087455 -247.472496) (xy 351.130076 -247.447889) (xy 351.176092 -247.430437) (xy 351.224311 -247.420593)
			(xy 351.273486 -247.418612) (xy 351.322341 -247.424544) (xy 351.369612 -247.438236) (xy 351.414074 -247.459334)
			(xy 351.454577 -247.48729) (xy 351.49007 -247.521382) (xy 351.519635 -247.560726) (xy 351.542506 -247.604303)
			(xy 351.55809 -247.650984) (xy 351.565985 -247.699561) (xy 351.56648 -247.724168) (xy 351.895422 -247.724168)
			(xy 351.899382 -247.675114) (xy 351.911159 -247.62733) (xy 351.93045 -247.582054) (xy 351.956753 -247.540458)
			(xy 351.989388 -247.503621) (xy 352.027509 -247.472496) (xy 352.07013 -247.447889) (xy 352.116146 -247.430437)
			(xy 352.164365 -247.420593) (xy 352.21354 -247.418612) (xy 352.262395 -247.424544) (xy 352.309666 -247.438236)
			(xy 352.354128 -247.459334) (xy 352.394631 -247.48729) (xy 352.430124 -247.521382) (xy 352.459689 -247.560726)
			(xy 352.48256 -247.604303) (xy 352.498144 -247.650984) (xy 352.506039 -247.699561) (xy 352.506534 -247.724168)
			(xy 352.835222 -247.724168) (xy 352.839182 -247.675114) (xy 352.850959 -247.62733) (xy 352.87025 -247.582054)
			(xy 352.896553 -247.540458) (xy 352.929188 -247.503621) (xy 352.967309 -247.472496) (xy 353.00993 -247.447889)
			(xy 353.055946 -247.430437) (xy 353.104165 -247.420593) (xy 353.15334 -247.418612) (xy 353.202195 -247.424544)
			(xy 353.249466 -247.438236) (xy 353.293928 -247.459334) (xy 353.334431 -247.48729) (xy 353.369924 -247.521382)
			(xy 353.399489 -247.560726) (xy 353.42236 -247.604303) (xy 353.437944 -247.650984) (xy 353.445839 -247.699561)
			(xy 353.446334 -247.724168) (xy 353.775276 -247.724168) (xy 353.779236 -247.675114) (xy 353.791013 -247.62733)
			(xy 353.810304 -247.582054) (xy 353.836607 -247.540458) (xy 353.869242 -247.503621) (xy 353.907363 -247.472496)
			(xy 353.949984 -247.447889) (xy 353.996 -247.430437) (xy 354.044219 -247.420593) (xy 354.093394 -247.418612)
			(xy 354.142249 -247.424544) (xy 354.18952 -247.438236) (xy 354.233982 -247.459334) (xy 354.274485 -247.48729)
			(xy 354.309978 -247.521382) (xy 354.339543 -247.560726) (xy 354.362414 -247.604303) (xy 354.377998 -247.650984)
			(xy 354.385893 -247.699561) (xy 354.386388 -247.724168) (xy 354.71533 -247.724168) (xy 354.71929 -247.675114)
			(xy 354.731067 -247.62733) (xy 354.750358 -247.582054) (xy 354.776661 -247.540458) (xy 354.809296 -247.503621)
			(xy 354.847417 -247.472496) (xy 354.890038 -247.447889) (xy 354.936054 -247.430437) (xy 354.984273 -247.420593)
			(xy 355.033448 -247.418612) (xy 355.082303 -247.424544) (xy 355.129574 -247.438236) (xy 355.174036 -247.459334)
			(xy 355.214539 -247.48729) (xy 355.250032 -247.521382) (xy 355.279597 -247.560726) (xy 355.302468 -247.604303)
			(xy 355.318052 -247.650984) (xy 355.325947 -247.699561) (xy 355.326442 -247.724168) (xy 355.655384 -247.724168)
			(xy 355.659344 -247.675114) (xy 355.671121 -247.62733) (xy 355.690412 -247.582054) (xy 355.716715 -247.540458)
			(xy 355.74935 -247.503621) (xy 355.787471 -247.472496) (xy 355.830092 -247.447889) (xy 355.876108 -247.430437)
			(xy 355.924327 -247.420593) (xy 355.973502 -247.418612) (xy 356.022357 -247.424544) (xy 356.069628 -247.438236)
			(xy 356.11409 -247.459334) (xy 356.154593 -247.48729) (xy 356.190086 -247.521382) (xy 356.219651 -247.560726)
			(xy 356.242522 -247.604303) (xy 356.258106 -247.650984) (xy 356.266001 -247.699561) (xy 356.266496 -247.724168)
			(xy 356.595438 -247.724168) (xy 356.599398 -247.675114) (xy 356.611175 -247.62733) (xy 356.630466 -247.582054)
			(xy 356.656769 -247.540458) (xy 356.689404 -247.503621) (xy 356.727525 -247.472496) (xy 356.770146 -247.447889)
			(xy 356.816162 -247.430437) (xy 356.864381 -247.420593) (xy 356.913556 -247.418612) (xy 356.962411 -247.424544)
			(xy 357.009682 -247.438236) (xy 357.054144 -247.459334) (xy 357.094647 -247.48729) (xy 357.13014 -247.521382)
			(xy 357.159705 -247.560726) (xy 357.182576 -247.604303) (xy 357.19816 -247.650984) (xy 357.206055 -247.699561)
			(xy 357.20655 -247.724168) (xy 357.535238 -247.724168) (xy 357.539198 -247.675114) (xy 357.550975 -247.62733)
			(xy 357.570266 -247.582054) (xy 357.596569 -247.540458) (xy 357.629204 -247.503621) (xy 357.667325 -247.472496)
			(xy 357.709946 -247.447889) (xy 357.755962 -247.430437) (xy 357.804181 -247.420593) (xy 357.853356 -247.418612)
			(xy 357.902211 -247.424544) (xy 357.949482 -247.438236) (xy 357.988941 -247.45696) (xy 359.396541 -247.45696)
			(xy 359.400571 -247.404462) (xy 359.412568 -247.353194) (xy 359.432251 -247.304359) (xy 359.459157 -247.2591)
			(xy 359.492657 -247.218479) (xy 359.531965 -247.183448) (xy 359.57616 -247.154828) (xy 359.624205 -247.133289)
			(xy 359.674976 -247.119337) (xy 359.727281 -247.113299) (xy 359.779895 -247.115316) (xy 359.831585 -247.12534)
			(xy 359.881138 -247.143138) (xy 359.927394 -247.168291) (xy 359.969268 -247.20021) (xy 360.00578 -247.238148)
			(xy 360.036072 -247.281214) (xy 360.059435 -247.328399) (xy 360.075321 -247.378598) (xy 360.083358 -247.430634)
			(xy 360.083862 -247.45696) (xy 360.083358 -247.483286) (xy 360.075321 -247.535322) (xy 360.059435 -247.585521)
			(xy 360.036072 -247.632706) (xy 360.00578 -247.675772) (xy 359.969268 -247.71371) (xy 359.955548 -247.724168)
			(xy 361.289104 -247.724168) (xy 361.293064 -247.675114) (xy 361.304841 -247.62733) (xy 361.324132 -247.582054)
			(xy 361.350435 -247.540458) (xy 361.38307 -247.503621) (xy 361.421191 -247.472496) (xy 361.463812 -247.447889)
			(xy 361.509828 -247.430437) (xy 361.558047 -247.420593) (xy 361.607222 -247.418612) (xy 361.656077 -247.424544)
			(xy 361.703348 -247.438236) (xy 361.74781 -247.459334) (xy 361.788313 -247.48729) (xy 361.823806 -247.521382)
			(xy 361.853371 -247.560726) (xy 361.876242 -247.604303) (xy 361.891826 -247.650984) (xy 361.899721 -247.699561)
			(xy 361.900216 -247.724168) (xy 362.228904 -247.724168) (xy 362.232864 -247.675114) (xy 362.244641 -247.62733)
			(xy 362.263932 -247.582054) (xy 362.290235 -247.540458) (xy 362.32287 -247.503621) (xy 362.360991 -247.472496)
			(xy 362.403612 -247.447889) (xy 362.449628 -247.430437) (xy 362.497847 -247.420593) (xy 362.547022 -247.418612)
			(xy 362.595877 -247.424544) (xy 362.643148 -247.438236) (xy 362.68761 -247.459334) (xy 362.728113 -247.48729)
			(xy 362.763606 -247.521382) (xy 362.793171 -247.560726) (xy 362.816042 -247.604303) (xy 362.831626 -247.650984)
			(xy 362.839521 -247.699561) (xy 362.840016 -247.724168) (xy 363.168958 -247.724168) (xy 363.172918 -247.675114)
			(xy 363.184695 -247.62733) (xy 363.203986 -247.582054) (xy 363.230289 -247.540458) (xy 363.262924 -247.503621)
			(xy 363.301045 -247.472496) (xy 363.343666 -247.447889) (xy 363.389682 -247.430437) (xy 363.437901 -247.420593)
			(xy 363.487076 -247.418612) (xy 363.535931 -247.424544) (xy 363.583202 -247.438236) (xy 363.627664 -247.459334)
			(xy 363.668167 -247.48729) (xy 363.70366 -247.521382) (xy 363.733225 -247.560726) (xy 363.756096 -247.604303)
			(xy 363.77168 -247.650984) (xy 363.779575 -247.699561) (xy 363.78007 -247.724168) (xy 363.780069 -247.7242)
			(xy 364.108908 -247.7242) (xy 364.11308 -247.67385) (xy 364.125483 -247.624874) (xy 364.145778 -247.578607)
			(xy 364.173412 -247.536312) (xy 364.207631 -247.499142) (xy 364.247501 -247.468112) (xy 364.291935 -247.444068)
			(xy 364.339721 -247.427665) (xy 364.389555 -247.419352) (xy 364.414816 -247.41886) (xy 365.35487 -247.41886)
			(xy 365.380127 -247.419414) (xy 365.429952 -247.427724) (xy 365.477729 -247.444122) (xy 365.522156 -247.468161)
			(xy 365.56202 -247.499184) (xy 365.596233 -247.536347) (xy 365.623863 -247.578634) (xy 365.644155 -247.624892)
			(xy 365.656556 -247.673859) (xy 365.660725 -247.724168) (xy 365.98912 -247.724168) (xy 365.99308 -247.675114)
			(xy 366.004857 -247.62733) (xy 366.024148 -247.582054) (xy 366.050451 -247.540458) (xy 366.083086 -247.503621)
			(xy 366.121207 -247.472496) (xy 366.163828 -247.447889) (xy 366.209844 -247.430437) (xy 366.258063 -247.420593)
			(xy 366.307238 -247.418612) (xy 366.356093 -247.424544) (xy 366.403364 -247.438236) (xy 366.447826 -247.459334)
			(xy 366.488329 -247.48729) (xy 366.523822 -247.521382) (xy 366.553387 -247.560726) (xy 366.576258 -247.604303)
			(xy 366.591842 -247.650984) (xy 366.599737 -247.699561) (xy 366.600232 -247.724168) (xy 366.600231 -247.7242)
			(xy 366.928808 -247.7242) (xy 366.93298 -247.673849) (xy 366.945384 -247.624872) (xy 366.96568 -247.578605)
			(xy 366.993314 -247.536309) (xy 367.027534 -247.499139) (xy 367.067406 -247.468109) (xy 367.111841 -247.444065)
			(xy 367.159628 -247.427663) (xy 367.209462 -247.419351) (xy 367.234724 -247.41886) (xy 368.174778 -247.41886)
			(xy 368.200034 -247.419415) (xy 368.249858 -247.427726) (xy 368.297635 -247.444124) (xy 368.34206 -247.468163)
			(xy 368.381923 -247.499187) (xy 368.416136 -247.536349) (xy 368.443764 -247.578636) (xy 368.464056 -247.624893)
			(xy 368.476457 -247.67386) (xy 368.480625 -247.724168) (xy 368.809028 -247.724168) (xy 368.812988 -247.675114)
			(xy 368.824765 -247.62733) (xy 368.844056 -247.582054) (xy 368.870359 -247.540458) (xy 368.902994 -247.503621)
			(xy 368.941115 -247.472496) (xy 368.983736 -247.447889) (xy 369.029752 -247.430437) (xy 369.077971 -247.420593)
			(xy 369.127146 -247.418612) (xy 369.176001 -247.424544) (xy 369.223272 -247.438236) (xy 369.267734 -247.459334)
			(xy 369.308237 -247.48729) (xy 369.34373 -247.521382) (xy 369.373295 -247.560726) (xy 369.396166 -247.604303)
			(xy 369.41175 -247.650984) (xy 369.419645 -247.699561) (xy 369.42014 -247.724168) (xy 369.420139 -247.7242)
			(xy 369.749037 -247.7242) (xy 369.753208 -247.673858) (xy 369.765609 -247.624889) (xy 369.785899 -247.578629)
			(xy 369.813527 -247.53634) (xy 369.847739 -247.499174) (xy 369.887601 -247.468147) (xy 369.932027 -247.444103)
			(xy 369.979804 -247.427699) (xy 370.029629 -247.419383) (xy 370.054886 -247.41886) (xy 370.99494 -247.41886)
			(xy 371.020191 -247.419449) (xy 371.070002 -247.427767) (xy 371.117765 -247.444169) (xy 371.162177 -247.468209)
			(xy 371.202028 -247.499231) (xy 371.236229 -247.536388) (xy 371.263848 -247.578667) (xy 371.284133 -247.624915)
			(xy 371.296529 -247.673871) (xy 371.300696 -247.724168) (xy 371.628936 -247.724168) (xy 371.632896 -247.675114)
			(xy 371.644673 -247.62733) (xy 371.663964 -247.582054) (xy 371.690267 -247.540458) (xy 371.722902 -247.503621)
			(xy 371.761023 -247.472496) (xy 371.803644 -247.447889) (xy 371.84966 -247.430437) (xy 371.897879 -247.420593)
			(xy 371.947054 -247.418612) (xy 371.995909 -247.424544) (xy 372.04318 -247.438236) (xy 372.087642 -247.459334)
			(xy 372.128145 -247.48729) (xy 372.163638 -247.521382) (xy 372.193203 -247.560726) (xy 372.216074 -247.604303)
			(xy 372.231658 -247.650984) (xy 372.239553 -247.699561) (xy 372.240048 -247.724168) (xy 372.240047 -247.7242)
			(xy 372.568937 -247.7242) (xy 372.573108 -247.673857) (xy 372.585509 -247.624888) (xy 372.605801 -247.578627)
			(xy 372.63343 -247.536337) (xy 372.667642 -247.499171) (xy 372.707506 -247.468144) (xy 372.751932 -247.444101)
			(xy 372.79971 -247.427698) (xy 372.849536 -247.419382) (xy 372.874794 -247.41886) (xy 373.814848 -247.41886)
			(xy 373.840098 -247.419449) (xy 373.889908 -247.427768) (xy 373.93767 -247.444172) (xy 373.982082 -247.468212)
			(xy 374.021931 -247.499233) (xy 374.056131 -247.53639) (xy 374.083749 -247.578669) (xy 374.104033 -247.624917)
			(xy 374.116429 -247.673872) (xy 374.120599 -247.7242) (xy 374.116429 -247.774528) (xy 374.104033 -247.823483)
			(xy 374.083749 -247.869731) (xy 374.056131 -247.91201) (xy 374.021931 -247.949166) (xy 373.982082 -247.980188)
			(xy 373.937671 -248.004228) (xy 373.889908 -248.020632) (xy 373.840098 -248.028951) (xy 373.814848 -248.029476)
			(xy 372.874794 -248.029476) (xy 372.849536 -248.029018) (xy 372.79971 -248.020702) (xy 372.751932 -248.004299)
			(xy 372.707506 -247.980256) (xy 372.667642 -247.949229) (xy 372.63343 -247.912063) (xy 372.605801 -247.869773)
			(xy 372.585509 -247.823512) (xy 372.573108 -247.774543) (xy 372.568937 -247.7242) (xy 372.240047 -247.7242)
			(xy 372.239553 -247.748775) (xy 372.231658 -247.797352) (xy 372.216074 -247.844033) (xy 372.193203 -247.88761)
			(xy 372.163638 -247.926954) (xy 372.128145 -247.961046) (xy 372.087642 -247.989002) (xy 372.04318 -248.0101)
			(xy 371.995909 -248.023792) (xy 371.947054 -248.029724) (xy 371.897879 -248.027743) (xy 371.84966 -248.017899)
			(xy 371.803644 -248.000447) (xy 371.761023 -247.97584) (xy 371.722902 -247.944715) (xy 371.690267 -247.907878)
			(xy 371.663964 -247.866282) (xy 371.644673 -247.821006) (xy 371.632896 -247.773222) (xy 371.628936 -247.724168)
			(xy 371.300696 -247.724168) (xy 371.300699 -247.7242) (xy 371.296529 -247.774529) (xy 371.284133 -247.823485)
			(xy 371.263848 -247.869733) (xy 371.236229 -247.912012) (xy 371.202028 -247.949169) (xy 371.162177 -247.980191)
			(xy 371.117765 -248.004231) (xy 371.070002 -248.020633) (xy 371.020191 -248.028951) (xy 370.99494 -248.029476)
			(xy 370.054886 -248.029476) (xy 370.029629 -248.029017) (xy 369.979804 -248.020701) (xy 369.932027 -248.004297)
			(xy 369.887601 -247.980253) (xy 369.847739 -247.949226) (xy 369.813527 -247.91206) (xy 369.785899 -247.869771)
			(xy 369.765609 -247.823511) (xy 369.753208 -247.774542) (xy 369.749037 -247.7242) (xy 369.420139 -247.7242)
			(xy 369.419645 -247.748775) (xy 369.41175 -247.797352) (xy 369.396166 -247.844033) (xy 369.373295 -247.88761)
			(xy 369.34373 -247.926954) (xy 369.308237 -247.961046) (xy 369.267734 -247.989002) (xy 369.223272 -248.0101)
			(xy 369.176001 -248.023792) (xy 369.127146 -248.029724) (xy 369.077971 -248.027743) (xy 369.029752 -248.017899)
			(xy 368.983736 -248.000447) (xy 368.941115 -247.97584) (xy 368.902994 -247.944715) (xy 368.870359 -247.907878)
			(xy 368.844056 -247.866282) (xy 368.824765 -247.821006) (xy 368.812988 -247.773222) (xy 368.809028 -247.724168)
			(xy 368.480625 -247.724168) (xy 368.480628 -247.7242) (xy 368.476457 -247.77454) (xy 368.464056 -247.823507)
			(xy 368.443764 -247.869764) (xy 368.416136 -247.912051) (xy 368.381923 -247.949213) (xy 368.34206 -247.980237)
			(xy 368.297635 -248.004276) (xy 368.249858 -248.020674) (xy 368.200034 -248.028985) (xy 368.174778 -248.029476)
			(xy 367.234724 -248.029476) (xy 367.209462 -248.029049) (xy 367.159628 -248.020737) (xy 367.111841 -248.004335)
			(xy 367.067406 -247.980291) (xy 367.027534 -247.949261) (xy 366.993314 -247.912091) (xy 366.96568 -247.869795)
			(xy 366.945384 -247.823528) (xy 366.93298 -247.774551) (xy 366.928808 -247.7242) (xy 366.600231 -247.7242)
			(xy 366.599737 -247.748775) (xy 366.591842 -247.797352) (xy 366.576258 -247.844033) (xy 366.553387 -247.88761)
			(xy 366.523822 -247.926954) (xy 366.488329 -247.961046) (xy 366.447826 -247.989002) (xy 366.403364 -248.0101)
			(xy 366.356093 -248.023792) (xy 366.307238 -248.029724) (xy 366.258063 -248.027743) (xy 366.209844 -248.017899)
			(xy 366.163828 -248.000447) (xy 366.121207 -247.97584) (xy 366.083086 -247.944715) (xy 366.050451 -247.907878)
			(xy 366.024148 -247.866282) (xy 366.004857 -247.821006) (xy 365.99308 -247.773222) (xy 365.98912 -247.724168)
			(xy 365.660725 -247.724168) (xy 365.660728 -247.7242) (xy 365.656556 -247.774541) (xy 365.644155 -247.823508)
			(xy 365.623863 -247.869766) (xy 365.596233 -247.912053) (xy 365.56202 -247.949216) (xy 365.522156 -247.980239)
			(xy 365.477729 -248.004278) (xy 365.429952 -248.020676) (xy 365.380127 -248.028986) (xy 365.35487 -248.029476)
			(xy 364.414816 -248.029476) (xy 364.389555 -248.029048) (xy 364.339721 -248.020735) (xy 364.291935 -248.004332)
			(xy 364.247501 -247.980288) (xy 364.207631 -247.949258) (xy 364.173412 -247.912088) (xy 364.145778 -247.869793)
			(xy 364.125483 -247.823526) (xy 364.11308 -247.77455) (xy 364.108908 -247.7242) (xy 363.780069 -247.7242)
			(xy 363.779575 -247.748775) (xy 363.77168 -247.797352) (xy 363.756096 -247.844033) (xy 363.733225 -247.88761)
			(xy 363.70366 -247.926954) (xy 363.668167 -247.961046) (xy 363.627664 -247.989002) (xy 363.583202 -248.0101)
			(xy 363.535931 -248.023792) (xy 363.487076 -248.029724) (xy 363.437901 -248.027743) (xy 363.389682 -248.017899)
			(xy 363.343666 -248.000447) (xy 363.301045 -247.97584) (xy 363.262924 -247.944715) (xy 363.230289 -247.907878)
			(xy 363.203986 -247.866282) (xy 363.184695 -247.821006) (xy 363.172918 -247.773222) (xy 363.168958 -247.724168)
			(xy 362.840016 -247.724168) (xy 362.839521 -247.748775) (xy 362.831626 -247.797352) (xy 362.816042 -247.844033)
			(xy 362.793171 -247.88761) (xy 362.763606 -247.926954) (xy 362.728113 -247.961046) (xy 362.68761 -247.989002)
			(xy 362.643148 -248.0101) (xy 362.595877 -248.023792) (xy 362.547022 -248.029724) (xy 362.497847 -248.027743)
			(xy 362.449628 -248.017899) (xy 362.403612 -248.000447) (xy 362.360991 -247.97584) (xy 362.32287 -247.944715)
			(xy 362.290235 -247.907878) (xy 362.263932 -247.866282) (xy 362.244641 -247.821006) (xy 362.232864 -247.773222)
			(xy 362.228904 -247.724168) (xy 361.900216 -247.724168) (xy 361.899721 -247.748775) (xy 361.891826 -247.797352)
			(xy 361.876242 -247.844033) (xy 361.853371 -247.88761) (xy 361.823806 -247.926954) (xy 361.788313 -247.961046)
			(xy 361.74781 -247.989002) (xy 361.703348 -248.0101) (xy 361.656077 -248.023792) (xy 361.607222 -248.029724)
			(xy 361.558047 -248.027743) (xy 361.509828 -248.017899) (xy 361.463812 -248.000447) (xy 361.421191 -247.97584)
			(xy 361.38307 -247.944715) (xy 361.350435 -247.907878) (xy 361.324132 -247.866282) (xy 361.304841 -247.821006)
			(xy 361.293064 -247.773222) (xy 361.289104 -247.724168) (xy 359.955548 -247.724168) (xy 359.927394 -247.745629)
			(xy 359.881138 -247.770782) (xy 359.831585 -247.78858) (xy 359.779895 -247.798604) (xy 359.727281 -247.800621)
			(xy 359.674976 -247.794583) (xy 359.624205 -247.780631) (xy 359.57616 -247.759092) (xy 359.531965 -247.730472)
			(xy 359.492657 -247.695441) (xy 359.459157 -247.65482) (xy 359.432251 -247.609561) (xy 359.412568 -247.560726)
			(xy 359.400571 -247.509458) (xy 359.396541 -247.45696) (xy 357.988941 -247.45696) (xy 357.993944 -247.459334)
			(xy 358.034447 -247.48729) (xy 358.06994 -247.521382) (xy 358.099505 -247.560726) (xy 358.122376 -247.604303)
			(xy 358.13796 -247.650984) (xy 358.145855 -247.699561) (xy 358.14635 -247.724168) (xy 358.145855 -247.748775)
			(xy 358.13796 -247.797352) (xy 358.122376 -247.844033) (xy 358.099505 -247.88761) (xy 358.06994 -247.926954)
			(xy 358.034447 -247.961046) (xy 357.993944 -247.989002) (xy 357.949482 -248.0101) (xy 357.902211 -248.023792)
			(xy 357.853356 -248.029724) (xy 357.804181 -248.027743) (xy 357.755962 -248.017899) (xy 357.709946 -248.000447)
			(xy 357.667325 -247.97584) (xy 357.629204 -247.944715) (xy 357.596569 -247.907878) (xy 357.570266 -247.866282)
			(xy 357.550975 -247.821006) (xy 357.539198 -247.773222) (xy 357.535238 -247.724168) (xy 357.20655 -247.724168)
			(xy 357.206055 -247.748775) (xy 357.19816 -247.797352) (xy 357.182576 -247.844033) (xy 357.159705 -247.88761)
			(xy 357.13014 -247.926954) (xy 357.094647 -247.961046) (xy 357.054144 -247.989002) (xy 357.009682 -248.0101)
			(xy 356.962411 -248.023792) (xy 356.913556 -248.029724) (xy 356.864381 -248.027743) (xy 356.816162 -248.017899)
			(xy 356.770146 -248.000447) (xy 356.727525 -247.97584) (xy 356.689404 -247.944715) (xy 356.656769 -247.907878)
			(xy 356.630466 -247.866282) (xy 356.611175 -247.821006) (xy 356.599398 -247.773222) (xy 356.595438 -247.724168)
			(xy 356.266496 -247.724168) (xy 356.266001 -247.748775) (xy 356.258106 -247.797352) (xy 356.242522 -247.844033)
			(xy 356.219651 -247.88761) (xy 356.190086 -247.926954) (xy 356.154593 -247.961046) (xy 356.11409 -247.989002)
			(xy 356.069628 -248.0101) (xy 356.022357 -248.023792) (xy 355.973502 -248.029724) (xy 355.924327 -248.027743)
			(xy 355.876108 -248.017899) (xy 355.830092 -248.000447) (xy 355.787471 -247.97584) (xy 355.74935 -247.944715)
			(xy 355.716715 -247.907878) (xy 355.690412 -247.866282) (xy 355.671121 -247.821006) (xy 355.659344 -247.773222)
			(xy 355.655384 -247.724168) (xy 355.326442 -247.724168) (xy 355.325947 -247.748775) (xy 355.318052 -247.797352)
			(xy 355.302468 -247.844033) (xy 355.279597 -247.88761) (xy 355.250032 -247.926954) (xy 355.214539 -247.961046)
			(xy 355.174036 -247.989002) (xy 355.129574 -248.0101) (xy 355.082303 -248.023792) (xy 355.033448 -248.029724)
			(xy 354.984273 -248.027743) (xy 354.936054 -248.017899) (xy 354.890038 -248.000447) (xy 354.847417 -247.97584)
			(xy 354.809296 -247.944715) (xy 354.776661 -247.907878) (xy 354.750358 -247.866282) (xy 354.731067 -247.821006)
			(xy 354.71929 -247.773222) (xy 354.71533 -247.724168) (xy 354.386388 -247.724168) (xy 354.385893 -247.748775)
			(xy 354.377998 -247.797352) (xy 354.362414 -247.844033) (xy 354.339543 -247.88761) (xy 354.309978 -247.926954)
			(xy 354.274485 -247.961046) (xy 354.233982 -247.989002) (xy 354.18952 -248.0101) (xy 354.142249 -248.023792)
			(xy 354.093394 -248.029724) (xy 354.044219 -248.027743) (xy 353.996 -248.017899) (xy 353.949984 -248.000447)
			(xy 353.907363 -247.97584) (xy 353.869242 -247.944715) (xy 353.836607 -247.907878) (xy 353.810304 -247.866282)
			(xy 353.791013 -247.821006) (xy 353.779236 -247.773222) (xy 353.775276 -247.724168) (xy 353.446334 -247.724168)
			(xy 353.445839 -247.748775) (xy 353.437944 -247.797352) (xy 353.42236 -247.844033) (xy 353.399489 -247.88761)
			(xy 353.369924 -247.926954) (xy 353.334431 -247.961046) (xy 353.293928 -247.989002) (xy 353.249466 -248.0101)
			(xy 353.202195 -248.023792) (xy 353.15334 -248.029724) (xy 353.104165 -248.027743) (xy 353.055946 -248.017899)
			(xy 353.00993 -248.000447) (xy 352.967309 -247.97584) (xy 352.929188 -247.944715) (xy 352.896553 -247.907878)
			(xy 352.87025 -247.866282) (xy 352.850959 -247.821006) (xy 352.839182 -247.773222) (xy 352.835222 -247.724168)
			(xy 352.506534 -247.724168) (xy 352.506039 -247.748775) (xy 352.498144 -247.797352) (xy 352.48256 -247.844033)
			(xy 352.459689 -247.88761) (xy 352.430124 -247.926954) (xy 352.394631 -247.961046) (xy 352.354128 -247.989002)
			(xy 352.309666 -248.0101) (xy 352.262395 -248.023792) (xy 352.21354 -248.029724) (xy 352.164365 -248.027743)
			(xy 352.116146 -248.017899) (xy 352.07013 -248.000447) (xy 352.027509 -247.97584) (xy 351.989388 -247.944715)
			(xy 351.956753 -247.907878) (xy 351.93045 -247.866282) (xy 351.911159 -247.821006) (xy 351.899382 -247.773222)
			(xy 351.895422 -247.724168) (xy 351.56648 -247.724168) (xy 351.565985 -247.748775) (xy 351.55809 -247.797352)
			(xy 351.542506 -247.844033) (xy 351.519635 -247.88761) (xy 351.49007 -247.926954) (xy 351.454577 -247.961046)
			(xy 351.414074 -247.989002) (xy 351.369612 -248.0101) (xy 351.322341 -248.023792) (xy 351.273486 -248.029724)
			(xy 351.224311 -248.027743) (xy 351.176092 -248.017899) (xy 351.130076 -248.000447) (xy 351.087455 -247.97584)
			(xy 351.049334 -247.944715) (xy 351.016699 -247.907878) (xy 350.990396 -247.866282) (xy 350.971105 -247.821006)
			(xy 350.959328 -247.773222) (xy 350.955368 -247.724168) (xy 350.626426 -247.724168) (xy 350.625931 -247.748775)
			(xy 350.618036 -247.797352) (xy 350.602452 -247.844033) (xy 350.579581 -247.88761) (xy 350.550016 -247.926954)
			(xy 350.514523 -247.961046) (xy 350.47402 -247.989002) (xy 350.429558 -248.0101) (xy 350.382287 -248.023792)
			(xy 350.333432 -248.029724) (xy 350.284257 -248.027743) (xy 350.236038 -248.017899) (xy 350.190022 -248.000447)
			(xy 350.147401 -247.97584) (xy 350.10928 -247.944715) (xy 350.076645 -247.907878) (xy 350.050342 -247.866282)
			(xy 350.031051 -247.821006) (xy 350.019274 -247.773222) (xy 350.015314 -247.724168) (xy 349.686372 -247.724168)
			(xy 349.685877 -247.748775) (xy 349.677982 -247.797352) (xy 349.662398 -247.844033) (xy 349.639527 -247.88761)
			(xy 349.609962 -247.926954) (xy 349.574469 -247.961046) (xy 349.533966 -247.989002) (xy 349.489504 -248.0101)
			(xy 349.442233 -248.023792) (xy 349.393378 -248.029724) (xy 349.344203 -248.027743) (xy 349.295984 -248.017899)
			(xy 349.249968 -248.000447) (xy 349.207347 -247.97584) (xy 349.169226 -247.944715) (xy 349.136591 -247.907878)
			(xy 349.110288 -247.866282) (xy 349.090997 -247.821006) (xy 349.07922 -247.773222) (xy 349.07526 -247.724168)
			(xy 348.746318 -247.724168) (xy 348.745823 -247.748775) (xy 348.737928 -247.797352) (xy 348.722344 -247.844033)
			(xy 348.699473 -247.88761) (xy 348.669908 -247.926954) (xy 348.634415 -247.961046) (xy 348.593912 -247.989002)
			(xy 348.54945 -248.0101) (xy 348.502179 -248.023792) (xy 348.453324 -248.029724) (xy 348.404149 -248.027743)
			(xy 348.35593 -248.017899) (xy 348.309914 -248.000447) (xy 348.267293 -247.97584) (xy 348.229172 -247.944715)
			(xy 348.196537 -247.907878) (xy 348.170234 -247.866282) (xy 348.150943 -247.821006) (xy 348.139166 -247.773222)
			(xy 348.135206 -247.724168) (xy 347.806518 -247.724168) (xy 347.806023 -247.748775) (xy 347.798128 -247.797352)
			(xy 347.782544 -247.844033) (xy 347.759673 -247.88761) (xy 347.730108 -247.926954) (xy 347.694615 -247.961046)
			(xy 347.654112 -247.989002) (xy 347.60965 -248.0101) (xy 347.562379 -248.023792) (xy 347.513524 -248.029724)
			(xy 347.464349 -248.027743) (xy 347.41613 -248.017899) (xy 347.370114 -248.000447) (xy 347.327493 -247.97584)
			(xy 347.289372 -247.944715) (xy 347.256737 -247.907878) (xy 347.230434 -247.866282) (xy 347.211143 -247.821006)
			(xy 347.199366 -247.773222) (xy 347.195406 -247.724168) (xy 346.866464 -247.724168) (xy 346.865969 -247.748775)
			(xy 346.858074 -247.797352) (xy 346.84249 -247.844033) (xy 346.819619 -247.88761) (xy 346.790054 -247.926954)
			(xy 346.754561 -247.961046) (xy 346.714058 -247.989002) (xy 346.669596 -248.0101) (xy 346.622325 -248.023792)
			(xy 346.57347 -248.029724) (xy 346.524295 -248.027743) (xy 346.476076 -248.017899) (xy 346.43006 -248.000447)
			(xy 346.387439 -247.97584) (xy 346.349318 -247.944715) (xy 346.316683 -247.907878) (xy 346.29038 -247.866282)
			(xy 346.271089 -247.821006) (xy 346.259312 -247.773222) (xy 346.255352 -247.724168) (xy 345.92641 -247.724168)
			(xy 345.925915 -247.748775) (xy 345.91802 -247.797352) (xy 345.902436 -247.844033) (xy 345.879565 -247.88761)
			(xy 345.85 -247.926954) (xy 345.814507 -247.961046) (xy 345.774004 -247.989002) (xy 345.729542 -248.0101)
			(xy 345.682271 -248.023792) (xy 345.633416 -248.029724) (xy 345.584241 -248.027743) (xy 345.536022 -248.017899)
			(xy 345.490006 -248.000447) (xy 345.447385 -247.97584) (xy 345.409264 -247.944715) (xy 345.376629 -247.907878)
			(xy 345.350326 -247.866282) (xy 345.331035 -247.821006) (xy 345.319258 -247.773222) (xy 345.315298 -247.724168)
			(xy 344.985878 -247.724168) (xy 344.98588 -247.74864) (xy 344.978088 -247.796939) (xy 344.962699 -247.843379)
			(xy 344.940108 -247.886774) (xy 344.910891 -247.926015) (xy 344.893646 -247.94337) (xy 344.886534 -247.950228)
			(xy 344.87485 -247.976644) (xy 344.87282 -247.981542) (xy 344.870644 -247.991917) (xy 344.870532 -247.997218)
			(xy 344.870532 -248.585228) (xy 344.870961 -248.595295) (xy 344.878686 -248.613889) (xy 344.885518 -248.621296)
			(xy 345.109546 -248.845324) (xy 345.116943 -248.852172) (xy 345.135542 -248.859901) (xy 345.145614 -248.86031)
			(xy 346.693998 -248.86031) (xy 346.703198 -248.85991) (xy 346.72042 -248.853426) (xy 346.734276 -248.841316)
			(xy 346.738956 -248.833386) (xy 346.786708 -248.743724) (xy 346.785184 -248.715784) (xy 346.77731 -248.7041)
			(xy 346.765123 -248.685143) (xy 346.745851 -248.644406) (xy 346.732763 -248.601283) (xy 346.726142 -248.556707)
			(xy 346.725748 -248.534174) (xy 346.72627 -248.508919) (xy 346.734583 -248.459097) (xy 346.750984 -248.411323)
			(xy 346.775025 -248.3669) (xy 346.806049 -248.32704) (xy 346.843211 -248.29283) (xy 346.885497 -248.265204)
			(xy 346.931753 -248.244914) (xy 346.980718 -248.232514) (xy 347.031056 -248.228343) (xy 347.081394 -248.232514)
			(xy 347.130359 -248.244914) (xy 347.176615 -248.265204) (xy 347.218901 -248.29283) (xy 347.256063 -248.32704)
			(xy 347.287087 -248.3669) (xy 347.311128 -248.411323) (xy 347.327529 -248.459097) (xy 347.335842 -248.508919)
			(xy 347.336364 -248.534174) (xy 349.545414 -248.534174) (xy 349.549374 -248.48512) (xy 349.561151 -248.437336)
			(xy 349.580442 -248.39206) (xy 349.606745 -248.350464) (xy 349.63938 -248.313627) (xy 349.677501 -248.282502)
			(xy 349.720122 -248.257895) (xy 349.766138 -248.240443) (xy 349.814357 -248.230599) (xy 349.863532 -248.228618)
			(xy 349.912387 -248.23455) (xy 349.959658 -248.248242) (xy 350.00412 -248.26934) (xy 350.044623 -248.297296)
			(xy 350.080116 -248.331388) (xy 350.109681 -248.370732) (xy 350.132552 -248.414309) (xy 350.148136 -248.46099)
			(xy 350.156031 -248.509567) (xy 350.156526 -248.534174) (xy 352.365322 -248.534174) (xy 352.369282 -248.48512)
			(xy 352.381059 -248.437336) (xy 352.40035 -248.39206) (xy 352.426653 -248.350464) (xy 352.459288 -248.313627)
			(xy 352.497409 -248.282502) (xy 352.54003 -248.257895) (xy 352.586046 -248.240443) (xy 352.634265 -248.230599)
			(xy 352.68344 -248.228618) (xy 352.732295 -248.23455) (xy 352.779566 -248.248242) (xy 352.824028 -248.26934)
			(xy 352.864531 -248.297296) (xy 352.900024 -248.331388) (xy 352.929589 -248.370732) (xy 352.95246 -248.414309)
			(xy 352.968044 -248.46099) (xy 352.975939 -248.509567) (xy 352.976434 -248.534174) (xy 355.18523 -248.534174)
			(xy 355.18919 -248.48512) (xy 355.200967 -248.437336) (xy 355.220258 -248.39206) (xy 355.246561 -248.350464)
			(xy 355.279196 -248.313627) (xy 355.317317 -248.282502) (xy 355.359938 -248.257895) (xy 355.405954 -248.240443)
			(xy 355.454173 -248.230599) (xy 355.503348 -248.228618) (xy 355.552203 -248.23455) (xy 355.599474 -248.248242)
			(xy 355.643936 -248.26934) (xy 355.684439 -248.297296) (xy 355.719932 -248.331388) (xy 355.749497 -248.370732)
			(xy 355.772368 -248.414309) (xy 355.787952 -248.46099) (xy 355.795847 -248.509567) (xy 355.796342 -248.534174)
			(xy 356.125284 -248.534174) (xy 356.129244 -248.48512) (xy 356.141021 -248.437336) (xy 356.160312 -248.39206)
			(xy 356.186615 -248.350464) (xy 356.21925 -248.313627) (xy 356.257371 -248.282502) (xy 356.299992 -248.257895)
			(xy 356.346008 -248.240443) (xy 356.394227 -248.230599) (xy 356.443402 -248.228618) (xy 356.492257 -248.23455)
			(xy 356.539528 -248.248242) (xy 356.58399 -248.26934) (xy 356.624493 -248.297296) (xy 356.659986 -248.331388)
			(xy 356.689551 -248.370732) (xy 356.712422 -248.414309) (xy 356.728006 -248.46099) (xy 356.735901 -248.509567)
			(xy 356.736396 -248.534174) (xy 357.065338 -248.534174) (xy 357.069298 -248.48512) (xy 357.081075 -248.437336)
			(xy 357.100366 -248.39206) (xy 357.126669 -248.350464) (xy 357.159304 -248.313627) (xy 357.197425 -248.282502)
			(xy 357.240046 -248.257895) (xy 357.286062 -248.240443) (xy 357.334281 -248.230599) (xy 357.383456 -248.228618)
			(xy 357.432311 -248.23455) (xy 357.479582 -248.248242) (xy 357.524044 -248.26934) (xy 357.564547 -248.297296)
			(xy 357.60004 -248.331388) (xy 357.629605 -248.370732) (xy 357.652476 -248.414309) (xy 357.66806 -248.46099)
			(xy 357.675955 -248.509567) (xy 357.67645 -248.534174) (xy 358.005392 -248.534174) (xy 358.009352 -248.48512)
			(xy 358.021129 -248.437336) (xy 358.04042 -248.39206) (xy 358.066723 -248.350464) (xy 358.099358 -248.313627)
			(xy 358.137479 -248.282502) (xy 358.1801 -248.257895) (xy 358.226116 -248.240443) (xy 358.274335 -248.230599)
			(xy 358.32351 -248.228618) (xy 358.372365 -248.23455) (xy 358.419636 -248.248242) (xy 358.464098 -248.26934)
			(xy 358.504601 -248.297296) (xy 358.540094 -248.331388) (xy 358.569659 -248.370732) (xy 358.59253 -248.414309)
			(xy 358.608114 -248.46099) (xy 358.616009 -248.509567) (xy 358.616504 -248.534174) (xy 360.81895 -248.534174)
			(xy 360.82291 -248.48512) (xy 360.834687 -248.437336) (xy 360.853978 -248.39206) (xy 360.880281 -248.350464)
			(xy 360.912916 -248.313627) (xy 360.951037 -248.282502) (xy 360.993658 -248.257895) (xy 361.039674 -248.240443)
			(xy 361.087893 -248.230599) (xy 361.137068 -248.228618) (xy 361.185923 -248.23455) (xy 361.233194 -248.248242)
			(xy 361.277656 -248.26934) (xy 361.318159 -248.297296) (xy 361.353652 -248.331388) (xy 361.383217 -248.370732)
			(xy 361.406088 -248.414309) (xy 361.421672 -248.46099) (xy 361.429567 -248.509567) (xy 361.430062 -248.534174)
			(xy 361.430061 -248.5342) (xy 361.758659 -248.5342) (xy 361.762835 -248.48381) (xy 361.775248 -248.434795)
			(xy 361.795559 -248.388491) (xy 361.823214 -248.346162) (xy 361.85746 -248.308962) (xy 361.897361 -248.277907)
			(xy 361.94183 -248.253842) (xy 361.989653 -248.237426) (xy 362.039527 -248.229104) (xy 362.064808 -248.228612)
			(xy 363.004862 -248.228612) (xy 363.030141 -248.229154) (xy 363.080009 -248.23747) (xy 363.127829 -248.253881)
			(xy 363.172294 -248.27794) (xy 363.212193 -248.30899) (xy 363.246437 -248.346184) (xy 363.274091 -248.388507)
			(xy 363.294401 -248.434806) (xy 363.306813 -248.483816) (xy 363.310987 -248.534174) (xy 363.639112 -248.534174)
			(xy 363.643072 -248.48512) (xy 363.654849 -248.437336) (xy 363.67414 -248.39206) (xy 363.700443 -248.350464)
			(xy 363.733078 -248.313627) (xy 363.771199 -248.282502) (xy 363.81382 -248.257895) (xy 363.859836 -248.240443)
			(xy 363.908055 -248.230599) (xy 363.95723 -248.228618) (xy 364.006085 -248.23455) (xy 364.053356 -248.248242)
			(xy 364.097818 -248.26934) (xy 364.138321 -248.297296) (xy 364.173814 -248.331388) (xy 364.203379 -248.370732)
			(xy 364.22625 -248.414309) (xy 364.241834 -248.46099) (xy 364.249729 -248.509567) (xy 364.250224 -248.534174)
			(xy 366.45902 -248.534174) (xy 366.46298 -248.48512) (xy 366.474757 -248.437336) (xy 366.494048 -248.39206)
			(xy 366.520351 -248.350464) (xy 366.552986 -248.313627) (xy 366.591107 -248.282502) (xy 366.633728 -248.257895)
			(xy 366.679744 -248.240443) (xy 366.727963 -248.230599) (xy 366.777138 -248.228618) (xy 366.825993 -248.23455)
			(xy 366.873264 -248.248242) (xy 366.917726 -248.26934) (xy 366.958229 -248.297296) (xy 366.993722 -248.331388)
			(xy 367.023287 -248.370732) (xy 367.046158 -248.414309) (xy 367.061742 -248.46099) (xy 367.069637 -248.509567)
			(xy 367.070132 -248.534174) (xy 369.278928 -248.534174) (xy 369.282888 -248.48512) (xy 369.294665 -248.437336)
			(xy 369.313956 -248.39206) (xy 369.340259 -248.350464) (xy 369.372894 -248.313627) (xy 369.411015 -248.282502)
			(xy 369.453636 -248.257895) (xy 369.499652 -248.240443) (xy 369.547871 -248.230599) (xy 369.597046 -248.228618)
			(xy 369.645901 -248.23455) (xy 369.693172 -248.248242) (xy 369.737634 -248.26934) (xy 369.778137 -248.297296)
			(xy 369.81363 -248.331388) (xy 369.843195 -248.370732) (xy 369.866066 -248.414309) (xy 369.88165 -248.46099)
			(xy 369.889545 -248.509567) (xy 369.89004 -248.534174) (xy 372.09909 -248.534174) (xy 372.10305 -248.48512)
			(xy 372.114827 -248.437336) (xy 372.134118 -248.39206) (xy 372.160421 -248.350464) (xy 372.193056 -248.313627)
			(xy 372.231177 -248.282502) (xy 372.273798 -248.257895) (xy 372.319814 -248.240443) (xy 372.368033 -248.230599)
			(xy 372.417208 -248.228618) (xy 372.466063 -248.23455) (xy 372.513334 -248.248242) (xy 372.557796 -248.26934)
			(xy 372.598299 -248.297296) (xy 372.633792 -248.331388) (xy 372.663357 -248.370732) (xy 372.686228 -248.414309)
			(xy 372.701812 -248.46099) (xy 372.709707 -248.509567) (xy 372.710202 -248.534174) (xy 372.709707 -248.558781)
			(xy 372.701812 -248.607358) (xy 372.686228 -248.654039) (xy 372.663357 -248.697616) (xy 372.633792 -248.73696)
			(xy 372.598299 -248.771052) (xy 372.557796 -248.799008) (xy 372.513334 -248.820106) (xy 372.466063 -248.833798)
			(xy 372.417208 -248.83973) (xy 372.368033 -248.837749) (xy 372.319814 -248.827905) (xy 372.273798 -248.810453)
			(xy 372.231177 -248.785846) (xy 372.193056 -248.754721) (xy 372.160421 -248.717884) (xy 372.134118 -248.676288)
			(xy 372.114827 -248.631012) (xy 372.10305 -248.583228) (xy 372.09909 -248.534174) (xy 369.89004 -248.534174)
			(xy 369.889545 -248.558781) (xy 369.88165 -248.607358) (xy 369.866066 -248.654039) (xy 369.843195 -248.697616)
			(xy 369.81363 -248.73696) (xy 369.778137 -248.771052) (xy 369.737634 -248.799008) (xy 369.693172 -248.820106)
			(xy 369.645901 -248.833798) (xy 369.597046 -248.83973) (xy 369.547871 -248.837749) (xy 369.499652 -248.827905)
			(xy 369.453636 -248.810453) (xy 369.411015 -248.785846) (xy 369.372894 -248.754721) (xy 369.340259 -248.717884)
			(xy 369.313956 -248.676288) (xy 369.294665 -248.631012) (xy 369.282888 -248.583228) (xy 369.278928 -248.534174)
			(xy 367.070132 -248.534174) (xy 367.069637 -248.558781) (xy 367.061742 -248.607358) (xy 367.046158 -248.654039)
			(xy 367.023287 -248.697616) (xy 366.993722 -248.73696) (xy 366.958229 -248.771052) (xy 366.917726 -248.799008)
			(xy 366.873264 -248.820106) (xy 366.825993 -248.833798) (xy 366.777138 -248.83973) (xy 366.727963 -248.837749)
			(xy 366.679744 -248.827905) (xy 366.633728 -248.810453) (xy 366.591107 -248.785846) (xy 366.552986 -248.754721)
			(xy 366.520351 -248.717884) (xy 366.494048 -248.676288) (xy 366.474757 -248.631012) (xy 366.46298 -248.583228)
			(xy 366.45902 -248.534174) (xy 364.250224 -248.534174) (xy 364.249729 -248.558781) (xy 364.241834 -248.607358)
			(xy 364.22625 -248.654039) (xy 364.203379 -248.697616) (xy 364.173814 -248.73696) (xy 364.138321 -248.771052)
			(xy 364.097818 -248.799008) (xy 364.053356 -248.820106) (xy 364.006085 -248.833798) (xy 363.95723 -248.83973)
			(xy 363.908055 -248.837749) (xy 363.859836 -248.827905) (xy 363.81382 -248.810453) (xy 363.771199 -248.785846)
			(xy 363.733078 -248.754721) (xy 363.700443 -248.717884) (xy 363.67414 -248.676288) (xy 363.654849 -248.631012)
			(xy 363.643072 -248.583228) (xy 363.639112 -248.534174) (xy 363.310987 -248.534174) (xy 363.310989 -248.5342)
			(xy 363.306813 -248.584584) (xy 363.294401 -248.633594) (xy 363.274091 -248.679893) (xy 363.246437 -248.722216)
			(xy 363.212193 -248.75941) (xy 363.172294 -248.79046) (xy 363.127829 -248.814519) (xy 363.080009 -248.83093)
			(xy 363.030141 -248.839246) (xy 363.004862 -248.839736) (xy 362.064808 -248.839736) (xy 362.039527 -248.839296)
			(xy 361.989653 -248.830974) (xy 361.94183 -248.814558) (xy 361.897361 -248.790493) (xy 361.85746 -248.759438)
			(xy 361.823214 -248.722238) (xy 361.795559 -248.679909) (xy 361.775248 -248.633605) (xy 361.762835 -248.58459)
			(xy 361.758659 -248.5342) (xy 361.430061 -248.5342) (xy 361.429567 -248.558781) (xy 361.421672 -248.607358)
			(xy 361.406088 -248.654039) (xy 361.383217 -248.697616) (xy 361.353652 -248.73696) (xy 361.318159 -248.771052)
			(xy 361.277656 -248.799008) (xy 361.233194 -248.820106) (xy 361.185923 -248.833798) (xy 361.137068 -248.83973)
			(xy 361.087893 -248.837749) (xy 361.039674 -248.827905) (xy 360.993658 -248.810453) (xy 360.951037 -248.785846)
			(xy 360.912916 -248.754721) (xy 360.880281 -248.717884) (xy 360.853978 -248.676288) (xy 360.834687 -248.631012)
			(xy 360.82291 -248.583228) (xy 360.81895 -248.534174) (xy 358.616504 -248.534174) (xy 358.616009 -248.558781)
			(xy 358.608114 -248.607358) (xy 358.59253 -248.654039) (xy 358.569659 -248.697616) (xy 358.540094 -248.73696)
			(xy 358.504601 -248.771052) (xy 358.464098 -248.799008) (xy 358.419636 -248.820106) (xy 358.372365 -248.833798)
			(xy 358.32351 -248.83973) (xy 358.274335 -248.837749) (xy 358.226116 -248.827905) (xy 358.1801 -248.810453)
			(xy 358.137479 -248.785846) (xy 358.099358 -248.754721) (xy 358.066723 -248.717884) (xy 358.04042 -248.676288)
			(xy 358.021129 -248.631012) (xy 358.009352 -248.583228) (xy 358.005392 -248.534174) (xy 357.67645 -248.534174)
			(xy 357.675955 -248.558781) (xy 357.66806 -248.607358) (xy 357.652476 -248.654039) (xy 357.629605 -248.697616)
			(xy 357.60004 -248.73696) (xy 357.564547 -248.771052) (xy 357.524044 -248.799008) (xy 357.479582 -248.820106)
			(xy 357.432311 -248.833798) (xy 357.383456 -248.83973) (xy 357.334281 -248.837749) (xy 357.286062 -248.827905)
			(xy 357.240046 -248.810453) (xy 357.197425 -248.785846) (xy 357.159304 -248.754721) (xy 357.126669 -248.717884)
			(xy 357.100366 -248.676288) (xy 357.081075 -248.631012) (xy 357.069298 -248.583228) (xy 357.065338 -248.534174)
			(xy 356.736396 -248.534174) (xy 356.735901 -248.558781) (xy 356.728006 -248.607358) (xy 356.712422 -248.654039)
			(xy 356.689551 -248.697616) (xy 356.659986 -248.73696) (xy 356.624493 -248.771052) (xy 356.58399 -248.799008)
			(xy 356.539528 -248.820106) (xy 356.492257 -248.833798) (xy 356.443402 -248.83973) (xy 356.394227 -248.837749)
			(xy 356.346008 -248.827905) (xy 356.299992 -248.810453) (xy 356.257371 -248.785846) (xy 356.21925 -248.754721)
			(xy 356.186615 -248.717884) (xy 356.160312 -248.676288) (xy 356.141021 -248.631012) (xy 356.129244 -248.583228)
			(xy 356.125284 -248.534174) (xy 355.796342 -248.534174) (xy 355.795847 -248.558781) (xy 355.787952 -248.607358)
			(xy 355.772368 -248.654039) (xy 355.749497 -248.697616) (xy 355.719932 -248.73696) (xy 355.684439 -248.771052)
			(xy 355.643936 -248.799008) (xy 355.599474 -248.820106) (xy 355.552203 -248.833798) (xy 355.503348 -248.83973)
			(xy 355.454173 -248.837749) (xy 355.405954 -248.827905) (xy 355.359938 -248.810453) (xy 355.317317 -248.785846)
			(xy 355.279196 -248.754721) (xy 355.246561 -248.717884) (xy 355.220258 -248.676288) (xy 355.200967 -248.631012)
			(xy 355.18919 -248.583228) (xy 355.18523 -248.534174) (xy 352.976434 -248.534174) (xy 352.975939 -248.558781)
			(xy 352.968044 -248.607358) (xy 352.95246 -248.654039) (xy 352.929589 -248.697616) (xy 352.900024 -248.73696)
			(xy 352.864531 -248.771052) (xy 352.824028 -248.799008) (xy 352.779566 -248.820106) (xy 352.732295 -248.833798)
			(xy 352.68344 -248.83973) (xy 352.634265 -248.837749) (xy 352.586046 -248.827905) (xy 352.54003 -248.810453)
			(xy 352.497409 -248.785846) (xy 352.459288 -248.754721) (xy 352.426653 -248.717884) (xy 352.40035 -248.676288)
			(xy 352.381059 -248.631012) (xy 352.369282 -248.583228) (xy 352.365322 -248.534174) (xy 350.156526 -248.534174)
			(xy 350.156031 -248.558781) (xy 350.148136 -248.607358) (xy 350.132552 -248.654039) (xy 350.109681 -248.697616)
			(xy 350.080116 -248.73696) (xy 350.044623 -248.771052) (xy 350.00412 -248.799008) (xy 349.959658 -248.820106)
			(xy 349.912387 -248.833798) (xy 349.863532 -248.83973) (xy 349.814357 -248.837749) (xy 349.766138 -248.827905)
			(xy 349.720122 -248.810453) (xy 349.677501 -248.785846) (xy 349.63938 -248.754721) (xy 349.606745 -248.717884)
			(xy 349.580442 -248.676288) (xy 349.561151 -248.631012) (xy 349.549374 -248.583228) (xy 349.545414 -248.534174)
			(xy 347.336364 -248.534174) (xy 347.336052 -248.553959) (xy 347.330961 -248.593199) (xy 347.326204 -248.612406)
			(xy 347.319274 -248.636788) (xy 347.298466 -248.683005) (xy 347.284802 -248.704354) (xy 347.276928 -248.716292)
			(xy 347.275404 -248.744232) (xy 347.323156 -248.833386) (xy 347.327813 -248.841341) (xy 347.341648 -248.853501)
			(xy 347.358902 -248.859946) (xy 347.368114 -248.86031) (xy 347.389958 -248.86031) (xy 347.399796 -248.860844)
			(xy 347.417959 -248.868429) (xy 347.425264 -248.875042) (xy 347.608398 -249.058176) (xy 347.617542 -249.061986)
			(xy 347.639641 -249.071587) (xy 347.680746 -249.096719) (xy 347.717394 -249.127997) (xy 347.748673 -249.164643)
			(xy 347.773807 -249.205748) (xy 347.783404 -249.227848) (xy 347.787214 -249.236992) (xy 347.894402 -249.34418)
			(xy 349.07526 -249.34418) (xy 349.07922 -249.295126) (xy 349.090997 -249.247342) (xy 349.110288 -249.202066)
			(xy 349.136591 -249.16047) (xy 349.169226 -249.123633) (xy 349.207347 -249.092508) (xy 349.249968 -249.067901)
			(xy 349.295984 -249.050449) (xy 349.344203 -249.040605) (xy 349.393378 -249.038624) (xy 349.442233 -249.044556)
			(xy 349.489504 -249.058248) (xy 349.533966 -249.079346) (xy 349.574469 -249.107302) (xy 349.609962 -249.141394)
			(xy 349.639527 -249.180738) (xy 349.662398 -249.224315) (xy 349.677982 -249.270996) (xy 349.685877 -249.319573)
			(xy 349.686372 -249.34418) (xy 350.955368 -249.34418) (xy 350.959328 -249.295126) (xy 350.971105 -249.247342)
			(xy 350.990396 -249.202066) (xy 351.016699 -249.16047) (xy 351.049334 -249.123633) (xy 351.087455 -249.092508)
			(xy 351.130076 -249.067901) (xy 351.176092 -249.050449) (xy 351.224311 -249.040605) (xy 351.273486 -249.038624)
			(xy 351.322341 -249.044556) (xy 351.369612 -249.058248) (xy 351.414074 -249.079346) (xy 351.454577 -249.107302)
			(xy 351.49007 -249.141394) (xy 351.519635 -249.180738) (xy 351.542506 -249.224315) (xy 351.55809 -249.270996)
			(xy 351.565985 -249.319573) (xy 351.56648 -249.34418) (xy 352.835222 -249.34418) (xy 352.839182 -249.295126)
			(xy 352.850959 -249.247342) (xy 352.87025 -249.202066) (xy 352.896553 -249.16047) (xy 352.929188 -249.123633)
			(xy 352.967309 -249.092508) (xy 353.00993 -249.067901) (xy 353.055946 -249.050449) (xy 353.104165 -249.040605)
			(xy 353.15334 -249.038624) (xy 353.202195 -249.044556) (xy 353.249466 -249.058248) (xy 353.293928 -249.079346)
			(xy 353.334431 -249.107302) (xy 353.369924 -249.141394) (xy 353.399489 -249.180738) (xy 353.42236 -249.224315)
			(xy 353.437944 -249.270996) (xy 353.445839 -249.319573) (xy 353.446334 -249.34418) (xy 354.71533 -249.34418)
			(xy 354.71929 -249.295126) (xy 354.731067 -249.247342) (xy 354.750358 -249.202066) (xy 354.776661 -249.16047)
			(xy 354.809296 -249.123633) (xy 354.847417 -249.092508) (xy 354.890038 -249.067901) (xy 354.936054 -249.050449)
			(xy 354.984273 -249.040605) (xy 355.033448 -249.038624) (xy 355.082303 -249.044556) (xy 355.129574 -249.058248)
			(xy 355.174036 -249.079346) (xy 355.214539 -249.107302) (xy 355.250032 -249.141394) (xy 355.279597 -249.180738)
			(xy 355.302468 -249.224315) (xy 355.318052 -249.270996) (xy 355.325947 -249.319573) (xy 355.326442 -249.34418)
			(xy 356.595438 -249.34418) (xy 356.599398 -249.295126) (xy 356.611175 -249.247342) (xy 356.630466 -249.202066)
			(xy 356.656769 -249.16047) (xy 356.689404 -249.123633) (xy 356.727525 -249.092508) (xy 356.770146 -249.067901)
			(xy 356.816162 -249.050449) (xy 356.864381 -249.040605) (xy 356.913556 -249.038624) (xy 356.962411 -249.044556)
			(xy 357.009682 -249.058248) (xy 357.054144 -249.079346) (xy 357.094647 -249.107302) (xy 357.13014 -249.141394)
			(xy 357.159705 -249.180738) (xy 357.182576 -249.224315) (xy 357.19816 -249.270996) (xy 357.206055 -249.319573)
			(xy 357.20655 -249.34418) (xy 357.206192 -249.36196) (xy 359.396541 -249.36196) (xy 359.400571 -249.309462)
			(xy 359.412568 -249.258194) (xy 359.432251 -249.209359) (xy 359.459157 -249.1641) (xy 359.492657 -249.123479)
			(xy 359.531965 -249.088448) (xy 359.57616 -249.059828) (xy 359.624205 -249.038289) (xy 359.674976 -249.024337)
			(xy 359.727281 -249.018299) (xy 359.779895 -249.020316) (xy 359.831585 -249.03034) (xy 359.881138 -249.048138)
			(xy 359.927394 -249.073291) (xy 359.969268 -249.10521) (xy 360.00578 -249.143148) (xy 360.036072 -249.186214)
			(xy 360.059435 -249.233399) (xy 360.075321 -249.283598) (xy 360.083358 -249.335634) (xy 360.083522 -249.34418)
			(xy 361.289104 -249.34418) (xy 361.293064 -249.295126) (xy 361.304841 -249.247342) (xy 361.324132 -249.202066)
			(xy 361.350435 -249.16047) (xy 361.38307 -249.123633) (xy 361.421191 -249.092508) (xy 361.463812 -249.067901)
			(xy 361.509828 -249.050449) (xy 361.558047 -249.040605) (xy 361.607222 -249.038624) (xy 361.656077 -249.044556)
			(xy 361.703348 -249.058248) (xy 361.74781 -249.079346) (xy 361.788313 -249.107302) (xy 361.823806 -249.141394)
			(xy 361.853371 -249.180738) (xy 361.876242 -249.224315) (xy 361.891826 -249.270996) (xy 361.899721 -249.319573)
			(xy 361.900216 -249.34418) (xy 363.168958 -249.34418) (xy 363.172918 -249.295126) (xy 363.184695 -249.247342)
			(xy 363.203986 -249.202066) (xy 363.230289 -249.16047) (xy 363.262924 -249.123633) (xy 363.301045 -249.092508)
			(xy 363.343666 -249.067901) (xy 363.389682 -249.050449) (xy 363.437901 -249.040605) (xy 363.487076 -249.038624)
			(xy 363.535931 -249.044556) (xy 363.583202 -249.058248) (xy 363.627664 -249.079346) (xy 363.668167 -249.107302)
			(xy 363.70366 -249.141394) (xy 363.733225 -249.180738) (xy 363.756096 -249.224315) (xy 363.77168 -249.270996)
			(xy 363.779575 -249.319573) (xy 363.78007 -249.34418) (xy 365.049066 -249.34418) (xy 365.053026 -249.295126)
			(xy 365.064803 -249.247342) (xy 365.084094 -249.202066) (xy 365.110397 -249.16047) (xy 365.143032 -249.123633)
			(xy 365.181153 -249.092508) (xy 365.223774 -249.067901) (xy 365.26979 -249.050449) (xy 365.318009 -249.040605)
			(xy 365.367184 -249.038624) (xy 365.416039 -249.044556) (xy 365.46331 -249.058248) (xy 365.507772 -249.079346)
			(xy 365.548275 -249.107302) (xy 365.583768 -249.141394) (xy 365.613333 -249.180738) (xy 365.636204 -249.224315)
			(xy 365.651788 -249.270996) (xy 365.659683 -249.319573) (xy 365.660178 -249.34418) (xy 366.92892 -249.34418)
			(xy 366.93288 -249.295126) (xy 366.944657 -249.247342) (xy 366.963948 -249.202066) (xy 366.990251 -249.16047)
			(xy 367.022886 -249.123633) (xy 367.061007 -249.092508) (xy 367.103628 -249.067901) (xy 367.149644 -249.050449)
			(xy 367.197863 -249.040605) (xy 367.247038 -249.038624) (xy 367.295893 -249.044556) (xy 367.343164 -249.058248)
			(xy 367.387626 -249.079346) (xy 367.428129 -249.107302) (xy 367.463622 -249.141394) (xy 367.493187 -249.180738)
			(xy 367.516058 -249.224315) (xy 367.531642 -249.270996) (xy 367.539537 -249.319573) (xy 367.540032 -249.34418)
			(xy 368.809028 -249.34418) (xy 368.812988 -249.295126) (xy 368.824765 -249.247342) (xy 368.844056 -249.202066)
			(xy 368.870359 -249.16047) (xy 368.902994 -249.123633) (xy 368.941115 -249.092508) (xy 368.983736 -249.067901)
			(xy 369.029752 -249.050449) (xy 369.077971 -249.040605) (xy 369.127146 -249.038624) (xy 369.176001 -249.044556)
			(xy 369.223272 -249.058248) (xy 369.267734 -249.079346) (xy 369.308237 -249.107302) (xy 369.34373 -249.141394)
			(xy 369.373295 -249.180738) (xy 369.396166 -249.224315) (xy 369.41175 -249.270996) (xy 369.419645 -249.319573)
			(xy 369.42014 -249.34418) (xy 370.688882 -249.34418) (xy 370.692842 -249.295126) (xy 370.704619 -249.247342)
			(xy 370.72391 -249.202066) (xy 370.750213 -249.16047) (xy 370.782848 -249.123633) (xy 370.820969 -249.092508)
			(xy 370.86359 -249.067901) (xy 370.909606 -249.050449) (xy 370.957825 -249.040605) (xy 371.007 -249.038624)
			(xy 371.055855 -249.044556) (xy 371.103126 -249.058248) (xy 371.147588 -249.079346) (xy 371.188091 -249.107302)
			(xy 371.223584 -249.141394) (xy 371.253149 -249.180738) (xy 371.27602 -249.224315) (xy 371.291604 -249.270996)
			(xy 371.299499 -249.319573) (xy 371.299994 -249.34418) (xy 372.56899 -249.34418) (xy 372.57295 -249.295126)
			(xy 372.584727 -249.247342) (xy 372.604018 -249.202066) (xy 372.630321 -249.16047) (xy 372.662956 -249.123633)
			(xy 372.701077 -249.092508) (xy 372.743698 -249.067901) (xy 372.789714 -249.050449) (xy 372.837933 -249.040605)
			(xy 372.887108 -249.038624) (xy 372.935963 -249.044556) (xy 372.983234 -249.058248) (xy 373.027696 -249.079346)
			(xy 373.068199 -249.107302) (xy 373.103692 -249.141394) (xy 373.133257 -249.180738) (xy 373.156128 -249.224315)
			(xy 373.171712 -249.270996) (xy 373.179607 -249.319573) (xy 373.180102 -249.34418) (xy 373.179607 -249.368787)
			(xy 373.171712 -249.417364) (xy 373.156128 -249.464045) (xy 373.133257 -249.507622) (xy 373.103692 -249.546966)
			(xy 373.068199 -249.581058) (xy 373.027696 -249.609014) (xy 372.983234 -249.630112) (xy 372.935963 -249.643804)
			(xy 372.887108 -249.649736) (xy 372.837933 -249.647755) (xy 372.789714 -249.637911) (xy 372.743698 -249.620459)
			(xy 372.701077 -249.595852) (xy 372.662956 -249.564727) (xy 372.630321 -249.52789) (xy 372.604018 -249.486294)
			(xy 372.584727 -249.441018) (xy 372.57295 -249.393234) (xy 372.56899 -249.34418) (xy 371.299994 -249.34418)
			(xy 371.299499 -249.368787) (xy 371.291604 -249.417364) (xy 371.27602 -249.464045) (xy 371.253149 -249.507622)
			(xy 371.223584 -249.546966) (xy 371.188091 -249.581058) (xy 371.147588 -249.609014) (xy 371.103126 -249.630112)
			(xy 371.055855 -249.643804) (xy 371.007 -249.649736) (xy 370.957825 -249.647755) (xy 370.909606 -249.637911)
			(xy 370.86359 -249.620459) (xy 370.820969 -249.595852) (xy 370.782848 -249.564727) (xy 370.750213 -249.52789)
			(xy 370.72391 -249.486294) (xy 370.704619 -249.441018) (xy 370.692842 -249.393234) (xy 370.688882 -249.34418)
			(xy 369.42014 -249.34418) (xy 369.419645 -249.368787) (xy 369.41175 -249.417364) (xy 369.396166 -249.464045)
			(xy 369.373295 -249.507622) (xy 369.34373 -249.546966) (xy 369.308237 -249.581058) (xy 369.267734 -249.609014)
			(xy 369.223272 -249.630112) (xy 369.176001 -249.643804) (xy 369.127146 -249.649736) (xy 369.077971 -249.647755)
			(xy 369.029752 -249.637911) (xy 368.983736 -249.620459) (xy 368.941115 -249.595852) (xy 368.902994 -249.564727)
			(xy 368.870359 -249.52789) (xy 368.844056 -249.486294) (xy 368.824765 -249.441018) (xy 368.812988 -249.393234)
			(xy 368.809028 -249.34418) (xy 367.540032 -249.34418) (xy 367.539537 -249.368787) (xy 367.531642 -249.417364)
			(xy 367.516058 -249.464045) (xy 367.493187 -249.507622) (xy 367.463622 -249.546966) (xy 367.428129 -249.581058)
			(xy 367.387626 -249.609014) (xy 367.343164 -249.630112) (xy 367.295893 -249.643804) (xy 367.247038 -249.649736)
			(xy 367.197863 -249.647755) (xy 367.149644 -249.637911) (xy 367.103628 -249.620459) (xy 367.061007 -249.595852)
			(xy 367.022886 -249.564727) (xy 366.990251 -249.52789) (xy 366.963948 -249.486294) (xy 366.944657 -249.441018)
			(xy 366.93288 -249.393234) (xy 366.92892 -249.34418) (xy 365.660178 -249.34418) (xy 365.659683 -249.368787)
			(xy 365.651788 -249.417364) (xy 365.636204 -249.464045) (xy 365.613333 -249.507622) (xy 365.583768 -249.546966)
			(xy 365.548275 -249.581058) (xy 365.507772 -249.609014) (xy 365.46331 -249.630112) (xy 365.416039 -249.643804)
			(xy 365.367184 -249.649736) (xy 365.318009 -249.647755) (xy 365.26979 -249.637911) (xy 365.223774 -249.620459)
			(xy 365.181153 -249.595852) (xy 365.143032 -249.564727) (xy 365.110397 -249.52789) (xy 365.084094 -249.486294)
			(xy 365.064803 -249.441018) (xy 365.053026 -249.393234) (xy 365.049066 -249.34418) (xy 363.78007 -249.34418)
			(xy 363.779575 -249.368787) (xy 363.77168 -249.417364) (xy 363.756096 -249.464045) (xy 363.733225 -249.507622)
			(xy 363.70366 -249.546966) (xy 363.668167 -249.581058) (xy 363.627664 -249.609014) (xy 363.583202 -249.630112)
			(xy 363.535931 -249.643804) (xy 363.487076 -249.649736) (xy 363.437901 -249.647755) (xy 363.389682 -249.637911)
			(xy 363.343666 -249.620459) (xy 363.301045 -249.595852) (xy 363.262924 -249.564727) (xy 363.230289 -249.52789)
			(xy 363.203986 -249.486294) (xy 363.184695 -249.441018) (xy 363.172918 -249.393234) (xy 363.168958 -249.34418)
			(xy 361.900216 -249.34418) (xy 361.899721 -249.368787) (xy 361.891826 -249.417364) (xy 361.876242 -249.464045)
			(xy 361.853371 -249.507622) (xy 361.823806 -249.546966) (xy 361.788313 -249.581058) (xy 361.74781 -249.609014)
			(xy 361.703348 -249.630112) (xy 361.656077 -249.643804) (xy 361.607222 -249.649736) (xy 361.558047 -249.647755)
			(xy 361.509828 -249.637911) (xy 361.463812 -249.620459) (xy 361.421191 -249.595852) (xy 361.38307 -249.564727)
			(xy 361.350435 -249.52789) (xy 361.324132 -249.486294) (xy 361.304841 -249.441018) (xy 361.293064 -249.393234)
			(xy 361.289104 -249.34418) (xy 360.083522 -249.34418) (xy 360.083862 -249.36196) (xy 360.083358 -249.388286)
			(xy 360.075321 -249.440322) (xy 360.059435 -249.490521) (xy 360.036072 -249.537706) (xy 360.00578 -249.580772)
			(xy 359.969268 -249.61871) (xy 359.927394 -249.650629) (xy 359.881138 -249.675782) (xy 359.831585 -249.69358)
			(xy 359.779895 -249.703604) (xy 359.727281 -249.705621) (xy 359.674976 -249.699583) (xy 359.624205 -249.685631)
			(xy 359.57616 -249.664092) (xy 359.531965 -249.635472) (xy 359.492657 -249.600441) (xy 359.459157 -249.55982)
			(xy 359.432251 -249.514561) (xy 359.412568 -249.465726) (xy 359.400571 -249.414458) (xy 359.396541 -249.36196)
			(xy 357.206192 -249.36196) (xy 357.206055 -249.368787) (xy 357.19816 -249.417364) (xy 357.182576 -249.464045)
			(xy 357.159705 -249.507622) (xy 357.13014 -249.546966) (xy 357.094647 -249.581058) (xy 357.054144 -249.609014)
			(xy 357.009682 -249.630112) (xy 356.962411 -249.643804) (xy 356.913556 -249.649736) (xy 356.864381 -249.647755)
			(xy 356.816162 -249.637911) (xy 356.770146 -249.620459) (xy 356.727525 -249.595852) (xy 356.689404 -249.564727)
			(xy 356.656769 -249.52789) (xy 356.630466 -249.486294) (xy 356.611175 -249.441018) (xy 356.599398 -249.393234)
			(xy 356.595438 -249.34418) (xy 355.326442 -249.34418) (xy 355.325947 -249.368787) (xy 355.318052 -249.417364)
			(xy 355.302468 -249.464045) (xy 355.279597 -249.507622) (xy 355.250032 -249.546966) (xy 355.214539 -249.581058)
			(xy 355.174036 -249.609014) (xy 355.129574 -249.630112) (xy 355.082303 -249.643804) (xy 355.033448 -249.649736)
			(xy 354.984273 -249.647755) (xy 354.936054 -249.637911) (xy 354.890038 -249.620459) (xy 354.847417 -249.595852)
			(xy 354.809296 -249.564727) (xy 354.776661 -249.52789) (xy 354.750358 -249.486294) (xy 354.731067 -249.441018)
			(xy 354.71929 -249.393234) (xy 354.71533 -249.34418) (xy 353.446334 -249.34418) (xy 353.445839 -249.368787)
			(xy 353.437944 -249.417364) (xy 353.42236 -249.464045) (xy 353.399489 -249.507622) (xy 353.369924 -249.546966)
			(xy 353.334431 -249.581058) (xy 353.293928 -249.609014) (xy 353.249466 -249.630112) (xy 353.202195 -249.643804)
			(xy 353.15334 -249.649736) (xy 353.104165 -249.647755) (xy 353.055946 -249.637911) (xy 353.00993 -249.620459)
			(xy 352.967309 -249.595852) (xy 352.929188 -249.564727) (xy 352.896553 -249.52789) (xy 352.87025 -249.486294)
			(xy 352.850959 -249.441018) (xy 352.839182 -249.393234) (xy 352.835222 -249.34418) (xy 351.56648 -249.34418)
			(xy 351.565985 -249.368787) (xy 351.55809 -249.417364) (xy 351.542506 -249.464045) (xy 351.519635 -249.507622)
			(xy 351.49007 -249.546966) (xy 351.454577 -249.581058) (xy 351.414074 -249.609014) (xy 351.369612 -249.630112)
			(xy 351.322341 -249.643804) (xy 351.273486 -249.649736) (xy 351.224311 -249.647755) (xy 351.176092 -249.637911)
			(xy 351.130076 -249.620459) (xy 351.087455 -249.595852) (xy 351.049334 -249.564727) (xy 351.016699 -249.52789)
			(xy 350.990396 -249.486294) (xy 350.971105 -249.441018) (xy 350.959328 -249.393234) (xy 350.955368 -249.34418)
			(xy 349.686372 -249.34418) (xy 349.685877 -249.368787) (xy 349.677982 -249.417364) (xy 349.662398 -249.464045)
			(xy 349.639527 -249.507622) (xy 349.609962 -249.546966) (xy 349.574469 -249.581058) (xy 349.533966 -249.609014)
			(xy 349.489504 -249.630112) (xy 349.442233 -249.643804) (xy 349.393378 -249.649736) (xy 349.344203 -249.647755)
			(xy 349.295984 -249.637911) (xy 349.249968 -249.620459) (xy 349.207347 -249.595852) (xy 349.169226 -249.564727)
			(xy 349.136591 -249.52789) (xy 349.110288 -249.486294) (xy 349.090997 -249.441018) (xy 349.07922 -249.393234)
			(xy 349.07526 -249.34418) (xy 347.894402 -249.34418) (xy 348.704408 -250.154186) (xy 349.545414 -250.154186)
			(xy 349.549374 -250.105132) (xy 349.561151 -250.057348) (xy 349.580442 -250.012072) (xy 349.606745 -249.970476)
			(xy 349.63938 -249.933639) (xy 349.677501 -249.902514) (xy 349.720122 -249.877907) (xy 349.766138 -249.860455)
			(xy 349.814357 -249.850611) (xy 349.863532 -249.84863) (xy 349.912387 -249.854562) (xy 349.959658 -249.868254)
			(xy 350.00412 -249.889352) (xy 350.044623 -249.917308) (xy 350.080116 -249.9514) (xy 350.109681 -249.990744)
			(xy 350.132552 -250.034321) (xy 350.148136 -250.081002) (xy 350.156031 -250.129579) (xy 350.156526 -250.154186)
			(xy 351.425268 -250.154186) (xy 351.429228 -250.105132) (xy 351.441005 -250.057348) (xy 351.460296 -250.012072)
			(xy 351.486599 -249.970476) (xy 351.519234 -249.933639) (xy 351.557355 -249.902514) (xy 351.599976 -249.877907)
			(xy 351.645992 -249.860455) (xy 351.694211 -249.850611) (xy 351.743386 -249.84863) (xy 351.792241 -249.854562)
			(xy 351.839512 -249.868254) (xy 351.883974 -249.889352) (xy 351.924477 -249.917308) (xy 351.95997 -249.9514)
			(xy 351.989535 -249.990744) (xy 352.012406 -250.034321) (xy 352.02799 -250.081002) (xy 352.035885 -250.129579)
			(xy 352.03638 -250.154186) (xy 353.305376 -250.154186) (xy 353.309336 -250.105132) (xy 353.321113 -250.057348)
			(xy 353.340404 -250.012072) (xy 353.366707 -249.970476) (xy 353.399342 -249.933639) (xy 353.437463 -249.902514)
			(xy 353.480084 -249.877907) (xy 353.5261 -249.860455) (xy 353.574319 -249.850611) (xy 353.623494 -249.84863)
			(xy 353.672349 -249.854562) (xy 353.71962 -249.868254) (xy 353.764082 -249.889352) (xy 353.804585 -249.917308)
			(xy 353.840078 -249.9514) (xy 353.869643 -249.990744) (xy 353.892514 -250.034321) (xy 353.908098 -250.081002)
			(xy 353.915993 -250.129579) (xy 353.916488 -250.154186) (xy 355.18523 -250.154186) (xy 355.18919 -250.105132)
			(xy 355.200967 -250.057348) (xy 355.220258 -250.012072) (xy 355.246561 -249.970476) (xy 355.279196 -249.933639)
			(xy 355.317317 -249.902514) (xy 355.359938 -249.877907) (xy 355.405954 -249.860455) (xy 355.454173 -249.850611)
			(xy 355.503348 -249.84863) (xy 355.552203 -249.854562) (xy 355.599474 -249.868254) (xy 355.643936 -249.889352)
			(xy 355.684439 -249.917308) (xy 355.719932 -249.9514) (xy 355.749497 -249.990744) (xy 355.772368 -250.034321)
			(xy 355.787952 -250.081002) (xy 355.795847 -250.129579) (xy 355.796342 -250.154186) (xy 357.065338 -250.154186)
			(xy 357.069298 -250.105132) (xy 357.081075 -250.057348) (xy 357.100366 -250.012072) (xy 357.126669 -249.970476)
			(xy 357.159304 -249.933639) (xy 357.197425 -249.902514) (xy 357.240046 -249.877907) (xy 357.286062 -249.860455)
			(xy 357.334281 -249.850611) (xy 357.383456 -249.84863) (xy 357.432311 -249.854562) (xy 357.479582 -249.868254)
			(xy 357.524044 -249.889352) (xy 357.564547 -249.917308) (xy 357.60004 -249.9514) (xy 357.629605 -249.990744)
			(xy 357.652476 -250.034321) (xy 357.66806 -250.081002) (xy 357.675955 -250.129579) (xy 357.67645 -250.154186)
			(xy 360.81895 -250.154186) (xy 360.82291 -250.105132) (xy 360.834687 -250.057348) (xy 360.853978 -250.012072)
			(xy 360.880281 -249.970476) (xy 360.912916 -249.933639) (xy 360.951037 -249.902514) (xy 360.993658 -249.877907)
			(xy 361.039674 -249.860455) (xy 361.087893 -249.850611) (xy 361.137068 -249.84863) (xy 361.185923 -249.854562)
			(xy 361.233194 -249.868254) (xy 361.277656 -249.889352) (xy 361.318159 -249.917308) (xy 361.353652 -249.9514)
			(xy 361.383217 -249.990744) (xy 361.406088 -250.034321) (xy 361.421672 -250.081002) (xy 361.429567 -250.129579)
			(xy 361.430062 -250.154186) (xy 362.699058 -250.154186) (xy 362.703018 -250.105132) (xy 362.714795 -250.057348)
			(xy 362.734086 -250.012072) (xy 362.760389 -249.970476) (xy 362.793024 -249.933639) (xy 362.831145 -249.902514)
			(xy 362.873766 -249.877907) (xy 362.919782 -249.860455) (xy 362.968001 -249.850611) (xy 363.017176 -249.84863)
			(xy 363.066031 -249.854562) (xy 363.113302 -249.868254) (xy 363.157764 -249.889352) (xy 363.198267 -249.917308)
			(xy 363.23376 -249.9514) (xy 363.263325 -249.990744) (xy 363.286196 -250.034321) (xy 363.30178 -250.081002)
			(xy 363.309675 -250.129579) (xy 363.31017 -250.154186) (xy 364.578912 -250.154186) (xy 364.582872 -250.105132)
			(xy 364.594649 -250.057348) (xy 364.61394 -250.012072) (xy 364.640243 -249.970476) (xy 364.672878 -249.933639)
			(xy 364.710999 -249.902514) (xy 364.75362 -249.877907) (xy 364.799636 -249.860455) (xy 364.847855 -249.850611)
			(xy 364.89703 -249.84863) (xy 364.945885 -249.854562) (xy 364.993156 -249.868254) (xy 365.037618 -249.889352)
			(xy 365.078121 -249.917308) (xy 365.113614 -249.9514) (xy 365.143179 -249.990744) (xy 365.16605 -250.034321)
			(xy 365.181634 -250.081002) (xy 365.189529 -250.129579) (xy 365.190024 -250.154186) (xy 365.189529 -250.178793)
			(xy 365.181634 -250.22737) (xy 365.16605 -250.274051) (xy 365.143179 -250.317628) (xy 365.113614 -250.356972)
			(xy 365.078121 -250.391064) (xy 365.037618 -250.41902) (xy 364.993156 -250.440118) (xy 364.945885 -250.45381)
			(xy 364.89703 -250.459742) (xy 364.847855 -250.457761) (xy 364.799636 -250.447917) (xy 364.75362 -250.430465)
			(xy 364.710999 -250.405858) (xy 364.672878 -250.374733) (xy 364.640243 -250.337896) (xy 364.61394 -250.2963)
			(xy 364.594649 -250.251024) (xy 364.582872 -250.20324) (xy 364.578912 -250.154186) (xy 363.31017 -250.154186)
			(xy 363.309675 -250.178793) (xy 363.30178 -250.22737) (xy 363.286196 -250.274051) (xy 363.263325 -250.317628)
			(xy 363.23376 -250.356972) (xy 363.198267 -250.391064) (xy 363.157764 -250.41902) (xy 363.113302 -250.440118)
			(xy 363.066031 -250.45381) (xy 363.017176 -250.459742) (xy 362.968001 -250.457761) (xy 362.919782 -250.447917)
			(xy 362.873766 -250.430465) (xy 362.831145 -250.405858) (xy 362.793024 -250.374733) (xy 362.760389 -250.337896)
			(xy 362.734086 -250.2963) (xy 362.714795 -250.251024) (xy 362.703018 -250.20324) (xy 362.699058 -250.154186)
			(xy 361.430062 -250.154186) (xy 361.429567 -250.178793) (xy 361.421672 -250.22737) (xy 361.406088 -250.274051)
			(xy 361.383217 -250.317628) (xy 361.353652 -250.356972) (xy 361.318159 -250.391064) (xy 361.277656 -250.41902)
			(xy 361.233194 -250.440118) (xy 361.185923 -250.45381) (xy 361.137068 -250.459742) (xy 361.087893 -250.457761)
			(xy 361.039674 -250.447917) (xy 360.993658 -250.430465) (xy 360.951037 -250.405858) (xy 360.912916 -250.374733)
			(xy 360.880281 -250.337896) (xy 360.853978 -250.2963) (xy 360.834687 -250.251024) (xy 360.82291 -250.20324)
			(xy 360.81895 -250.154186) (xy 357.67645 -250.154186) (xy 357.675955 -250.178793) (xy 357.66806 -250.22737)
			(xy 357.652476 -250.274051) (xy 357.629605 -250.317628) (xy 357.60004 -250.356972) (xy 357.564547 -250.391064)
			(xy 357.524044 -250.41902) (xy 357.479582 -250.440118) (xy 357.432311 -250.45381) (xy 357.383456 -250.459742)
			(xy 357.334281 -250.457761) (xy 357.286062 -250.447917) (xy 357.240046 -250.430465) (xy 357.197425 -250.405858)
			(xy 357.159304 -250.374733) (xy 357.126669 -250.337896) (xy 357.100366 -250.2963) (xy 357.081075 -250.251024)
			(xy 357.069298 -250.20324) (xy 357.065338 -250.154186) (xy 355.796342 -250.154186) (xy 355.795847 -250.178793)
			(xy 355.787952 -250.22737) (xy 355.772368 -250.274051) (xy 355.749497 -250.317628) (xy 355.719932 -250.356972)
			(xy 355.684439 -250.391064) (xy 355.643936 -250.41902) (xy 355.599474 -250.440118) (xy 355.552203 -250.45381)
			(xy 355.503348 -250.459742) (xy 355.454173 -250.457761) (xy 355.405954 -250.447917) (xy 355.359938 -250.430465)
			(xy 355.317317 -250.405858) (xy 355.279196 -250.374733) (xy 355.246561 -250.337896) (xy 355.220258 -250.2963)
			(xy 355.200967 -250.251024) (xy 355.18919 -250.20324) (xy 355.18523 -250.154186) (xy 353.916488 -250.154186)
			(xy 353.915993 -250.178793) (xy 353.908098 -250.22737) (xy 353.892514 -250.274051) (xy 353.869643 -250.317628)
			(xy 353.840078 -250.356972) (xy 353.804585 -250.391064) (xy 353.764082 -250.41902) (xy 353.71962 -250.440118)
			(xy 353.672349 -250.45381) (xy 353.623494 -250.459742) (xy 353.574319 -250.457761) (xy 353.5261 -250.447917)
			(xy 353.480084 -250.430465) (xy 353.437463 -250.405858) (xy 353.399342 -250.374733) (xy 353.366707 -250.337896)
			(xy 353.340404 -250.2963) (xy 353.321113 -250.251024) (xy 353.309336 -250.20324) (xy 353.305376 -250.154186)
			(xy 352.03638 -250.154186) (xy 352.035885 -250.178793) (xy 352.02799 -250.22737) (xy 352.012406 -250.274051)
			(xy 351.989535 -250.317628) (xy 351.95997 -250.356972) (xy 351.924477 -250.391064) (xy 351.883974 -250.41902)
			(xy 351.839512 -250.440118) (xy 351.792241 -250.45381) (xy 351.743386 -250.459742) (xy 351.694211 -250.457761)
			(xy 351.645992 -250.447917) (xy 351.599976 -250.430465) (xy 351.557355 -250.405858) (xy 351.519234 -250.374733)
			(xy 351.486599 -250.337896) (xy 351.460296 -250.2963) (xy 351.441005 -250.251024) (xy 351.429228 -250.20324)
			(xy 351.425268 -250.154186) (xy 350.156526 -250.154186) (xy 350.156031 -250.178793) (xy 350.148136 -250.22737)
			(xy 350.132552 -250.274051) (xy 350.109681 -250.317628) (xy 350.080116 -250.356972) (xy 350.044623 -250.391064)
			(xy 350.00412 -250.41902) (xy 349.959658 -250.440118) (xy 349.912387 -250.45381) (xy 349.863532 -250.459742)
			(xy 349.814357 -250.457761) (xy 349.766138 -250.447917) (xy 349.720122 -250.430465) (xy 349.677501 -250.405858)
			(xy 349.63938 -250.374733) (xy 349.606745 -250.337896) (xy 349.580442 -250.2963) (xy 349.561151 -250.251024)
			(xy 349.549374 -250.20324) (xy 349.545414 -250.154186) (xy 348.704408 -250.154186) (xy 349.22841 -250.678188)
			(xy 349.25762 -250.684538) (xy 349.271844 -250.679204) (xy 349.298159 -250.669763) (xy 349.353115 -250.659532)
			(xy 349.381064 -250.658884) (xy 349.405059 -250.659327) (xy 349.45246 -250.66683) (xy 349.498103 -250.681655)
			(xy 349.540864 -250.703438) (xy 349.579692 -250.731643) (xy 349.613628 -250.765575) (xy 349.641839 -250.804398)
			(xy 349.663628 -250.847157) (xy 349.67846 -250.892798) (xy 349.685969 -250.940197) (xy 349.686372 -250.964192)
			(xy 349.685726 -250.992142) (xy 349.675503 -251.0471) (xy 349.666052 -251.073412) (xy 349.660718 -251.087636)
			(xy 349.667068 -251.116846) (xy 349.808546 -251.258324) (xy 349.815943 -251.265172) (xy 349.834542 -251.272901)
			(xy 349.844614 -251.27331) (xy 350.729804 -251.27331)
		)
		(stroke
			(width 0)
			(type solid)
		)
		(fill yes)
		(layer "In6.Cu")
		(net "PVDDCR_CPU0_P0")
	)
	(gr_poly
		(pts
			(xy 370.704872 -201.178668) (xy 370.714657 -201.178217) (xy 370.732809 -201.170899) (xy 370.740178 -201.164444)
			(xy 370.790978 -201.115676) (xy 370.793546 -201.113104) (xy 370.798005 -201.107366) (xy 370.799868 -201.104246)
			(xy 370.806472 -201.092562) (xy 370.80698 -201.079862) (xy 370.808176 -201.053616) (xy 370.816877 -201.001802)
			(xy 370.832598 -200.951669) (xy 370.855041 -200.904164) (xy 370.883784 -200.860184) (xy 370.900706 -200.840086)
			(xy 370.906802 -200.832974) (xy 370.913152 -200.81621) (xy 370.913152 -200.746106) (xy 370.91275 -200.736825)
			(xy 370.906105 -200.719494) (xy 370.900198 -200.712324) (xy 370.881917 -200.691012) (xy 370.851074 -200.644095)
			(xy 370.827353 -200.593204) (xy 370.811257 -200.539413) (xy 370.803124 -200.483858) (xy 370.802662 -200.455784)
			(xy 370.803231 -200.425847) (xy 370.812496 -200.366696) (xy 370.830802 -200.309689) (xy 370.857706 -200.256202)
			(xy 370.892562 -200.20752) (xy 370.913152 -200.185782) (xy 370.924074 -200.174606) (xy 370.929662 -200.14438)
			(xy 370.917978 -200.117456) (xy 370.91378 -200.108813) (xy 370.900207 -200.095234) (xy 370.891562 -200.09104)
			(xy 370.864638 -200.079356) (xy 370.834412 -200.084944) (xy 370.823236 -200.095866) (xy 370.801493 -200.116452)
			(xy 370.752819 -200.151321) (xy 370.699333 -200.178233) (xy 370.642326 -200.19654) (xy 370.583171 -200.2058)
			(xy 370.553234 -200.206356) (xy 370.52569 -200.20589) (xy 370.471161 -200.198054) (xy 370.418303 -200.182538)
			(xy 370.368192 -200.159656) (xy 370.321847 -200.129874) (xy 370.280213 -200.0938) (xy 370.244137 -200.052168)
			(xy 370.214353 -200.005824) (xy 370.191469 -199.955714) (xy 370.175949 -199.902856) (xy 370.168111 -199.848328)
			(xy 370.167662 -199.820784) (xy 370.168234 -199.790812) (xy 370.177521 -199.731591) (xy 370.19587 -199.674523)
			(xy 370.222837 -199.620986) (xy 370.25777 -199.572272) (xy 370.278406 -199.550528) (xy 370.289582 -199.539098)
			(xy 370.29517 -199.508872) (xy 370.278406 -199.470264) (xy 370.271548 -199.463406) (xy 370.270278 -199.462136)
			(xy 370.262912 -199.45477) (xy 370.253768 -199.450706) (xy 370.248967 -199.44882) (xy 370.238858 -199.44678)
			(xy 370.233702 -199.446642) (xy 370.22151 -199.446642) (xy 370.186458 -199.460866) (xy 370.179346 -199.46747)
			(xy 370.158007 -199.486778) (xy 370.110609 -199.519411) (xy 370.058848 -199.544557) (xy 370.003899 -199.561646)
			(xy 369.947007 -199.570291) (xy 369.918234 -199.570848) (xy 369.89098 -199.570365) (xy 369.837027 -199.562612)
			(xy 369.784725 -199.54726) (xy 369.735141 -199.524622) (xy 369.689284 -199.495157) (xy 369.648086 -199.459466)
			(xy 369.612387 -199.418275) (xy 369.582914 -199.372424) (xy 369.560265 -199.322844) (xy 369.544904 -199.270546)
			(xy 369.537141 -199.216594) (xy 369.536726 -199.18934) (xy 369.537202 -199.161972) (xy 369.545034 -199.107798)
			(xy 369.560528 -199.0553) (xy 369.583367 -199.005555) (xy 369.613082 -198.959586) (xy 369.630706 -198.938642)
			(xy 369.636802 -198.93153) (xy 369.643152 -198.914766) (xy 369.643152 -198.838566) (xy 369.643095 -198.834292)
			(xy 369.641694 -198.825862) (xy 369.640358 -198.821802) (xy 369.636802 -198.81215) (xy 369.630452 -198.804784)
			(xy 369.612862 -198.783857) (xy 369.583228 -198.737918) (xy 369.560454 -198.68822) (xy 369.545005 -198.635781)
			(xy 369.537197 -198.581674) (xy 369.536726 -198.55434) (xy 369.537202 -198.526972) (xy 369.545034 -198.472798)
			(xy 369.560528 -198.4203) (xy 369.583367 -198.370555) (xy 369.613082 -198.324586) (xy 369.630706 -198.303642)
			(xy 369.636802 -198.29653) (xy 369.643152 -198.279766) (xy 369.643152 -198.203566) (xy 369.643095 -198.199292)
			(xy 369.641694 -198.190862) (xy 369.640358 -198.186802) (xy 369.636802 -198.17715) (xy 369.630452 -198.169784)
			(xy 369.612862 -198.148857) (xy 369.583228 -198.102918) (xy 369.560454 -198.05322) (xy 369.545005 -198.000781)
			(xy 369.537197 -197.946674) (xy 369.536726 -197.91934) (xy 369.537186 -197.892512) (xy 369.544711 -197.839386)
			(xy 369.559604 -197.787838) (xy 369.581573 -197.738885) (xy 369.610182 -197.693492) (xy 369.62715 -197.672706)
			(xy 369.633246 -197.665594) (xy 369.639342 -197.648576) (xy 369.63858 -197.606158) (xy 369.63858 -197.60565)
			(xy 369.637818 -197.562978) (xy 369.631214 -197.54596) (xy 369.625118 -197.539102) (xy 369.606839 -197.518003)
			(xy 369.576011 -197.471464) (xy 369.552294 -197.420929) (xy 369.536193 -197.367478) (xy 369.528053 -197.312252)
			(xy 369.527582 -197.28434) (xy 369.528057 -197.256971) (xy 369.535889 -197.202797) (xy 369.551382 -197.150298)
			(xy 369.574219 -197.100552) (xy 369.60393 -197.05458) (xy 369.621562 -197.033642) (xy 369.627658 -197.02653)
			(xy 369.634008 -197.009766) (xy 369.634008 -196.933566) (xy 369.63395 -196.929292) (xy 369.632548 -196.920862)
			(xy 369.631214 -196.916802) (xy 369.627658 -196.90715) (xy 369.621308 -196.899784) (xy 369.60372 -196.878856)
			(xy 369.574089 -196.832916) (xy 369.551318 -196.783218) (xy 369.53587 -196.73078) (xy 369.528064 -196.676673)
			(xy 369.527582 -196.64934) (xy 369.528057 -196.621971) (xy 369.535889 -196.567797) (xy 369.551382 -196.515298)
			(xy 369.574219 -196.465552) (xy 369.60393 -196.41958) (xy 369.621562 -196.398642) (xy 369.627658 -196.39153)
			(xy 369.634008 -196.374766) (xy 369.634008 -196.298566) (xy 369.63395 -196.294292) (xy 369.632548 -196.285862)
			(xy 369.631214 -196.281802) (xy 369.627658 -196.27215) (xy 369.621308 -196.264784) (xy 369.60372 -196.243856)
			(xy 369.574089 -196.197916) (xy 369.551318 -196.148218) (xy 369.53587 -196.09578) (xy 369.528064 -196.041673)
			(xy 369.527582 -196.01434) (xy 369.528057 -195.986971) (xy 369.535889 -195.932797) (xy 369.551382 -195.880298)
			(xy 369.574219 -195.830552) (xy 369.60393 -195.78458) (xy 369.621562 -195.763642) (xy 369.627658 -195.75653)
			(xy 369.634008 -195.739766) (xy 369.634008 -195.663566) (xy 369.63395 -195.659292) (xy 369.632548 -195.650862)
			(xy 369.631214 -195.646802) (xy 369.627658 -195.63715) (xy 369.621308 -195.629784) (xy 369.60372 -195.608856)
			(xy 369.574089 -195.562916) (xy 369.551318 -195.513218) (xy 369.53587 -195.46078) (xy 369.528064 -195.406673)
			(xy 369.527582 -195.37934) (xy 369.528113 -195.350853) (xy 369.536586 -195.294511) (xy 369.553335 -195.240054)
			(xy 369.577989 -195.188689) (xy 369.609999 -195.141556) (xy 369.628928 -195.12026) (xy 369.635532 -195.113148)
			(xy 369.64239 -195.095622) (xy 369.64239 -195.00723) (xy 369.635532 -194.989704) (xy 369.628928 -194.982592)
			(xy 369.609981 -194.96131) (xy 369.577963 -194.914179) (xy 369.553309 -194.862811) (xy 369.536567 -194.808348)
			(xy 369.528108 -194.752001) (xy 369.527582 -194.723512) (xy 369.528044 -194.696258) (xy 369.5358 -194.642305)
			(xy 369.551154 -194.590006) (xy 369.573796 -194.540423) (xy 369.603264 -194.494568) (xy 369.638957 -194.453373)
			(xy 369.68015 -194.417677) (xy 369.726004 -194.388207) (xy 369.775585 -194.365562) (xy 369.827884 -194.350204)
			(xy 369.881836 -194.342446) (xy 369.90909 -194.342004) (xy 369.936458 -194.342482) (xy 369.99063 -194.350317)
			(xy 370.043126 -194.365815) (xy 370.092868 -194.388655) (xy 370.138836 -194.41837) (xy 370.159788 -194.435984)
			(xy 370.1669 -194.44208) (xy 370.183664 -194.44843) (xy 370.259864 -194.44843) (xy 370.264137 -194.44837)
			(xy 370.272566 -194.446964) (xy 370.276628 -194.445636) (xy 370.28628 -194.44208) (xy 370.293646 -194.43573)
			(xy 370.314574 -194.418143) (xy 370.360514 -194.388514) (xy 370.410212 -194.365745) (xy 370.462651 -194.350301)
			(xy 370.516757 -194.342498) (xy 370.54409 -194.342004) (xy 370.571458 -194.342482) (xy 370.62563 -194.350317)
			(xy 370.678126 -194.365815) (xy 370.727868 -194.388655) (xy 370.773836 -194.41837) (xy 370.794788 -194.435984)
			(xy 370.8019 -194.44208) (xy 370.818664 -194.44843) (xy 370.894864 -194.44843) (xy 370.899137 -194.44837)
			(xy 370.907566 -194.446964) (xy 370.911628 -194.445636) (xy 370.92128 -194.44208) (xy 370.928646 -194.43573)
			(xy 370.949574 -194.418143) (xy 370.995514 -194.388514) (xy 371.045212 -194.365745) (xy 371.097651 -194.350301)
			(xy 371.151757 -194.342498) (xy 371.17909 -194.342004) (xy 371.206343 -194.342467) (xy 371.260294 -194.350223)
			(xy 371.312593 -194.365578) (xy 371.362173 -194.38822) (xy 371.408027 -194.417688) (xy 371.44922 -194.453382)
			(xy 371.484913 -194.494575) (xy 371.514381 -194.540428) (xy 371.537023 -194.590009) (xy 371.552378 -194.642308)
			(xy 371.560133 -194.696259) (xy 371.560598 -194.723512) (xy 371.560126 -194.750281) (xy 371.552605 -194.803288)
			(xy 371.537755 -194.854725) (xy 371.515866 -194.903583) (xy 371.487368 -194.948906) (xy 371.470428 -194.969638)
			(xy 371.46865 -194.971924) (xy 371.465602 -194.97675) (xy 371.46152 -194.983273) (xy 371.457131 -194.998013)
			(xy 371.456966 -195.005706) (xy 371.457474 -195.038472) (xy 371.457474 -195.03898) (xy 371.457728 -195.062094)
			(xy 371.457854 -195.066641) (xy 371.459519 -195.075583) (xy 371.46103 -195.079874) (xy 371.470682 -195.104512)
			(xy 371.47627 -195.111116) (xy 371.493354 -195.131929) (xy 371.522118 -195.177448) (xy 371.544204 -195.226555)
			(xy 371.559176 -195.278277) (xy 371.566736 -195.331589) (xy 371.567202 -195.358512) (xy 371.566729 -195.385882)
			(xy 371.558904 -195.440059) (xy 371.543416 -195.492562) (xy 371.520583 -195.542312) (xy 371.490873 -195.588288)
			(xy 371.473222 -195.60921) (xy 371.467126 -195.616322) (xy 371.460776 -195.633086) (xy 371.460776 -195.709286)
			(xy 371.460838 -195.713559) (xy 371.462248 -195.721986) (xy 371.46357 -195.72605) (xy 371.467126 -195.735702)
			(xy 371.473476 -195.743068) (xy 371.491067 -195.763995) (xy 371.520705 -195.809933) (xy 371.543484 -195.859631)
			(xy 371.558938 -195.91207) (xy 371.566752 -195.966178) (xy 371.567202 -195.993512) (xy 371.566729 -196.020882)
			(xy 371.558904 -196.075059) (xy 371.543416 -196.127562) (xy 371.520583 -196.177312) (xy 371.490873 -196.223288)
			(xy 371.473222 -196.24421) (xy 371.467126 -196.251322) (xy 371.460776 -196.268086) (xy 371.460776 -196.344286)
			(xy 371.460838 -196.348559) (xy 371.462248 -196.356986) (xy 371.46357 -196.36105) (xy 371.467126 -196.370702)
			(xy 371.473476 -196.378068) (xy 371.491067 -196.398995) (xy 371.520705 -196.444933) (xy 371.543484 -196.494631)
			(xy 371.558938 -196.54707) (xy 371.566752 -196.601178) (xy 371.567202 -196.628512) (xy 371.566729 -196.655882)
			(xy 371.558904 -196.710059) (xy 371.543416 -196.762562) (xy 371.520583 -196.812312) (xy 371.490873 -196.858288)
			(xy 371.473222 -196.87921) (xy 371.467126 -196.886322) (xy 371.460776 -196.903086) (xy 371.460776 -196.979286)
			(xy 371.460838 -196.983559) (xy 371.462248 -196.991986) (xy 371.46357 -196.99605) (xy 371.467126 -197.005702)
			(xy 371.473476 -197.013068) (xy 371.491067 -197.033995) (xy 371.520705 -197.079933) (xy 371.543484 -197.129631)
			(xy 371.558938 -197.18207) (xy 371.566752 -197.236178) (xy 371.567202 -197.263512) (xy 371.567202 -197.273164)
			(xy 371.566037 -197.300329) (xy 371.556962 -197.353937) (xy 371.540361 -197.405711) (xy 371.51657 -197.4546)
			(xy 371.486073 -197.499612) (xy 371.468142 -197.520052) (xy 371.462021 -197.527333) (xy 371.455239 -197.545088)
			(xy 371.454934 -197.554596) (xy 371.455188 -197.622414) (xy 371.455342 -197.627099) (xy 371.457127 -197.636302)
			(xy 371.458744 -197.640702) (xy 371.4623 -197.650354) (xy 371.468904 -197.657466) (xy 371.487759 -197.678704)
			(xy 371.519618 -197.725717) (xy 371.544151 -197.776935) (xy 371.560814 -197.831226) (xy 371.569241 -197.887389)
			(xy 371.569742 -197.915784) (xy 371.569264 -197.943152) (xy 371.561429 -197.997323) (xy 371.54593 -198.049819)
			(xy 371.523088 -198.09956) (xy 371.49337 -198.145525) (xy 371.475762 -198.166482) (xy 371.469666 -198.173594)
			(xy 371.463316 -198.190358) (xy 371.463316 -198.266558) (xy 371.463376 -198.270831) (xy 371.464782 -198.27926)
			(xy 371.46611 -198.283322) (xy 371.469666 -198.292974) (xy 371.476016 -198.30034) (xy 371.493606 -198.321267)
			(xy 371.523239 -198.367206) (xy 371.546013 -198.416904) (xy 371.56146 -198.469343) (xy 371.569264 -198.52345)
			(xy 371.569742 -198.550784) (xy 371.569264 -198.578152) (xy 371.561429 -198.632323) (xy 371.54593 -198.684819)
			(xy 371.523088 -198.73456) (xy 371.49337 -198.780525) (xy 371.475762 -198.801482) (xy 371.469666 -198.808594)
			(xy 371.463316 -198.825358) (xy 371.463316 -198.901558) (xy 371.463376 -198.905831) (xy 371.464782 -198.91426)
			(xy 371.46611 -198.918322) (xy 371.469666 -198.927974) (xy 371.476016 -198.93534) (xy 371.493606 -198.956267)
			(xy 371.523239 -199.002206) (xy 371.546013 -199.051904) (xy 371.56146 -199.104343) (xy 371.569264 -199.15845)
			(xy 371.569742 -199.185784) (xy 371.569264 -199.213152) (xy 371.561429 -199.267323) (xy 371.54593 -199.319819)
			(xy 371.523088 -199.36956) (xy 371.49337 -199.415525) (xy 371.475762 -199.436482) (xy 371.469666 -199.443594)
			(xy 371.463316 -199.460358) (xy 371.463316 -199.513698) (xy 371.463633 -199.522216) (xy 371.469204 -199.538316)
			(xy 371.474238 -199.545194) (xy 371.477032 -199.54875) (xy 371.478302 -199.550274) (xy 371.496421 -199.570392)
			(xy 371.527603 -199.614651) (xy 371.552478 -199.662739) (xy 371.570584 -199.713762) (xy 371.581585 -199.766774)
			(xy 371.585275 -199.820788) (xy 371.581588 -199.874803) (xy 371.57059 -199.927815) (xy 371.552487 -199.97884)
			(xy 371.527615 -200.026929) (xy 371.496436 -200.07119) (xy 371.478302 -200.091294) (xy 371.477032 -200.092818)
			(xy 371.474238 -200.096374) (xy 371.469211 -200.103257) (xy 371.463631 -200.119352) (xy 371.463316 -200.12787)
			(xy 371.463316 -200.165462) (xy 371.463712 -200.174746) (xy 371.470346 -200.192087) (xy 371.47627 -200.199244)
			(xy 371.494558 -200.220553) (xy 371.525416 -200.267467) (xy 371.549149 -200.318358) (xy 371.565256 -200.372152)
			(xy 371.573396 -200.427712) (xy 371.573398 -200.483865) (xy 371.565261 -200.539425) (xy 371.549158 -200.593219)
			(xy 371.525428 -200.644112) (xy 371.494573 -200.691028) (xy 371.47627 -200.712324) (xy 371.470403 -200.719517)
			(xy 371.463761 -200.736835) (xy 371.463316 -200.746106) (xy 371.463316 -200.806558) (xy 371.463376 -200.810831)
			(xy 371.464782 -200.81926) (xy 371.46611 -200.823322) (xy 371.469666 -200.832974) (xy 371.476016 -200.84034)
			(xy 371.492933 -200.860435) (xy 371.521659 -200.904412) (xy 371.544067 -200.95192) (xy 371.559731 -201.002058)
			(xy 371.568354 -201.053873) (xy 371.569488 -201.080116) (xy 371.569742 -201.089768) (xy 371.573806 -201.098912)
			(xy 371.575907 -201.103516) (xy 371.581659 -201.111842) (xy 371.585236 -201.115422) (xy 371.63629 -201.164444)
			(xy 371.643639 -201.170934) (xy 371.661801 -201.178269) (xy 371.671596 -201.178668) (xy 373.448072 -201.178668)
			(xy 373.457857 -201.178217) (xy 373.476009 -201.170899) (xy 373.483378 -201.164444) (xy 373.534178 -201.115676)
			(xy 373.536746 -201.113104) (xy 373.541205 -201.107366) (xy 373.543068 -201.104246) (xy 373.549672 -201.092562)
			(xy 373.55018 -201.079862) (xy 373.551376 -201.053616) (xy 373.560077 -201.001802) (xy 373.575798 -200.951669)
			(xy 373.598241 -200.904164) (xy 373.626984 -200.860184) (xy 373.643906 -200.840086) (xy 373.650002 -200.832974)
			(xy 373.656352 -200.81621) (xy 373.656352 -200.74001) (xy 373.65629 -200.735737) (xy 373.65488 -200.72731)
			(xy 373.653558 -200.723246) (xy 373.650002 -200.713594) (xy 373.643652 -200.706228) (xy 373.62606 -200.685301)
			(xy 373.596421 -200.639364) (xy 373.57364 -200.589666) (xy 373.558185 -200.537227) (xy 373.550372 -200.483119)
			(xy 373.549926 -200.455784) (xy 373.550399 -200.428414) (xy 373.558225 -200.374238) (xy 373.573715 -200.321736)
			(xy 373.59655 -200.271987) (xy 373.626261 -200.226013) (xy 373.643906 -200.205086) (xy 373.650002 -200.197974)
			(xy 373.656352 -200.18121) (xy 373.656352 -200.10501) (xy 373.65629 -200.100737) (xy 373.65488 -200.09231)
			(xy 373.653558 -200.088246) (xy 373.650002 -200.078594) (xy 373.643652 -200.071228) (xy 373.62606 -200.050301)
			(xy 373.596421 -200.004364) (xy 373.57364 -199.954666) (xy 373.558185 -199.902227) (xy 373.550372 -199.848119)
			(xy 373.549926 -199.820784) (xy 373.550399 -199.793414) (xy 373.558225 -199.739238) (xy 373.573715 -199.686736)
			(xy 373.59655 -199.636987) (xy 373.626261 -199.591013) (xy 373.643906 -199.570086) (xy 373.650002 -199.562974)
			(xy 373.656352 -199.54621) (xy 373.656352 -199.47001) (xy 373.65629 -199.465737) (xy 373.65488 -199.45731)
			(xy 373.653558 -199.453246) (xy 373.650002 -199.443594) (xy 373.643652 -199.436228) (xy 373.62606 -199.415301)
			(xy 373.596421 -199.369364) (xy 373.57364 -199.319666) (xy 373.558185 -199.267227) (xy 373.550372 -199.213119)
			(xy 373.549926 -199.185784) (xy 373.550399 -199.158414) (xy 373.558225 -199.104238) (xy 373.573715 -199.051736)
			(xy 373.59655 -199.001987) (xy 373.626261 -198.956013) (xy 373.643906 -198.935086) (xy 373.650002 -198.927974)
			(xy 373.656352 -198.91121) (xy 373.656352 -198.83501) (xy 373.65629 -198.830737) (xy 373.65488 -198.82231)
			(xy 373.653558 -198.818246) (xy 373.650002 -198.808594) (xy 373.643652 -198.801228) (xy 373.62606 -198.780301)
			(xy 373.596421 -198.734364) (xy 373.57364 -198.684666) (xy 373.558185 -198.632227) (xy 373.550372 -198.578119)
			(xy 373.549926 -198.550784) (xy 373.550399 -198.523414) (xy 373.558225 -198.469238) (xy 373.573715 -198.416736)
			(xy 373.59655 -198.366987) (xy 373.626261 -198.321013) (xy 373.643906 -198.300086) (xy 373.650002 -198.292974)
			(xy 373.656352 -198.27621) (xy 373.656352 -198.20001) (xy 373.65629 -198.195737) (xy 373.65488 -198.18731)
			(xy 373.653558 -198.183246) (xy 373.650002 -198.173594) (xy 373.643652 -198.166228) (xy 373.62606 -198.145301)
			(xy 373.596421 -198.099364) (xy 373.57364 -198.049666) (xy 373.558185 -197.997227) (xy 373.550372 -197.943119)
			(xy 373.549926 -197.915784) (xy 373.549926 -197.906132) (xy 373.551091 -197.878968) (xy 373.560168 -197.82536)
			(xy 373.57677 -197.773587) (xy 373.600563 -197.724699) (xy 373.631062 -197.679689) (xy 373.648986 -197.659244)
			(xy 373.655103 -197.651961) (xy 373.66188 -197.634207) (xy 373.662194 -197.6247) (xy 373.66194 -197.556882)
			(xy 373.661785 -197.552197) (xy 373.660001 -197.542994) (xy 373.658384 -197.538594) (xy 373.654828 -197.528942)
			(xy 373.648224 -197.52183) (xy 373.629368 -197.500593) (xy 373.597507 -197.45358) (xy 373.572973 -197.402362)
			(xy 373.556309 -197.34807) (xy 373.547882 -197.291908) (xy 373.547386 -197.263512) (xy 373.547864 -197.236144)
			(xy 373.555699 -197.181972) (xy 373.571195 -197.129475) (xy 373.594035 -197.079732) (xy 373.623748 -197.033763)
			(xy 373.641366 -197.012814) (xy 373.647462 -197.005702) (xy 373.653812 -196.988938) (xy 373.653812 -196.912738)
			(xy 373.653752 -196.908465) (xy 373.652346 -196.900036) (xy 373.651018 -196.895974) (xy 373.647462 -196.886322)
			(xy 373.641112 -196.878956) (xy 373.623525 -196.858027) (xy 373.593898 -196.812087) (xy 373.571129 -196.762389)
			(xy 373.555686 -196.70995) (xy 373.547883 -196.655845) (xy 373.547386 -196.628512) (xy 373.547864 -196.601144)
			(xy 373.555699 -196.546972) (xy 373.571195 -196.494475) (xy 373.594035 -196.444732) (xy 373.623748 -196.398763)
			(xy 373.641366 -196.377814) (xy 373.647462 -196.370702) (xy 373.653812 -196.353938) (xy 373.653812 -196.277738)
			(xy 373.653752 -196.273465) (xy 373.652346 -196.265036) (xy 373.651018 -196.260974) (xy 373.647462 -196.251322)
			(xy 373.641112 -196.243956) (xy 373.623525 -196.223027) (xy 373.593898 -196.177087) (xy 373.571129 -196.127389)
			(xy 373.555686 -196.07495) (xy 373.547883 -196.020845) (xy 373.547386 -195.993512) (xy 373.547864 -195.966144)
			(xy 373.555699 -195.911972) (xy 373.571195 -195.859475) (xy 373.594035 -195.809732) (xy 373.623748 -195.763763)
			(xy 373.641366 -195.742814) (xy 373.647462 -195.735702) (xy 373.653812 -195.718938) (xy 373.653812 -195.642738)
			(xy 373.653752 -195.638465) (xy 373.652346 -195.630036) (xy 373.651018 -195.625974) (xy 373.647462 -195.616322)
			(xy 373.641112 -195.608956) (xy 373.623862 -195.58844) (xy 373.594679 -195.54348) (xy 373.572071 -195.49488)
			(xy 373.55648 -195.443597) (xy 373.548214 -195.390637) (xy 373.547386 -195.363846) (xy 373.547386 -195.358258)
			(xy 373.547873 -195.331149) (xy 373.555577 -195.277479) (xy 373.57081 -195.225444) (xy 373.593264 -195.176093)
			(xy 373.622485 -195.130422) (xy 373.639842 -195.109592) (xy 373.645938 -195.10248) (xy 373.652034 -195.085462)
			(xy 373.651526 -194.999864) (xy 373.645176 -194.9831) (xy 373.638826 -194.975988) (xy 373.620926 -194.95497)
			(xy 373.590741 -194.908747) (xy 373.567533 -194.858656) (xy 373.551786 -194.805744) (xy 373.543828 -194.751115)
			(xy 373.543322 -194.723512) (xy 373.543785 -194.696259) (xy 373.55154 -194.642309) (xy 373.566896 -194.590011)
			(xy 373.589538 -194.540431) (xy 373.619006 -194.494579) (xy 373.6547 -194.453387) (xy 373.695893 -194.417695)
			(xy 373.741747 -194.388229) (xy 373.791328 -194.365589) (xy 373.843626 -194.350236) (xy 373.897577 -194.342483)
			(xy 373.92483 -194.342004) (xy 373.952199 -194.342478) (xy 374.006375 -194.350306) (xy 374.058876 -194.365796)
			(xy 374.108625 -194.388631) (xy 374.154598 -194.418342) (xy 374.175528 -194.435984) (xy 374.18264 -194.44208)
			(xy 374.199404 -194.44843) (xy 374.275604 -194.44843) (xy 374.279878 -194.448375) (xy 374.28831 -194.446979)
			(xy 374.292368 -194.445636) (xy 374.30202 -194.44208) (xy 374.309386 -194.43573) (xy 374.330313 -194.418139)
			(xy 374.376252 -194.388504) (xy 374.425949 -194.365726) (xy 374.478388 -194.350274) (xy 374.532496 -194.342463)
			(xy 374.55983 -194.342004) (xy 374.587199 -194.342478) (xy 374.641375 -194.350306) (xy 374.693876 -194.365796)
			(xy 374.743625 -194.388631) (xy 374.789598 -194.418342) (xy 374.810528 -194.435984) (xy 374.81764 -194.44208)
			(xy 374.834404 -194.44843) (xy 374.910604 -194.44843) (xy 374.914878 -194.448375) (xy 374.92331 -194.446979)
			(xy 374.927368 -194.445636) (xy 374.93702 -194.44208) (xy 374.944386 -194.43573) (xy 374.965313 -194.418139)
			(xy 375.011252 -194.388504) (xy 375.060949 -194.365726) (xy 375.113388 -194.350274) (xy 375.167496 -194.342463)
			(xy 375.19483 -194.342004) (xy 375.221976 -194.342485) (xy 375.275718 -194.350186) (xy 375.327826 -194.365429)
			(xy 375.377247 -194.387905) (xy 375.422982 -194.41716) (xy 375.464107 -194.452604) (xy 375.499792 -194.49352)
			(xy 375.529316 -194.539083) (xy 375.552083 -194.58837) (xy 375.567632 -194.640388) (xy 375.575649 -194.694084)
			(xy 375.576338 -194.721226) (xy 375.576338 -194.723766) (xy 375.575813 -194.751614) (xy 375.567678 -194.806715)
			(xy 375.551621 -194.860048) (xy 375.527981 -194.91048) (xy 375.497261 -194.95694) (xy 375.479056 -194.97802)
			(xy 375.478802 -194.978274) (xy 375.472452 -194.98564) (xy 375.46915 -194.994276) (xy 375.467563 -194.998744)
			(xy 375.465896 -195.008077) (xy 375.465848 -195.012818) (xy 375.466356 -195.04914) (xy 375.46661 -195.090796)
			(xy 375.473722 -195.108322) (xy 375.480326 -195.115434) (xy 375.499515 -195.136741) (xy 375.531932 -195.184035)
			(xy 375.556904 -195.23565) (xy 375.573866 -195.290421) (xy 375.582438 -195.347115) (xy 375.582942 -195.375784)
			(xy 375.582464 -195.403152) (xy 375.574629 -195.457323) (xy 375.55913 -195.509819) (xy 375.536288 -195.55956)
			(xy 375.50657 -195.605525) (xy 375.488962 -195.626482) (xy 375.482866 -195.633594) (xy 375.476516 -195.650358)
			(xy 375.476516 -195.726558) (xy 375.476576 -195.730831) (xy 375.477982 -195.73926) (xy 375.47931 -195.743322)
			(xy 375.482866 -195.752974) (xy 375.489216 -195.76034) (xy 375.506806 -195.781267) (xy 375.536439 -195.827206)
			(xy 375.559213 -195.876904) (xy 375.57466 -195.929343) (xy 375.582464 -195.98345) (xy 375.582942 -196.010784)
			(xy 375.582464 -196.038152) (xy 375.574629 -196.092323) (xy 375.55913 -196.144819) (xy 375.536288 -196.19456)
			(xy 375.50657 -196.240525) (xy 375.488962 -196.261482) (xy 375.482866 -196.268594) (xy 375.476516 -196.285358)
			(xy 375.476516 -196.361558) (xy 375.476576 -196.365831) (xy 375.477982 -196.37426) (xy 375.47931 -196.378322)
			(xy 375.482866 -196.387974) (xy 375.489216 -196.39534) (xy 375.506806 -196.416267) (xy 375.536439 -196.462206)
			(xy 375.559213 -196.511904) (xy 375.57466 -196.564343) (xy 375.582464 -196.61845) (xy 375.582942 -196.645784)
			(xy 375.582464 -196.673152) (xy 375.574629 -196.727323) (xy 375.55913 -196.779819) (xy 375.536288 -196.82956)
			(xy 375.50657 -196.875525) (xy 375.488962 -196.896482) (xy 375.482866 -196.903594) (xy 375.476516 -196.920358)
			(xy 375.476516 -196.996558) (xy 375.476576 -197.000831) (xy 375.477982 -197.00926) (xy 375.47931 -197.013322)
			(xy 375.482866 -197.022974) (xy 375.489216 -197.03034) (xy 375.506806 -197.051267) (xy 375.536439 -197.097206)
			(xy 375.559213 -197.146904) (xy 375.57466 -197.199343) (xy 375.582464 -197.25345) (xy 375.582942 -197.280784)
			(xy 375.58288 -197.28434) (xy 377.93041 -197.28434) (xy 377.930897 -197.25697) (xy 377.938709 -197.202792)
			(xy 377.954193 -197.150289) (xy 377.977031 -197.100542) (xy 378.006751 -197.054574) (xy 378.02439 -197.033642)
			(xy 378.030486 -197.02653) (xy 378.036836 -197.009512) (xy 378.036836 -196.924168) (xy 378.030486 -196.90715)
			(xy 378.02439 -196.900038) (xy 378.00679 -196.879073) (xy 377.977066 -196.83311) (xy 377.954221 -196.783369)
			(xy 377.938723 -196.730872) (xy 377.930892 -196.676698) (xy 377.930887 -196.621962) (xy 377.93871 -196.567787)
			(xy 377.9542 -196.515288) (xy 377.977037 -196.465543) (xy 378.006754 -196.419575) (xy 378.02439 -196.398642)
			(xy 378.030486 -196.39153) (xy 378.036836 -196.374512) (xy 378.036836 -196.289168) (xy 378.030486 -196.27215)
			(xy 378.02439 -196.265038) (xy 378.00679 -196.244073) (xy 377.977066 -196.19811) (xy 377.954221 -196.148369)
			(xy 377.938723 -196.095872) (xy 377.930892 -196.041698) (xy 377.930887 -195.986962) (xy 377.93871 -195.932787)
			(xy 377.9542 -195.880288) (xy 377.977037 -195.830543) (xy 378.006754 -195.784575) (xy 378.02439 -195.763642)
			(xy 378.030486 -195.75653) (xy 378.036836 -195.739512) (xy 378.036836 -195.654168) (xy 378.030486 -195.63715)
			(xy 378.02439 -195.630038) (xy 378.006754 -195.609104) (xy 377.977042 -195.563131) (xy 377.954205 -195.513384)
			(xy 377.938714 -195.460884) (xy 377.930885 -195.406709) (xy 377.93041 -195.37934) (xy 377.930926 -195.350851)
			(xy 377.93939 -195.294504) (xy 377.956136 -195.240042) (xy 377.980792 -195.188675) (xy 378.01281 -195.141543)
			(xy 378.031756 -195.12026) (xy 378.03836 -195.113148) (xy 378.045218 -195.095622) (xy 378.045218 -195.00723)
			(xy 378.03836 -194.989704) (xy 378.031756 -194.982592) (xy 378.012809 -194.961311) (xy 377.9808 -194.914175)
			(xy 377.95615 -194.862806) (xy 377.939405 -194.808345) (xy 377.930938 -194.752001) (xy 377.93041 -194.723512)
			(xy 377.930867 -194.696259) (xy 377.938622 -194.642307) (xy 377.953978 -194.590007) (xy 377.97662 -194.540426)
			(xy 378.006089 -194.494572) (xy 378.041783 -194.453379) (xy 378.082977 -194.417685) (xy 378.128831 -194.388217)
			(xy 378.178413 -194.365576) (xy 378.230712 -194.350221) (xy 378.284665 -194.342466) (xy 378.311918 -194.342004)
			(xy 378.339289 -194.342459) (xy 378.393468 -194.350279) (xy 378.445972 -194.365771) (xy 378.495718 -194.388615)
			(xy 378.541685 -194.418342) (xy 378.562616 -194.435984) (xy 378.569728 -194.44208) (xy 378.586746 -194.44843)
			(xy 378.67209 -194.44843) (xy 378.689108 -194.44208) (xy 378.69622 -194.435984) (xy 378.717153 -194.418343)
			(xy 378.763121 -194.388619) (xy 378.812867 -194.365773) (xy 378.865369 -194.350277) (xy 378.919547 -194.342448)
			(xy 378.974289 -194.342448) (xy 379.028467 -194.350277) (xy 379.080969 -194.365773) (xy 379.130715 -194.388619)
			(xy 379.176683 -194.418343) (xy 379.197616 -194.435984) (xy 379.204728 -194.44208) (xy 379.221746 -194.44843)
			(xy 379.30709 -194.44843) (xy 379.324108 -194.44208) (xy 379.33122 -194.435984) (xy 379.352169 -194.418366)
			(xy 379.398138 -194.388652) (xy 379.447881 -194.365812) (xy 379.500378 -194.350316) (xy 379.55455 -194.342482)
			(xy 379.581918 -194.342004) (xy 379.60917 -194.342461) (xy 379.66312 -194.35022) (xy 379.715416 -194.365578)
			(xy 379.764994 -194.388222) (xy 379.810845 -194.417692) (xy 379.852035 -194.453386) (xy 379.887726 -194.494579)
			(xy 379.917192 -194.540433) (xy 379.939832 -194.590013) (xy 379.955186 -194.64231) (xy 379.962941 -194.69626)
			(xy 379.963426 -194.723512) (xy 381.94615 -194.723512) (xy 381.946689 -194.696263) (xy 381.954443 -194.642319)
			(xy 381.969795 -194.590028) (xy 381.992431 -194.540454) (xy 382.021892 -194.494606) (xy 382.057578 -194.453416)
			(xy 382.098762 -194.417725) (xy 382.144607 -194.388257) (xy 382.194178 -194.365613) (xy 382.246467 -194.350255)
			(xy 382.300409 -194.342493) (xy 382.327658 -194.342004) (xy 382.355027 -194.342494) (xy 382.409205 -194.350306)
			(xy 382.461708 -194.365789) (xy 382.511456 -194.388626) (xy 382.557424 -194.418345) (xy 382.578356 -194.435984)
			(xy 382.585468 -194.44208) (xy 382.602486 -194.44843) (xy 382.68783 -194.44843) (xy 382.704848 -194.44208)
			(xy 382.71196 -194.435984) (xy 382.732893 -194.418343) (xy 382.778861 -194.388619) (xy 382.828607 -194.365773)
			(xy 382.881109 -194.350277) (xy 382.935287 -194.342448) (xy 382.990029 -194.342448) (xy 383.044207 -194.350277)
			(xy 383.096709 -194.365773) (xy 383.146455 -194.388619) (xy 383.192423 -194.418343) (xy 383.213356 -194.435984)
			(xy 383.220468 -194.44208) (xy 383.237486 -194.44843) (xy 383.32283 -194.44843) (xy 383.339848 -194.44208)
			(xy 383.34696 -194.435984) (xy 383.367894 -194.418348) (xy 383.413867 -194.388636) (xy 383.463614 -194.3658)
			(xy 383.516114 -194.350308) (xy 383.570289 -194.342479) (xy 383.597658 -194.342004) (xy 383.62491 -194.342494)
			(xy 383.678861 -194.350246) (xy 383.731159 -194.365597) (xy 383.78074 -194.388236) (xy 383.826594 -194.417701)
			(xy 383.867787 -194.453392) (xy 383.903481 -194.494582) (xy 383.93295 -194.540434) (xy 383.955592 -194.590013)
			(xy 383.970948 -194.64231) (xy 383.978703 -194.69626) (xy 383.979166 -194.723512) (xy 383.978663 -194.751115)
			(xy 383.970705 -194.805745) (xy 383.954957 -194.858657) (xy 383.931748 -194.908747) (xy 383.901562 -194.95497)
			(xy 383.883662 -194.975988) (xy 383.877312 -194.983354) (xy 383.870708 -195.001134) (xy 383.87274 -195.089526)
			(xy 383.880106 -195.106798) (xy 383.886964 -195.11391) (xy 383.90698 -195.135409) (xy 383.940892 -195.183366)
			(xy 383.967056 -195.235954) (xy 383.984852 -195.29193) (xy 383.993861 -195.349972) (xy 383.994406 -195.37934)
			(xy 383.993903 -195.406709) (xy 383.986094 -195.460886) (xy 383.970613 -195.513389) (xy 383.94778 -195.563136)
			(xy 383.918063 -195.609105) (xy 383.900426 -195.630038) (xy 383.89433 -195.63715) (xy 383.88798 -195.654168)
			(xy 383.88798 -195.739512) (xy 383.89433 -195.75653) (xy 383.900426 -195.763642) (xy 383.918108 -195.784542)
			(xy 383.947835 -195.830514) (xy 383.97068 -195.880266) (xy 383.986176 -195.932773) (xy 383.994002 -195.986957)
			(xy 383.993997 -196.041703) (xy 383.986163 -196.095886) (xy 383.970659 -196.148391) (xy 383.947806 -196.198139)
			(xy 383.918071 -196.244106) (xy 383.900426 -196.265038) (xy 383.89433 -196.27215) (xy 383.88798 -196.289168)
			(xy 383.88798 -196.374512) (xy 383.89433 -196.39153) (xy 383.900426 -196.398642) (xy 383.918108 -196.419542)
			(xy 383.947835 -196.465514) (xy 383.97068 -196.515266) (xy 383.986176 -196.567773) (xy 383.994002 -196.621957)
			(xy 383.993997 -196.676703) (xy 383.986163 -196.730886) (xy 383.970659 -196.783391) (xy 383.947806 -196.833139)
			(xy 383.918071 -196.879106) (xy 383.900426 -196.900038) (xy 383.89433 -196.90715) (xy 383.88798 -196.924168)
			(xy 383.88798 -197.009512) (xy 383.89433 -197.02653) (xy 383.900426 -197.033642) (xy 383.918108 -197.054542)
			(xy 383.947835 -197.100514) (xy 383.97068 -197.150266) (xy 383.986176 -197.202773) (xy 383.994002 -197.256957)
			(xy 383.993997 -197.311703) (xy 383.986163 -197.365886) (xy 383.970659 -197.418391) (xy 383.947806 -197.468139)
			(xy 383.918071 -197.514106) (xy 383.900426 -197.535038) (xy 383.89433 -197.54215) (xy 383.88798 -197.559168)
			(xy 383.88798 -197.644512) (xy 383.89433 -197.66153) (xy 383.900426 -197.668642) (xy 383.918108 -197.689542)
			(xy 383.947835 -197.735514) (xy 383.97068 -197.785266) (xy 383.986176 -197.837773) (xy 383.994002 -197.891957)
			(xy 383.993997 -197.946703) (xy 383.986163 -198.000886) (xy 383.970659 -198.053391) (xy 383.947806 -198.103139)
			(xy 383.918071 -198.149106) (xy 383.900426 -198.170038) (xy 383.89433 -198.17715) (xy 383.88798 -198.194168)
			(xy 383.88798 -198.279512) (xy 383.89433 -198.29653) (xy 383.900426 -198.303642) (xy 383.918108 -198.324542)
			(xy 383.947835 -198.370514) (xy 383.97068 -198.420266) (xy 383.986176 -198.472773) (xy 383.994002 -198.526957)
			(xy 383.993997 -198.581703) (xy 383.986163 -198.635886) (xy 383.970659 -198.688391) (xy 383.947806 -198.738139)
			(xy 383.918071 -198.784106) (xy 383.900426 -198.805038) (xy 383.89433 -198.81215) (xy 383.88798 -198.829168)
			(xy 383.88798 -198.914512) (xy 383.89433 -198.93153) (xy 383.900426 -198.938642) (xy 383.918108 -198.959542)
			(xy 383.947835 -199.005514) (xy 383.97068 -199.055266) (xy 383.986176 -199.107773) (xy 383.994002 -199.161957)
			(xy 383.993997 -199.216703) (xy 383.986163 -199.270886) (xy 383.970659 -199.323391) (xy 383.947806 -199.373139)
			(xy 383.918071 -199.419106) (xy 383.900426 -199.440038) (xy 383.89433 -199.44715) (xy 383.88798 -199.464168)
			(xy 383.88798 -199.549512) (xy 383.89433 -199.56653) (xy 383.900426 -199.573642) (xy 383.918055 -199.594582)
			(xy 383.947768 -199.640553) (xy 383.970605 -199.690298) (xy 383.986099 -199.742797) (xy 383.99393 -199.796971)
			(xy 383.994406 -199.82434) (xy 386.26161 -199.82434) (xy 386.262097 -199.79697) (xy 386.269909 -199.742792)
			(xy 386.285393 -199.690289) (xy 386.308231 -199.640542) (xy 386.337951 -199.594574) (xy 386.35559 -199.573642)
			(xy 386.361686 -199.56653) (xy 386.368036 -199.549512) (xy 386.368036 -199.464168) (xy 386.361686 -199.44715)
			(xy 386.35559 -199.440038) (xy 386.33799 -199.419073) (xy 386.308266 -199.37311) (xy 386.285421 -199.323369)
			(xy 386.269923 -199.270872) (xy 386.262092 -199.216698) (xy 386.262087 -199.161962) (xy 386.26991 -199.107787)
			(xy 386.2854 -199.055288) (xy 386.308237 -199.005543) (xy 386.337954 -198.959575) (xy 386.35559 -198.938642)
			(xy 386.361686 -198.93153) (xy 386.368036 -198.914512) (xy 386.368036 -198.829168) (xy 386.361686 -198.81215)
			(xy 386.35559 -198.805038) (xy 386.33799 -198.784073) (xy 386.308266 -198.73811) (xy 386.285421 -198.688369)
			(xy 386.269923 -198.635872) (xy 386.262092 -198.581698) (xy 386.262087 -198.526962) (xy 386.26991 -198.472787)
			(xy 386.2854 -198.420288) (xy 386.308237 -198.370543) (xy 386.337954 -198.324575) (xy 386.35559 -198.303642)
			(xy 386.361686 -198.29653) (xy 386.368036 -198.279512) (xy 386.368036 -198.194168) (xy 386.361686 -198.17715)
			(xy 386.35559 -198.170038) (xy 386.33799 -198.149073) (xy 386.308266 -198.10311) (xy 386.285421 -198.053369)
			(xy 386.269923 -198.000872) (xy 386.262092 -197.946698) (xy 386.262087 -197.891962) (xy 386.26991 -197.837787)
			(xy 386.2854 -197.785288) (xy 386.308237 -197.735543) (xy 386.337954 -197.689575) (xy 386.35559 -197.668642)
			(xy 386.361686 -197.66153) (xy 386.368036 -197.644512) (xy 386.368036 -197.559168) (xy 386.361686 -197.54215)
			(xy 386.35559 -197.535038) (xy 386.33799 -197.514073) (xy 386.308266 -197.46811) (xy 386.285421 -197.418369)
			(xy 386.269923 -197.365872) (xy 386.262092 -197.311698) (xy 386.262087 -197.256962) (xy 386.26991 -197.202787)
			(xy 386.2854 -197.150288) (xy 386.308237 -197.100543) (xy 386.337954 -197.054575) (xy 386.35559 -197.033642)
			(xy 386.361686 -197.02653) (xy 386.368036 -197.009512) (xy 386.368036 -196.924168) (xy 386.361686 -196.90715)
			(xy 386.35559 -196.900038) (xy 386.33799 -196.879073) (xy 386.308266 -196.83311) (xy 386.285421 -196.783369)
			(xy 386.269923 -196.730872) (xy 386.262092 -196.676698) (xy 386.262087 -196.621962) (xy 386.26991 -196.567787)
			(xy 386.2854 -196.515288) (xy 386.308237 -196.465543) (xy 386.337954 -196.419575) (xy 386.35559 -196.398642)
			(xy 386.361686 -196.39153) (xy 386.368036 -196.374512) (xy 386.368036 -196.289168) (xy 386.361686 -196.27215)
			(xy 386.35559 -196.265038) (xy 386.33799 -196.244073) (xy 386.308266 -196.19811) (xy 386.285421 -196.148369)
			(xy 386.269923 -196.095872) (xy 386.262092 -196.041698) (xy 386.262087 -195.986962) (xy 386.26991 -195.932787)
			(xy 386.2854 -195.880288) (xy 386.308237 -195.830543) (xy 386.337954 -195.784575) (xy 386.35559 -195.763642)
			(xy 386.361686 -195.75653) (xy 386.368036 -195.739512) (xy 386.368036 -195.654168) (xy 386.361686 -195.63715)
			(xy 386.35559 -195.630038) (xy 386.337954 -195.609104) (xy 386.308242 -195.563131) (xy 386.285405 -195.513384)
			(xy 386.269914 -195.460884) (xy 386.262085 -195.406709) (xy 386.26161 -195.37934) (xy 386.262126 -195.350851)
			(xy 386.27059 -195.294504) (xy 386.287336 -195.240042) (xy 386.311992 -195.188675) (xy 386.34401 -195.141543)
			(xy 386.362956 -195.12026) (xy 386.36956 -195.113148) (xy 386.376418 -195.095622) (xy 386.376418 -195.00723)
			(xy 386.36956 -194.989704) (xy 386.362956 -194.982592) (xy 386.344009 -194.961311) (xy 386.312 -194.914175)
			(xy 386.28735 -194.862806) (xy 386.270605 -194.808345) (xy 386.262138 -194.752001) (xy 386.26161 -194.723512)
			(xy 386.262067 -194.696259) (xy 386.269822 -194.642307) (xy 386.285178 -194.590007) (xy 386.30782 -194.540426)
			(xy 386.337289 -194.494572) (xy 386.372983 -194.453379) (xy 386.414177 -194.417685) (xy 386.460031 -194.388217)
			(xy 386.509613 -194.365576) (xy 386.561912 -194.350221) (xy 386.615865 -194.342466) (xy 386.643118 -194.342004)
			(xy 386.670489 -194.342459) (xy 386.724668 -194.350279) (xy 386.777172 -194.365771) (xy 386.826918 -194.388615)
			(xy 386.872885 -194.418342) (xy 386.893816 -194.435984) (xy 386.900928 -194.44208) (xy 386.917946 -194.44843)
			(xy 387.00329 -194.44843) (xy 387.020308 -194.44208) (xy 387.02742 -194.435984) (xy 387.048353 -194.418343)
			(xy 387.094321 -194.388619) (xy 387.144067 -194.365773) (xy 387.196569 -194.350277) (xy 387.250747 -194.342448)
			(xy 387.305489 -194.342448) (xy 387.359667 -194.350277) (xy 387.412169 -194.365773) (xy 387.461915 -194.388619)
			(xy 387.507883 -194.418343) (xy 387.528816 -194.435984) (xy 387.535928 -194.44208) (xy 387.552946 -194.44843)
			(xy 387.63829 -194.44843) (xy 387.655308 -194.44208) (xy 387.66242 -194.435984) (xy 387.683369 -194.418366)
			(xy 387.729338 -194.388652) (xy 387.779081 -194.365812) (xy 387.831578 -194.350316) (xy 387.88575 -194.342482)
			(xy 387.913118 -194.342004) (xy 387.94037 -194.342461) (xy 387.99432 -194.35022) (xy 388.046616 -194.365578)
			(xy 388.096194 -194.388222) (xy 388.142045 -194.417692) (xy 388.183235 -194.453386) (xy 388.218926 -194.494579)
			(xy 388.248392 -194.540433) (xy 388.271032 -194.590013) (xy 388.286386 -194.64231) (xy 388.294141 -194.69626)
			(xy 388.294626 -194.723512) (xy 388.294178 -194.750483) (xy 388.286569 -194.803884) (xy 388.271505 -194.855679)
			(xy 388.249287 -194.904832) (xy 388.22036 -194.950361) (xy 388.203186 -194.971162) (xy 388.19709 -194.978274)
			(xy 388.190994 -194.995292) (xy 388.191756 -195.08089) (xy 388.19836 -195.097654) (xy 388.20471 -195.104766)
			(xy 388.222802 -195.125838) (xy 388.253307 -195.172247) (xy 388.276767 -195.222585) (xy 388.292688 -195.275792)
			(xy 388.300732 -195.330743) (xy 388.30123 -195.358512) (xy 388.300788 -195.385883) (xy 388.292967 -195.440064)
			(xy 388.277473 -195.492568) (xy 388.254626 -195.542315) (xy 388.224895 -195.58828) (xy 388.20725 -195.60921)
			(xy 388.201154 -195.616322) (xy 388.194804 -195.63334) (xy 388.194804 -195.718684) (xy 388.201154 -195.735702)
			(xy 388.20725 -195.742814) (xy 388.224903 -195.763737) (xy 388.254629 -195.809706) (xy 388.277476 -195.859453)
			(xy 388.292972 -195.911957) (xy 388.3008 -195.966138) (xy 388.300799 -196.02088) (xy 388.292968 -196.07506)
			(xy 388.277469 -196.127563) (xy 388.254621 -196.17731) (xy 388.224892 -196.223278) (xy 388.20725 -196.24421)
			(xy 388.201154 -196.251322) (xy 388.194804 -196.26834) (xy 388.194804 -196.353684) (xy 388.201154 -196.370702)
			(xy 388.20725 -196.377814) (xy 388.224903 -196.398737) (xy 388.254629 -196.444706) (xy 388.277476 -196.494453)
			(xy 388.292972 -196.546957) (xy 388.3008 -196.601138) (xy 388.300799 -196.65588) (xy 388.292968 -196.71006)
			(xy 388.277469 -196.762563) (xy 388.254621 -196.81231) (xy 388.224892 -196.858278) (xy 388.20725 -196.87921)
			(xy 388.201154 -196.886322) (xy 388.194804 -196.90334) (xy 388.194804 -196.988684) (xy 388.201154 -197.005702)
			(xy 388.20725 -197.012814) (xy 388.224854 -197.033774) (xy 388.254573 -197.079738) (xy 388.277417 -197.129479)
			(xy 388.292916 -197.181973) (xy 388.300752 -197.236145) (xy 388.30123 -197.263512) (xy 388.300721 -197.292382)
			(xy 388.292039 -197.349466) (xy 388.274858 -197.404592) (xy 388.249572 -197.456501) (xy 388.216756 -197.50401)
			(xy 388.197344 -197.525386) (xy 388.190486 -197.532244) (xy 388.183628 -197.550024) (xy 388.182612 -197.638416)
			(xy 388.189216 -197.655942) (xy 388.19582 -197.663308) (xy 388.214294 -197.684467) (xy 388.245486 -197.731179)
			(xy 388.269503 -197.781955) (xy 388.285826 -197.8357) (xy 388.294103 -197.891256) (xy 388.294626 -197.91934)
			(xy 388.294143 -197.94671) (xy 388.286332 -198.000889) (xy 388.270848 -198.053393) (xy 388.248009 -198.10314)
			(xy 388.218287 -198.149107) (xy 388.200646 -198.170038) (xy 388.19455 -198.17715) (xy 388.1882 -198.194168)
			(xy 388.1882 -198.279512) (xy 388.19455 -198.29653) (xy 388.200646 -198.303642) (xy 388.218327 -198.324542)
			(xy 388.248052 -198.370515) (xy 388.270897 -198.420267) (xy 388.286391 -198.472774) (xy 388.294217 -198.526957)
			(xy 388.294212 -198.581703) (xy 388.286378 -198.635885) (xy 388.270876 -198.68839) (xy 388.248023 -198.738138)
			(xy 388.218291 -198.784106) (xy 388.200646 -198.805038) (xy 388.19455 -198.81215) (xy 388.1882 -198.829168)
			(xy 388.1882 -198.914512) (xy 388.19455 -198.93153) (xy 388.200646 -198.938642) (xy 388.218327 -198.959542)
			(xy 388.248052 -199.005515) (xy 388.270897 -199.055267) (xy 388.286391 -199.107774) (xy 388.294217 -199.161957)
			(xy 388.294212 -199.216703) (xy 388.286378 -199.270885) (xy 388.272957 -199.31634) (xy 390.27735 -199.31634)
			(xy 390.277878 -199.287423) (xy 390.286602 -199.230252) (xy 390.303857 -199.175052) (xy 390.329247 -199.12309)
			(xy 390.36219 -199.075556) (xy 390.40193 -199.03354) (xy 390.424416 -199.01535) (xy 390.433154 -199.007765)
			(xy 390.44335 -198.987024) (xy 390.443974 -198.975472) (xy 390.443974 -198.895208) (xy 390.443408 -198.883639)
			(xy 390.433211 -198.862868) (xy 390.424416 -198.85533) (xy 390.40195 -198.837118) (xy 390.362213 -198.795103)
			(xy 390.329272 -198.747573) (xy 390.30388 -198.695615) (xy 390.28662 -198.640421) (xy 390.277887 -198.583255)
			(xy 390.27735 -198.55434) (xy 390.277827 -198.52697) (xy 390.285641 -198.472791) (xy 390.301126 -198.420287)
			(xy 390.323966 -198.37054) (xy 390.353689 -198.324574) (xy 390.37133 -198.303642) (xy 390.377426 -198.29653)
			(xy 390.383776 -198.279512) (xy 390.383776 -198.194168) (xy 390.377426 -198.17715) (xy 390.37133 -198.170038)
			(xy 390.3537 -198.149099) (xy 390.323986 -198.103128) (xy 390.301148 -198.053383) (xy 390.285654 -198.000883)
			(xy 390.277825 -197.946709) (xy 390.27735 -197.91934) (xy 390.27787 -197.890636) (xy 390.286467 -197.833876)
			(xy 390.303472 -197.779046) (xy 390.328502 -197.727382) (xy 390.360991 -197.680053) (xy 390.38022 -197.658736)
			(xy 390.387078 -197.651624) (xy 390.393936 -197.634098) (xy 390.394444 -197.545452) (xy 390.38784 -197.527926)
			(xy 390.381236 -197.520814) (xy 390.362555 -197.499613) (xy 390.331021 -197.452725) (xy 390.306745 -197.4017)
			(xy 390.29026 -197.347652) (xy 390.281926 -197.291765) (xy 390.281414 -197.263512) (xy 390.281884 -197.236142)
			(xy 390.2897 -197.181963) (xy 390.305188 -197.12946) (xy 390.328029 -197.079713) (xy 390.357753 -197.033746)
			(xy 390.375394 -197.012814) (xy 390.38149 -197.005702) (xy 390.38784 -196.988684) (xy 390.38784 -196.90334)
			(xy 390.38149 -196.886322) (xy 390.375394 -196.87921) (xy 390.357766 -196.858267) (xy 390.328044 -196.8123)
			(xy 390.3052 -196.762555) (xy 390.289704 -196.710055) (xy 390.281875 -196.655879) (xy 390.281874 -196.601139)
			(xy 390.2897 -196.546962) (xy 390.305193 -196.494461) (xy 390.328035 -196.444716) (xy 390.357756 -196.398747)
			(xy 390.375394 -196.377814) (xy 390.38149 -196.370702) (xy 390.38784 -196.353684) (xy 390.38784 -196.26834)
			(xy 390.38149 -196.251322) (xy 390.375394 -196.24421) (xy 390.357766 -196.223267) (xy 390.328044 -196.1773)
			(xy 390.3052 -196.127555) (xy 390.289704 -196.075055) (xy 390.281875 -196.020879) (xy 390.281874 -195.966139)
			(xy 390.2897 -195.911962) (xy 390.305193 -195.859461) (xy 390.328035 -195.809716) (xy 390.357756 -195.763747)
			(xy 390.375394 -195.742814) (xy 390.38149 -195.735702) (xy 390.38784 -195.718684) (xy 390.38784 -195.63334)
			(xy 390.38149 -195.616322) (xy 390.375394 -195.60921) (xy 390.357745 -195.588286) (xy 390.328035 -195.542311)
			(xy 390.305201 -195.492561) (xy 390.289712 -195.440059) (xy 390.281887 -195.385882) (xy 390.281414 -195.358512)
			(xy 390.281869 -195.331377) (xy 390.289564 -195.277656) (xy 390.304799 -195.22557) (xy 390.327268 -195.17617)
			(xy 390.356515 -195.130456) (xy 390.37387 -195.109592) (xy 390.379966 -195.10248) (xy 390.386062 -195.085462)
			(xy 390.385554 -195.000118) (xy 390.379204 -194.9831) (xy 390.372854 -194.975988) (xy 390.354961 -194.954963)
			(xy 390.324767 -194.908745) (xy 390.301552 -194.858657) (xy 390.2858 -194.805745) (xy 390.27784 -194.751115)
			(xy 390.27735 -194.723512) (xy 390.277889 -194.696263) (xy 390.285643 -194.642319) (xy 390.300995 -194.590028)
			(xy 390.323631 -194.540454) (xy 390.353092 -194.494606) (xy 390.388778 -194.453416) (xy 390.429962 -194.417725)
			(xy 390.475807 -194.388257) (xy 390.525378 -194.365613) (xy 390.577667 -194.350255) (xy 390.631609 -194.342493)
			(xy 390.658858 -194.342004) (xy 390.686227 -194.342494) (xy 390.740405 -194.350306) (xy 390.792908 -194.365789)
			(xy 390.842656 -194.388626) (xy 390.888624 -194.418345) (xy 390.909556 -194.435984) (xy 390.916668 -194.44208)
			(xy 390.933686 -194.44843) (xy 391.01903 -194.44843) (xy 391.036048 -194.44208) (xy 391.04316 -194.435984)
			(xy 391.064094 -194.418348) (xy 391.110067 -194.388636) (xy 391.159814 -194.3658) (xy 391.212314 -194.350308)
			(xy 391.266489 -194.342479) (xy 391.293858 -194.342004) (xy 391.32111 -194.342494) (xy 391.375061 -194.350246)
			(xy 391.427359 -194.365597) (xy 391.47694 -194.388236) (xy 391.522794 -194.417701) (xy 391.563987 -194.453392)
			(xy 391.599681 -194.494582) (xy 391.62915 -194.540434) (xy 391.651792 -194.590013) (xy 391.667148 -194.64231)
			(xy 391.674903 -194.69626) (xy 391.675366 -194.723512) (xy 391.674872 -194.750645) (xy 391.667187 -194.804365)
			(xy 391.651961 -194.856451) (xy 391.629501 -194.905851) (xy 391.600261 -194.951567) (xy 391.58291 -194.972432)
			(xy 391.576814 -194.979544) (xy 391.570718 -194.996562) (xy 391.571226 -195.081906) (xy 391.577576 -195.098924)
			(xy 391.583926 -195.106036) (xy 391.601827 -195.127054) (xy 391.63202 -195.173274) (xy 391.655234 -195.223364)
			(xy 391.670985 -195.276277) (xy 391.678942 -195.330908) (xy 391.67943 -195.358512) (xy 391.678988 -195.385883)
			(xy 391.671167 -195.440064) (xy 391.655673 -195.492568) (xy 391.632826 -195.542315) (xy 391.603095 -195.58828)
			(xy 391.58545 -195.60921) (xy 391.579354 -195.616322) (xy 391.573004 -195.63334) (xy 391.573004 -195.718684)
			(xy 391.579354 -195.735702) (xy 391.58545 -195.742814) (xy 391.603103 -195.763737) (xy 391.632829 -195.809706)
			(xy 391.655676 -195.859453) (xy 391.671172 -195.911957) (xy 391.679 -195.966138) (xy 391.678999 -196.02088)
			(xy 391.671168 -196.07506) (xy 391.655669 -196.127563) (xy 391.632821 -196.17731) (xy 391.603092 -196.223278)
			(xy 391.58545 -196.24421) (xy 391.579354 -196.251322) (xy 391.573004 -196.26834) (xy 391.573004 -196.353684)
			(xy 391.579354 -196.370702) (xy 391.58545 -196.377814) (xy 391.603103 -196.398737) (xy 391.632829 -196.444706)
			(xy 391.655676 -196.494453) (xy 391.671172 -196.546957) (xy 391.679 -196.601138) (xy 391.678999 -196.65588)
			(xy 391.671168 -196.71006) (xy 391.655669 -196.762563) (xy 391.632821 -196.81231) (xy 391.603092 -196.858278)
			(xy 391.58545 -196.87921) (xy 391.579354 -196.886322) (xy 391.573004 -196.90334) (xy 391.573004 -196.988684)
			(xy 391.579354 -197.005702) (xy 391.58545 -197.012814) (xy 391.603054 -197.033774) (xy 391.632773 -197.079738)
			(xy 391.655617 -197.129479) (xy 391.671116 -197.181973) (xy 391.678952 -197.236145) (xy 391.67943 -197.263512)
			(xy 391.678947 -197.292217) (xy 391.670342 -197.348979) (xy 391.653328 -197.40381) (xy 391.62829 -197.455473)
			(xy 391.595793 -197.5028) (xy 391.57656 -197.524116) (xy 391.569702 -197.531228) (xy 391.562844 -197.548754)
			(xy 391.562336 -197.6374) (xy 391.56894 -197.654926) (xy 391.575544 -197.662038) (xy 391.594246 -197.683221)
			(xy 391.625778 -197.730114) (xy 391.65005 -197.781144) (xy 391.66653 -197.835195) (xy 391.674858 -197.891086)
			(xy 391.675366 -197.91934) (xy 391.674873 -197.946709) (xy 391.667063 -198.000888) (xy 391.651581 -198.053391)
			(xy 391.628745 -198.103138) (xy 391.599025 -198.149106) (xy 391.581386 -198.170038) (xy 391.57529 -198.17715)
			(xy 391.56894 -198.194168) (xy 391.56894 -198.279512) (xy 391.57529 -198.29653) (xy 391.581386 -198.303642)
			(xy 391.599009 -198.324587) (xy 391.628724 -198.370556) (xy 391.651563 -198.4203) (xy 391.667058 -198.472798)
			(xy 391.67489 -198.526972) (xy 391.675366 -198.55434) (xy 391.674982 -198.581596) (xy 391.667219 -198.635552)
			(xy 391.651855 -198.687854) (xy 391.629205 -198.737437) (xy 391.599729 -198.783292) (xy 391.564027 -198.824485)
			(xy 391.522826 -198.860178) (xy 391.476965 -198.889645) (xy 391.427377 -198.912284) (xy 391.375072 -198.927636)
			(xy 391.321114 -198.935388) (xy 391.293858 -198.935848) (xy 391.266488 -198.935361) (xy 391.21231 -198.92755)
			(xy 391.159806 -198.912066) (xy 391.110059 -198.889229) (xy 391.064092 -198.859508) (xy 391.04316 -198.841868)
			(xy 391.036048 -198.835772) (xy 391.01903 -198.829422) (xy 390.933686 -198.829422) (xy 390.916668 -198.835772)
			(xy 390.909556 -198.841868) (xy 390.8933 -198.85533) (xy 390.884529 -198.862883) (xy 390.874351 -198.883648)
			(xy 390.873742 -198.895208) (xy 390.873742 -198.975472) (xy 390.874314 -198.98704) (xy 390.884506 -199.007812)
			(xy 390.8933 -199.01535) (xy 390.91576 -199.033569) (xy 390.955496 -199.075583) (xy 390.988438 -199.123112)
			(xy 391.013831 -199.175068) (xy 391.031092 -199.23026) (xy 391.039827 -199.287426) (xy 391.040366 -199.31634)
			(xy 391.03988 -199.343591) (xy 391.032124 -199.397539) (xy 391.016769 -199.449834) (xy 390.994127 -199.499411)
			(xy 390.964661 -199.545261) (xy 390.92897 -199.586452) (xy 390.887779 -199.622143) (xy 390.841929 -199.651609)
			(xy 390.792352 -199.674251) (xy 390.740057 -199.689606) (xy 390.686109 -199.697362) (xy 390.631607 -199.697362)
			(xy 390.577659 -199.689606) (xy 390.525364 -199.674251) (xy 390.475787 -199.651609) (xy 390.429937 -199.622143)
			(xy 390.388746 -199.586452) (xy 390.353055 -199.545261) (xy 390.323589 -199.499411) (xy 390.300947 -199.449834)
			(xy 390.285592 -199.397539) (xy 390.277836 -199.343591) (xy 390.27735 -199.31634) (xy 388.272957 -199.31634)
			(xy 388.270876 -199.32339) (xy 388.248023 -199.373138) (xy 388.218291 -199.419106) (xy 388.200646 -199.440038)
			(xy 388.19455 -199.44715) (xy 388.1882 -199.464168) (xy 388.1882 -199.549512) (xy 388.19455 -199.56653)
			(xy 388.200646 -199.573642) (xy 388.218263 -199.594592) (xy 388.24798 -199.640559) (xy 388.270821 -199.690302)
			(xy 388.286317 -199.742799) (xy 388.29415 -199.796972) (xy 388.294626 -199.82434) (xy 388.294159 -199.851591)
			(xy 388.286398 -199.905539) (xy 388.271039 -199.957833) (xy 388.248394 -200.007409) (xy 388.218925 -200.053258)
			(xy 388.183232 -200.094448) (xy 388.142041 -200.130139) (xy 388.09619 -200.159605) (xy 388.046612 -200.182246)
			(xy 387.994317 -200.197603) (xy 387.940369 -200.205361) (xy 387.913118 -200.205848) (xy 387.885748 -200.205384)
			(xy 387.831568 -200.197568) (xy 387.779064 -200.182079) (xy 387.729317 -200.159236) (xy 387.683351 -200.12951)
			(xy 387.66242 -200.111868) (xy 387.655308 -200.105772) (xy 387.63829 -200.099422) (xy 387.552946 -200.099422)
			(xy 387.535928 -200.105772) (xy 387.528816 -200.111868) (xy 387.507883 -200.129509) (xy 387.461915 -200.159233)
			(xy 387.412169 -200.182079) (xy 387.359667 -200.197575) (xy 387.305489 -200.205404) (xy 387.250747 -200.205404)
			(xy 387.196569 -200.197575) (xy 387.144067 -200.182079) (xy 387.094321 -200.159233) (xy 387.048353 -200.129509)
			(xy 387.02742 -200.111868) (xy 387.020308 -200.105772) (xy 387.00329 -200.099422) (xy 386.917946 -200.099422)
			(xy 386.900928 -200.105772) (xy 386.893816 -200.111868) (xy 386.872885 -200.129508) (xy 386.826912 -200.159221)
			(xy 386.777165 -200.182057) (xy 386.724663 -200.197548) (xy 386.670487 -200.205375) (xy 386.643118 -200.205848)
			(xy 386.615869 -200.205305) (xy 386.561925 -200.197552) (xy 386.509634 -200.182201) (xy 386.46006 -200.159565)
			(xy 386.414211 -200.130105) (xy 386.373022 -200.094419) (xy 386.33733 -200.053235) (xy 386.307863 -200.007391)
			(xy 386.285219 -199.95782) (xy 386.26986 -199.905531) (xy 386.262099 -199.851589) (xy 386.26161 -199.82434)
			(xy 383.994406 -199.82434) (xy 383.993959 -199.851592) (xy 383.986197 -199.905542) (xy 383.970837 -199.957837)
			(xy 383.948191 -200.007415) (xy 383.91872 -200.053265) (xy 383.883025 -200.094455) (xy 383.841831 -200.130146)
			(xy 383.795978 -200.159611) (xy 383.746398 -200.182252) (xy 383.6941 -200.197606) (xy 383.64015 -200.205362)
			(xy 383.612898 -200.205848) (xy 383.585527 -200.205396) (xy 383.531347 -200.197577) (xy 383.478843 -200.182085)
			(xy 383.429096 -200.15924) (xy 383.383131 -200.129511) (xy 383.3622 -200.111868) (xy 383.355088 -200.105772)
			(xy 383.33807 -200.099422) (xy 383.252726 -200.099422) (xy 383.235708 -200.105772) (xy 383.228596 -200.111868)
			(xy 383.207663 -200.129509) (xy 383.161695 -200.159233) (xy 383.111949 -200.182079) (xy 383.059447 -200.197575)
			(xy 383.005269 -200.205404) (xy 382.950527 -200.205404) (xy 382.896349 -200.197575) (xy 382.843847 -200.182079)
			(xy 382.794101 -200.159233) (xy 382.748133 -200.129509) (xy 382.7272 -200.111868) (xy 382.720088 -200.105772)
			(xy 382.70307 -200.099422) (xy 382.617726 -200.099422) (xy 382.600708 -200.105772) (xy 382.593596 -200.111868)
			(xy 382.572672 -200.129517) (xy 382.526698 -200.159229) (xy 382.476948 -200.182063) (xy 382.424445 -200.197552)
			(xy 382.370268 -200.205376) (xy 382.342898 -200.205848) (xy 382.315649 -200.205324) (xy 382.261704 -200.197568)
			(xy 382.209413 -200.182215) (xy 382.159838 -200.159577) (xy 382.11399 -200.130114) (xy 382.0728 -200.094426)
			(xy 382.037109 -200.053241) (xy 382.007642 -200.007395) (xy 381.984998 -199.957823) (xy 381.96964 -199.905533)
			(xy 381.961879 -199.851589) (xy 381.96139 -199.82434) (xy 381.961882 -199.796971) (xy 381.969694 -199.742793)
			(xy 381.985177 -199.69029) (xy 382.008013 -199.640543) (xy 382.037732 -199.594575) (xy 382.05537 -199.573642)
			(xy 382.061466 -199.56653) (xy 382.067816 -199.549512) (xy 382.067816 -199.464168) (xy 382.061466 -199.44715)
			(xy 382.05537 -199.440038) (xy 382.037767 -199.419074) (xy 382.008037 -199.373113) (xy 381.985187 -199.323372)
			(xy 381.969685 -199.270874) (xy 381.961852 -199.216699) (xy 381.961848 -199.161961) (xy 381.969673 -199.107785)
			(xy 381.985165 -199.055284) (xy 382.008008 -199.00554) (xy 382.03773 -198.959574) (xy 382.05537 -198.938642)
			(xy 382.061466 -198.93153) (xy 382.067816 -198.914512) (xy 382.067816 -198.829168) (xy 382.061466 -198.81215)
			(xy 382.05537 -198.805038) (xy 382.037767 -198.784074) (xy 382.008037 -198.738113) (xy 381.985187 -198.688372)
			(xy 381.969685 -198.635874) (xy 381.961852 -198.581699) (xy 381.961848 -198.526961) (xy 381.969673 -198.472785)
			(xy 381.985165 -198.420284) (xy 382.008008 -198.37054) (xy 382.03773 -198.324574) (xy 382.05537 -198.303642)
			(xy 382.061466 -198.29653) (xy 382.067816 -198.279512) (xy 382.067816 -198.194168) (xy 382.061466 -198.17715)
			(xy 382.05537 -198.170038) (xy 382.037731 -198.149106) (xy 382.00802 -198.103133) (xy 381.985184 -198.053385)
			(xy 381.969693 -198.000885) (xy 381.961865 -197.946709) (xy 381.96139 -197.91934) (xy 381.961892 -197.891502)
			(xy 381.969997 -197.83642) (xy 381.986012 -197.783097) (xy 382.009598 -197.732663) (xy 382.040254 -197.686188)
			(xy 382.058418 -197.665086) (xy 382.064768 -197.657974) (xy 382.071372 -197.640194) (xy 382.069848 -197.551802)
			(xy 382.062736 -197.534276) (xy 382.056132 -197.527164) (xy 382.036377 -197.505752) (xy 382.002977 -197.45802)
			(xy 381.977212 -197.405771) (xy 381.959679 -197.350214) (xy 381.950786 -197.29264) (xy 381.950214 -197.263512)
			(xy 381.950684 -197.236142) (xy 381.9585 -197.181963) (xy 381.973988 -197.12946) (xy 381.996829 -197.079713)
			(xy 382.026553 -197.033746) (xy 382.044194 -197.012814) (xy 382.05029 -197.005702) (xy 382.05664 -196.988684)
			(xy 382.05664 -196.90334) (xy 382.05029 -196.886322) (xy 382.044194 -196.87921) (xy 382.026566 -196.858267)
			(xy 381.996844 -196.8123) (xy 381.974 -196.762555) (xy 381.958504 -196.710055) (xy 381.950675 -196.655879)
			(xy 381.950674 -196.601139) (xy 381.9585 -196.546962) (xy 381.973993 -196.494461) (xy 381.996835 -196.444716)
			(xy 382.026556 -196.398747) (xy 382.044194 -196.377814) (xy 382.05029 -196.370702) (xy 382.05664 -196.353684)
			(xy 382.05664 -196.26834) (xy 382.05029 -196.251322) (xy 382.044194 -196.24421) (xy 382.026566 -196.223267)
			(xy 381.996844 -196.1773) (xy 381.974 -196.127555) (xy 381.958504 -196.075055) (xy 381.950675 -196.020879)
			(xy 381.950674 -195.966139) (xy 381.9585 -195.911962) (xy 381.973993 -195.859461) (xy 381.996835 -195.809716)
			(xy 382.026556 -195.763747) (xy 382.044194 -195.742814) (xy 382.05029 -195.735702) (xy 382.05664 -195.718684)
			(xy 382.05664 -195.63334) (xy 382.05029 -195.616322) (xy 382.044194 -195.60921) (xy 382.026545 -195.588286)
			(xy 381.996835 -195.542311) (xy 381.974001 -195.492561) (xy 381.958512 -195.440059) (xy 381.950687 -195.385882)
			(xy 381.950214 -195.358512) (xy 381.950669 -195.331377) (xy 381.958364 -195.277656) (xy 381.973599 -195.22557)
			(xy 381.996068 -195.17617) (xy 382.025315 -195.130456) (xy 382.04267 -195.109592) (xy 382.048766 -195.10248)
			(xy 382.054862 -195.085462) (xy 382.054354 -195.000118) (xy 382.048004 -194.9831) (xy 382.041654 -194.975988)
			(xy 382.023761 -194.954963) (xy 381.993567 -194.908745) (xy 381.970352 -194.858657) (xy 381.9546 -194.805745)
			(xy 381.94664 -194.751115) (xy 381.94615 -194.723512) (xy 379.963426 -194.723512) (xy 379.962978 -194.750483)
			(xy 379.955369 -194.803884) (xy 379.940305 -194.855679) (xy 379.918087 -194.904832) (xy 379.88916 -194.950361)
			(xy 379.871986 -194.971162) (xy 379.86589 -194.978274) (xy 379.859794 -194.995292) (xy 379.860556 -195.08089)
			(xy 379.86716 -195.097654) (xy 379.87351 -195.104766) (xy 379.891602 -195.125838) (xy 379.922107 -195.172247)
			(xy 379.945567 -195.222585) (xy 379.961488 -195.275792) (xy 379.969532 -195.330743) (xy 379.97003 -195.358512)
			(xy 379.969588 -195.385883) (xy 379.961767 -195.440064) (xy 379.946273 -195.492568) (xy 379.923426 -195.542315)
			(xy 379.893695 -195.58828) (xy 379.87605 -195.60921) (xy 379.869954 -195.616322) (xy 379.863604 -195.63334)
			(xy 379.863604 -195.718684) (xy 379.869954 -195.735702) (xy 379.87605 -195.742814) (xy 379.893703 -195.763737)
			(xy 379.923429 -195.809706) (xy 379.946276 -195.859453) (xy 379.961772 -195.911957) (xy 379.9696 -195.966138)
			(xy 379.969599 -196.02088) (xy 379.961768 -196.07506) (xy 379.946269 -196.127563) (xy 379.923421 -196.17731)
			(xy 379.893692 -196.223278) (xy 379.87605 -196.24421) (xy 379.869954 -196.251322) (xy 379.863604 -196.26834)
			(xy 379.863604 -196.353684) (xy 379.869954 -196.370702) (xy 379.87605 -196.377814) (xy 379.893703 -196.398737)
			(xy 379.923429 -196.444706) (xy 379.946276 -196.494453) (xy 379.961772 -196.546957) (xy 379.9696 -196.601138)
			(xy 379.969599 -196.65588) (xy 379.961768 -196.71006) (xy 379.946269 -196.762563) (xy 379.923421 -196.81231)
			(xy 379.893692 -196.858278) (xy 379.87605 -196.87921) (xy 379.869954 -196.886322) (xy 379.863604 -196.90334)
			(xy 379.863604 -196.988684) (xy 379.869954 -197.005702) (xy 379.87605 -197.012814) (xy 379.893654 -197.033774)
			(xy 379.923373 -197.079738) (xy 379.946217 -197.129479) (xy 379.961716 -197.181973) (xy 379.969552 -197.236145)
			(xy 379.97003 -197.263512) (xy 379.969519 -197.29135) (xy 379.961419 -197.346433) (xy 379.945408 -197.399756)
			(xy 379.921823 -197.45019) (xy 379.891166 -197.496665) (xy 379.873002 -197.517766) (xy 379.866652 -197.524878)
			(xy 379.860048 -197.542658) (xy 379.861572 -197.63105) (xy 379.868684 -197.648576) (xy 379.875288 -197.655688)
			(xy 379.895007 -197.677132) (xy 379.928415 -197.724854) (xy 379.954188 -197.777095) (xy 379.971729 -197.832645)
			(xy 379.98063 -197.890214) (xy 379.981206 -197.91934) (xy 379.980703 -197.946709) (xy 379.972894 -198.000886)
			(xy 379.957413 -198.053389) (xy 379.93458 -198.103136) (xy 379.904863 -198.149105) (xy 379.887226 -198.170038)
			(xy 379.88113 -198.17715) (xy 379.87478 -198.194168) (xy 379.87478 -198.279512) (xy 379.88113 -198.29653)
			(xy 379.887226 -198.303642) (xy 379.904908 -198.324542) (xy 379.934635 -198.370514) (xy 379.95748 -198.420266)
			(xy 379.972976 -198.472773) (xy 379.980802 -198.526957) (xy 379.980797 -198.581703) (xy 379.972963 -198.635886)
			(xy 379.957459 -198.688391) (xy 379.934606 -198.738139) (xy 379.904871 -198.784106) (xy 379.887226 -198.805038)
			(xy 379.88113 -198.81215) (xy 379.87478 -198.829168) (xy 379.87478 -198.914512) (xy 379.88113 -198.93153)
			(xy 379.887226 -198.938642) (xy 379.904908 -198.959542) (xy 379.934635 -199.005514) (xy 379.95748 -199.055266)
			(xy 379.972976 -199.107773) (xy 379.980802 -199.161957) (xy 379.980797 -199.216703) (xy 379.972963 -199.270886)
			(xy 379.957459 -199.323391) (xy 379.934606 -199.373139) (xy 379.904871 -199.419106) (xy 379.887226 -199.440038)
			(xy 379.88113 -199.44715) (xy 379.87478 -199.464168) (xy 379.87478 -199.549512) (xy 379.88113 -199.56653)
			(xy 379.887226 -199.573642) (xy 379.904855 -199.594582) (xy 379.934568 -199.640553) (xy 379.957405 -199.690298)
			(xy 379.972899 -199.742797) (xy 379.98073 -199.796971) (xy 379.981206 -199.82434) (xy 379.980759 -199.851592)
			(xy 379.972997 -199.905542) (xy 379.957637 -199.957837) (xy 379.934991 -200.007415) (xy 379.90552 -200.053265)
			(xy 379.869825 -200.094455) (xy 379.828631 -200.130146) (xy 379.782778 -200.159611) (xy 379.733198 -200.182252)
			(xy 379.6809 -200.197606) (xy 379.62695 -200.205362) (xy 379.599698 -200.205848) (xy 379.572327 -200.205396)
			(xy 379.518147 -200.197577) (xy 379.465643 -200.182085) (xy 379.415896 -200.15924) (xy 379.369931 -200.129511)
			(xy 379.349 -200.111868) (xy 379.341888 -200.105772) (xy 379.32487 -200.099422) (xy 379.239526 -200.099422)
			(xy 379.222508 -200.105772) (xy 379.215396 -200.111868) (xy 379.194463 -200.129509) (xy 379.148495 -200.159233)
			(xy 379.098749 -200.182079) (xy 379.046247 -200.197575) (xy 378.992069 -200.205404) (xy 378.937327 -200.205404)
			(xy 378.883149 -200.197575) (xy 378.830647 -200.182079) (xy 378.780901 -200.159233) (xy 378.734933 -200.129509)
			(xy 378.714 -200.111868) (xy 378.706888 -200.105772) (xy 378.68987 -200.099422) (xy 378.604526 -200.099422)
			(xy 378.587508 -200.105772) (xy 378.580396 -200.111868) (xy 378.559472 -200.129517) (xy 378.513498 -200.159229)
			(xy 378.463748 -200.182063) (xy 378.411245 -200.197552) (xy 378.357068 -200.205376) (xy 378.329698 -200.205848)
			(xy 378.302449 -200.205324) (xy 378.248504 -200.197568) (xy 378.196213 -200.182215) (xy 378.146638 -200.159577)
			(xy 378.10079 -200.130114) (xy 378.0596 -200.094426) (xy 378.023909 -200.053241) (xy 377.994442 -200.007395)
			(xy 377.971798 -199.957823) (xy 377.95644 -199.905533) (xy 377.948679 -199.851589) (xy 377.94819 -199.82434)
			(xy 377.948682 -199.796971) (xy 377.956494 -199.742793) (xy 377.971977 -199.69029) (xy 377.994813 -199.640543)
			(xy 378.024532 -199.594575) (xy 378.04217 -199.573642) (xy 378.048266 -199.56653) (xy 378.054616 -199.549512)
			(xy 378.054616 -199.464168) (xy 378.048266 -199.44715) (xy 378.04217 -199.440038) (xy 378.024567 -199.419074)
			(xy 377.994837 -199.373113) (xy 377.971987 -199.323372) (xy 377.956485 -199.270874) (xy 377.948652 -199.216699)
			(xy 377.948648 -199.161961) (xy 377.956473 -199.107785) (xy 377.971965 -199.055284) (xy 377.994808 -199.00554)
			(xy 378.02453 -198.959574) (xy 378.04217 -198.938642) (xy 378.048266 -198.93153) (xy 378.054616 -198.914512)
			(xy 378.054616 -198.829168) (xy 378.048266 -198.81215) (xy 378.04217 -198.805038) (xy 378.024567 -198.784074)
			(xy 377.994837 -198.738113) (xy 377.971987 -198.688372) (xy 377.956485 -198.635874) (xy 377.948652 -198.581699)
			(xy 377.948648 -198.526961) (xy 377.956473 -198.472785) (xy 377.971965 -198.420284) (xy 377.994808 -198.37054)
			(xy 378.02453 -198.324574) (xy 378.04217 -198.303642) (xy 378.048266 -198.29653) (xy 378.054616 -198.279512)
			(xy 378.054616 -198.194168) (xy 378.048266 -198.17715) (xy 378.04217 -198.170038) (xy 378.024531 -198.149106)
			(xy 377.99482 -198.103133) (xy 377.971984 -198.053385) (xy 377.956493 -198.000885) (xy 377.948665 -197.946709)
			(xy 377.94819 -197.91934) (xy 377.948668 -197.893038) (xy 377.955894 -197.840933) (xy 377.970215 -197.790316)
			(xy 377.991358 -197.742149) (xy 378.018922 -197.697345) (xy 378.035312 -197.67677) (xy 378.041408 -197.669404)
			(xy 378.04725 -197.652386) (xy 378.04471 -197.566788) (xy 378.037852 -197.550024) (xy 378.031502 -197.543166)
			(xy 378.012619 -197.521877) (xy 377.980695 -197.474774) (xy 377.956108 -197.423457) (xy 377.939401 -197.369062)
			(xy 377.930943 -197.312791) (xy 377.93041 -197.28434) (xy 375.58288 -197.28434) (xy 375.582464 -197.308152)
			(xy 375.574629 -197.362323) (xy 375.55913 -197.414819) (xy 375.536288 -197.46456) (xy 375.50657 -197.510525)
			(xy 375.488962 -197.531482) (xy 375.482866 -197.538594) (xy 375.476516 -197.555358) (xy 375.476516 -197.631558)
			(xy 375.476576 -197.635831) (xy 375.477982 -197.64426) (xy 375.47931 -197.648322) (xy 375.482866 -197.657974)
			(xy 375.489216 -197.66534) (xy 375.506806 -197.686267) (xy 375.536439 -197.732206) (xy 375.559213 -197.781904)
			(xy 375.57466 -197.834343) (xy 375.582464 -197.88845) (xy 375.582942 -197.915784) (xy 375.582464 -197.943152)
			(xy 375.574629 -197.997323) (xy 375.55913 -198.049819) (xy 375.536288 -198.09956) (xy 375.50657 -198.145525)
			(xy 375.488962 -198.166482) (xy 375.482866 -198.173594) (xy 375.476516 -198.190358) (xy 375.476516 -198.266558)
			(xy 375.476576 -198.270831) (xy 375.477982 -198.27926) (xy 375.47931 -198.283322) (xy 375.482866 -198.292974)
			(xy 375.489216 -198.30034) (xy 375.506806 -198.321267) (xy 375.536439 -198.367206) (xy 375.559213 -198.416904)
			(xy 375.57466 -198.469343) (xy 375.582464 -198.52345) (xy 375.582942 -198.550784) (xy 375.582464 -198.578152)
			(xy 375.574629 -198.632323) (xy 375.55913 -198.684819) (xy 375.536288 -198.73456) (xy 375.50657 -198.780525)
			(xy 375.488962 -198.801482) (xy 375.482866 -198.808594) (xy 375.476516 -198.825358) (xy 375.476516 -198.901558)
			(xy 375.476576 -198.905831) (xy 375.477982 -198.91426) (xy 375.47931 -198.918322) (xy 375.482866 -198.927974)
			(xy 375.489216 -198.93534) (xy 375.506806 -198.956267) (xy 375.536439 -199.002206) (xy 375.559213 -199.051904)
			(xy 375.57466 -199.104343) (xy 375.582464 -199.15845) (xy 375.582942 -199.185784) (xy 375.582464 -199.213152)
			(xy 375.574629 -199.267323) (xy 375.55913 -199.319819) (xy 375.536288 -199.36956) (xy 375.50657 -199.415525)
			(xy 375.488962 -199.436482) (xy 375.482866 -199.443594) (xy 375.476516 -199.460358) (xy 375.476516 -199.536558)
			(xy 375.476576 -199.540831) (xy 375.477982 -199.54926) (xy 375.47931 -199.553322) (xy 375.482866 -199.562974)
			(xy 375.489216 -199.57034) (xy 375.506806 -199.591267) (xy 375.536439 -199.637206) (xy 375.559213 -199.686904)
			(xy 375.57466 -199.739343) (xy 375.582464 -199.79345) (xy 375.582942 -199.820784) (xy 375.582464 -199.848152)
			(xy 375.574629 -199.902323) (xy 375.55913 -199.954819) (xy 375.536288 -200.00456) (xy 375.50657 -200.050525)
			(xy 375.488962 -200.071482) (xy 375.482866 -200.078594) (xy 375.476516 -200.095358) (xy 375.476516 -200.171558)
			(xy 375.476576 -200.175831) (xy 375.477982 -200.18426) (xy 375.47931 -200.188322) (xy 375.482866 -200.197974)
			(xy 375.489216 -200.20534) (xy 375.506806 -200.226267) (xy 375.536439 -200.272206) (xy 375.559213 -200.321904)
			(xy 375.57466 -200.374343) (xy 375.582464 -200.42845) (xy 375.582942 -200.455784) (xy 375.582464 -200.483152)
			(xy 375.574629 -200.537323) (xy 375.55913 -200.589819) (xy 375.536288 -200.63956) (xy 375.50657 -200.685525)
			(xy 375.488962 -200.706482) (xy 375.482866 -200.713594) (xy 375.476516 -200.730358) (xy 375.476516 -200.806558)
			(xy 375.476576 -200.810831) (xy 375.477982 -200.81926) (xy 375.47931 -200.823322) (xy 375.482866 -200.832974)
			(xy 375.489216 -200.84034) (xy 375.506133 -200.860435) (xy 375.534859 -200.904412) (xy 375.557267 -200.95192)
			(xy 375.572931 -201.002058) (xy 375.581554 -201.053873) (xy 375.582688 -201.080116) (xy 375.582942 -201.089768)
			(xy 375.587006 -201.098912) (xy 375.589107 -201.103516) (xy 375.594859 -201.111842) (xy 375.598436 -201.115422)
			(xy 375.64949 -201.164444) (xy 375.656839 -201.170934) (xy 375.675001 -201.178269) (xy 375.684796 -201.178668)
			(xy 399.81251 -201.178668) (xy 399.822387 -201.178209) (xy 399.840685 -201.170764) (xy 399.84807 -201.16419)
			(xy 399.848324 -201.163936) (xy 410.695394 -190.316866) (xy 410.702789 -190.310011) (xy 410.721388 -190.302264)
			(xy 410.731462 -190.30188) (xy 413.005778 -190.30188) (xy 413.01565 -190.301409) (xy 413.033931 -190.293948)
			(xy 413.041338 -190.287402) (xy 413.041592 -190.287148) (xy 427.208442 -176.120298) (xy 427.20895 -176.11979)
			(xy 427.215539 -176.112411) (xy 427.223005 -176.094112) (xy 427.223428 -176.08423) (xy 427.223428 -144.520412)
			(xy 427.222894 -144.510423) (xy 427.215186 -144.491985) (xy 427.208442 -144.484598) (xy 415.130488 -132.406644)
			(xy 415.123144 -132.39983) (xy 415.104681 -132.392095) (xy 415.094674 -132.391658) (xy 407.116026 -132.391658)
			(xy 407.105783 -132.39213) (xy 407.086921 -132.400128) (xy 407.07945 -132.407152) (xy 407.021538 -132.467096)
			(xy 407.014172 -132.486146) (xy 407.014426 -132.49656) (xy 407.01468 -132.508752) (xy 407.014194 -132.536003)
			(xy 407.006438 -132.589951) (xy 406.991083 -132.642246) (xy 406.968441 -132.691823) (xy 406.938975 -132.737673)
			(xy 406.903284 -132.778864) (xy 406.862093 -132.814555) (xy 406.816243 -132.844021) (xy 406.766666 -132.866663)
			(xy 406.714371 -132.882018) (xy 406.660423 -132.889774) (xy 406.605921 -132.889774) (xy 406.551973 -132.882018)
			(xy 406.499678 -132.866663) (xy 406.450101 -132.844021) (xy 406.404251 -132.814555) (xy 406.36306 -132.778864)
			(xy 406.327369 -132.737673) (xy 406.297903 -132.691823) (xy 406.275261 -132.642246) (xy 406.259906 -132.589951)
			(xy 406.25215 -132.536003) (xy 406.251664 -132.508752) (xy 406.251918 -132.49656) (xy 406.252172 -132.486146)
			(xy 406.244806 -132.467096) (xy 406.186894 -132.407152) (xy 406.179444 -132.400094) (xy 406.16057 -132.392086)
			(xy 406.150318 -132.391658) (xy 392.801856 -132.391658) (xy 392.791791 -132.392091) (xy 392.773203 -132.399823)
			(xy 392.765788 -132.406644) (xy 391.445496 -133.726936) (xy 391.438651 -133.734302) (xy 391.430899 -133.752838)
			(xy 391.430893 -133.77293) (xy 391.438633 -133.791471) (xy 391.445496 -133.798818) (xy 391.5809 -133.9342)
			(xy 408.346656 -133.9342) (xy 408.347192 -133.905462) (xy 408.355813 -133.848635) (xy 408.372861 -133.793745)
			(xy 408.39795 -133.742033) (xy 408.430511 -133.69467) (xy 408.44978 -133.673342) (xy 408.456384 -133.66623)
			(xy 408.463496 -133.648704) (xy 408.463496 -133.559296) (xy 408.456384 -133.54177) (xy 408.44978 -133.534658)
			(xy 408.430516 -133.513325) (xy 408.397947 -133.465965) (xy 408.372853 -133.414255) (xy 408.355801 -133.359366)
			(xy 408.347177 -133.302539) (xy 408.346656 -133.2738) (xy 408.347178 -133.24655) (xy 408.354933 -133.192606)
			(xy 408.370287 -133.140314) (xy 408.392925 -133.090739) (xy 408.422388 -133.04489) (xy 408.458076 -133.003701)
			(xy 408.499262 -132.96801) (xy 408.545107 -132.938542) (xy 408.59468 -132.915899) (xy 408.646971 -132.900541)
			(xy 408.700914 -132.89278) (xy 408.728164 -132.892292) (xy 408.75701 -132.892836) (xy 408.814046 -132.901511)
			(xy 408.869122 -132.918685) (xy 408.92098 -132.943964) (xy 408.968436 -132.976772) (xy 408.989784 -132.996178)
			(xy 408.996896 -133.002782) (xy 409.01493 -133.009894) (xy 409.104084 -133.009894) (xy 409.122118 -133.002782)
			(xy 409.12923 -132.996178) (xy 409.150581 -132.976775) (xy 409.198042 -132.943978) (xy 409.2499 -132.9187)
			(xy 409.304973 -132.901518) (xy 409.362005 -132.892825) (xy 409.39085 -132.892292) (xy 409.418102 -132.892802)
			(xy 409.472051 -132.900552) (xy 409.524348 -132.915902) (xy 409.573928 -132.938538) (xy 409.619781 -132.968001)
			(xy 409.660974 -133.00369) (xy 409.696669 -133.044879) (xy 409.726138 -133.090728) (xy 409.748781 -133.140305)
			(xy 409.764137 -133.1926) (xy 409.771895 -133.246548) (xy 409.772358 -133.2738) (xy 409.771819 -133.302538)
			(xy 409.763198 -133.359364) (xy 409.74615 -133.414254) (xy 409.721063 -133.465966) (xy 409.688502 -133.51333)
			(xy 409.669234 -133.534658) (xy 409.66263 -133.54177) (xy 409.655518 -133.559296) (xy 409.655518 -133.648704)
			(xy 409.66263 -133.66623) (xy 409.669234 -133.673342) (xy 409.6885 -133.694673) (xy 409.721068 -133.742034)
			(xy 409.746162 -133.793744) (xy 409.763214 -133.848634) (xy 409.771837 -133.905461) (xy 409.772358 -133.9342)
			(xy 409.771945 -133.961455) (xy 409.764186 -134.01541) (xy 409.748828 -134.067712) (xy 409.726182 -134.117296)
			(xy 409.696709 -134.163151) (xy 409.66101 -134.204345) (xy 409.619811 -134.240039) (xy 409.573952 -134.269506)
			(xy 409.524365 -134.292145) (xy 409.472062 -134.307497) (xy 409.418105 -134.315248) (xy 409.39085 -134.315708)
			(xy 409.362004 -134.315156) (xy 409.304969 -134.306482) (xy 409.249893 -134.28931) (xy 409.198035 -134.264033)
			(xy 409.150579 -134.231228) (xy 409.12923 -134.211822) (xy 409.122118 -134.205218) (xy 409.104084 -134.198106)
			(xy 409.01493 -134.198106) (xy 408.996896 -134.205218) (xy 408.989784 -134.211822) (xy 408.968427 -134.231218)
			(xy 408.920968 -134.264017) (xy 408.869111 -134.289296) (xy 408.81404 -134.306479) (xy 408.757009 -134.315174)
			(xy 408.728164 -134.315708) (xy 408.700912 -134.315256) (xy 408.646963 -134.307494) (xy 408.594668 -134.292135)
			(xy 408.54509 -134.269489) (xy 408.49924 -134.240019) (xy 408.45805 -134.204324) (xy 408.422359 -134.163131)
			(xy 408.392893 -134.117278) (xy 408.370253 -134.067699) (xy 408.354898 -134.015402) (xy 408.347142 -133.961452)
			(xy 408.346656 -133.9342) (xy 391.5809 -133.9342) (xy 392.444134 -134.797292) (xy 393.769848 -134.797292)
			(xy 393.773919 -134.74167) (xy 393.786045 -134.687233) (xy 393.805968 -134.635142) (xy 393.833264 -134.586507)
			(xy 393.86735 -134.542364) (xy 393.907499 -134.503655) (xy 393.952857 -134.471204) (xy 394.002457 -134.445703)
			(xy 394.055241 -134.427696) (xy 394.110084 -134.417566) (xy 394.165818 -134.415529) (xy 394.221255 -134.421629)
			(xy 394.275212 -134.435735) (xy 394.326541 -134.457547) (xy 394.374147 -134.486601) (xy 394.417015 -134.522276)
			(xy 394.454232 -134.563813) (xy 394.485005 -134.610326) (xy 394.508677 -134.660823) (xy 394.524745 -134.71423)
			(xy 394.532865 -134.769406) (xy 394.533374 -134.797292) (xy 394.532865 -134.825178) (xy 394.524745 -134.880354)
			(xy 394.509386 -134.931404) (xy 407.260042 -134.931404) (xy 407.264113 -134.875782) (xy 407.276239 -134.821345)
			(xy 407.296162 -134.769254) (xy 407.323458 -134.720619) (xy 407.357544 -134.676476) (xy 407.397693 -134.637767)
			(xy 407.443051 -134.605316) (xy 407.492651 -134.579815) (xy 407.545435 -134.561808) (xy 407.600278 -134.551678)
			(xy 407.656012 -134.549641) (xy 407.711449 -134.555741) (xy 407.765406 -134.569847) (xy 407.816735 -134.591659)
			(xy 407.864341 -134.620713) (xy 407.907209 -134.656388) (xy 407.944426 -134.697925) (xy 407.975199 -134.744438)
			(xy 407.998871 -134.794935) (xy 408.014939 -134.848342) (xy 408.023059 -134.903518) (xy 408.023568 -134.931404)
			(xy 408.023059 -134.95929) (xy 408.014939 -135.014466) (xy 407.998871 -135.067873) (xy 407.992236 -135.082026)
			(xy 409.362908 -135.082026) (xy 409.366979 -135.026404) (xy 409.379105 -134.971967) (xy 409.399028 -134.919876)
			(xy 409.426324 -134.871241) (xy 409.46041 -134.827098) (xy 409.500559 -134.788389) (xy 409.545917 -134.755938)
			(xy 409.595517 -134.730437) (xy 409.648301 -134.71243) (xy 409.703144 -134.7023) (xy 409.758878 -134.700263)
			(xy 409.814315 -134.706363) (xy 409.868272 -134.720469) (xy 409.919601 -134.742281) (xy 409.967207 -134.771335)
			(xy 410.010075 -134.80701) (xy 410.047292 -134.848547) (xy 410.078065 -134.89506) (xy 410.101737 -134.945557)
			(xy 410.117805 -134.998964) (xy 410.125925 -135.05414) (xy 410.126434 -135.082026) (xy 410.125925 -135.109912)
			(xy 410.117805 -135.165088) (xy 410.101737 -135.218495) (xy 410.078065 -135.268992) (xy 410.047292 -135.315505)
			(xy 410.010075 -135.357042) (xy 409.967207 -135.392717) (xy 409.919601 -135.421771) (xy 409.868272 -135.443583)
			(xy 409.814315 -135.457689) (xy 409.758878 -135.463789) (xy 409.703144 -135.461752) (xy 409.648301 -135.451622)
			(xy 409.595517 -135.433615) (xy 409.545917 -135.408114) (xy 409.500559 -135.375663) (xy 409.46041 -135.336954)
			(xy 409.426324 -135.292811) (xy 409.399028 -135.244176) (xy 409.379105 -135.192085) (xy 409.366979 -135.137648)
			(xy 409.362908 -135.082026) (xy 407.992236 -135.082026) (xy 407.975199 -135.11837) (xy 407.944426 -135.164883)
			(xy 407.907209 -135.20642) (xy 407.864341 -135.242095) (xy 407.816735 -135.271149) (xy 407.765406 -135.292961)
			(xy 407.711449 -135.307067) (xy 407.656012 -135.313167) (xy 407.600278 -135.31113) (xy 407.545435 -135.301)
			(xy 407.492651 -135.282993) (xy 407.443051 -135.257492) (xy 407.397693 -135.225041) (xy 407.357544 -135.186332)
			(xy 407.323458 -135.142189) (xy 407.296162 -135.093554) (xy 407.276239 -135.041463) (xy 407.264113 -134.987026)
			(xy 407.260042 -134.931404) (xy 394.509386 -134.931404) (xy 394.508677 -134.933761) (xy 394.485005 -134.984258)
			(xy 394.454232 -135.030771) (xy 394.417015 -135.072308) (xy 394.374147 -135.107983) (xy 394.326541 -135.137037)
			(xy 394.275212 -135.158849) (xy 394.221255 -135.172955) (xy 394.165818 -135.179055) (xy 394.110084 -135.177018)
			(xy 394.055241 -135.166888) (xy 394.002457 -135.148881) (xy 393.952857 -135.12338) (xy 393.907499 -135.090929)
			(xy 393.86735 -135.05222) (xy 393.833264 -135.008077) (xy 393.805968 -134.959442) (xy 393.786045 -134.907351)
			(xy 393.773919 -134.852914) (xy 393.769848 -134.797292) (xy 392.444134 -134.797292) (xy 392.991594 -135.344662)
			(xy 393.012386 -135.366257) (xy 393.047599 -135.414769) (xy 393.074781 -135.468197) (xy 393.093262 -135.525222)
			(xy 393.102585 -135.584437) (xy 393.1031 -135.61441) (xy 393.1031 -135.66013) (xy 398.415254 -135.66013)
			(xy 398.419325 -135.604508) (xy 398.431451 -135.550071) (xy 398.451374 -135.49798) (xy 398.47867 -135.449345)
			(xy 398.512756 -135.405202) (xy 398.552905 -135.366493) (xy 398.598263 -135.334042) (xy 398.647863 -135.308541)
			(xy 398.700647 -135.290534) (xy 398.75549 -135.280404) (xy 398.811224 -135.278367) (xy 398.866661 -135.284467)
			(xy 398.920618 -135.298573) (xy 398.971947 -135.320385) (xy 399.019553 -135.349439) (xy 399.062421 -135.385114)
			(xy 399.099638 -135.426651) (xy 399.130411 -135.473164) (xy 399.154083 -135.523661) (xy 399.170151 -135.577068)
			(xy 399.178271 -135.632244) (xy 399.17878 -135.66013) (xy 399.178271 -135.688016) (xy 399.170151 -135.743192)
			(xy 399.154083 -135.796599) (xy 399.130411 -135.847096) (xy 399.099638 -135.893609) (xy 399.062421 -135.935146)
			(xy 399.019553 -135.970821) (xy 398.971947 -135.999875) (xy 398.920618 -136.021687) (xy 398.866661 -136.035793)
			(xy 398.811224 -136.041893) (xy 398.75549 -136.039856) (xy 398.700647 -136.029726) (xy 398.647863 -136.011719)
			(xy 398.598263 -135.986218) (xy 398.552905 -135.953767) (xy 398.512756 -135.915058) (xy 398.47867 -135.870915)
			(xy 398.451374 -135.82228) (xy 398.431451 -135.770189) (xy 398.419325 -135.715752) (xy 398.415254 -135.66013)
			(xy 393.1031 -135.66013) (xy 393.1031 -136.231376) (xy 405.077928 -136.231376) (xy 405.081999 -136.175754)
			(xy 405.094125 -136.121317) (xy 405.114048 -136.069226) (xy 405.141344 -136.020591) (xy 405.17543 -135.976448)
			(xy 405.215579 -135.937739) (xy 405.260937 -135.905288) (xy 405.310537 -135.879787) (xy 405.363321 -135.86178)
			(xy 405.418164 -135.85165) (xy 405.473898 -135.849613) (xy 405.529335 -135.855713) (xy 405.583292 -135.869819)
			(xy 405.634621 -135.891631) (xy 405.682227 -135.920685) (xy 405.725095 -135.95636) (xy 405.762312 -135.997897)
			(xy 405.793085 -136.04441) (xy 405.816757 -136.094907) (xy 405.832825 -136.148314) (xy 405.840945 -136.20349)
			(xy 405.841454 -136.231376) (xy 407.285696 -136.231376) (xy 407.289767 -136.175754) (xy 407.301893 -136.121317)
			(xy 407.321816 -136.069226) (xy 407.349112 -136.020591) (xy 407.383198 -135.976448) (xy 407.423347 -135.937739)
			(xy 407.468705 -135.905288) (xy 407.518305 -135.879787) (xy 407.571089 -135.86178) (xy 407.625932 -135.85165)
			(xy 407.681666 -135.849613) (xy 407.737103 -135.855713) (xy 407.79106 -135.869819) (xy 407.842389 -135.891631)
			(xy 407.889995 -135.920685) (xy 407.932863 -135.95636) (xy 407.97008 -135.997897) (xy 408.000853 -136.04441)
			(xy 408.024525 -136.094907) (xy 408.040593 -136.148314) (xy 408.048713 -136.20349) (xy 408.049222 -136.231376)
			(xy 408.048713 -136.259262) (xy 408.040593 -136.314438) (xy 408.024525 -136.367845) (xy 408.000853 -136.418342)
			(xy 407.97008 -136.464855) (xy 407.932863 -136.506392) (xy 407.889995 -136.542067) (xy 407.842389 -136.571121)
			(xy 407.79106 -136.592933) (xy 407.737103 -136.607039) (xy 407.681666 -136.613139) (xy 407.625932 -136.611102)
			(xy 407.571089 -136.600972) (xy 407.518305 -136.582965) (xy 407.468705 -136.557464) (xy 407.423347 -136.525013)
			(xy 407.383198 -136.486304) (xy 407.349112 -136.442161) (xy 407.321816 -136.393526) (xy 407.301893 -136.341435)
			(xy 407.289767 -136.286998) (xy 407.285696 -136.231376) (xy 405.841454 -136.231376) (xy 405.840945 -136.259262)
			(xy 405.832825 -136.314438) (xy 405.816757 -136.367845) (xy 405.793085 -136.418342) (xy 405.762312 -136.464855)
			(xy 405.725095 -136.506392) (xy 405.682227 -136.542067) (xy 405.634621 -136.571121) (xy 405.583292 -136.592933)
			(xy 405.529335 -136.607039) (xy 405.473898 -136.613139) (xy 405.418164 -136.611102) (xy 405.363321 -136.600972)
			(xy 405.310537 -136.582965) (xy 405.260937 -136.557464) (xy 405.215579 -136.525013) (xy 405.17543 -136.486304)
			(xy 405.141344 -136.442161) (xy 405.114048 -136.393526) (xy 405.094125 -136.341435) (xy 405.081999 -136.286998)
			(xy 405.077928 -136.231376) (xy 393.1031 -136.231376) (xy 393.1031 -137.456926) (xy 393.102614 -137.484159)
			(xy 393.094863 -137.538071) (xy 393.079518 -137.590331) (xy 393.056892 -137.639875) (xy 393.027445 -137.685695)
			(xy 392.991778 -137.726858) (xy 392.950615 -137.762525) (xy 392.904795 -137.791972) (xy 392.855251 -137.814598)
			(xy 392.802991 -137.829943) (xy 392.749079 -137.837694) (xy 392.694613 -137.837694) (xy 392.640701 -137.829943)
			(xy 392.588441 -137.814598) (xy 392.538897 -137.791972) (xy 392.493077 -137.762525) (xy 392.451914 -137.726858)
			(xy 392.416247 -137.685695) (xy 392.3868 -137.639875) (xy 392.364174 -137.590331) (xy 392.348829 -137.538071)
			(xy 392.341078 -137.484159) (xy 392.340592 -137.456926) (xy 392.340592 -135.79348) (xy 392.340165 -135.783412)
			(xy 392.332445 -135.764813) (xy 392.325606 -135.757412) (xy 390.870186 -134.302246) (xy 390.862842 -134.295433)
			(xy 390.844379 -134.287698) (xy 390.834372 -134.28726) (xy 363.027214 -134.28726) (xy 363.017152 -134.2877)
			(xy 362.998576 -134.295444) (xy 362.991146 -134.302246) (xy 362.470192 -134.8232) (xy 364.209582 -134.8232)
			(xy 364.213653 -134.767578) (xy 364.225779 -134.713141) (xy 364.245702 -134.66105) (xy 364.272998 -134.612415)
			(xy 364.307084 -134.568272) (xy 364.347233 -134.529563) (xy 364.392591 -134.497112) (xy 364.442191 -134.471611)
			(xy 364.494975 -134.453604) (xy 364.549818 -134.443474) (xy 364.605552 -134.441437) (xy 364.660989 -134.447537)
			(xy 364.714946 -134.461643) (xy 364.766275 -134.483455) (xy 364.813881 -134.512509) (xy 364.856749 -134.548184)
			(xy 364.893966 -134.589721) (xy 364.924739 -134.636234) (xy 364.948411 -134.686731) (xy 364.964479 -134.740138)
			(xy 364.97132 -134.786624) (xy 371.93931 -134.786624) (xy 371.943381 -134.731002) (xy 371.955507 -134.676565)
			(xy 371.97543 -134.624474) (xy 372.002726 -134.575839) (xy 372.036812 -134.531696) (xy 372.076961 -134.492987)
			(xy 372.122319 -134.460536) (xy 372.171919 -134.435035) (xy 372.224703 -134.417028) (xy 372.279546 -134.406898)
			(xy 372.33528 -134.404861) (xy 372.390717 -134.410961) (xy 372.444674 -134.425067) (xy 372.496003 -134.446879)
			(xy 372.543609 -134.475933) (xy 372.586477 -134.511608) (xy 372.623694 -134.553145) (xy 372.654467 -134.599658)
			(xy 372.678139 -134.650155) (xy 372.694207 -134.703562) (xy 372.702327 -134.758738) (xy 372.702836 -134.786624)
			(xy 374.33326 -134.786624) (xy 374.337331 -134.731002) (xy 374.349457 -134.676565) (xy 374.36938 -134.624474)
			(xy 374.396676 -134.575839) (xy 374.430762 -134.531696) (xy 374.470911 -134.492987) (xy 374.516269 -134.460536)
			(xy 374.565869 -134.435035) (xy 374.618653 -134.417028) (xy 374.673496 -134.406898) (xy 374.72923 -134.404861)
			(xy 374.784667 -134.410961) (xy 374.838624 -134.425067) (xy 374.889953 -134.446879) (xy 374.937559 -134.475933)
			(xy 374.980427 -134.511608) (xy 375.017644 -134.553145) (xy 375.048417 -134.599658) (xy 375.072089 -134.650155)
			(xy 375.088157 -134.703562) (xy 375.096277 -134.758738) (xy 375.096786 -134.786624) (xy 375.096277 -134.81451)
			(xy 375.088157 -134.869686) (xy 375.072089 -134.923093) (xy 375.048417 -134.97359) (xy 375.017644 -135.020103)
			(xy 374.980427 -135.06164) (xy 374.937559 -135.097315) (xy 374.889953 -135.126369) (xy 374.838624 -135.148181)
			(xy 374.784667 -135.162287) (xy 374.72923 -135.168387) (xy 374.673496 -135.16635) (xy 374.618653 -135.15622)
			(xy 374.565869 -135.138213) (xy 374.516269 -135.112712) (xy 374.470911 -135.080261) (xy 374.430762 -135.041552)
			(xy 374.396676 -134.997409) (xy 374.36938 -134.948774) (xy 374.349457 -134.896683) (xy 374.337331 -134.842246)
			(xy 374.33326 -134.786624) (xy 372.702836 -134.786624) (xy 372.702327 -134.81451) (xy 372.694207 -134.869686)
			(xy 372.678139 -134.923093) (xy 372.654467 -134.97359) (xy 372.623694 -135.020103) (xy 372.586477 -135.06164)
			(xy 372.543609 -135.097315) (xy 372.496003 -135.126369) (xy 372.444674 -135.148181) (xy 372.390717 -135.162287)
			(xy 372.33528 -135.168387) (xy 372.279546 -135.16635) (xy 372.224703 -135.15622) (xy 372.171919 -135.138213)
			(xy 372.122319 -135.112712) (xy 372.076961 -135.080261) (xy 372.036812 -135.041552) (xy 372.002726 -134.997409)
			(xy 371.97543 -134.948774) (xy 371.955507 -134.896683) (xy 371.943381 -134.842246) (xy 371.93931 -134.786624)
			(xy 364.97132 -134.786624) (xy 364.972599 -134.795314) (xy 364.973108 -134.8232) (xy 364.972599 -134.851086)
			(xy 364.964479 -134.906262) (xy 364.948411 -134.959669) (xy 364.924739 -135.010166) (xy 364.893966 -135.056679)
			(xy 364.856749 -135.098216) (xy 364.813881 -135.133891) (xy 364.766275 -135.162945) (xy 364.714946 -135.184757)
			(xy 364.660989 -135.198863) (xy 364.605552 -135.204963) (xy 364.549818 -135.202926) (xy 364.494975 -135.192796)
			(xy 364.442191 -135.174789) (xy 364.392591 -135.149288) (xy 364.347233 -135.116837) (xy 364.307084 -135.078128)
			(xy 364.272998 -135.033985) (xy 364.245702 -134.98535) (xy 364.225779 -134.933259) (xy 364.213653 -134.878822)
			(xy 364.209582 -134.8232) (xy 362.470192 -134.8232) (xy 361.809792 -135.4836) (xy 363.193582 -135.4836)
			(xy 363.197653 -135.427978) (xy 363.209779 -135.373541) (xy 363.229702 -135.32145) (xy 363.256998 -135.272815)
			(xy 363.291084 -135.228672) (xy 363.331233 -135.189963) (xy 363.376591 -135.157512) (xy 363.426191 -135.132011)
			(xy 363.478975 -135.114004) (xy 363.533818 -135.103874) (xy 363.589552 -135.101837) (xy 363.644989 -135.107937)
			(xy 363.698946 -135.122043) (xy 363.750275 -135.143855) (xy 363.797881 -135.172909) (xy 363.840749 -135.208584)
			(xy 363.877966 -135.250121) (xy 363.908739 -135.296634) (xy 363.932411 -135.347131) (xy 363.948479 -135.400538)
			(xy 363.956599 -135.455714) (xy 363.957108 -135.4836) (xy 363.956599 -135.511486) (xy 363.948479 -135.566662)
			(xy 363.932411 -135.620069) (xy 363.908739 -135.670566) (xy 363.877966 -135.717079) (xy 363.840749 -135.758616)
			(xy 363.797881 -135.794291) (xy 363.750275 -135.823345) (xy 363.698946 -135.845157) (xy 363.644989 -135.859263)
			(xy 363.589552 -135.865363) (xy 363.533818 -135.863326) (xy 363.478975 -135.853196) (xy 363.426191 -135.835189)
			(xy 363.376591 -135.809688) (xy 363.331233 -135.777237) (xy 363.291084 -135.738528) (xy 363.256998 -135.694385)
			(xy 363.229702 -135.64575) (xy 363.209779 -135.593659) (xy 363.197653 -135.539222) (xy 363.193582 -135.4836)
			(xy 361.809792 -135.4836) (xy 361.098592 -136.1948) (xy 364.209582 -136.1948) (xy 364.213653 -136.139178)
			(xy 364.225779 -136.084741) (xy 364.245702 -136.03265) (xy 364.272998 -135.984015) (xy 364.307084 -135.939872)
			(xy 364.347233 -135.901163) (xy 364.392591 -135.868712) (xy 364.442191 -135.843211) (xy 364.494975 -135.825204)
			(xy 364.549818 -135.815074) (xy 364.605552 -135.813037) (xy 364.660989 -135.819137) (xy 364.714946 -135.833243)
			(xy 364.766275 -135.855055) (xy 364.813881 -135.884109) (xy 364.856749 -135.919784) (xy 364.893966 -135.961321)
			(xy 364.924739 -136.007834) (xy 364.948411 -136.058331) (xy 364.964479 -136.111738) (xy 364.972599 -136.166914)
			(xy 364.973108 -136.1948) (xy 364.972599 -136.222686) (xy 364.964479 -136.277862) (xy 364.948411 -136.331269)
			(xy 364.924739 -136.381766) (xy 364.893966 -136.428279) (xy 364.856749 -136.469816) (xy 364.813881 -136.505491)
			(xy 364.766275 -136.534545) (xy 364.714946 -136.556357) (xy 364.660989 -136.570463) (xy 364.605552 -136.576563)
			(xy 364.549818 -136.574526) (xy 364.494975 -136.564396) (xy 364.442191 -136.546389) (xy 364.392591 -136.520888)
			(xy 364.347233 -136.488437) (xy 364.307084 -136.449728) (xy 364.272998 -136.405585) (xy 364.245702 -136.35695)
			(xy 364.225779 -136.304859) (xy 364.213653 -136.250422) (xy 364.209582 -136.1948) (xy 361.098592 -136.1948)
			(xy 360.438192 -136.8552) (xy 363.168182 -136.8552) (xy 363.172253 -136.799578) (xy 363.184379 -136.745141)
			(xy 363.204302 -136.69305) (xy 363.231598 -136.644415) (xy 363.265684 -136.600272) (xy 363.305833 -136.561563)
			(xy 363.351191 -136.529112) (xy 363.400791 -136.503611) (xy 363.453575 -136.485604) (xy 363.508418 -136.475474)
			(xy 363.564152 -136.473437) (xy 363.619589 -136.479537) (xy 363.673546 -136.493643) (xy 363.724875 -136.515455)
			(xy 363.772481 -136.544509) (xy 363.815349 -136.580184) (xy 363.852566 -136.621721) (xy 363.883339 -136.668234)
			(xy 363.907011 -136.718731) (xy 363.923079 -136.772138) (xy 363.931199 -136.827314) (xy 363.931708 -136.8552)
			(xy 363.931199 -136.883086) (xy 363.923079 -136.938262) (xy 363.907011 -136.991669) (xy 363.883339 -137.042166)
			(xy 363.852566 -137.088679) (xy 363.815349 -137.130216) (xy 363.772481 -137.165891) (xy 363.724875 -137.194945)
			(xy 363.673546 -137.216757) (xy 363.619589 -137.230863) (xy 363.564152 -137.236963) (xy 363.508418 -137.234926)
			(xy 363.453575 -137.224796) (xy 363.400791 -137.206789) (xy 363.351191 -137.181288) (xy 363.305833 -137.148837)
			(xy 363.265684 -137.110128) (xy 363.231598 -137.065985) (xy 363.204302 -137.01735) (xy 363.184379 -136.965259)
			(xy 363.172253 -136.910822) (xy 363.168182 -136.8552) (xy 360.438192 -136.8552) (xy 358.530652 -138.76274)
			(xy 358.523254 -138.769585) (xy 358.504655 -138.777312) (xy 358.494584 -138.777726) (xy 343.396316 -138.777726)
			(xy 343.386253 -138.778165) (xy 343.367673 -138.785904) (xy 343.360248 -138.792712) (xy 340.197186 -141.955774)
			(xy 340.18982 -141.962886) (xy 340.1822 -141.981682) (xy 340.1822 -147.904962) (xy 344.785959 -147.904962)
			(xy 344.789955 -147.743437) (xy 344.801934 -147.582308) (xy 344.821868 -147.421968) (xy 344.849706 -147.26281)
			(xy 344.885381 -147.105224) (xy 344.928806 -146.949595) (xy 344.979874 -146.796304) (xy 345.038461 -146.645725)
			(xy 345.104422 -146.498229) (xy 345.177597 -146.354175) (xy 345.257807 -146.213915) (xy 345.344854 -146.077795)
			(xy 345.438527 -145.946145) (xy 345.538596 -145.819289) (xy 345.644816 -145.697537) (xy 345.756927 -145.581187)
			(xy 345.874654 -145.470524) (xy 345.997711 -145.365818) (xy 346.125794 -145.267326) (xy 346.258592 -145.175289)
			(xy 346.395779 -145.089931) (xy 346.53702 -145.011463) (xy 346.681968 -144.940075) (xy 346.830269 -144.875943)
			(xy 346.981561 -144.819223) (xy 347.135472 -144.770055) (xy 347.291626 -144.728558) (xy 347.449642 -144.694835)
			(xy 347.609132 -144.668967) (xy 347.769706 -144.651018) (xy 347.930971 -144.641033) (xy 348.092533 -144.639034)
			(xy 348.253995 -144.645028) (xy 348.414964 -144.659) (xy 348.575045 -144.680915) (xy 348.733847 -144.710719)
			(xy 348.89098 -144.748341) (xy 349.04606 -144.793687) (xy 349.198708 -144.846647) (xy 349.34855 -144.907092)
			(xy 349.49522 -144.974872) (xy 349.638358 -145.049823) (xy 349.777614 -145.131761) (xy 349.912648 -145.220486)
			(xy 350.043129 -145.31578) (xy 350.168737 -145.41741) (xy 350.289166 -145.525128) (xy 350.40412 -145.638669)
			(xy 350.513319 -145.757756) (xy 350.616495 -145.882098) (xy 350.713396 -146.01139) (xy 350.803783 -146.145317)
			(xy 350.887438 -146.283549) (xy 350.964153 -146.425749) (xy 351.033743 -146.571569) (xy 351.096036 -146.720652)
			(xy 351.15088 -146.872633) (xy 351.198141 -147.027141) (xy 351.237703 -147.183797) (xy 351.269469 -147.342217)
			(xy 351.293362 -147.502015) (xy 351.309324 -147.662799) (xy 351.317314 -147.824175) (xy 351.317814 -147.904962)
			(xy 351.317314 -147.985749) (xy 351.309324 -148.147125) (xy 351.293362 -148.307909) (xy 351.269469 -148.467707)
			(xy 351.237703 -148.626127) (xy 351.198141 -148.782783) (xy 351.15088 -148.937291) (xy 351.096036 -149.089272)
			(xy 351.033743 -149.238355) (xy 350.964153 -149.384175) (xy 350.887438 -149.526375) (xy 350.803783 -149.664607)
			(xy 350.713396 -149.798534) (xy 350.616495 -149.927826) (xy 350.513319 -150.052168) (xy 350.40412 -150.171255)
			(xy 350.289166 -150.284796) (xy 350.168737 -150.392514) (xy 350.043129 -150.494144) (xy 349.912648 -150.589438)
			(xy 349.777614 -150.678163) (xy 349.638358 -150.760101) (xy 349.49522 -150.835052) (xy 349.34855 -150.902832)
			(xy 349.198708 -150.963277) (xy 349.04606 -151.016237) (xy 348.89098 -151.061583) (xy 348.733847 -151.099205)
			(xy 348.575045 -151.129009) (xy 348.414964 -151.150924) (xy 348.253995 -151.164896) (xy 348.092533 -151.17089)
			(xy 347.930971 -151.168891) (xy 347.769706 -151.158906) (xy 347.609132 -151.140957) (xy 347.449642 -151.115089)
			(xy 347.291626 -151.081366) (xy 347.135472 -151.039869) (xy 346.981561 -150.990701) (xy 346.830269 -150.933981)
			(xy 346.681968 -150.869849) (xy 346.53702 -150.798461) (xy 346.395779 -150.719993) (xy 346.258592 -150.634635)
			(xy 346.125794 -150.542598) (xy 345.997711 -150.444106) (xy 345.874654 -150.3394) (xy 345.756927 -150.228737)
			(xy 345.644816 -150.112387) (xy 345.538596 -149.990635) (xy 345.438527 -149.863779) (xy 345.344854 -149.732129)
			(xy 345.257807 -149.596009) (xy 345.177597 -149.455749) (xy 345.104422 -149.311695) (xy 345.038461 -149.164199)
			(xy 344.979874 -149.01362) (xy 344.928806 -148.860329) (xy 344.885381 -148.7047) (xy 344.849706 -148.547114)
			(xy 344.821868 -148.387956) (xy 344.801934 -148.227616) (xy 344.789955 -148.066487) (xy 344.785959 -147.904962)
			(xy 340.1822 -147.904962) (xy 340.1822 -155.858718) (xy 340.181773 -155.868787) (xy 340.174054 -155.887386)
			(xy 340.167214 -155.894786) (xy 339.262466 -156.799534) (xy 347.421454 -156.799534) (xy 347.42201 -156.772285)
			(xy 347.429761 -156.718342) (xy 347.44511 -156.666051) (xy 347.467744 -156.616477) (xy 347.497203 -156.570628)
			(xy 347.532887 -156.529438) (xy 347.57407 -156.493746) (xy 347.619913 -156.464278) (xy 347.669484 -156.441635)
			(xy 347.721772 -156.426276) (xy 347.775713 -156.418515) (xy 347.802962 -156.418026) (xy 347.828906 -156.418448)
			(xy 347.880313 -156.425498) (xy 347.930287 -156.43946) (xy 347.977904 -156.460076) (xy 348.00032 -156.473144)
			(xy 348.015306 -156.482288) (xy 348.04985 -156.47797) (xy 368.131852 -136.395968) (xy 368.146383 -136.382217)
			(xy 368.179666 -136.360036) (xy 368.216635 -136.34477) (xy 368.255871 -136.337005) (xy 368.27587 -136.336532)
			(xy 372.614698 -136.336532) (xy 372.624769 -136.336123) (xy 372.643368 -136.328393) (xy 372.650766 -136.321546)
			(xy 373.381524 -135.590534) (xy 373.396 -135.5767) (xy 373.429276 -135.554442) (xy 373.466259 -135.539111)
			(xy 373.505525 -135.5313) (xy 373.525542 -135.530844) (xy 376.770392 -135.530844) (xy 376.790404 -135.531356)
			(xy 376.829656 -135.539176) (xy 376.866631 -135.554497) (xy 376.899911 -135.576732) (xy 376.91441 -135.590534)
			(xy 378.424027 -137.100151) (xy 378.717556 -137.100151) (xy 378.717556 -137.045649) (xy 378.725312 -136.991702)
			(xy 378.740665 -136.939408) (xy 378.763305 -136.889831) (xy 378.792768 -136.84398) (xy 378.828457 -136.802788)
			(xy 378.869645 -136.767095) (xy 378.915492 -136.737626) (xy 378.965067 -136.714981) (xy 379.017359 -136.699621)
			(xy 379.071305 -136.691859) (xy 379.098556 -136.69137) (xy 379.113476 -136.691493) (xy 379.143229 -136.69378)
			(xy 379.157992 -136.695942) (xy 379.170184 -136.697974) (xy 379.193044 -136.690608) (xy 380.172468 -135.71093)
			(xy 380.186924 -135.697075) (xy 380.220208 -135.67482) (xy 380.257197 -135.659496) (xy 380.296467 -135.651692)
			(xy 380.316486 -135.65124) (xy 387.563614 -135.65124) (xy 387.583626 -135.65174) (xy 387.622879 -135.659564)
			(xy 387.659854 -135.674889) (xy 387.693133 -135.697127) (xy 387.707632 -135.71093) (xy 390.074404 -138.077702)
			(xy 390.700004 -138.077702) (xy 390.704075 -138.02208) (xy 390.716201 -137.967643) (xy 390.736124 -137.915552)
			(xy 390.76342 -137.866917) (xy 390.797506 -137.822774) (xy 390.837655 -137.784065) (xy 390.883013 -137.751614)
			(xy 390.932613 -137.726113) (xy 390.985397 -137.708106) (xy 391.04024 -137.697976) (xy 391.095974 -137.695939)
			(xy 391.151411 -137.702039) (xy 391.205368 -137.716145) (xy 391.256697 -137.737957) (xy 391.304303 -137.767011)
			(xy 391.347171 -137.802686) (xy 391.384388 -137.844223) (xy 391.415161 -137.890736) (xy 391.438833 -137.941233)
			(xy 391.454901 -137.99464) (xy 391.457331 -138.011154) (xy 399.242786 -138.011154) (xy 399.246857 -137.955532)
			(xy 399.258983 -137.901095) (xy 399.278906 -137.849004) (xy 399.306202 -137.800369) (xy 399.340288 -137.756226)
			(xy 399.380437 -137.717517) (xy 399.425795 -137.685066) (xy 399.475395 -137.659565) (xy 399.528179 -137.641558)
			(xy 399.583022 -137.631428) (xy 399.638756 -137.629391) (xy 399.694193 -137.635491) (xy 399.74815 -137.649597)
			(xy 399.799479 -137.671409) (xy 399.847085 -137.700463) (xy 399.889953 -137.736138) (xy 399.92717 -137.777675)
			(xy 399.957943 -137.824188) (xy 399.981615 -137.874685) (xy 399.982095 -137.87628) (xy 410.808168 -137.87628)
			(xy 410.812239 -137.820658) (xy 410.824365 -137.766221) (xy 410.844288 -137.71413) (xy 410.871584 -137.665495)
			(xy 410.90567 -137.621352) (xy 410.945819 -137.582643) (xy 410.991177 -137.550192) (xy 411.040777 -137.524691)
			(xy 411.093561 -137.506684) (xy 411.148404 -137.496554) (xy 411.204138 -137.494517) (xy 411.259575 -137.500617)
			(xy 411.313532 -137.514723) (xy 411.364861 -137.536535) (xy 411.412467 -137.565589) (xy 411.455335 -137.601264)
			(xy 411.492552 -137.642801) (xy 411.523325 -137.689314) (xy 411.546997 -137.739811) (xy 411.563065 -137.793218)
			(xy 411.571185 -137.848394) (xy 411.571694 -137.87628) (xy 411.571185 -137.904166) (xy 411.563065 -137.959342)
			(xy 411.546997 -138.012749) (xy 411.523325 -138.063246) (xy 411.492552 -138.109759) (xy 411.455335 -138.151296)
			(xy 411.412467 -138.186971) (xy 411.364861 -138.216025) (xy 411.313532 -138.237837) (xy 411.259575 -138.251943)
			(xy 411.204138 -138.258043) (xy 411.148404 -138.256006) (xy 411.093561 -138.245876) (xy 411.040777 -138.227869)
			(xy 410.991177 -138.202368) (xy 410.945819 -138.169917) (xy 410.90567 -138.131208) (xy 410.871584 -138.087065)
			(xy 410.844288 -138.03843) (xy 410.824365 -137.986339) (xy 410.812239 -137.931902) (xy 410.808168 -137.87628)
			(xy 399.982095 -137.87628) (xy 399.997683 -137.928092) (xy 400.005803 -137.983268) (xy 400.006312 -138.011154)
			(xy 400.005803 -138.03904) (xy 399.997683 -138.094216) (xy 399.981615 -138.147623) (xy 399.957943 -138.19812)
			(xy 399.92717 -138.244633) (xy 399.889953 -138.28617) (xy 399.847085 -138.321845) (xy 399.799479 -138.350899)
			(xy 399.74815 -138.372711) (xy 399.694193 -138.386817) (xy 399.638756 -138.392917) (xy 399.583022 -138.39088)
			(xy 399.528179 -138.38075) (xy 399.475395 -138.362743) (xy 399.425795 -138.337242) (xy 399.380437 -138.304791)
			(xy 399.340288 -138.266082) (xy 399.306202 -138.221939) (xy 399.278906 -138.173304) (xy 399.258983 -138.121213)
			(xy 399.246857 -138.066776) (xy 399.242786 -138.011154) (xy 391.457331 -138.011154) (xy 391.463021 -138.049816)
			(xy 391.46353 -138.077702) (xy 391.463021 -138.105588) (xy 391.454901 -138.160764) (xy 391.438833 -138.214171)
			(xy 391.415161 -138.264668) (xy 391.384388 -138.311181) (xy 391.347171 -138.352718) (xy 391.304303 -138.388393)
			(xy 391.256697 -138.417447) (xy 391.205368 -138.439259) (xy 391.151411 -138.453365) (xy 391.095974 -138.459465)
			(xy 391.04024 -138.457428) (xy 390.985397 -138.447298) (xy 390.932613 -138.429291) (xy 390.883013 -138.40379)
			(xy 390.837655 -138.371339) (xy 390.797506 -138.33263) (xy 390.76342 -138.288487) (xy 390.736124 -138.239852)
			(xy 390.716201 -138.187761) (xy 390.704075 -138.133324) (xy 390.700004 -138.077702) (xy 390.074404 -138.077702)
			(xy 390.613646 -138.616944) (xy 390.627486 -138.631414) (xy 390.649744 -138.664692) (xy 390.665073 -138.701677)
			(xy 390.672882 -138.740944) (xy 390.673336 -138.760962) (xy 390.673336 -138.936984) (xy 399.28368 -138.936984)
			(xy 399.287751 -138.881362) (xy 399.299877 -138.826925) (xy 399.3198 -138.774834) (xy 399.347096 -138.726199)
			(xy 399.381182 -138.682056) (xy 399.421331 -138.643347) (xy 399.466689 -138.610896) (xy 399.516289 -138.585395)
			(xy 399.569073 -138.567388) (xy 399.623916 -138.557258) (xy 399.67965 -138.555221) (xy 399.735087 -138.561321)
			(xy 399.789044 -138.575427) (xy 399.840373 -138.597239) (xy 399.887979 -138.626293) (xy 399.930847 -138.661968)
			(xy 399.968064 -138.703505) (xy 399.998837 -138.750018) (xy 400.022509 -138.800515) (xy 400.038577 -138.853922)
			(xy 400.046697 -138.909098) (xy 400.047206 -138.936984) (xy 400.046697 -138.96487) (xy 400.038577 -139.020046)
			(xy 400.022509 -139.073453) (xy 399.998837 -139.12395) (xy 399.968064 -139.170463) (xy 399.930847 -139.212)
			(xy 399.887979 -139.247675) (xy 399.840373 -139.276729) (xy 399.789044 -139.298541) (xy 399.735087 -139.312647)
			(xy 399.67965 -139.318747) (xy 399.623916 -139.31671) (xy 399.569073 -139.30658) (xy 399.516289 -139.288573)
			(xy 399.466689 -139.263072) (xy 399.421331 -139.230621) (xy 399.381182 -139.191912) (xy 399.347096 -139.147769)
			(xy 399.3198 -139.099134) (xy 399.299877 -139.047043) (xy 399.287751 -138.992606) (xy 399.28368 -138.936984)
			(xy 390.673336 -138.936984) (xy 390.673336 -139.47267) (xy 410.103318 -139.47267) (xy 410.107389 -139.417048)
			(xy 410.119515 -139.362611) (xy 410.139438 -139.31052) (xy 410.166734 -139.261885) (xy 410.20082 -139.217742)
			(xy 410.240969 -139.179033) (xy 410.286327 -139.146582) (xy 410.335927 -139.121081) (xy 410.388711 -139.103074)
			(xy 410.443554 -139.092944) (xy 410.499288 -139.090907) (xy 410.554725 -139.097007) (xy 410.608682 -139.111113)
			(xy 410.660011 -139.132925) (xy 410.707617 -139.161979) (xy 410.750485 -139.197654) (xy 410.787702 -139.239191)
			(xy 410.818475 -139.285704) (xy 410.842147 -139.336201) (xy 410.858215 -139.389608) (xy 410.866335 -139.444784)
			(xy 410.866844 -139.47267) (xy 410.866335 -139.500556) (xy 410.858215 -139.555732) (xy 410.842147 -139.609139)
			(xy 410.818475 -139.659636) (xy 410.787702 -139.706149) (xy 410.750485 -139.747686) (xy 410.707617 -139.783361)
			(xy 410.660011 -139.812415) (xy 410.608682 -139.834227) (xy 410.554725 -139.848333) (xy 410.499288 -139.854433)
			(xy 410.443554 -139.852396) (xy 410.388711 -139.842266) (xy 410.335927 -139.824259) (xy 410.286327 -139.798758)
			(xy 410.240969 -139.766307) (xy 410.20082 -139.727598) (xy 410.166734 -139.683455) (xy 410.139438 -139.63482)
			(xy 410.119515 -139.582729) (xy 410.107389 -139.528292) (xy 410.103318 -139.47267) (xy 390.673336 -139.47267)
			(xy 390.673336 -141.316456) (xy 410.132274 -141.316456) (xy 410.136345 -141.260834) (xy 410.148471 -141.206397)
			(xy 410.168394 -141.154306) (xy 410.19569 -141.105671) (xy 410.229776 -141.061528) (xy 410.269925 -141.022819)
			(xy 410.315283 -140.990368) (xy 410.364883 -140.964867) (xy 410.417667 -140.94686) (xy 410.47251 -140.93673)
			(xy 410.528244 -140.934693) (xy 410.583681 -140.940793) (xy 410.637638 -140.954899) (xy 410.688967 -140.976711)
			(xy 410.736573 -141.005765) (xy 410.779441 -141.04144) (xy 410.816658 -141.082977) (xy 410.847431 -141.12949)
			(xy 410.871103 -141.179987) (xy 410.887171 -141.233394) (xy 410.895291 -141.28857) (xy 410.8958 -141.316456)
			(xy 410.895291 -141.344342) (xy 410.887171 -141.399518) (xy 410.871103 -141.452925) (xy 410.847431 -141.503422)
			(xy 410.816658 -141.549935) (xy 410.779441 -141.591472) (xy 410.736573 -141.627147) (xy 410.688967 -141.656201)
			(xy 410.637638 -141.678013) (xy 410.583681 -141.692119) (xy 410.528244 -141.698219) (xy 410.47251 -141.696182)
			(xy 410.417667 -141.686052) (xy 410.364883 -141.668045) (xy 410.315283 -141.642544) (xy 410.269925 -141.610093)
			(xy 410.229776 -141.571384) (xy 410.19569 -141.527241) (xy 410.168394 -141.478606) (xy 410.148471 -141.426515)
			(xy 410.136345 -141.372078) (xy 410.132274 -141.316456) (xy 390.673336 -141.316456) (xy 390.673336 -141.59865)
			(xy 390.67375 -141.608235) (xy 390.680771 -141.626074) (xy 390.693824 -141.640114) (xy 390.702292 -141.644624)
			(xy 390.798812 -141.69009) (xy 390.827768 -141.686534) (xy 390.839452 -141.677136) (xy 390.860014 -141.660726)
			(xy 390.904819 -141.633156) (xy 390.952989 -141.612008) (xy 391.003609 -141.597684) (xy 391.055718 -141.590454)
			(xy 391.082022 -141.590014) (xy 391.109274 -141.590457) (xy 391.163222 -141.598217) (xy 391.215517 -141.613575)
			(xy 391.265095 -141.636218) (xy 391.310945 -141.665687) (xy 391.352135 -141.701381) (xy 391.387826 -141.742573)
			(xy 391.417292 -141.788425) (xy 391.439933 -141.838003) (xy 391.455288 -141.890299) (xy 391.463044 -141.944248)
			(xy 391.463044 -141.998752) (xy 391.455288 -142.052701) (xy 391.439933 -142.104997) (xy 391.417292 -142.154575)
			(xy 391.387826 -142.200427) (xy 391.352135 -142.241619) (xy 391.310945 -142.277313) (xy 391.265095 -142.306782)
			(xy 391.215517 -142.329425) (xy 391.163222 -142.344783) (xy 391.109274 -142.352543) (xy 391.082022 -142.35303)
			(xy 391.055719 -142.35258) (xy 391.003612 -142.34535) (xy 390.952994 -142.331024) (xy 390.904827 -142.309874)
			(xy 390.860026 -142.282302) (xy 390.839452 -142.265908) (xy 390.827768 -142.25651) (xy 390.798812 -142.252954)
			(xy 390.702292 -142.29842) (xy 390.693777 -142.302875) (xy 390.680662 -142.316901) (xy 390.673682 -142.33479)
			(xy 390.673336 -142.344394) (xy 390.673336 -142.751048) (xy 392.29868 -142.751048) (xy 392.302751 -142.695426)
			(xy 392.314877 -142.640989) (xy 392.3348 -142.588898) (xy 392.362096 -142.540263) (xy 392.396182 -142.49612)
			(xy 392.436331 -142.457411) (xy 392.481689 -142.42496) (xy 392.531289 -142.399459) (xy 392.584073 -142.381452)
			(xy 392.638916 -142.371322) (xy 392.69465 -142.369285) (xy 392.750087 -142.375385) (xy 392.804044 -142.389491)
			(xy 392.855373 -142.411303) (xy 392.902979 -142.440357) (xy 392.945847 -142.476032) (xy 392.983064 -142.517569)
			(xy 393.009986 -142.558262) (xy 415.08502 -142.558262) (xy 415.089091 -142.50264) (xy 415.101217 -142.448203)
			(xy 415.12114 -142.396112) (xy 415.148436 -142.347477) (xy 415.182522 -142.303334) (xy 415.222671 -142.264625)
			(xy 415.268029 -142.232174) (xy 415.317629 -142.206673) (xy 415.370413 -142.188666) (xy 415.425256 -142.178536)
			(xy 415.48099 -142.176499) (xy 415.536427 -142.182599) (xy 415.590384 -142.196705) (xy 415.641713 -142.218517)
			(xy 415.689319 -142.247571) (xy 415.732187 -142.283246) (xy 415.769404 -142.324783) (xy 415.800177 -142.371296)
			(xy 415.823849 -142.421793) (xy 415.839917 -142.4752) (xy 415.848037 -142.530376) (xy 415.848546 -142.558262)
			(xy 415.848037 -142.586148) (xy 415.839917 -142.641324) (xy 415.823849 -142.694731) (xy 415.800177 -142.745228)
			(xy 415.769404 -142.791741) (xy 415.732187 -142.833278) (xy 415.689319 -142.868953) (xy 415.641713 -142.898007)
			(xy 415.590384 -142.919819) (xy 415.536427 -142.933925) (xy 415.48099 -142.940025) (xy 415.425256 -142.937988)
			(xy 415.370413 -142.927858) (xy 415.317629 -142.909851) (xy 415.268029 -142.88435) (xy 415.222671 -142.851899)
			(xy 415.182522 -142.81319) (xy 415.148436 -142.769047) (xy 415.12114 -142.720412) (xy 415.101217 -142.668321)
			(xy 415.089091 -142.613884) (xy 415.08502 -142.558262) (xy 393.009986 -142.558262) (xy 393.013837 -142.564082)
			(xy 393.037509 -142.614579) (xy 393.053577 -142.667986) (xy 393.061697 -142.723162) (xy 393.062206 -142.751048)
			(xy 393.061697 -142.778934) (xy 393.053577 -142.83411) (xy 393.037509 -142.887517) (xy 393.013837 -142.938014)
			(xy 392.983064 -142.984527) (xy 392.945847 -143.026064) (xy 392.902979 -143.061739) (xy 392.855373 -143.090793)
			(xy 392.804044 -143.112605) (xy 392.750087 -143.126711) (xy 392.69465 -143.132811) (xy 392.638916 -143.130774)
			(xy 392.584073 -143.120644) (xy 392.531289 -143.102637) (xy 392.481689 -143.077136) (xy 392.436331 -143.044685)
			(xy 392.396182 -143.005976) (xy 392.362096 -142.961833) (xy 392.3348 -142.913198) (xy 392.314877 -142.861107)
			(xy 392.302751 -142.80667) (xy 392.29868 -142.751048) (xy 390.673336 -142.751048) (xy 390.673336 -143.926052)
			(xy 390.673695 -143.936099) (xy 390.681291 -143.954695) (xy 390.688068 -143.96212) (xy 392.527768 -145.801588)
			(xy 399.016726 -145.801588) (xy 399.020797 -145.745966) (xy 399.032923 -145.691529) (xy 399.052846 -145.639438)
			(xy 399.080142 -145.590803) (xy 399.114228 -145.54666) (xy 399.154377 -145.507951) (xy 399.199735 -145.4755)
			(xy 399.249335 -145.449999) (xy 399.302119 -145.431992) (xy 399.356962 -145.421862) (xy 399.412696 -145.419825)
			(xy 399.468133 -145.425925) (xy 399.52209 -145.440031) (xy 399.573419 -145.461843) (xy 399.621025 -145.490897)
			(xy 399.663893 -145.526572) (xy 399.70111 -145.568109) (xy 399.731883 -145.614622) (xy 399.755555 -145.665119)
			(xy 399.771623 -145.718526) (xy 399.779743 -145.773702) (xy 399.780252 -145.801588) (xy 399.779743 -145.829474)
			(xy 399.771623 -145.88465) (xy 399.755555 -145.938057) (xy 399.731883 -145.988554) (xy 399.70111 -146.035067)
			(xy 399.663893 -146.076604) (xy 399.621025 -146.112279) (xy 399.573419 -146.141333) (xy 399.52209 -146.163145)
			(xy 399.468133 -146.177251) (xy 399.412696 -146.183351) (xy 399.356962 -146.181314) (xy 399.302119 -146.171184)
			(xy 399.249335 -146.153177) (xy 399.199735 -146.127676) (xy 399.154377 -146.095225) (xy 399.114228 -146.056516)
			(xy 399.080142 -146.012373) (xy 399.052846 -145.963738) (xy 399.032923 -145.911647) (xy 399.020797 -145.85721)
			(xy 399.016726 -145.801588) (xy 392.527768 -145.801588) (xy 392.705082 -145.97888) (xy 392.718945 -145.993329)
			(xy 392.741197 -146.026615) (xy 392.75652 -146.063607) (xy 392.764321 -146.102878) (xy 392.764772 -146.122898)
			(xy 392.764772 -147.419822) (xy 396.174466 -147.419822) (xy 396.178537 -147.3642) (xy 396.190663 -147.309763)
			(xy 396.210586 -147.257672) (xy 396.237882 -147.209037) (xy 396.271968 -147.164894) (xy 396.312117 -147.126185)
			(xy 396.357475 -147.093734) (xy 396.407075 -147.068233) (xy 396.459859 -147.050226) (xy 396.514702 -147.040096)
			(xy 396.570436 -147.038059) (xy 396.625873 -147.044159) (xy 396.644322 -147.048982) (xy 399.016726 -147.048982)
			(xy 399.020797 -146.99336) (xy 399.032923 -146.938923) (xy 399.052846 -146.886832) (xy 399.080142 -146.838197)
			(xy 399.114228 -146.794054) (xy 399.154377 -146.755345) (xy 399.199735 -146.722894) (xy 399.249335 -146.697393)
			(xy 399.302119 -146.679386) (xy 399.356962 -146.669256) (xy 399.412696 -146.667219) (xy 399.468133 -146.673319)
			(xy 399.52209 -146.687425) (xy 399.573419 -146.709237) (xy 399.621025 -146.738291) (xy 399.663893 -146.773966)
			(xy 399.70111 -146.815503) (xy 399.731883 -146.862016) (xy 399.755555 -146.912513) (xy 399.771623 -146.96592)
			(xy 399.779743 -147.021096) (xy 399.780252 -147.048982) (xy 399.779743 -147.076868) (xy 399.771623 -147.132044)
			(xy 399.755555 -147.185451) (xy 399.731883 -147.235948) (xy 399.70111 -147.282461) (xy 399.663893 -147.323998)
			(xy 399.621025 -147.359673) (xy 399.573419 -147.388727) (xy 399.52209 -147.410539) (xy 399.468133 -147.424645)
			(xy 399.412696 -147.430745) (xy 399.356962 -147.428708) (xy 399.302119 -147.418578) (xy 399.249335 -147.400571)
			(xy 399.199735 -147.37507) (xy 399.154377 -147.342619) (xy 399.114228 -147.30391) (xy 399.080142 -147.259767)
			(xy 399.052846 -147.211132) (xy 399.032923 -147.159041) (xy 399.020797 -147.104604) (xy 399.016726 -147.048982)
			(xy 396.644322 -147.048982) (xy 396.67983 -147.058265) (xy 396.731159 -147.080077) (xy 396.778765 -147.109131)
			(xy 396.821633 -147.144806) (xy 396.85885 -147.186343) (xy 396.889623 -147.232856) (xy 396.913295 -147.283353)
			(xy 396.929363 -147.33676) (xy 396.937483 -147.391936) (xy 396.937992 -147.419822) (xy 396.937483 -147.447708)
			(xy 396.929363 -147.502884) (xy 396.913295 -147.556291) (xy 396.889623 -147.606788) (xy 396.85885 -147.653301)
			(xy 396.821633 -147.694838) (xy 396.778765 -147.730513) (xy 396.731159 -147.759567) (xy 396.67983 -147.781379)
			(xy 396.625873 -147.795485) (xy 396.570436 -147.801585) (xy 396.514702 -147.799548) (xy 396.459859 -147.789418)
			(xy 396.407075 -147.771411) (xy 396.357475 -147.74591) (xy 396.312117 -147.713459) (xy 396.271968 -147.67475)
			(xy 396.237882 -147.630607) (xy 396.210586 -147.581972) (xy 396.190663 -147.529881) (xy 396.178537 -147.475444)
			(xy 396.174466 -147.419822) (xy 392.764772 -147.419822) (xy 392.764772 -148.435151) (xy 396.37106 -148.435151)
			(xy 396.37106 -148.380649) (xy 396.378816 -148.326702) (xy 396.39417 -148.274408) (xy 396.416809 -148.22483)
			(xy 396.446274 -148.17898) (xy 396.481963 -148.137788) (xy 396.523151 -148.102095) (xy 396.568999 -148.072627)
			(xy 396.618574 -148.049982) (xy 396.670867 -148.034623) (xy 396.724813 -148.026862) (xy 396.752064 -148.026374)
			(xy 396.779321 -148.026858) (xy 396.833275 -148.034645) (xy 396.885571 -148.050035) (xy 396.935143 -148.072716)
			(xy 396.958312 -148.08708) (xy 396.97025 -148.094446) (xy 396.997174 -148.095716) (xy 397.100298 -148.04136)
			(xy 397.114522 -148.018246) (xy 397.11503 -148.004276) (xy 397.116244 -147.977504) (xy 397.125109 -147.924654)
			(xy 397.141284 -147.873565) (xy 397.16445 -147.825243) (xy 397.194152 -147.78064) (xy 397.229805 -147.740632)
			(xy 397.270707 -147.706009) (xy 397.316052 -147.677452) (xy 397.364948 -147.655523) (xy 397.416432 -147.640653)
			(xy 397.46949 -147.633136) (xy 397.496284 -147.632674) (xy 397.523534 -147.633193) (xy 397.57748 -147.640947)
			(xy 397.629773 -147.656299) (xy 397.679348 -147.678937) (xy 397.725198 -147.7084) (xy 397.766388 -147.744088)
			(xy 397.80208 -147.785275) (xy 397.831547 -147.831122) (xy 397.854189 -147.880696) (xy 397.869546 -147.932987)
			(xy 397.877304 -147.986932) (xy 397.877792 -148.014182) (xy 398.003776 -148.014182) (xy 398.004262 -147.986931)
			(xy 398.012018 -147.932983) (xy 398.027373 -147.880688) (xy 398.050015 -147.831111) (xy 398.079481 -147.785261)
			(xy 398.115172 -147.74407) (xy 398.156363 -147.708379) (xy 398.202213 -147.678913) (xy 398.25179 -147.656271)
			(xy 398.304085 -147.640916) (xy 398.358033 -147.63316) (xy 398.412535 -147.63316) (xy 398.466483 -147.640916)
			(xy 398.518778 -147.656271) (xy 398.568355 -147.678913) (xy 398.614205 -147.708379) (xy 398.655396 -147.74407)
			(xy 398.691087 -147.785261) (xy 398.720553 -147.831111) (xy 398.743195 -147.880688) (xy 398.75855 -147.932983)
			(xy 398.759269 -147.937982) (xy 399.016726 -147.937982) (xy 399.020797 -147.88236) (xy 399.032923 -147.827923)
			(xy 399.052846 -147.775832) (xy 399.080142 -147.727197) (xy 399.114228 -147.683054) (xy 399.154377 -147.644345)
			(xy 399.199735 -147.611894) (xy 399.249335 -147.586393) (xy 399.302119 -147.568386) (xy 399.356962 -147.558256)
			(xy 399.412696 -147.556219) (xy 399.468133 -147.562319) (xy 399.52209 -147.576425) (xy 399.573419 -147.598237)
			(xy 399.621025 -147.627291) (xy 399.663893 -147.662966) (xy 399.70111 -147.704503) (xy 399.731883 -147.751016)
			(xy 399.755555 -147.801513) (xy 399.771623 -147.85492) (xy 399.779743 -147.910096) (xy 399.780252 -147.937982)
			(xy 399.779743 -147.965868) (xy 399.771623 -148.021044) (xy 399.755555 -148.074451) (xy 399.731883 -148.124948)
			(xy 399.70111 -148.171461) (xy 399.663893 -148.212998) (xy 399.621025 -148.248673) (xy 399.573419 -148.277727)
			(xy 399.52209 -148.299539) (xy 399.468133 -148.313645) (xy 399.412696 -148.319745) (xy 399.356962 -148.317708)
			(xy 399.302119 -148.307578) (xy 399.249335 -148.289571) (xy 399.199735 -148.26407) (xy 399.154377 -148.231619)
			(xy 399.114228 -148.19291) (xy 399.080142 -148.148767) (xy 399.052846 -148.100132) (xy 399.032923 -148.048041)
			(xy 399.020797 -147.993604) (xy 399.016726 -147.937982) (xy 398.759269 -147.937982) (xy 398.766306 -147.986931)
			(xy 398.766792 -148.014182) (xy 398.766326 -148.041728) (xy 398.75841 -148.096247) (xy 398.742727 -148.149059)
			(xy 398.719603 -148.199062) (xy 398.68952 -148.245215) (xy 398.653105 -148.286555) (xy 398.632426 -148.304758)
			(xy 398.621425 -148.314681) (xy 398.605327 -148.339543) (xy 398.59703 -148.367976) (xy 398.597231 -148.397594)
			(xy 398.605912 -148.425912) (xy 398.622345 -148.450554) (xy 398.645152 -148.469452) (xy 398.658588 -148.4757)
			(xy 398.684099 -148.487036) (xy 398.731775 -148.516077) (xy 398.774711 -148.551755) (xy 398.811989 -148.593309)
			(xy 398.842815 -148.639851) (xy 398.86653 -148.690388) (xy 398.882628 -148.743841) (xy 398.890765 -148.79907)
			(xy 398.891252 -148.826982) (xy 399.016726 -148.826982) (xy 399.020797 -148.77136) (xy 399.032923 -148.716923)
			(xy 399.052846 -148.664832) (xy 399.080142 -148.616197) (xy 399.114228 -148.572054) (xy 399.154377 -148.533345)
			(xy 399.199735 -148.500894) (xy 399.249335 -148.475393) (xy 399.302119 -148.457386) (xy 399.356962 -148.447256)
			(xy 399.412696 -148.445219) (xy 399.468133 -148.451319) (xy 399.52209 -148.465425) (xy 399.573419 -148.487237)
			(xy 399.621025 -148.516291) (xy 399.663893 -148.551966) (xy 399.70111 -148.593503) (xy 399.731883 -148.640016)
			(xy 399.755555 -148.690513) (xy 399.771623 -148.74392) (xy 399.779743 -148.799096) (xy 399.780252 -148.826982)
			(xy 399.779743 -148.854868) (xy 399.771623 -148.910044) (xy 399.755555 -148.963451) (xy 399.731883 -149.013948)
			(xy 399.70111 -149.060461) (xy 399.663893 -149.101998) (xy 399.621025 -149.137673) (xy 399.573419 -149.166727)
			(xy 399.52209 -149.188539) (xy 399.468133 -149.202645) (xy 399.412696 -149.208745) (xy 399.356962 -149.206708)
			(xy 399.302119 -149.196578) (xy 399.249335 -149.178571) (xy 399.199735 -149.15307) (xy 399.154377 -149.120619)
			(xy 399.114228 -149.08191) (xy 399.080142 -149.037767) (xy 399.052846 -148.989132) (xy 399.032923 -148.937041)
			(xy 399.020797 -148.882604) (xy 399.016726 -148.826982) (xy 398.891252 -148.826982) (xy 398.890766 -148.854233)
			(xy 398.88301 -148.908181) (xy 398.867655 -148.960476) (xy 398.845013 -149.010053) (xy 398.815547 -149.055903)
			(xy 398.779856 -149.097094) (xy 398.738665 -149.132785) (xy 398.692815 -149.162251) (xy 398.643238 -149.184893)
			(xy 398.590943 -149.200248) (xy 398.536995 -149.208004) (xy 398.482493 -149.208004) (xy 398.428545 -149.200248)
			(xy 398.37625 -149.184893) (xy 398.326673 -149.162251) (xy 398.280823 -149.132785) (xy 398.239632 -149.097094)
			(xy 398.203941 -149.055903) (xy 398.174475 -149.010053) (xy 398.151833 -148.960476) (xy 398.136478 -148.908181)
			(xy 398.128722 -148.854233) (xy 398.128236 -148.826982) (xy 398.128737 -148.799437) (xy 398.136644 -148.744919)
			(xy 398.15232 -148.692108) (xy 398.175437 -148.642104) (xy 398.205514 -148.595951) (xy 398.241925 -148.55461)
			(xy 398.262602 -148.536406) (xy 398.273524 -148.526404) (xy 398.289618 -148.501561) (xy 398.297918 -148.473148)
			(xy 398.297727 -148.443548) (xy 398.289062 -148.415245) (xy 398.272649 -148.390611) (xy 398.249865 -148.371715)
			(xy 398.23644 -148.365464) (xy 398.210921 -148.354143) (xy 398.163243 -148.325102) (xy 398.120306 -148.289422)
			(xy 398.083027 -148.247867) (xy 398.052202 -148.201322) (xy 398.028489 -148.150782) (xy 398.012394 -148.097326)
			(xy 398.004261 -148.042095) (xy 398.003776 -148.014182) (xy 397.877792 -148.014182) (xy 397.877326 -148.041728)
			(xy 397.86941 -148.096247) (xy 397.853727 -148.149059) (xy 397.830603 -148.199062) (xy 397.80052 -148.245215)
			(xy 397.764105 -148.286555) (xy 397.743426 -148.304758) (xy 397.733266 -148.313394) (xy 397.724122 -148.338032)
			(xy 397.74114 -148.449792) (xy 397.757396 -148.47062) (xy 397.769588 -148.4757) (xy 397.795099 -148.487036)
			(xy 397.842775 -148.516077) (xy 397.885711 -148.551755) (xy 397.922989 -148.593309) (xy 397.953815 -148.639851)
			(xy 397.97753 -148.690388) (xy 397.993628 -148.743841) (xy 398.001765 -148.79907) (xy 398.002252 -148.826982)
			(xy 398.001766 -148.854233) (xy 397.99401 -148.908181) (xy 397.978655 -148.960476) (xy 397.956013 -149.010053)
			(xy 397.926547 -149.055903) (xy 397.890856 -149.097094) (xy 397.849665 -149.132785) (xy 397.803815 -149.162251)
			(xy 397.754238 -149.184893) (xy 397.701943 -149.200248) (xy 397.647995 -149.208004) (xy 397.593493 -149.208004)
			(xy 397.539545 -149.200248) (xy 397.48725 -149.184893) (xy 397.437673 -149.162251) (xy 397.391823 -149.132785)
			(xy 397.350632 -149.097094) (xy 397.314941 -149.055903) (xy 397.285475 -149.010053) (xy 397.262833 -148.960476)
			(xy 397.247478 -148.908181) (xy 397.239722 -148.854233) (xy 397.239236 -148.826982) (xy 397.239737 -148.799437)
			(xy 397.247644 -148.744919) (xy 397.26332 -148.692108) (xy 397.286437 -148.642104) (xy 397.316514 -148.595951)
			(xy 397.352925 -148.55461) (xy 397.373602 -148.536406) (xy 397.383762 -148.52777) (xy 397.392906 -148.503132)
			(xy 397.375888 -148.391372) (xy 397.359632 -148.370544) (xy 397.34744 -148.365464) (xy 397.332538 -148.35893)
			(xy 397.303797 -148.343668) (xy 397.290036 -148.334984) (xy 397.278098 -148.327618) (xy 397.251174 -148.326348)
			(xy 397.14805 -148.380704) (xy 397.133826 -148.403818) (xy 397.133318 -148.417788) (xy 397.132213 -148.444566)
			(xy 397.123338 -148.497423) (xy 397.107153 -148.548516) (xy 397.083975 -148.596842) (xy 397.054262 -148.641447)
			(xy 397.018598 -148.681455) (xy 396.977685 -148.716077) (xy 396.932329 -148.744631) (xy 396.883423 -148.766557)
			(xy 396.831929 -148.781421) (xy 396.778862 -148.788931) (xy 396.752064 -148.78939) (xy 396.724813 -148.788938)
			(xy 396.670867 -148.781177) (xy 396.618574 -148.765818) (xy 396.568999 -148.743173) (xy 396.523151 -148.713705)
			(xy 396.481963 -148.678012) (xy 396.446274 -148.63682) (xy 396.416809 -148.59097) (xy 396.39417 -148.541392)
			(xy 396.378816 -148.489098) (xy 396.37106 -148.435151) (xy 392.764772 -148.435151) (xy 392.764772 -148.82114)
			(xy 392.765127 -148.831187) (xy 392.772725 -148.849784) (xy 392.779504 -148.857208) (xy 393.219178 -149.296882)
			(xy 396.370046 -149.296882) (xy 396.374117 -149.24126) (xy 396.386243 -149.186823) (xy 396.406166 -149.134732)
			(xy 396.433462 -149.086097) (xy 396.467548 -149.041954) (xy 396.507697 -149.003245) (xy 396.553055 -148.970794)
			(xy 396.602655 -148.945293) (xy 396.655439 -148.927286) (xy 396.710282 -148.917156) (xy 396.766016 -148.915119)
			(xy 396.821453 -148.921219) (xy 396.87541 -148.935325) (xy 396.926739 -148.957137) (xy 396.974345 -148.986191)
			(xy 397.017213 -149.021866) (xy 397.05443 -149.063403) (xy 397.085203 -149.109916) (xy 397.108875 -149.160413)
			(xy 397.124943 -149.21382) (xy 397.133063 -149.268996) (xy 397.133572 -149.296882) (xy 397.133063 -149.324768)
			(xy 397.124943 -149.379944) (xy 397.108875 -149.433351) (xy 397.085203 -149.483848) (xy 397.05443 -149.530361)
			(xy 397.017213 -149.571898) (xy 396.974345 -149.607573) (xy 396.926739 -149.636627) (xy 396.87541 -149.658439)
			(xy 396.821453 -149.672545) (xy 396.766016 -149.678645) (xy 396.710282 -149.676608) (xy 396.655439 -149.666478)
			(xy 396.602655 -149.648471) (xy 396.553055 -149.62297) (xy 396.507697 -149.590519) (xy 396.467548 -149.55181)
			(xy 396.433462 -149.507667) (xy 396.406166 -149.459032) (xy 396.386243 -149.406941) (xy 396.374117 -149.352504)
			(xy 396.370046 -149.296882) (xy 393.219178 -149.296882) (xy 393.638278 -149.715982) (xy 397.238726 -149.715982)
			(xy 397.242797 -149.66036) (xy 397.254923 -149.605923) (xy 397.274846 -149.553832) (xy 397.302142 -149.505197)
			(xy 397.336228 -149.461054) (xy 397.376377 -149.422345) (xy 397.421735 -149.389894) (xy 397.471335 -149.364393)
			(xy 397.524119 -149.346386) (xy 397.578962 -149.336256) (xy 397.634696 -149.334219) (xy 397.690133 -149.340319)
			(xy 397.74409 -149.354425) (xy 397.795419 -149.376237) (xy 397.843025 -149.405291) (xy 397.885893 -149.440966)
			(xy 397.92311 -149.482503) (xy 397.953883 -149.529016) (xy 397.977555 -149.579513) (xy 397.993623 -149.63292)
			(xy 398.001743 -149.688096) (xy 398.002252 -149.715982) (xy 398.127726 -149.715982) (xy 398.131797 -149.66036)
			(xy 398.143923 -149.605923) (xy 398.163846 -149.553832) (xy 398.191142 -149.505197) (xy 398.225228 -149.461054)
			(xy 398.265377 -149.422345) (xy 398.310735 -149.389894) (xy 398.360335 -149.364393) (xy 398.413119 -149.346386)
			(xy 398.467962 -149.336256) (xy 398.523696 -149.334219) (xy 398.579133 -149.340319) (xy 398.63309 -149.354425)
			(xy 398.684419 -149.376237) (xy 398.732025 -149.405291) (xy 398.774893 -149.440966) (xy 398.81211 -149.482503)
			(xy 398.842883 -149.529016) (xy 398.866555 -149.579513) (xy 398.882623 -149.63292) (xy 398.890743 -149.688096)
			(xy 398.891252 -149.715982) (xy 399.016726 -149.715982) (xy 399.020797 -149.66036) (xy 399.032923 -149.605923)
			(xy 399.052846 -149.553832) (xy 399.080142 -149.505197) (xy 399.114228 -149.461054) (xy 399.154377 -149.422345)
			(xy 399.199735 -149.389894) (xy 399.249335 -149.364393) (xy 399.302119 -149.346386) (xy 399.356962 -149.336256)
			(xy 399.412696 -149.334219) (xy 399.468133 -149.340319) (xy 399.52209 -149.354425) (xy 399.573419 -149.376237)
			(xy 399.621025 -149.405291) (xy 399.663893 -149.440966) (xy 399.70111 -149.482503) (xy 399.731883 -149.529016)
			(xy 399.755555 -149.579513) (xy 399.771623 -149.63292) (xy 399.779743 -149.688096) (xy 399.780252 -149.715982)
			(xy 399.779743 -149.743868) (xy 399.771623 -149.799044) (xy 399.755555 -149.852451) (xy 399.731883 -149.902948)
			(xy 399.70111 -149.949461) (xy 399.663893 -149.990998) (xy 399.621025 -150.026673) (xy 399.573419 -150.055727)
			(xy 399.52209 -150.077539) (xy 399.468133 -150.091645) (xy 399.412696 -150.097745) (xy 399.356962 -150.095708)
			(xy 399.302119 -150.085578) (xy 399.249335 -150.067571) (xy 399.199735 -150.04207) (xy 399.154377 -150.009619)
			(xy 399.114228 -149.97091) (xy 399.080142 -149.926767) (xy 399.052846 -149.878132) (xy 399.032923 -149.826041)
			(xy 399.020797 -149.771604) (xy 399.016726 -149.715982) (xy 398.891252 -149.715982) (xy 398.890743 -149.743868)
			(xy 398.882623 -149.799044) (xy 398.866555 -149.852451) (xy 398.842883 -149.902948) (xy 398.81211 -149.949461)
			(xy 398.774893 -149.990998) (xy 398.732025 -150.026673) (xy 398.684419 -150.055727) (xy 398.63309 -150.077539)
			(xy 398.579133 -150.091645) (xy 398.523696 -150.097745) (xy 398.467962 -150.095708) (xy 398.413119 -150.085578)
			(xy 398.360335 -150.067571) (xy 398.310735 -150.04207) (xy 398.265377 -150.009619) (xy 398.225228 -149.97091)
			(xy 398.191142 -149.926767) (xy 398.163846 -149.878132) (xy 398.143923 -149.826041) (xy 398.131797 -149.771604)
			(xy 398.127726 -149.715982) (xy 398.002252 -149.715982) (xy 398.001743 -149.743868) (xy 397.993623 -149.799044)
			(xy 397.977555 -149.852451) (xy 397.953883 -149.902948) (xy 397.92311 -149.949461) (xy 397.885893 -149.990998)
			(xy 397.843025 -150.026673) (xy 397.795419 -150.055727) (xy 397.74409 -150.077539) (xy 397.690133 -150.091645)
			(xy 397.634696 -150.097745) (xy 397.578962 -150.095708) (xy 397.524119 -150.085578) (xy 397.471335 -150.067571)
			(xy 397.421735 -150.04207) (xy 397.376377 -150.009619) (xy 397.336228 -149.97091) (xy 397.302142 -149.926767)
			(xy 397.274846 -149.878132) (xy 397.254923 -149.826041) (xy 397.242797 -149.771604) (xy 397.238726 -149.715982)
			(xy 393.638278 -149.715982) (xy 394.360908 -150.438612) (xy 394.368399 -150.445293) (xy 394.386951 -150.452892)
			(xy 394.396976 -150.453344) (xy 397.095218 -150.453344) (xy 397.11523 -150.453841) (xy 397.154484 -150.461665)
			(xy 397.191459 -150.476991) (xy 397.224737 -150.49923) (xy 397.239236 -150.513034) (xy 399.376579 -152.650444)
			(xy 408.315158 -152.650444) (xy 408.319229 -152.594822) (xy 408.331355 -152.540385) (xy 408.351278 -152.488294)
			(xy 408.378574 -152.439659) (xy 408.41266 -152.395516) (xy 408.452809 -152.356807) (xy 408.498167 -152.324356)
			(xy 408.547767 -152.298855) (xy 408.600551 -152.280848) (xy 408.655394 -152.270718) (xy 408.711128 -152.268681)
			(xy 408.766565 -152.274781) (xy 408.820522 -152.288887) (xy 408.871851 -152.310699) (xy 408.919457 -152.339753)
			(xy 408.962325 -152.375428) (xy 408.99872 -152.416048) (xy 419.022302 -152.416048) (xy 419.022302 -152.361552)
			(xy 419.030058 -152.307609) (xy 419.04541 -152.25532) (xy 419.068048 -152.205747) (xy 419.097511 -152.159901)
			(xy 419.133197 -152.118714) (xy 419.174382 -152.083025) (xy 419.220226 -152.05356) (xy 419.269797 -152.030919)
			(xy 419.322086 -152.015563) (xy 419.376028 -152.007804) (xy 419.403276 -152.007316) (xy 419.432193 -152.007846)
			(xy 419.489364 -152.016571) (xy 419.544562 -152.033827) (xy 419.596524 -152.059216) (xy 419.644058 -152.092158)
			(xy 419.686076 -152.131897) (xy 419.704266 -152.154382) (xy 419.711833 -152.163138) (xy 419.732588 -152.173322)
			(xy 419.744144 -152.17394) (xy 419.824408 -152.17394) (xy 419.83598 -152.173395) (xy 419.856752 -152.163185)
			(xy 419.864286 -152.154382) (xy 419.881039 -152.133599) (xy 419.919393 -152.096469) (xy 419.962547 -152.065047)
			(xy 420.009661 -152.039948) (xy 420.059813 -152.021662) (xy 420.112024 -152.010545) (xy 420.165276 -152.006815)
			(xy 420.218528 -152.010545) (xy 420.270739 -152.021662) (xy 420.320891 -152.039948) (xy 420.368005 -152.065047)
			(xy 420.411159 -152.096469) (xy 420.449513 -152.133599) (xy 420.466266 -152.154382) (xy 420.473833 -152.163138)
			(xy 420.494588 -152.173322) (xy 420.506144 -152.17394) (xy 420.586408 -152.17394) (xy 420.59798 -152.173395)
			(xy 420.618752 -152.163185) (xy 420.626286 -152.154382) (xy 420.643039 -152.133599) (xy 420.681393 -152.096469)
			(xy 420.724547 -152.065047) (xy 420.771661 -152.039948) (xy 420.821813 -152.021662) (xy 420.874024 -152.010545)
			(xy 420.927276 -152.006815) (xy 420.980528 -152.010545) (xy 421.032739 -152.021662) (xy 421.082891 -152.039948)
			(xy 421.130005 -152.065047) (xy 421.173159 -152.096469) (xy 421.211513 -152.133599) (xy 421.228266 -152.154382)
			(xy 421.235833 -152.163138) (xy 421.256588 -152.173322) (xy 421.268144 -152.17394) (xy 421.348408 -152.17394)
			(xy 421.35998 -152.173395) (xy 421.380752 -152.163185) (xy 421.388286 -152.154382) (xy 421.40648 -152.131901)
			(xy 421.4485 -152.092167) (xy 421.496034 -152.059228) (xy 421.547995 -152.033839) (xy 421.603192 -152.016582)
			(xy 421.66036 -152.007852) (xy 421.689276 -152.007316) (xy 421.716532 -152.007729) (xy 421.770489 -152.015484)
			(xy 421.822793 -152.030839) (xy 421.872379 -152.053481) (xy 421.918238 -152.082951) (xy 421.959436 -152.118647)
			(xy 421.995135 -152.159843) (xy 422.024607 -152.2057) (xy 422.047253 -152.255285) (xy 422.062611 -152.307588)
			(xy 422.070369 -152.361544) (xy 422.070369 -152.416056) (xy 422.062611 -152.470012) (xy 422.047253 -152.522315)
			(xy 422.024607 -152.5719) (xy 421.995135 -152.617757) (xy 421.959436 -152.658953) (xy 421.918238 -152.694649)
			(xy 421.872379 -152.724119) (xy 421.822793 -152.746761) (xy 421.770489 -152.762116) (xy 421.716532 -152.769871)
			(xy 421.689276 -152.770332) (xy 421.66036 -152.769785) (xy 421.603189 -152.761065) (xy 421.54799 -152.743815)
			(xy 421.496027 -152.718429) (xy 421.448493 -152.685489) (xy 421.406476 -152.64575) (xy 421.388286 -152.623266)
			(xy 421.380732 -152.614497) (xy 421.359967 -152.604319) (xy 421.348408 -152.603708) (xy 421.268144 -152.603708)
			(xy 421.256579 -152.604301) (xy 421.235807 -152.614479) (xy 421.228266 -152.623266) (xy 421.211513 -152.644049)
			(xy 421.173159 -152.681179) (xy 421.130005 -152.712601) (xy 421.082891 -152.7377) (xy 421.032739 -152.755986)
			(xy 420.980528 -152.767103) (xy 420.927276 -152.770833) (xy 420.874024 -152.767103) (xy 420.821813 -152.755986)
			(xy 420.771661 -152.7377) (xy 420.724547 -152.712601) (xy 420.681393 -152.681179) (xy 420.643039 -152.644049)
			(xy 420.626286 -152.623266) (xy 420.618732 -152.614497) (xy 420.597967 -152.604319) (xy 420.586408 -152.603708)
			(xy 420.506144 -152.603708) (xy 420.494579 -152.604301) (xy 420.473807 -152.614479) (xy 420.466266 -152.623266)
			(xy 420.449513 -152.644049) (xy 420.411159 -152.681179) (xy 420.368005 -152.712601) (xy 420.320891 -152.7377)
			(xy 420.270739 -152.755986) (xy 420.218528 -152.767103) (xy 420.165276 -152.770833) (xy 420.112024 -152.767103)
			(xy 420.059813 -152.755986) (xy 420.009661 -152.7377) (xy 419.962547 -152.712601) (xy 419.919393 -152.681179)
			(xy 419.881039 -152.644049) (xy 419.864286 -152.623266) (xy 419.856732 -152.614497) (xy 419.835967 -152.604319)
			(xy 419.824408 -152.603708) (xy 419.744144 -152.603708) (xy 419.732579 -152.604301) (xy 419.711807 -152.614479)
			(xy 419.704266 -152.623266) (xy 419.686086 -152.645759) (xy 419.644065 -152.685495) (xy 419.596528 -152.718434)
			(xy 419.544564 -152.743821) (xy 419.489364 -152.761075) (xy 419.432193 -152.7698) (xy 419.403276 -152.770332)
			(xy 419.376028 -152.769796) (xy 419.322086 -152.762037) (xy 419.269797 -152.746681) (xy 419.220226 -152.72404)
			(xy 419.174382 -152.694575) (xy 419.133197 -152.658886) (xy 419.097511 -152.617699) (xy 419.068048 -152.571853)
			(xy 419.04541 -152.52228) (xy 419.030058 -152.469991) (xy 419.022302 -152.416048) (xy 408.99872 -152.416048)
			(xy 408.999542 -152.416965) (xy 409.030315 -152.463478) (xy 409.053987 -152.513975) (xy 409.070055 -152.567382)
			(xy 409.078175 -152.622558) (xy 409.078684 -152.650444) (xy 409.078175 -152.67833) (xy 409.070055 -152.733506)
			(xy 409.053987 -152.786913) (xy 409.030315 -152.83741) (xy 408.999542 -152.883923) (xy 408.962325 -152.92546)
			(xy 408.919457 -152.961135) (xy 408.871851 -152.990189) (xy 408.820522 -153.012001) (xy 408.766565 -153.026107)
			(xy 408.711128 -153.032207) (xy 408.655394 -153.03017) (xy 408.600551 -153.02004) (xy 408.547767 -153.002033)
			(xy 408.498167 -152.976532) (xy 408.452809 -152.944081) (xy 408.41266 -152.905372) (xy 408.378574 -152.861229)
			(xy 408.351278 -152.812594) (xy 408.331355 -152.760503) (xy 408.319229 -152.706066) (xy 408.315158 -152.650444)
			(xy 399.376579 -152.650444) (xy 399.891929 -153.16581) (xy 411.48203 -153.16581) (xy 411.486101 -153.110188)
			(xy 411.498227 -153.055751) (xy 411.51815 -153.00366) (xy 411.545446 -152.955025) (xy 411.579532 -152.910882)
			(xy 411.619681 -152.872173) (xy 411.665039 -152.839722) (xy 411.714639 -152.814221) (xy 411.767423 -152.796214)
			(xy 411.822266 -152.786084) (xy 411.878 -152.784047) (xy 411.933437 -152.790147) (xy 411.987394 -152.804253)
			(xy 412.038723 -152.826065) (xy 412.086329 -152.855119) (xy 412.129197 -152.890794) (xy 412.166414 -152.932331)
			(xy 412.197187 -152.978844) (xy 412.220859 -153.029341) (xy 412.236927 -153.082748) (xy 412.245047 -153.137924)
			(xy 412.245556 -153.16581) (xy 412.37103 -153.16581) (xy 412.375101 -153.110188) (xy 412.387227 -153.055751)
			(xy 412.40715 -153.00366) (xy 412.434446 -152.955025) (xy 412.468532 -152.910882) (xy 412.508681 -152.872173)
			(xy 412.554039 -152.839722) (xy 412.603639 -152.814221) (xy 412.656423 -152.796214) (xy 412.711266 -152.786084)
			(xy 412.767 -152.784047) (xy 412.822437 -152.790147) (xy 412.876394 -152.804253) (xy 412.927723 -152.826065)
			(xy 412.975329 -152.855119) (xy 413.018197 -152.890794) (xy 413.055414 -152.932331) (xy 413.086187 -152.978844)
			(xy 413.109859 -153.029341) (xy 413.125927 -153.082748) (xy 413.134047 -153.137924) (xy 413.134556 -153.16581)
			(xy 413.26003 -153.16581) (xy 413.264101 -153.110188) (xy 413.276227 -153.055751) (xy 413.29615 -153.00366)
			(xy 413.323446 -152.955025) (xy 413.357532 -152.910882) (xy 413.397681 -152.872173) (xy 413.443039 -152.839722)
			(xy 413.492639 -152.814221) (xy 413.545423 -152.796214) (xy 413.600266 -152.786084) (xy 413.656 -152.784047)
			(xy 413.711437 -152.790147) (xy 413.765394 -152.804253) (xy 413.816723 -152.826065) (xy 413.864329 -152.855119)
			(xy 413.907197 -152.890794) (xy 413.944414 -152.932331) (xy 413.975187 -152.978844) (xy 413.998859 -153.029341)
			(xy 414.014927 -153.082748) (xy 414.023047 -153.137924) (xy 414.023556 -153.16581) (xy 414.14903 -153.16581)
			(xy 414.153101 -153.110188) (xy 414.165227 -153.055751) (xy 414.18515 -153.00366) (xy 414.212446 -152.955025)
			(xy 414.246532 -152.910882) (xy 414.286681 -152.872173) (xy 414.332039 -152.839722) (xy 414.381639 -152.814221)
			(xy 414.434423 -152.796214) (xy 414.489266 -152.786084) (xy 414.545 -152.784047) (xy 414.600437 -152.790147)
			(xy 414.654394 -152.804253) (xy 414.705723 -152.826065) (xy 414.753329 -152.855119) (xy 414.796197 -152.890794)
			(xy 414.833414 -152.932331) (xy 414.864187 -152.978844) (xy 414.887859 -153.029341) (xy 414.903927 -153.082748)
			(xy 414.912047 -153.137924) (xy 414.912556 -153.16581) (xy 414.912047 -153.193696) (xy 414.903927 -153.248872)
			(xy 414.887859 -153.302279) (xy 414.864187 -153.352776) (xy 414.833414 -153.399289) (xy 414.796197 -153.440826)
			(xy 414.753329 -153.476501) (xy 414.705723 -153.505555) (xy 414.654394 -153.527367) (xy 414.600437 -153.541473)
			(xy 414.545 -153.547573) (xy 414.489266 -153.545536) (xy 414.434423 -153.535406) (xy 414.381639 -153.517399)
			(xy 414.332039 -153.491898) (xy 414.286681 -153.459447) (xy 414.246532 -153.420738) (xy 414.212446 -153.376595)
			(xy 414.18515 -153.32796) (xy 414.165227 -153.275869) (xy 414.153101 -153.221432) (xy 414.14903 -153.16581)
			(xy 414.023556 -153.16581) (xy 414.023047 -153.193696) (xy 414.014927 -153.248872) (xy 413.998859 -153.302279)
			(xy 413.975187 -153.352776) (xy 413.944414 -153.399289) (xy 413.907197 -153.440826) (xy 413.864329 -153.476501)
			(xy 413.816723 -153.505555) (xy 413.765394 -153.527367) (xy 413.711437 -153.541473) (xy 413.656 -153.547573)
			(xy 413.600266 -153.545536) (xy 413.545423 -153.535406) (xy 413.492639 -153.517399) (xy 413.443039 -153.491898)
			(xy 413.397681 -153.459447) (xy 413.357532 -153.420738) (xy 413.323446 -153.376595) (xy 413.29615 -153.32796)
			(xy 413.276227 -153.275869) (xy 413.264101 -153.221432) (xy 413.26003 -153.16581) (xy 413.134556 -153.16581)
			(xy 413.134047 -153.193696) (xy 413.125927 -153.248872) (xy 413.109859 -153.302279) (xy 413.086187 -153.352776)
			(xy 413.055414 -153.399289) (xy 413.018197 -153.440826) (xy 412.975329 -153.476501) (xy 412.927723 -153.505555)
			(xy 412.876394 -153.527367) (xy 412.822437 -153.541473) (xy 412.767 -153.547573) (xy 412.711266 -153.545536)
			(xy 412.656423 -153.535406) (xy 412.603639 -153.517399) (xy 412.554039 -153.491898) (xy 412.508681 -153.459447)
			(xy 412.468532 -153.420738) (xy 412.434446 -153.376595) (xy 412.40715 -153.32796) (xy 412.387227 -153.275869)
			(xy 412.375101 -153.221432) (xy 412.37103 -153.16581) (xy 412.245556 -153.16581) (xy 412.245047 -153.193696)
			(xy 412.236927 -153.248872) (xy 412.220859 -153.302279) (xy 412.197187 -153.352776) (xy 412.166414 -153.399289)
			(xy 412.129197 -153.440826) (xy 412.086329 -153.476501) (xy 412.038723 -153.505555) (xy 411.987394 -153.527367)
			(xy 411.933437 -153.541473) (xy 411.878 -153.547573) (xy 411.822266 -153.545536) (xy 411.767423 -153.535406)
			(xy 411.714639 -153.517399) (xy 411.665039 -153.491898) (xy 411.619681 -153.459447) (xy 411.579532 -153.420738)
			(xy 411.545446 -153.376595) (xy 411.51815 -153.32796) (xy 411.498227 -153.275869) (xy 411.486101 -153.221432)
			(xy 411.48203 -153.16581) (xy 399.891929 -153.16581) (xy 402.208844 -155.482798) (xy 410.680916 -155.482798)
			(xy 410.681427 -155.453881) (xy 410.690157 -155.396709) (xy 410.707416 -155.34151) (xy 410.732809 -155.289548)
			(xy 410.765754 -155.242014) (xy 410.805496 -155.199998) (xy 410.827982 -155.181808) (xy 410.83675 -155.174253)
			(xy 410.846927 -155.153488) (xy 410.84754 -155.14193) (xy 410.84754 -155.061666) (xy 410.846953 -155.0501)
			(xy 410.836772 -155.029327) (xy 410.827982 -155.021788) (xy 410.805489 -155.003608) (xy 410.765755 -154.961586)
			(xy 410.732818 -154.914048) (xy 410.707431 -154.862085) (xy 410.690177 -154.806886) (xy 410.68145 -154.749715)
			(xy 410.680916 -154.720798) (xy 410.681355 -154.694076) (xy 410.688826 -154.641156) (xy 410.703609 -154.589796)
			(xy 410.725413 -154.541001) (xy 410.753813 -154.495726) (xy 410.788252 -154.454857) (xy 410.828056 -154.419193)
			(xy 410.872448 -154.389431) (xy 410.896308 -154.37739) (xy 410.909262 -154.37104) (xy 410.924502 -154.347418)
			(xy 410.927296 -154.228038) (xy 410.913072 -154.203654) (xy 410.900372 -154.196542) (xy 410.874888 -154.182125)
			(xy 410.828285 -154.14668) (xy 410.787647 -154.10453) (xy 410.753925 -154.056666) (xy 410.727913 -154.004211)
			(xy 410.710222 -153.948398) (xy 410.701266 -153.890537) (xy 410.700728 -153.861262) (xy 410.701214 -153.834011)
			(xy 410.70897 -153.780063) (xy 410.724325 -153.727768) (xy 410.746967 -153.678191) (xy 410.776433 -153.632341)
			(xy 410.812124 -153.59115) (xy 410.853315 -153.555459) (xy 410.899165 -153.525993) (xy 410.948742 -153.503351)
			(xy 411.001037 -153.487996) (xy 411.054985 -153.48024) (xy 411.109487 -153.48024) (xy 411.163435 -153.487996)
			(xy 411.21573 -153.503351) (xy 411.265307 -153.525993) (xy 411.311157 -153.555459) (xy 411.352348 -153.59115)
			(xy 411.388039 -153.632341) (xy 411.417505 -153.678191) (xy 411.440147 -153.727768) (xy 411.455502 -153.780063)
			(xy 411.463258 -153.834011) (xy 411.463744 -153.861262) (xy 411.463294 -153.887984) (xy 411.455828 -153.940905)
			(xy 411.441048 -153.992265) (xy 411.419247 -154.041061) (xy 411.390848 -154.086337) (xy 411.35641 -154.127206)
			(xy 411.316605 -154.16287) (xy 411.272212 -154.19263) (xy 411.248352 -154.20467) (xy 411.235398 -154.21102)
			(xy 411.220158 -154.234642) (xy 411.217364 -154.354022) (xy 411.231588 -154.378406) (xy 411.244288 -154.385518)
			(xy 411.269789 -154.399908) (xy 411.316393 -154.435355) (xy 411.357033 -154.477509) (xy 411.390754 -154.525378)
			(xy 411.416763 -154.577837) (xy 411.434449 -154.633656) (xy 411.443398 -154.691521) (xy 411.443932 -154.720798)
			(xy 411.443438 -154.749716) (xy 411.434708 -154.80689) (xy 411.417447 -154.86209) (xy 411.39205 -154.914052)
			(xy 411.359101 -154.961585) (xy 411.319354 -155.0036) (xy 411.296866 -155.021788) (xy 411.288108 -155.029354)
			(xy 411.277924 -155.05011) (xy 411.277308 -155.061666) (xy 411.277308 -155.14193) (xy 411.277916 -155.153493)
			(xy 411.288084 -155.174265) (xy 411.296866 -155.181808) (xy 411.319346 -155.200003) (xy 411.359083 -155.242021)
			(xy 411.392024 -155.289555) (xy 411.417413 -155.341515) (xy 411.434669 -155.396713) (xy 411.443398 -155.453882)
			(xy 411.443932 -155.482798) (xy 411.443446 -155.510049) (xy 411.43569 -155.563997) (xy 411.431713 -155.57754)
			(xy 415.148268 -155.57754) (xy 415.148789 -155.548623) (xy 415.157514 -155.491451) (xy 415.17477 -155.436251)
			(xy 415.200161 -155.384288) (xy 415.233105 -155.336755) (xy 415.272847 -155.294739) (xy 415.295334 -155.27655)
			(xy 415.304075 -155.268968) (xy 415.314268 -155.248224) (xy 415.314892 -155.236672) (xy 415.314892 -155.156408)
			(xy 415.314319 -155.14484) (xy 415.304127 -155.124069) (xy 415.295334 -155.11653) (xy 415.272872 -155.098313)
			(xy 415.233134 -155.0563) (xy 415.200191 -155.008771) (xy 415.174799 -154.956814) (xy 415.157538 -154.901621)
			(xy 415.148805 -154.844455) (xy 415.148268 -154.81554) (xy 415.148712 -154.788817) (xy 415.156179 -154.735896)
			(xy 415.170959 -154.684535) (xy 415.192761 -154.635739) (xy 415.22116 -154.590464) (xy 415.2556 -154.549594)
			(xy 415.295406 -154.513931) (xy 415.339799 -154.484172) (xy 415.36366 -154.472132) (xy 415.376614 -154.465782)
			(xy 415.391854 -154.44216) (xy 415.394648 -154.32278) (xy 415.380424 -154.298396) (xy 415.367724 -154.291284)
			(xy 415.342227 -154.276888) (xy 415.295622 -154.241442) (xy 415.254981 -154.19929) (xy 415.22126 -154.151422)
			(xy 415.19525 -154.098963) (xy 415.177563 -154.043145) (xy 415.168614 -153.98528) (xy 415.16808 -153.956004)
			(xy 415.168566 -153.928753) (xy 415.176322 -153.874805) (xy 415.191677 -153.82251) (xy 415.214319 -153.772933)
			(xy 415.243785 -153.727083) (xy 415.279476 -153.685892) (xy 415.320667 -153.650201) (xy 415.366517 -153.620735)
			(xy 415.416094 -153.598093) (xy 415.468389 -153.582738) (xy 415.522337 -153.574982) (xy 415.576839 -153.574982)
			(xy 415.630787 -153.582738) (xy 415.683082 -153.598093) (xy 415.732659 -153.620735) (xy 415.778509 -153.650201)
			(xy 415.8197 -153.685892) (xy 415.855391 -153.727083) (xy 415.884857 -153.772933) (xy 415.907499 -153.82251)
			(xy 415.922854 -153.874805) (xy 415.93061 -153.928753) (xy 415.931096 -153.956004) (xy 415.930652 -153.982726)
			(xy 415.923181 -154.035646) (xy 415.908398 -154.087005) (xy 415.886595 -154.135799) (xy 415.858196 -154.181074)
			(xy 415.823758 -154.221944) (xy 415.783954 -154.257608) (xy 415.739563 -154.28737) (xy 415.715704 -154.299412)
			(xy 415.70275 -154.305762) (xy 415.68751 -154.329384) (xy 415.684716 -154.448764) (xy 415.69894 -154.473148)
			(xy 415.71164 -154.48026) (xy 415.737128 -154.494671) (xy 415.78373 -154.530117) (xy 415.824368 -154.572268)
			(xy 415.858089 -154.620134) (xy 415.8841 -154.672589) (xy 415.901791 -154.728403) (xy 415.910746 -154.786265)
			(xy 415.911284 -154.81554) (xy 415.911053 -154.82755) (xy 419.022278 -154.82755) (xy 419.022278 -154.77305)
			(xy 419.030034 -154.719104) (xy 419.045388 -154.666811) (xy 419.068027 -154.617236) (xy 419.097491 -154.571386)
			(xy 419.13318 -154.530197) (xy 419.174367 -154.494505) (xy 419.220215 -154.465038) (xy 419.269789 -154.442396)
			(xy 419.322081 -154.427039) (xy 419.376026 -154.419279) (xy 419.403276 -154.418792) (xy 419.432194 -154.419293)
			(xy 419.489368 -154.42802) (xy 419.544568 -154.445279) (xy 419.596531 -154.470674) (xy 419.644064 -154.503623)
			(xy 419.686078 -154.543369) (xy 419.704266 -154.565858) (xy 419.711837 -154.57461) (xy 419.732589 -154.584797)
			(xy 419.744144 -154.585416) (xy 419.824408 -154.585416) (xy 419.835976 -154.584844) (xy 419.856746 -154.57465)
			(xy 419.864286 -154.565858) (xy 419.881039 -154.545075) (xy 419.919393 -154.507945) (xy 419.962547 -154.476523)
			(xy 420.009661 -154.451424) (xy 420.059813 -154.433138) (xy 420.112024 -154.422021) (xy 420.165276 -154.418291)
			(xy 420.218528 -154.422021) (xy 420.270739 -154.433138) (xy 420.320891 -154.451424) (xy 420.368005 -154.476523)
			(xy 420.411159 -154.507945) (xy 420.449513 -154.545075) (xy 420.466266 -154.565858) (xy 420.473837 -154.57461)
			(xy 420.494589 -154.584797) (xy 420.506144 -154.585416) (xy 420.586408 -154.585416) (xy 420.597976 -154.584844)
			(xy 420.618746 -154.57465) (xy 420.626286 -154.565858) (xy 420.643039 -154.545075) (xy 420.681393 -154.507945)
			(xy 420.724547 -154.476523) (xy 420.771661 -154.451424) (xy 420.821813 -154.433138) (xy 420.874024 -154.422021)
			(xy 420.927276 -154.418291) (xy 420.980528 -154.422021) (xy 421.032739 -154.433138) (xy 421.082891 -154.451424)
			(xy 421.130005 -154.476523) (xy 421.173159 -154.507945) (xy 421.211513 -154.545075) (xy 421.228266 -154.565858)
			(xy 421.235837 -154.57461) (xy 421.256589 -154.584797) (xy 421.268144 -154.585416) (xy 421.348408 -154.585416)
			(xy 421.359976 -154.584844) (xy 421.380746 -154.57465) (xy 421.388286 -154.565858) (xy 421.406474 -154.543372)
			(xy 421.448496 -154.503639) (xy 421.496032 -154.470702) (xy 421.547993 -154.445314) (xy 421.603191 -154.428058)
			(xy 421.66036 -154.419328) (xy 421.689276 -154.418792) (xy 421.71653 -154.419254) (xy 421.770483 -154.427008)
			(xy 421.822784 -154.442362) (xy 421.872367 -154.465003) (xy 421.918223 -154.49447) (xy 421.959419 -154.530164)
			(xy 421.995115 -154.571357) (xy 422.024586 -154.617212) (xy 422.04723 -154.666793) (xy 422.062587 -154.719093)
			(xy 422.070345 -154.773046) (xy 422.070345 -154.827554) (xy 422.062587 -154.881507) (xy 422.04723 -154.933807)
			(xy 422.024586 -154.983388) (xy 421.995115 -155.029243) (xy 421.959419 -155.070436) (xy 421.918223 -155.10613)
			(xy 421.872367 -155.135597) (xy 421.822784 -155.158238) (xy 421.770483 -155.173592) (xy 421.71653 -155.181346)
			(xy 421.689276 -155.181808) (xy 421.660359 -155.18127) (xy 421.603188 -155.17255) (xy 421.547988 -155.155298)
			(xy 421.496025 -155.12991) (xy 421.448491 -155.096968) (xy 421.406475 -155.057228) (xy 421.388286 -155.034742)
			(xy 421.380736 -155.025968) (xy 421.359968 -155.015794) (xy 421.348408 -155.015184) (xy 421.268144 -155.015184)
			(xy 421.25658 -155.015785) (xy 421.235809 -155.025959) (xy 421.228266 -155.034742) (xy 421.211513 -155.055525)
			(xy 421.173159 -155.092655) (xy 421.130005 -155.124077) (xy 421.082891 -155.149176) (xy 421.032739 -155.167462)
			(xy 420.980528 -155.178579) (xy 420.927276 -155.182309) (xy 420.874024 -155.178579) (xy 420.821813 -155.167462)
			(xy 420.771661 -155.149176) (xy 420.724547 -155.124077) (xy 420.681393 -155.092655) (xy 420.643039 -155.055525)
			(xy 420.626286 -155.034742) (xy 420.618736 -155.025968) (xy 420.597968 -155.015794) (xy 420.586408 -155.015184)
			(xy 420.506144 -155.015184) (xy 420.49458 -155.015785) (xy 420.473809 -155.025959) (xy 420.466266 -155.034742)
			(xy 420.449513 -155.055525) (xy 420.411159 -155.092655) (xy 420.368005 -155.124077) (xy 420.320891 -155.149176)
			(xy 420.270739 -155.167462) (xy 420.218528 -155.178579) (xy 420.165276 -155.182309) (xy 420.112024 -155.178579)
			(xy 420.059813 -155.167462) (xy 420.009661 -155.149176) (xy 419.962547 -155.124077) (xy 419.919393 -155.092655)
			(xy 419.881039 -155.055525) (xy 419.864286 -155.034742) (xy 419.856736 -155.025968) (xy 419.835968 -155.015794)
			(xy 419.824408 -155.015184) (xy 419.744144 -155.015184) (xy 419.73258 -155.015785) (xy 419.711809 -155.025959)
			(xy 419.704266 -155.034742) (xy 419.686105 -155.057251) (xy 419.644078 -155.096982) (xy 419.596536 -155.129917)
			(xy 419.544569 -155.155301) (xy 419.489367 -155.172552) (xy 419.432194 -155.181276) (xy 419.403276 -155.181808)
			(xy 419.376026 -155.181321) (xy 419.322081 -155.173561) (xy 419.269789 -155.158204) (xy 419.220215 -155.135562)
			(xy 419.174367 -155.106095) (xy 419.13318 -155.070403) (xy 419.097491 -155.029214) (xy 419.068027 -154.983364)
			(xy 419.045388 -154.933789) (xy 419.030034 -154.881496) (xy 419.022278 -154.82755) (xy 415.911053 -154.82755)
			(xy 415.910729 -154.844456) (xy 415.902008 -154.901625) (xy 415.884758 -154.956824) (xy 415.859373 -155.008786)
			(xy 415.826436 -155.056321) (xy 415.786701 -155.098339) (xy 415.764218 -155.11653) (xy 415.755433 -155.124069)
			(xy 415.745265 -155.144846) (xy 415.74466 -155.156408) (xy 415.74466 -155.236672) (xy 415.745226 -155.248241)
			(xy 415.755422 -155.269013) (xy 415.764218 -155.27655) (xy 415.786681 -155.294765) (xy 415.826417 -155.33678)
			(xy 415.859358 -155.38431) (xy 415.884749 -155.436267) (xy 415.90201 -155.49146) (xy 415.910745 -155.548625)
			(xy 415.911284 -155.57754) (xy 415.910798 -155.604791) (xy 415.903042 -155.658739) (xy 415.887687 -155.711034)
			(xy 415.865045 -155.760611) (xy 415.835579 -155.806461) (xy 415.799888 -155.847652) (xy 415.758697 -155.883343)
			(xy 415.712847 -155.912809) (xy 415.66327 -155.935451) (xy 415.610975 -155.950806) (xy 415.557027 -155.958562)
			(xy 415.502525 -155.958562) (xy 415.448577 -155.950806) (xy 415.396282 -155.935451) (xy 415.346705 -155.912809)
			(xy 415.300855 -155.883343) (xy 415.259664 -155.847652) (xy 415.223973 -155.806461) (xy 415.194507 -155.760611)
			(xy 415.171865 -155.711034) (xy 415.15651 -155.658739) (xy 415.148754 -155.604791) (xy 415.148268 -155.57754)
			(xy 411.431713 -155.57754) (xy 411.420335 -155.616292) (xy 411.397693 -155.665869) (xy 411.368227 -155.711719)
			(xy 411.332536 -155.75291) (xy 411.291345 -155.788601) (xy 411.245495 -155.818067) (xy 411.195918 -155.840709)
			(xy 411.143623 -155.856064) (xy 411.089675 -155.86382) (xy 411.035173 -155.86382) (xy 410.981225 -155.856064)
			(xy 410.92893 -155.840709) (xy 410.879353 -155.818067) (xy 410.833503 -155.788601) (xy 410.792312 -155.75291)
			(xy 410.756621 -155.711719) (xy 410.727155 -155.665869) (xy 410.704513 -155.616292) (xy 410.689158 -155.563997)
			(xy 410.681402 -155.510049) (xy 410.680916 -155.482798) (xy 402.208844 -155.482798) (xy 403.322853 -156.596842)
			(xy 419.77132 -156.596842) (xy 419.775391 -156.54122) (xy 419.787517 -156.486783) (xy 419.80744 -156.434692)
			(xy 419.834736 -156.386057) (xy 419.868822 -156.341914) (xy 419.908971 -156.303205) (xy 419.954329 -156.270754)
			(xy 420.003929 -156.245253) (xy 420.056713 -156.227246) (xy 420.111556 -156.217116) (xy 420.16729 -156.215079)
			(xy 420.222727 -156.221179) (xy 420.276684 -156.235285) (xy 420.328013 -156.257097) (xy 420.375619 -156.286151)
			(xy 420.418487 -156.321826) (xy 420.455704 -156.363363) (xy 420.486477 -156.409876) (xy 420.510149 -156.460373)
			(xy 420.526217 -156.51378) (xy 420.534337 -156.568956) (xy 420.534846 -156.596842) (xy 420.534337 -156.624728)
			(xy 420.526217 -156.679904) (xy 420.510149 -156.733311) (xy 420.486477 -156.783808) (xy 420.455704 -156.830321)
			(xy 420.418487 -156.871858) (xy 420.375619 -156.907533) (xy 420.328013 -156.936587) (xy 420.276684 -156.958399)
			(xy 420.222727 -156.972505) (xy 420.16729 -156.978605) (xy 420.111556 -156.976568) (xy 420.056713 -156.966438)
			(xy 420.003929 -156.948431) (xy 419.954329 -156.92293) (xy 419.908971 -156.890479) (xy 419.868822 -156.85177)
			(xy 419.834736 -156.807627) (xy 419.80744 -156.758992) (xy 419.787517 -156.706901) (xy 419.775391 -156.652464)
			(xy 419.77132 -156.596842) (xy 403.322853 -156.596842) (xy 403.944626 -157.218634) (xy 417.996114 -157.218634)
			(xy 418.000185 -157.163012) (xy 418.012311 -157.108575) (xy 418.032234 -157.056484) (xy 418.05953 -157.007849)
			(xy 418.093616 -156.963706) (xy 418.133765 -156.924997) (xy 418.179123 -156.892546) (xy 418.228723 -156.867045)
			(xy 418.281507 -156.849038) (xy 418.33635 -156.838908) (xy 418.392084 -156.836871) (xy 418.447521 -156.842971)
			(xy 418.501478 -156.857077) (xy 418.552807 -156.878889) (xy 418.600413 -156.907943) (xy 418.643281 -156.943618)
			(xy 418.680498 -156.985155) (xy 418.711271 -157.031668) (xy 418.734943 -157.082165) (xy 418.751011 -157.135572)
			(xy 418.759131 -157.190748) (xy 418.75964 -157.218634) (xy 418.759131 -157.24652) (xy 418.751011 -157.301696)
			(xy 418.734943 -157.355103) (xy 418.711271 -157.4056) (xy 418.680498 -157.452113) (xy 418.643281 -157.49365)
			(xy 418.600413 -157.529325) (xy 418.552807 -157.558379) (xy 418.501478 -157.580191) (xy 418.447521 -157.594297)
			(xy 418.392084 -157.600397) (xy 418.33635 -157.59836) (xy 418.281507 -157.58823) (xy 418.228723 -157.570223)
			(xy 418.179123 -157.544722) (xy 418.133765 -157.512271) (xy 418.093616 -157.473562) (xy 418.05953 -157.429419)
			(xy 418.032234 -157.380784) (xy 418.012311 -157.328693) (xy 418.000185 -157.274256) (xy 417.996114 -157.218634)
			(xy 403.944626 -157.218634) (xy 405.331676 -158.605728) (xy 405.339142 -158.612441) (xy 405.357713 -158.62002)
			(xy 405.367744 -158.62046) (xy 412.46044 -158.62046) (xy 412.480452 -158.620967) (xy 412.519703 -158.628792)
			(xy 412.556678 -158.644116) (xy 412.589958 -158.666349) (xy 412.604458 -158.68015) (xy 413.13354 -159.209486)
			(xy 413.140934 -159.216334) (xy 413.159538 -159.22405) (xy 413.169608 -159.224472) (xy 414.255458 -159.224472)
			(xy 414.267522 -159.223785) (xy 414.288995 -159.212776) (xy 414.296606 -159.20339) (xy 414.314685 -159.179513)
			(xy 414.357064 -159.137199) (xy 414.405535 -159.102028) (xy 414.458907 -159.074862) (xy 414.515868 -159.05637)
			(xy 414.575018 -159.047006) (xy 414.604962 -159.046418) (xy 414.632215 -159.046891) (xy 414.686167 -159.054643)
			(xy 414.738466 -159.069996) (xy 414.788048 -159.092636) (xy 414.833903 -159.122102) (xy 414.875096 -159.157795)
			(xy 414.910791 -159.198988) (xy 414.940259 -159.244841) (xy 414.9629 -159.294422) (xy 414.978254 -159.346721)
			(xy 414.986008 -159.400673) (xy 414.98647 -159.427926) (xy 414.985809 -159.459489) (xy 414.975423 -159.521754)
			(xy 414.954937 -159.581463) (xy 414.940496 -159.609536) (xy 414.93567 -159.618426) (xy 414.933638 -159.637984)
			(xy 414.959292 -159.726122) (xy 414.971738 -159.741616) (xy 414.980628 -159.746696) (xy 414.987994 -159.75076)
			(xy 414.997646 -159.756602) (xy 415.019744 -159.758634) (xy 415.114232 -159.725106) (xy 415.130234 -159.709612)
			(xy 415.134298 -159.699198) (xy 415.144978 -159.672415) (xy 415.173267 -159.622172) (xy 415.208799 -159.576762)
			(xy 415.250763 -159.537219) (xy 415.298203 -159.504446) (xy 415.350036 -159.479189) (xy 415.405082 -159.462026)
			(xy 415.462084 -159.453346) (xy 415.490914 -159.452818) (xy 415.518166 -159.453253) (xy 415.572116 -159.461011)
			(xy 415.624413 -159.476369) (xy 415.673992 -159.499012) (xy 415.719844 -159.528481) (xy 415.761035 -159.564175)
			(xy 415.796727 -159.605368) (xy 415.826194 -159.65122) (xy 415.848836 -159.7008) (xy 415.864192 -159.753097)
			(xy 415.871948 -159.807048) (xy 415.871948 -159.861552) (xy 415.864192 -159.915503) (xy 415.854839 -159.947356)
			(xy 416.113722 -159.947356) (xy 416.114177 -159.91988) (xy 416.122076 -159.865499) (xy 416.137703 -159.812816)
			(xy 416.160735 -159.762924) (xy 416.190693 -159.716857) (xy 416.208464 -159.695896) (xy 416.21456 -159.688784)
			(xy 416.22091 -159.671766) (xy 416.22091 -159.585914) (xy 416.21456 -159.568896) (xy 416.208464 -159.561784)
			(xy 416.190706 -159.540817) (xy 416.160781 -159.494736) (xy 416.137768 -159.444843) (xy 416.122141 -159.392167)
			(xy 416.114222 -159.337796) (xy 416.113722 -159.310324) (xy 416.114208 -159.283073) (xy 416.121964 -159.229125)
			(xy 416.137319 -159.17683) (xy 416.159961 -159.127253) (xy 416.189427 -159.081403) (xy 416.225118 -159.040212)
			(xy 416.266309 -159.004521) (xy 416.312159 -158.975055) (xy 416.361736 -158.952413) (xy 416.414031 -158.937058)
			(xy 416.467979 -158.929302) (xy 416.522481 -158.929302) (xy 416.576429 -158.937058) (xy 416.628724 -158.952413)
			(xy 416.678301 -158.975055) (xy 416.724151 -159.004521) (xy 416.765342 -159.040212) (xy 416.801033 -159.081403)
			(xy 416.830499 -159.127253) (xy 416.853141 -159.17683) (xy 416.868496 -159.229125) (xy 416.876252 -159.283073)
			(xy 416.876738 -159.310324) (xy 416.876256 -159.337799) (xy 416.868362 -159.392178) (xy 416.85274 -159.44486)
			(xy 416.829715 -159.494753) (xy 416.799763 -159.540822) (xy 416.781996 -159.561784) (xy 416.7759 -159.568896)
			(xy 416.76955 -159.585914) (xy 416.76955 -159.671766) (xy 416.7759 -159.688784) (xy 416.781996 -159.695896)
			(xy 416.799738 -159.716876) (xy 416.829667 -159.762952) (xy 416.852684 -159.812842) (xy 416.868314 -159.865515)
			(xy 416.876236 -159.919885) (xy 416.876738 -159.947356) (xy 416.876252 -159.974607) (xy 416.874619 -159.985964)
			(xy 417.451538 -159.985964) (xy 417.455609 -159.930342) (xy 417.467735 -159.875905) (xy 417.487658 -159.823814)
			(xy 417.514954 -159.775179) (xy 417.54904 -159.731036) (xy 417.589189 -159.692327) (xy 417.634547 -159.659876)
			(xy 417.684147 -159.634375) (xy 417.736931 -159.616368) (xy 417.791774 -159.606238) (xy 417.847508 -159.604201)
			(xy 417.902945 -159.610301) (xy 417.956902 -159.624407) (xy 418.008231 -159.646219) (xy 418.055837 -159.675273)
			(xy 418.098705 -159.710948) (xy 418.135922 -159.752485) (xy 418.166695 -159.798998) (xy 418.190367 -159.849495)
			(xy 418.206435 -159.902902) (xy 418.214555 -159.958078) (xy 418.215064 -159.985964) (xy 418.214555 -160.01385)
			(xy 418.206435 -160.069026) (xy 418.190367 -160.122433) (xy 418.166695 -160.17293) (xy 418.135922 -160.219443)
			(xy 418.098705 -160.26098) (xy 418.055837 -160.296655) (xy 418.008231 -160.325709) (xy 417.956902 -160.347521)
			(xy 417.902945 -160.361627) (xy 417.847508 -160.367727) (xy 417.791774 -160.36569) (xy 417.736931 -160.35556)
			(xy 417.684147 -160.337553) (xy 417.634547 -160.312052) (xy 417.589189 -160.279601) (xy 417.54904 -160.240892)
			(xy 417.514954 -160.196749) (xy 417.487658 -160.148114) (xy 417.467735 -160.096023) (xy 417.455609 -160.041586)
			(xy 417.451538 -159.985964) (xy 416.874619 -159.985964) (xy 416.868496 -160.028555) (xy 416.853141 -160.08085)
			(xy 416.830499 -160.130427) (xy 416.801033 -160.176277) (xy 416.765342 -160.217468) (xy 416.724151 -160.253159)
			(xy 416.678301 -160.282625) (xy 416.628724 -160.305267) (xy 416.576429 -160.320622) (xy 416.522481 -160.328378)
			(xy 416.467979 -160.328378) (xy 416.414031 -160.320622) (xy 416.361736 -160.305267) (xy 416.312159 -160.282625)
			(xy 416.266309 -160.253159) (xy 416.225118 -160.217468) (xy 416.189427 -160.176277) (xy 416.159961 -160.130427)
			(xy 416.137319 -160.08085) (xy 416.121964 -160.028555) (xy 416.114208 -159.974607) (xy 416.113722 -159.947356)
			(xy 415.854839 -159.947356) (xy 415.848836 -159.9678) (xy 415.826194 -160.01738) (xy 415.796727 -160.063232)
			(xy 415.761035 -160.104425) (xy 415.719844 -160.140119) (xy 415.673992 -160.169588) (xy 415.624413 -160.192231)
			(xy 415.572116 -160.207589) (xy 415.518166 -160.215347) (xy 415.490914 -160.215834) (xy 415.465679 -160.215426)
			(xy 415.415646 -160.208811) (xy 415.366925 -160.195641) (xy 415.320373 -160.176147) (xy 415.298382 -160.163764)
			(xy 415.28873 -160.157922) (xy 415.266632 -160.15589) (xy 415.172144 -160.189418) (xy 415.156142 -160.204912)
			(xy 415.152078 -160.215326) (xy 415.141347 -160.242087) (xy 415.113063 -160.292327) (xy 415.077537 -160.337735)
			(xy 415.03558 -160.377277) (xy 414.988148 -160.410052) (xy 414.936322 -160.435313) (xy 414.881285 -160.452484)
			(xy 414.824289 -160.461173) (xy 414.795462 -160.461706) (xy 414.76821 -160.461258) (xy 414.714261 -160.453496)
			(xy 414.661965 -160.438136) (xy 414.612388 -160.41549) (xy 414.566537 -160.38602) (xy 414.525347 -160.350324)
			(xy 414.489656 -160.309131) (xy 414.460191 -160.263277) (xy 414.43755 -160.213697) (xy 414.422196 -160.1614)
			(xy 414.41444 -160.10745) (xy 414.413954 -160.080198) (xy 414.414622 -160.048636) (xy 414.425005 -159.98637)
			(xy 414.445487 -159.926661) (xy 414.459928 -159.898588) (xy 414.464754 -159.889698) (xy 414.466786 -159.87014)
			(xy 414.441132 -159.782002) (xy 414.428686 -159.766508) (xy 414.419796 -159.761428) (xy 414.395872 -159.747575)
			(xy 414.351926 -159.71404) (xy 414.313275 -159.674516) (xy 414.296606 -159.652462) (xy 414.289012 -159.643056)
			(xy 414.267528 -159.63205) (xy 414.255458 -159.63138) (xy 413.064198 -159.63138) (xy 413.044192 -159.630946)
			(xy 413.004938 -159.623206) (xy 412.967953 -159.607946) (xy 412.934662 -159.585753) (xy 412.92018 -159.571944)
			(xy 412.391098 -159.042608) (xy 412.383614 -159.035919) (xy 412.365057 -159.028327) (xy 412.35503 -159.027876)
			(xy 405.262334 -159.027876) (xy 405.24232 -159.027403) (xy 405.203066 -159.01957) (xy 405.166091 -159.004237)
			(xy 405.132814 -158.981992) (xy 405.118316 -158.968186) (xy 397.025876 -150.875492) (xy 397.01839 -150.868805)
			(xy 396.999835 -150.86121) (xy 396.989808 -150.86076) (xy 394.291566 -150.86076) (xy 394.271553 -150.860272)
			(xy 394.2323 -150.852444) (xy 394.195324 -150.837116) (xy 394.162046 -150.814875) (xy 394.147548 -150.80107)
			(xy 392.417046 -149.070568) (xy 392.40321 -149.056094) (xy 392.380952 -149.022817) (xy 392.365622 -148.985833)
			(xy 392.357811 -148.946568) (xy 392.357356 -148.92655) (xy 392.357356 -146.228308) (xy 392.35702 -146.218259)
			(xy 392.349408 -146.199663) (xy 392.342624 -146.19224) (xy 390.32561 -144.17548) (xy 390.311774 -144.161006)
			(xy 390.289517 -144.127729) (xy 390.274188 -144.090745) (xy 390.266376 -144.05148) (xy 390.26592 -144.031462)
			(xy 390.26592 -138.866372) (xy 390.265561 -138.856325) (xy 390.257966 -138.837728) (xy 390.251188 -138.830304)
			(xy 387.494272 -136.073388) (xy 387.486788 -136.066698) (xy 387.468231 -136.059105) (xy 387.458204 -136.058656)
			(xy 385.57962 -136.058656) (xy 385.569382 -136.059111) (xy 385.550527 -136.067101) (xy 385.536262 -136.081792)
			(xy 385.532122 -136.091168) (xy 385.492498 -136.194546) (xy 385.499864 -136.225026) (xy 385.511548 -136.235694)
			(xy 385.53104 -136.253861) (xy 385.565292 -136.294676) (xy 385.593531 -136.339861) (xy 385.615207 -136.388535)
			(xy 385.629898 -136.439753) (xy 385.637319 -136.492517) (xy 385.637786 -136.519158) (xy 385.637359 -136.544541)
			(xy 385.630625 -136.594858) (xy 385.617284 -136.643839) (xy 385.597571 -136.690621) (xy 385.571833 -136.734379)
			(xy 385.556506 -136.754616) (xy 385.547362 -136.766046) (xy 385.544314 -136.794748) (xy 385.590796 -136.890252)
			(xy 385.595288 -136.89864) (xy 385.609267 -136.911528) (xy 385.627006 -136.918374) (xy 385.636516 -136.9187)
			(xy 386.014214 -136.9187) (xy 386.034226 -136.919211) (xy 386.073477 -136.927033) (xy 386.110452 -136.942355)
			(xy 386.143732 -136.964589) (xy 386.158232 -136.97839) (xy 388.811516 -139.631674) (xy 388.825291 -139.646182)
			(xy 388.847464 -139.679475) (xy 388.862723 -139.716451) (xy 388.870482 -139.755691) (xy 388.870952 -139.775692)
			(xy 388.870952 -140.902182) (xy 388.871361 -140.912537) (xy 388.87945 -140.931594) (xy 388.894433 -140.945883)
			(xy 388.903972 -140.949934) (xy 389.008112 -140.988796) (xy 389.038846 -140.980922) (xy 389.04926 -140.968984)
			(xy 389.067456 -140.948743) (xy 389.108633 -140.913149) (xy 389.154449 -140.883767) (xy 389.203975 -140.861192)
			(xy 389.256206 -140.845883) (xy 389.310082 -140.838149) (xy 389.337296 -140.837666) (xy 389.364547 -140.838181)
			(xy 389.418495 -140.845937) (xy 389.47079 -140.861292) (xy 389.520367 -140.883932) (xy 389.566217 -140.913398)
			(xy 389.607408 -140.949089) (xy 389.643099 -140.990279) (xy 389.672566 -141.03613) (xy 389.695207 -141.085707)
			(xy 389.710562 -141.138001) (xy 389.718319 -141.191949) (xy 389.718319 -141.246451) (xy 389.710562 -141.300399)
			(xy 389.695207 -141.352693) (xy 389.672566 -141.40227) (xy 389.643099 -141.448121) (xy 389.607408 -141.489311)
			(xy 389.566217 -141.525002) (xy 389.520367 -141.554468) (xy 389.47079 -141.577108) (xy 389.418495 -141.592463)
			(xy 389.364547 -141.600219) (xy 389.337296 -141.600682) (xy 389.310084 -141.600157) (xy 389.25621 -141.592434)
			(xy 389.203981 -141.577133) (xy 389.154457 -141.554563) (xy 389.108644 -141.525183) (xy 389.067472 -141.489589)
			(xy 389.04926 -141.469364) (xy 389.038846 -141.457426) (xy 389.008112 -141.449552) (xy 388.903972 -141.488414)
			(xy 388.894478 -141.492518) (xy 388.879573 -141.506833) (xy 388.871447 -141.525834) (xy 388.870952 -141.536166)
			(xy 388.870952 -142.646654) (xy 388.871515 -142.656638) (xy 388.879232 -142.67506) (xy 388.893398 -142.68914)
			(xy 388.902448 -142.69339) (xy 389.00354 -142.735554) (xy 389.033258 -142.729712) (xy 389.044434 -142.718536)
			(xy 389.066022 -142.697883) (xy 389.114427 -142.662868) (xy 389.1677 -142.63583) (xy 389.224538 -142.617429)
			(xy 389.283549 -142.608117) (xy 389.31342 -142.607538) (xy 389.340675 -142.607936) (xy 389.394631 -142.615697)
			(xy 389.446933 -142.631058) (xy 389.496516 -142.653706) (xy 389.542372 -142.683181) (xy 389.583565 -142.718881)
			(xy 389.619259 -142.760081) (xy 389.648725 -142.805942) (xy 389.671365 -142.855529) (xy 389.686717 -142.907833)
			(xy 389.694468 -142.96179) (xy 389.694928 -142.989046) (xy 389.69442 -143.008096) (xy 389.693912 -143.01851)
			(xy 389.70077 -143.037306) (xy 389.763762 -143.105886) (xy 389.78205 -143.114268) (xy 389.792464 -143.114776)
			(xy 389.819095 -143.116143) (xy 389.871619 -143.125347) (xy 389.922349 -143.141777) (xy 389.970296 -143.165112)
			(xy 390.014525 -143.194899) (xy 390.054174 -143.230556) (xy 390.08847 -143.271388) (xy 390.116745 -143.316598)
			(xy 390.138446 -143.365307) (xy 390.153152 -143.416563) (xy 390.160575 -143.469368) (xy 390.161018 -143.49603)
			(xy 390.160532 -143.523281) (xy 390.152776 -143.577229) (xy 390.137421 -143.629524) (xy 390.114779 -143.679101)
			(xy 390.085313 -143.724951) (xy 390.049622 -143.766142) (xy 390.008431 -143.801833) (xy 389.962581 -143.831299)
			(xy 389.913004 -143.853941) (xy 389.860709 -143.869296) (xy 389.806761 -143.877052) (xy 389.752259 -143.877052)
			(xy 389.698311 -143.869296) (xy 389.646016 -143.853941) (xy 389.596439 -143.831299) (xy 389.550589 -143.801833)
			(xy 389.509398 -143.766142) (xy 389.473707 -143.724951) (xy 389.444241 -143.679101) (xy 389.421599 -143.629524)
			(xy 389.406244 -143.577229) (xy 389.398488 -143.523281) (xy 389.398002 -143.49603) (xy 389.39851 -143.47698)
			(xy 389.399018 -143.466566) (xy 389.39216 -143.44777) (xy 389.329168 -143.37919) (xy 389.31088 -143.370808)
			(xy 389.300466 -143.3703) (xy 389.271926 -143.368833) (xy 389.215739 -143.358396) (xy 389.161739 -143.339694)
			(xy 389.111133 -143.313145) (xy 389.065053 -143.279344) (xy 389.044434 -143.259556) (xy 389.033258 -143.24838)
			(xy 389.00354 -143.242538) (xy 388.902448 -143.284702) (xy 388.893385 -143.288933) (xy 388.87921 -143.303019)
			(xy 388.871487 -143.321449) (xy 388.870952 -143.331438) (xy 388.870952 -144.307052) (xy 388.871389 -144.31712)
			(xy 388.8791 -144.335719) (xy 388.885938 -144.34312) (xy 390.233662 -145.69059) (xy 390.247479 -145.705081)
			(xy 390.269741 -145.738352) (xy 390.285076 -145.77533) (xy 390.292893 -145.814592) (xy 390.293352 -145.834608)
			(xy 390.293352 -147.147534) (xy 390.293892 -147.158595) (xy 390.303105 -147.178702) (xy 390.319931 -147.193056)
			(xy 390.330436 -147.196556) (xy 390.441434 -147.22729) (xy 390.47293 -147.21459) (xy 390.482074 -147.199858)
			(xy 390.504201 -147.16383) (xy 390.554252 -147.095681) (xy 390.610462 -147.032516) (xy 390.672338 -146.974889)
			(xy 390.739336 -146.923307) (xy 390.810869 -146.878223) (xy 390.886307 -146.840032) (xy 390.964989 -146.809071)
			(xy 391.046223 -146.78561) (xy 391.129297 -146.769855) (xy 391.213481 -146.761946) (xy 391.255758 -146.761454)
			(xy 391.298711 -146.762023) (xy 391.384229 -146.770185) (xy 391.468584 -146.78644) (xy 391.551012 -146.810639)
			(xy 391.630766 -146.842565) (xy 391.707124 -146.881927) (xy 391.779395 -146.92837) (xy 391.846924 -146.981472)
			(xy 391.909099 -147.040753) (xy 391.965357 -147.105675) (xy 392.015189 -147.175652) (xy 392.058144 -147.250049)
			(xy 392.093832 -147.328192) (xy 392.12193 -147.409373) (xy 392.142184 -147.492858) (xy 392.15441 -147.577891)
			(xy 392.158498 -147.6637) (xy 392.15441 -147.749509) (xy 392.142184 -147.834542) (xy 392.12193 -147.918027)
			(xy 392.093832 -147.999208) (xy 392.058144 -148.077351) (xy 392.015189 -148.151748) (xy 391.965357 -148.221725)
			(xy 391.909099 -148.286647) (xy 391.846924 -148.345928) (xy 391.779395 -148.39903) (xy 391.707124 -148.445473)
			(xy 391.630766 -148.484835) (xy 391.551012 -148.516761) (xy 391.468584 -148.54096) (xy 391.384229 -148.557215)
			(xy 391.298711 -148.565377) (xy 391.255758 -148.56587) (xy 391.213484 -148.565323) (xy 391.129306 -148.557407)
			(xy 391.046239 -148.541649) (xy 390.965011 -148.518186) (xy 390.886334 -148.487225) (xy 390.810901 -148.449038)
			(xy 390.739372 -148.403959) (xy 390.672375 -148.352385) (xy 390.610498 -148.294767) (xy 390.554285 -148.231612)
			(xy 390.504228 -148.163474) (xy 390.482074 -148.127466) (xy 390.47293 -148.112734) (xy 390.441434 -148.100034)
			(xy 390.330436 -148.130768) (xy 390.319966 -148.134333) (xy 390.303177 -148.148691) (xy 390.293913 -148.168746)
			(xy 390.293352 -148.17979) (xy 390.293352 -149.167596) (xy 390.293736 -149.17764) (xy 390.301314 -149.196237)
			(xy 390.308084 -149.203664) (xy 392.567668 -151.463248) (xy 392.575134 -151.46996) (xy 392.593705 -151.47754)
			(xy 392.603736 -151.47798) (xy 395.936724 -151.47798) (xy 395.956735 -151.478491) (xy 395.995987 -151.486314)
			(xy 396.032962 -151.501636) (xy 396.066242 -151.523869) (xy 396.080742 -151.53767) (xy 406.025096 -161.482024)
			(xy 406.038892 -161.496514) (xy 406.061062 -161.529812) (xy 406.076315 -161.566794) (xy 406.084067 -161.60604)
			(xy 406.084532 -161.626042) (xy 406.084532 -161.701988) (xy 410.43733 -161.701988) (xy 410.437846 -161.674415)
			(xy 410.445787 -161.619844) (xy 410.461501 -161.566985) (xy 410.484662 -161.516938) (xy 410.514786 -161.470747)
			(xy 410.551246 -161.429375) (xy 410.57195 -161.411158) (xy 410.580091 -161.403576) (xy 410.589431 -161.383409)
			(xy 410.589984 -161.372296) (xy 410.589984 -161.29508) (xy 410.589448 -161.283966) (xy 410.580088 -161.263807)
			(xy 410.57195 -161.256218) (xy 410.55123 -161.238017) (xy 410.514762 -161.196645) (xy 410.484632 -161.150454)
			(xy 410.461467 -161.100405) (xy 410.44575 -161.047542) (xy 410.43781 -160.992967) (xy 410.437811 -160.937817)
			(xy 410.445754 -160.883243) (xy 410.461472 -160.83038) (xy 410.484639 -160.780332) (xy 410.514772 -160.734142)
			(xy 410.551241 -160.692772) (xy 410.57195 -160.674558) (xy 410.580091 -160.666976) (xy 410.589431 -160.646809)
			(xy 410.589984 -160.635696) (xy 410.589984 -160.55848) (xy 410.589448 -160.547366) (xy 410.580088 -160.527207)
			(xy 410.57195 -160.519618) (xy 410.551234 -160.501412) (xy 410.514767 -160.460041) (xy 410.484636 -160.413849)
			(xy 410.461472 -160.363801) (xy 410.445756 -160.310938) (xy 410.437816 -160.256363) (xy 410.43733 -160.228788)
			(xy 410.437744 -160.201533) (xy 410.445503 -160.147578) (xy 410.460863 -160.095277) (xy 410.48351 -160.045694)
			(xy 410.512982 -159.99984) (xy 410.548681 -159.958646) (xy 410.58988 -159.922952) (xy 410.635738 -159.893486)
			(xy 410.685324 -159.870845) (xy 410.737627 -159.855493) (xy 410.791583 -159.84774) (xy 410.818838 -159.84728)
			(xy 410.846694 -159.847784) (xy 410.901809 -159.855912) (xy 410.955159 -159.871962) (xy 411.005611 -159.895592)
			(xy 411.052095 -159.926301) (xy 411.093624 -159.963438) (xy 411.129317 -160.006215) (xy 411.158417 -160.053723)
			(xy 411.180305 -160.104955) (xy 411.1879 -160.13176) (xy 411.190186 -160.14065) (xy 411.200854 -160.15589)
			(xy 411.272736 -160.203642) (xy 411.29077 -160.207706) (xy 411.299914 -160.206436) (xy 411.312931 -160.204767)
			(xy 411.339115 -160.202987) (xy 411.352238 -160.20288) (xy 411.366387 -160.20297) (xy 411.39461 -160.205007)
			(xy 411.408626 -160.206944) (xy 411.418786 -160.208468) (xy 411.438344 -160.203642) (xy 411.512766 -160.147762)
			(xy 411.522926 -160.130236) (xy 411.524196 -160.120076) (xy 411.528288 -160.092923) (xy 411.543259 -160.040092)
			(xy 411.565649 -159.989953) (xy 411.594995 -159.943541) (xy 411.630692 -159.901816) (xy 411.672002 -159.865639)
			(xy 411.718071 -159.835758) (xy 411.767948 -159.81279) (xy 411.820602 -159.797209) (xy 411.874946 -159.789337)
			(xy 411.902402 -159.78886) (xy 411.929652 -159.789376) (xy 411.983597 -159.797132) (xy 412.035889 -159.812486)
			(xy 412.085464 -159.835125) (xy 412.131313 -159.864588) (xy 412.172502 -159.900276) (xy 412.208194 -159.941463)
			(xy 412.237661 -159.987309) (xy 412.260304 -160.036883) (xy 412.275662 -160.089174) (xy 412.283422 -160.143118)
			(xy 412.28391 -160.170368) (xy 412.283419 -160.197942) (xy 412.275471 -160.252513) (xy 412.259751 -160.305372)
			(xy 412.236585 -160.355418) (xy 412.206458 -160.401609) (xy 412.169995 -160.442981) (xy 412.14929 -160.461198)
			(xy 412.141175 -160.468804) (xy 412.131819 -160.488953) (xy 412.131256 -160.50006) (xy 412.131256 -160.577276)
			(xy 412.131804 -160.588389) (xy 412.141155 -160.608548) (xy 412.14929 -160.616138) (xy 412.170021 -160.634328)
			(xy 412.20649 -160.675701) (xy 412.23662 -160.721895) (xy 412.259782 -160.771947) (xy 412.275494 -160.824814)
			(xy 412.283428 -160.879392) (xy 412.283462 -160.881314) (xy 416.872418 -160.881314) (xy 416.876489 -160.825692)
			(xy 416.888615 -160.771255) (xy 416.908538 -160.719164) (xy 416.935834 -160.670529) (xy 416.96992 -160.626386)
			(xy 417.010069 -160.587677) (xy 417.055427 -160.555226) (xy 417.105027 -160.529725) (xy 417.157811 -160.511718)
			(xy 417.212654 -160.501588) (xy 417.268388 -160.499551) (xy 417.323825 -160.505651) (xy 417.377782 -160.519757)
			(xy 417.429111 -160.541569) (xy 417.476717 -160.570623) (xy 417.519585 -160.606298) (xy 417.556802 -160.647835)
			(xy 417.587575 -160.694348) (xy 417.611247 -160.744845) (xy 417.627315 -160.798252) (xy 417.635435 -160.853428)
			(xy 417.635944 -160.881314) (xy 417.635435 -160.9092) (xy 417.627315 -160.964376) (xy 417.611247 -161.017783)
			(xy 417.587575 -161.06828) (xy 417.556802 -161.114793) (xy 417.519585 -161.15633) (xy 417.476717 -161.192005)
			(xy 417.429111 -161.221059) (xy 417.377782 -161.242871) (xy 417.323825 -161.256977) (xy 417.268388 -161.263077)
			(xy 417.212654 -161.26104) (xy 417.157811 -161.25091) (xy 417.105027 -161.232903) (xy 417.055427 -161.207402)
			(xy 417.010069 -161.174951) (xy 416.96992 -161.136242) (xy 416.935834 -161.092099) (xy 416.908538 -161.043464)
			(xy 416.888615 -160.991373) (xy 416.876489 -160.936936) (xy 416.872418 -160.881314) (xy 412.283462 -160.881314)
			(xy 412.28391 -160.906968) (xy 412.283415 -160.93422) (xy 412.275662 -160.98817) (xy 412.26031 -161.040467)
			(xy 412.237672 -161.090047) (xy 412.208207 -161.1359) (xy 412.172517 -161.177093) (xy 412.131327 -161.212787)
			(xy 412.085477 -161.242256) (xy 412.035899 -161.264899) (xy 411.983603 -161.280255) (xy 411.929654 -161.288013)
			(xy 411.902402 -161.288476) (xy 411.868112 -161.286952) (xy 411.857952 -161.285936) (xy 411.838648 -161.292032)
			(xy 411.768036 -161.351214) (xy 411.758638 -161.369248) (xy 411.757622 -161.379408) (xy 411.75463 -161.407576)
			(xy 411.741462 -161.462667) (xy 411.720289 -161.515204) (xy 411.691577 -161.56403) (xy 411.655957 -161.608072)
			(xy 411.614214 -161.646359) (xy 411.567266 -161.67805) (xy 411.516147 -161.702447) (xy 411.46198 -161.719013)
			(xy 411.405959 -161.727383) (xy 411.377638 -161.727896) (xy 411.359619 -161.72768) (xy 411.323744 -161.724243)
			(xy 411.30601 -161.721038) (xy 411.296612 -161.71926) (xy 411.277562 -161.72307) (xy 411.202378 -161.770822)
			(xy 411.190948 -161.78657) (xy 411.188662 -161.795968) (xy 411.181299 -161.823022) (xy 411.159665 -161.87475)
			(xy 411.130696 -161.922756) (xy 411.095016 -161.966007) (xy 411.053392 -162.003573) (xy 411.006721 -162.034646)
			(xy 410.956005 -162.058557) (xy 410.902338 -162.074791) (xy 410.846873 -162.082999) (xy 410.818838 -162.083496)
			(xy 410.791586 -162.083009) (xy 410.737635 -162.075257) (xy 410.685337 -162.059905) (xy 410.635756 -162.037266)
			(xy 410.589902 -162.007801) (xy 410.548709 -161.97211) (xy 410.513014 -161.930919) (xy 410.483546 -161.885067)
			(xy 410.460904 -161.835488) (xy 410.445548 -161.783191) (xy 410.437793 -161.72924) (xy 410.43733 -161.701988)
			(xy 406.084532 -161.701988) (xy 406.084532 -163.256214) (xy 412.105348 -163.256214) (xy 412.105858 -163.227297)
			(xy 412.114586 -163.170124) (xy 412.131845 -163.114924) (xy 412.157238 -163.062962) (xy 412.190184 -163.015429)
			(xy 412.229927 -162.973413) (xy 412.252414 -162.955224) (xy 412.261163 -162.94765) (xy 412.271353 -162.9269)
			(xy 412.271972 -162.915346) (xy 412.271972 -162.835082) (xy 412.271422 -162.823511) (xy 412.261214 -162.80274)
			(xy 412.252414 -162.795204) (xy 412.229935 -162.777007) (xy 412.190199 -162.734989) (xy 412.157259 -162.687456)
			(xy 412.13187 -162.635495) (xy 412.114613 -162.580299) (xy 412.105883 -162.52313) (xy 412.105348 -162.494214)
			(xy 412.105894 -162.466154) (xy 412.114126 -162.410641) (xy 412.1304 -162.356932) (xy 412.154364 -162.306186)
			(xy 412.185502 -162.259497) (xy 412.223142 -162.217872) (xy 412.266473 -162.182208) (xy 412.29026 -162.167316)
			(xy 412.299912 -162.161474) (xy 412.312104 -162.14344) (xy 412.329122 -162.04565) (xy 412.323534 -162.024568)
			(xy 412.316422 -162.015678) (xy 412.300531 -161.995603) (xy 412.273783 -161.951945) (xy 412.253257 -161.905041)
			(xy 412.239338 -161.855769) (xy 412.232287 -161.805057) (xy 412.23184 -161.779458) (xy 412.232317 -161.752843)
			(xy 412.239898 -161.700154) (xy 412.254898 -161.649081) (xy 412.277014 -161.600662) (xy 412.305794 -161.555882)
			(xy 412.340653 -161.515653) (xy 412.380882 -161.480794) (xy 412.425662 -161.452014) (xy 412.474081 -161.429898)
			(xy 412.525154 -161.414898) (xy 412.577843 -161.407317) (xy 412.604458 -161.40684) (xy 412.63088 -161.407278)
			(xy 412.683196 -161.414735) (xy 412.733934 -161.429505) (xy 412.782078 -161.451293) (xy 412.826663 -161.479661)
			(xy 412.847028 -161.496502) (xy 412.853886 -161.502598) (xy 412.870904 -161.508694) (xy 412.955232 -161.508694)
			(xy 412.97225 -161.502598) (xy 412.979108 -161.496502) (xy 412.999474 -161.479663) (xy 413.04406 -161.451298)
			(xy 413.092204 -161.429511) (xy 413.142941 -161.41474) (xy 413.195256 -161.40728) (xy 413.2481 -161.40728)
			(xy 413.300415 -161.41474) (xy 413.351152 -161.429511) (xy 413.399296 -161.451298) (xy 413.443882 -161.479663)
			(xy 413.464248 -161.496502) (xy 413.471106 -161.502598) (xy 413.488124 -161.508694) (xy 413.572452 -161.508694)
			(xy 413.58947 -161.502598) (xy 413.596328 -161.496502) (xy 413.616683 -161.479651) (xy 413.661276 -161.451298)
			(xy 413.709423 -161.429521) (xy 413.760162 -161.414756) (xy 413.812476 -161.407299) (xy 413.838898 -161.40684)
			(xy 413.866782 -161.407419) (xy 413.921926 -161.415731) (xy 413.975216 -161.432168) (xy 414.025461 -161.456364)
			(xy 414.071538 -161.487779) (xy 414.112419 -161.525711) (xy 414.147189 -161.569311) (xy 414.175073 -161.617607)
			(xy 414.195447 -161.669519) (xy 414.207856 -161.723889) (xy 414.212024 -161.7795) (xy 414.207856 -161.835111)
			(xy 414.195447 -161.889481) (xy 414.175073 -161.941393) (xy 414.147189 -161.989689) (xy 414.112419 -162.033289)
			(xy 414.071538 -162.071221) (xy 414.025461 -162.102636) (xy 413.975216 -162.126832) (xy 413.921926 -162.143269)
			(xy 413.866782 -162.151581) (xy 413.838898 -162.152076) (xy 413.812477 -162.151601) (xy 413.760163 -162.144153)
			(xy 413.709425 -162.129391) (xy 413.661281 -162.107611) (xy 413.616695 -162.079251) (xy 413.596328 -162.062414)
			(xy 413.58947 -162.056318) (xy 413.572452 -162.050222) (xy 413.488124 -162.050222) (xy 413.471106 -162.056318)
			(xy 413.464248 -162.062414) (xy 413.443882 -162.079253) (xy 413.399296 -162.107618) (xy 413.351152 -162.129405)
			(xy 413.300415 -162.144176) (xy 413.2481 -162.151636) (xy 413.195256 -162.151636) (xy 413.142941 -162.144176)
			(xy 413.092204 -162.129405) (xy 413.04406 -162.107618) (xy 412.999474 -162.079253) (xy 412.979108 -162.062414)
			(xy 412.97225 -162.056318) (xy 412.955232 -162.050222) (xy 412.870904 -162.050222) (xy 412.853886 -162.056318)
			(xy 412.847028 -162.062414) (xy 412.836226 -162.071478) (xy 412.813466 -162.088129) (xy 412.801562 -162.095688)
			(xy 412.79191 -162.10153) (xy 412.779972 -162.119818) (xy 412.764732 -162.218116) (xy 412.770574 -162.238944)
			(xy 412.77794 -162.24758) (xy 412.794941 -162.268341) (xy 412.823546 -162.31374) (xy 412.845507 -162.3627)
			(xy 412.860393 -162.414253) (xy 412.867909 -162.467384) (xy 412.868364 -162.494214) (xy 412.867797 -162.523129)
			(xy 412.85908 -162.580299) (xy 412.841833 -162.635497) (xy 412.81645 -162.687459) (xy 412.783514 -162.734994)
			(xy 412.74378 -162.777013) (xy 412.721298 -162.795204) (xy 412.712538 -162.802768) (xy 412.702354 -162.823525)
			(xy 412.70174 -162.835082) (xy 412.70174 -162.915346) (xy 412.702327 -162.926912) (xy 412.712509 -162.947684)
			(xy 412.721298 -162.955224) (xy 412.743793 -162.973402) (xy 412.783527 -163.015424) (xy 412.816465 -163.062962)
			(xy 412.841851 -163.114926) (xy 412.859105 -163.170126) (xy 412.867831 -163.227297) (xy 412.868364 -163.256214)
			(xy 412.867878 -163.283465) (xy 412.860122 -163.337413) (xy 412.844767 -163.389708) (xy 412.822125 -163.439285)
			(xy 412.792659 -163.485135) (xy 412.756968 -163.526326) (xy 412.715777 -163.562017) (xy 412.669927 -163.591483)
			(xy 412.62035 -163.614125) (xy 412.568055 -163.62948) (xy 412.514107 -163.637236) (xy 412.459605 -163.637236)
			(xy 412.405657 -163.62948) (xy 412.353362 -163.614125) (xy 412.303785 -163.591483) (xy 412.257935 -163.562017)
			(xy 412.216744 -163.526326) (xy 412.181053 -163.485135) (xy 412.151587 -163.439285) (xy 412.128945 -163.389708)
			(xy 412.11359 -163.337413) (xy 412.105834 -163.283465) (xy 412.105348 -163.256214) (xy 406.084532 -163.256214)
			(xy 406.084532 -163.806632) (xy 406.084933 -163.816704) (xy 406.09267 -163.835302) (xy 406.099518 -163.8427)
			(xy 406.128474 -163.871656) (xy 406.151334 -163.879022) (xy 406.163526 -163.87699) (xy 406.17829 -163.874834)
			(xy 406.208042 -163.872544) (xy 406.222962 -163.872418) (xy 406.250215 -163.872891) (xy 406.304167 -163.880643)
			(xy 406.356466 -163.895996) (xy 406.406048 -163.918636) (xy 406.451903 -163.948102) (xy 406.493096 -163.983795)
			(xy 406.528791 -164.024988) (xy 406.558259 -164.070841) (xy 406.5809 -164.120422) (xy 406.596254 -164.172721)
			(xy 406.604008 -164.226673) (xy 406.60447 -164.253926) (xy 406.603809 -164.285489) (xy 406.593423 -164.347754)
			(xy 406.572937 -164.407463) (xy 406.558496 -164.435536) (xy 406.55367 -164.444426) (xy 406.551638 -164.463984)
			(xy 406.577292 -164.552122) (xy 406.589738 -164.567616) (xy 406.598628 -164.572696) (xy 406.605994 -164.57676)
			(xy 406.615646 -164.582602) (xy 406.637744 -164.584634) (xy 406.732232 -164.551106) (xy 406.748234 -164.535612)
			(xy 406.752298 -164.525198) (xy 406.762978 -164.498415) (xy 406.791267 -164.448172) (xy 406.826799 -164.402762)
			(xy 406.868763 -164.363219) (xy 406.916203 -164.330446) (xy 406.968036 -164.305189) (xy 407.023082 -164.288026)
			(xy 407.080084 -164.279346) (xy 407.108914 -164.278818) (xy 407.136166 -164.279253) (xy 407.190116 -164.287011)
			(xy 407.242413 -164.302369) (xy 407.291992 -164.325012) (xy 407.337844 -164.354481) (xy 407.379035 -164.390175)
			(xy 407.414727 -164.431368) (xy 407.444194 -164.47722) (xy 407.466836 -164.5268) (xy 407.482192 -164.579097)
			(xy 407.489948 -164.633048) (xy 407.489948 -164.687552) (xy 407.482192 -164.741503) (xy 407.472839 -164.773356)
			(xy 407.731722 -164.773356) (xy 407.732177 -164.74588) (xy 407.740076 -164.691499) (xy 407.755703 -164.638816)
			(xy 407.778735 -164.588924) (xy 407.808693 -164.542857) (xy 407.826464 -164.521896) (xy 407.83256 -164.514784)
			(xy 407.83891 -164.497766) (xy 407.83891 -164.411914) (xy 407.83256 -164.394896) (xy 407.826464 -164.387784)
			(xy 407.808706 -164.366817) (xy 407.778781 -164.320736) (xy 407.755768 -164.270843) (xy 407.740141 -164.218167)
			(xy 407.732222 -164.163796) (xy 407.731722 -164.136324) (xy 407.732208 -164.109073) (xy 407.739964 -164.055125)
			(xy 407.755319 -164.00283) (xy 407.777961 -163.953253) (xy 407.807427 -163.907403) (xy 407.843118 -163.866212)
			(xy 407.884309 -163.830521) (xy 407.930159 -163.801055) (xy 407.979736 -163.778413) (xy 408.032031 -163.763058)
			(xy 408.085979 -163.755302) (xy 408.140481 -163.755302) (xy 408.194429 -163.763058) (xy 408.246724 -163.778413)
			(xy 408.296301 -163.801055) (xy 408.342151 -163.830521) (xy 408.383342 -163.866212) (xy 408.419033 -163.907403)
			(xy 408.448499 -163.953253) (xy 408.471141 -164.00283) (xy 408.486496 -164.055125) (xy 408.494252 -164.109073)
			(xy 408.494738 -164.136324) (xy 408.494256 -164.163799) (xy 408.486362 -164.218178) (xy 408.47074 -164.27086)
			(xy 408.447715 -164.320753) (xy 408.417763 -164.366822) (xy 408.399996 -164.387784) (xy 408.3939 -164.394896)
			(xy 408.38755 -164.411914) (xy 408.38755 -164.497766) (xy 408.3939 -164.514784) (xy 408.399996 -164.521896)
			(xy 408.417738 -164.542876) (xy 408.447667 -164.588952) (xy 408.470684 -164.638842) (xy 408.486314 -164.691515)
			(xy 408.494236 -164.745885) (xy 408.494738 -164.773356) (xy 408.494252 -164.800607) (xy 408.492619 -164.811964)
			(xy 409.069538 -164.811964) (xy 409.073609 -164.756342) (xy 409.085735 -164.701905) (xy 409.105658 -164.649814)
			(xy 409.132954 -164.601179) (xy 409.16704 -164.557036) (xy 409.207189 -164.518327) (xy 409.252547 -164.485876)
			(xy 409.302147 -164.460375) (xy 409.354931 -164.442368) (xy 409.409774 -164.432238) (xy 409.465508 -164.430201)
			(xy 409.520945 -164.436301) (xy 409.574902 -164.450407) (xy 409.626231 -164.472219) (xy 409.673837 -164.501273)
			(xy 409.716705 -164.536948) (xy 409.753922 -164.578485) (xy 409.784695 -164.624998) (xy 409.808367 -164.675495)
			(xy 409.824435 -164.728902) (xy 409.832555 -164.784078) (xy 409.833064 -164.811964) (xy 409.832555 -164.83985)
			(xy 409.824435 -164.895026) (xy 409.808367 -164.948433) (xy 409.784695 -164.99893) (xy 409.753922 -165.045443)
			(xy 409.716705 -165.08698) (xy 409.673837 -165.122655) (xy 409.626231 -165.151709) (xy 409.574902 -165.173521)
			(xy 409.520945 -165.187627) (xy 409.465508 -165.193727) (xy 409.409774 -165.19169) (xy 409.354931 -165.18156)
			(xy 409.302147 -165.163553) (xy 409.252547 -165.138052) (xy 409.207189 -165.105601) (xy 409.16704 -165.066892)
			(xy 409.132954 -165.022749) (xy 409.105658 -164.974114) (xy 409.085735 -164.922023) (xy 409.073609 -164.867586)
			(xy 409.069538 -164.811964) (xy 408.492619 -164.811964) (xy 408.486496 -164.854555) (xy 408.471141 -164.90685)
			(xy 408.448499 -164.956427) (xy 408.419033 -165.002277) (xy 408.383342 -165.043468) (xy 408.342151 -165.079159)
			(xy 408.296301 -165.108625) (xy 408.246724 -165.131267) (xy 408.194429 -165.146622) (xy 408.140481 -165.154378)
			(xy 408.085979 -165.154378) (xy 408.032031 -165.146622) (xy 407.979736 -165.131267) (xy 407.930159 -165.108625)
			(xy 407.884309 -165.079159) (xy 407.843118 -165.043468) (xy 407.807427 -165.002277) (xy 407.777961 -164.956427)
			(xy 407.755319 -164.90685) (xy 407.739964 -164.854555) (xy 407.732208 -164.800607) (xy 407.731722 -164.773356)
			(xy 407.472839 -164.773356) (xy 407.466836 -164.7938) (xy 407.444194 -164.84338) (xy 407.414727 -164.889232)
			(xy 407.379035 -164.930425) (xy 407.337844 -164.966119) (xy 407.291992 -164.995588) (xy 407.242413 -165.018231)
			(xy 407.190116 -165.033589) (xy 407.136166 -165.041347) (xy 407.108914 -165.041834) (xy 407.083679 -165.041426)
			(xy 407.033646 -165.034811) (xy 406.984925 -165.021641) (xy 406.938373 -165.002147) (xy 406.916382 -164.989764)
			(xy 406.90673 -164.983922) (xy 406.884632 -164.98189) (xy 406.790144 -165.015418) (xy 406.774142 -165.030912)
			(xy 406.770078 -165.041326) (xy 406.759347 -165.068087) (xy 406.731063 -165.118327) (xy 406.695537 -165.163735)
			(xy 406.65358 -165.203277) (xy 406.606148 -165.236052) (xy 406.554322 -165.261313) (xy 406.499285 -165.278484)
			(xy 406.442289 -165.287173) (xy 406.413462 -165.287706) (xy 406.38621 -165.287258) (xy 406.332261 -165.279496)
			(xy 406.279965 -165.264136) (xy 406.230388 -165.24149) (xy 406.184537 -165.21202) (xy 406.143347 -165.176324)
			(xy 406.107656 -165.135131) (xy 406.078191 -165.089277) (xy 406.05555 -165.039697) (xy 406.040196 -164.9874)
			(xy 406.03244 -164.93345) (xy 406.031954 -164.906198) (xy 406.032622 -164.874636) (xy 406.043005 -164.81237)
			(xy 406.063487 -164.752661) (xy 406.077928 -164.724588) (xy 406.082754 -164.715698) (xy 406.084786 -164.69614)
			(xy 406.059132 -164.608002) (xy 406.046686 -164.592508) (xy 406.037796 -164.587428) (xy 406.012678 -164.572907)
			(xy 405.966796 -164.537399) (xy 405.926822 -164.49535) (xy 405.893679 -164.447732) (xy 405.868131 -164.395642)
			(xy 405.850768 -164.340284) (xy 405.841991 -164.282935) (xy 405.841454 -164.253926) (xy 405.841575 -164.239006)
			(xy 405.843863 -164.209253) (xy 405.846026 -164.19449) (xy 405.848058 -164.182298) (xy 405.840692 -164.159438)
			(xy 405.73706 -164.05606) (xy 405.723313 -164.041526) (xy 405.701132 -164.008244) (xy 405.685864 -163.971276)
			(xy 405.678097 -163.932041) (xy 405.677624 -163.912042) (xy 405.677624 -161.731452) (xy 405.677191 -161.721383)
			(xy 405.669478 -161.702784) (xy 405.662638 -161.695384) (xy 395.867382 -151.900128) (xy 395.859901 -151.893435)
			(xy 395.841341 -151.885845) (xy 395.831314 -151.885396) (xy 392.498326 -151.885396) (xy 392.478313 -151.884922)
			(xy 392.439059 -151.877089) (xy 392.402084 -151.861756) (xy 392.368806 -151.839512) (xy 392.354308 -151.825706)
			(xy 389.945626 -149.417024) (xy 389.931766 -149.402572) (xy 389.909513 -149.369287) (xy 389.89419 -149.332297)
			(xy 389.886387 -149.293026) (xy 389.885936 -149.273006) (xy 389.885936 -145.940018) (xy 389.8856 -145.929969)
			(xy 389.877989 -145.911372) (xy 389.871204 -145.90395) (xy 388.52348 -144.55648) (xy 388.509682 -144.541992)
			(xy 388.487514 -144.508692) (xy 388.472261 -144.47171) (xy 388.464509 -144.432465) (xy 388.464044 -144.412462)
			(xy 388.464044 -142.695168) (xy 388.463586 -142.685753) (xy 388.456776 -142.668197) (xy 388.444086 -142.654285)
			(xy 388.43585 -142.649702) (xy 388.34187 -142.602458) (xy 388.313422 -142.604998) (xy 388.301738 -142.613634)
			(xy 388.276953 -142.631282) (xy 388.222931 -142.659268) (xy 388.165153 -142.678326) (xy 388.105082 -142.687975)
			(xy 388.074662 -142.688564) (xy 388.047409 -142.688164) (xy 387.99346 -142.680402) (xy 387.941163 -142.665042)
			(xy 387.891585 -142.642396) (xy 387.845734 -142.612925) (xy 387.804544 -142.577229) (xy 387.768852 -142.536035)
			(xy 387.739386 -142.490181) (xy 387.716745 -142.440601) (xy 387.70139 -142.388303) (xy 387.693634 -142.334353)
			(xy 387.693634 -142.279847) (xy 387.70139 -142.225897) (xy 387.716745 -142.173599) (xy 387.739386 -142.124019)
			(xy 387.768852 -142.078165) (xy 387.804544 -142.036971) (xy 387.845734 -142.001275) (xy 387.891585 -141.971804)
			(xy 387.941163 -141.949158) (xy 387.99346 -141.933798) (xy 388.047409 -141.926036) (xy 388.074662 -141.925548)
			(xy 388.105081 -141.926142) (xy 388.16515 -141.935793) (xy 388.222925 -141.954856) (xy 388.276941 -141.982848)
			(xy 388.301738 -142.000478) (xy 388.313422 -142.009114) (xy 388.34187 -142.011654) (xy 388.43585 -141.96441)
			(xy 388.44415 -141.959913) (xy 388.456866 -141.945975) (xy 388.463675 -141.928378) (xy 388.464044 -141.918944)
			(xy 388.464044 -139.881102) (xy 388.463632 -139.871031) (xy 388.455903 -139.852432) (xy 388.449058 -139.845034)
			(xy 385.944872 -137.340848) (xy 385.937392 -137.334153) (xy 385.918832 -137.326564) (xy 385.908804 -137.326116)
			(xy 380.346712 -137.326116) (xy 380.336664 -137.326461) (xy 380.318068 -137.334067) (xy 380.310644 -137.340848)
			(xy 380.103888 -137.547604) (xy 380.096522 -137.570464) (xy 380.098554 -137.582656) (xy 380.100714 -137.59742)
			(xy 380.103002 -137.627172) (xy 380.103126 -137.642092) (xy 380.103028 -137.652912) (xy 380.101757 -137.674515)
			(xy 380.100586 -137.685272) (xy 380.099316 -137.697718) (xy 380.108206 -137.720832) (xy 380.189486 -137.79246)
			(xy 380.213616 -137.798302) (xy 380.225808 -137.795254) (xy 380.24819 -137.79013) (xy 380.293781 -137.784658)
			(xy 380.31674 -137.784332) (xy 380.33166 -137.784456) (xy 380.361413 -137.786743) (xy 380.376176 -137.788904)
			(xy 380.388368 -137.790936) (xy 380.411228 -137.78357) (xy 380.675134 -137.51941) (xy 380.689602 -137.505568)
			(xy 380.722881 -137.483312) (xy 380.759867 -137.467984) (xy 380.799134 -137.460175) (xy 380.819152 -137.45972)
			(xy 385.009898 -137.45972) (xy 385.029909 -137.460236) (xy 385.069161 -137.468055) (xy 385.106136 -137.483376)
			(xy 385.139416 -137.505609) (xy 385.153916 -137.51941) (xy 387.402578 -139.768072) (xy 387.416436 -139.782525)
			(xy 387.43869 -139.81581) (xy 387.454013 -139.8528) (xy 387.461817 -139.892071) (xy 387.462268 -139.91209)
			(xy 387.462268 -147.663916) (xy 387.462637 -147.673962) (xy 387.470225 -147.692559) (xy 387.477 -147.699984)
			(xy 387.649466 -147.87245) (xy 387.657367 -147.879571) (xy 387.677192 -147.887206) (xy 387.698411 -147.886146)
			(xy 387.70814 -147.881848) (xy 387.808978 -147.83181) (xy 387.824218 -147.802854) (xy 387.821932 -147.786598)
			(xy 387.817996 -147.756017) (xy 387.8138 -147.694495) (xy 387.81355 -147.663662) (xy 387.814122 -147.62114)
			(xy 387.822129 -147.536473) (xy 387.838069 -147.452936) (xy 387.861799 -147.37127) (xy 387.893109 -147.292199)
			(xy 387.931721 -147.216425) (xy 387.977294 -147.144622) (xy 388.029421 -147.077426) (xy 388.08764 -147.015434)
			(xy 388.151435 -146.959196) (xy 388.22024 -146.909211) (xy 388.293443 -146.865923) (xy 388.370395 -146.829716)
			(xy 388.450413 -146.800912) (xy 388.532786 -146.779766) (xy 388.616784 -146.766466) (xy 388.701661 -146.761129)
			(xy 388.786663 -146.763804) (xy 388.871036 -146.774467) (xy 388.954031 -146.793022) (xy 389.034912 -146.819306)
			(xy 389.112961 -146.853085) (xy 389.187484 -146.894058) (xy 389.25782 -146.941863) (xy 389.323346 -146.996076)
			(xy 389.383478 -147.056214) (xy 389.437685 -147.121744) (xy 389.485484 -147.192085) (xy 389.526451 -147.266611)
			(xy 389.560222 -147.344663) (xy 389.586499 -147.425546) (xy 389.605047 -147.508543) (xy 389.615702 -147.592917)
			(xy 389.618369 -147.677919) (xy 389.613026 -147.762796) (xy 389.599718 -147.846792) (xy 389.578565 -147.929164)
			(xy 389.549753 -148.009179) (xy 389.51354 -148.086128) (xy 389.470245 -148.159327) (xy 389.420254 -148.228127)
			(xy 389.364011 -148.291917) (xy 389.302013 -148.350131) (xy 389.234813 -148.402252) (xy 389.163005 -148.447818)
			(xy 389.087228 -148.486424) (xy 389.008155 -148.517727) (xy 388.926486 -148.54145) (xy 388.842947 -148.557382)
			(xy 388.75828 -148.565381) (xy 388.715758 -148.56587) (xy 388.684925 -148.565624) (xy 388.623403 -148.561426)
			(xy 388.592822 -148.557488) (xy 388.576566 -148.555202) (xy 388.54761 -148.570442) (xy 388.497572 -148.67128)
			(xy 388.493344 -148.681028) (xy 388.492302 -148.702221) (xy 388.499887 -148.722037) (xy 388.50697 -148.729954)
			(xy 392.618976 -152.841706) (xy 392.63276 -152.856207) (xy 392.654933 -152.889501) (xy 392.67019 -152.926479)
			(xy 392.677945 -152.965722) (xy 392.678412 -152.985724) (xy 392.678412 -166.527988) (xy 402.05533 -166.527988)
			(xy 402.055846 -166.500415) (xy 402.063787 -166.445844) (xy 402.079501 -166.392985) (xy 402.102662 -166.342938)
			(xy 402.132786 -166.296747) (xy 402.169246 -166.255375) (xy 402.18995 -166.237158) (xy 402.198091 -166.229576)
			(xy 402.207431 -166.209409) (xy 402.207984 -166.198296) (xy 402.207984 -166.12108) (xy 402.207448 -166.109966)
			(xy 402.198088 -166.089807) (xy 402.18995 -166.082218) (xy 402.16923 -166.064017) (xy 402.132762 -166.022645)
			(xy 402.102632 -165.976454) (xy 402.079467 -165.926405) (xy 402.06375 -165.873542) (xy 402.05581 -165.818967)
			(xy 402.055811 -165.763817) (xy 402.063754 -165.709243) (xy 402.079472 -165.65638) (xy 402.102639 -165.606332)
			(xy 402.132772 -165.560142) (xy 402.169241 -165.518772) (xy 402.18995 -165.500558) (xy 402.198091 -165.492976)
			(xy 402.207431 -165.472809) (xy 402.207984 -165.461696) (xy 402.207984 -165.38448) (xy 402.207448 -165.373366)
			(xy 402.198088 -165.353207) (xy 402.18995 -165.345618) (xy 402.169234 -165.327412) (xy 402.132767 -165.286041)
			(xy 402.102636 -165.239849) (xy 402.079472 -165.189801) (xy 402.063756 -165.136938) (xy 402.055816 -165.082363)
			(xy 402.05533 -165.054788) (xy 402.055744 -165.027533) (xy 402.063503 -164.973578) (xy 402.078863 -164.921277)
			(xy 402.10151 -164.871694) (xy 402.130982 -164.82584) (xy 402.166681 -164.784646) (xy 402.20788 -164.748952)
			(xy 402.253738 -164.719486) (xy 402.303324 -164.696845) (xy 402.355627 -164.681493) (xy 402.409583 -164.67374)
			(xy 402.436838 -164.67328) (xy 402.464694 -164.673784) (xy 402.519809 -164.681912) (xy 402.573159 -164.697962)
			(xy 402.623611 -164.721592) (xy 402.670095 -164.752301) (xy 402.711624 -164.789438) (xy 402.747317 -164.832215)
			(xy 402.776417 -164.879723) (xy 402.798305 -164.930955) (xy 402.8059 -164.95776) (xy 402.808186 -164.96665)
			(xy 402.818854 -164.98189) (xy 402.890736 -165.029642) (xy 402.90877 -165.033706) (xy 402.917914 -165.032436)
			(xy 402.930931 -165.030767) (xy 402.957115 -165.028987) (xy 402.970238 -165.02888) (xy 402.984387 -165.02897)
			(xy 403.01261 -165.031007) (xy 403.026626 -165.032944) (xy 403.036786 -165.034468) (xy 403.056344 -165.029642)
			(xy 403.130766 -164.973762) (xy 403.140926 -164.956236) (xy 403.142196 -164.946076) (xy 403.146288 -164.918923)
			(xy 403.161259 -164.866092) (xy 403.183649 -164.815953) (xy 403.212995 -164.769541) (xy 403.248692 -164.727816)
			(xy 403.290002 -164.691639) (xy 403.336071 -164.661758) (xy 403.385948 -164.63879) (xy 403.438602 -164.623209)
			(xy 403.492946 -164.615337) (xy 403.520402 -164.61486) (xy 403.547652 -164.615376) (xy 403.601597 -164.623132)
			(xy 403.653889 -164.638486) (xy 403.703464 -164.661125) (xy 403.749313 -164.690588) (xy 403.790502 -164.726276)
			(xy 403.826194 -164.767463) (xy 403.855661 -164.813309) (xy 403.878304 -164.862883) (xy 403.893662 -164.915174)
			(xy 403.901422 -164.969118) (xy 403.90191 -164.996368) (xy 403.901419 -165.023942) (xy 403.893471 -165.078513)
			(xy 403.877751 -165.131372) (xy 403.854585 -165.181418) (xy 403.824458 -165.227609) (xy 403.787995 -165.268981)
			(xy 403.76729 -165.287198) (xy 403.759175 -165.294804) (xy 403.749819 -165.314953) (xy 403.749256 -165.32606)
			(xy 403.749256 -165.403276) (xy 403.749804 -165.414389) (xy 403.759155 -165.434548) (xy 403.76729 -165.442138)
			(xy 403.788021 -165.460328) (xy 403.82449 -165.501701) (xy 403.85462 -165.547895) (xy 403.877782 -165.597947)
			(xy 403.893494 -165.650814) (xy 403.901428 -165.705392) (xy 403.901462 -165.707314) (xy 408.490418 -165.707314)
			(xy 408.494489 -165.651692) (xy 408.506615 -165.597255) (xy 408.526538 -165.545164) (xy 408.553834 -165.496529)
			(xy 408.58792 -165.452386) (xy 408.628069 -165.413677) (xy 408.673427 -165.381226) (xy 408.723027 -165.355725)
			(xy 408.775811 -165.337718) (xy 408.830654 -165.327588) (xy 408.886388 -165.325551) (xy 408.941825 -165.331651)
			(xy 408.995782 -165.345757) (xy 409.047111 -165.367569) (xy 409.094717 -165.396623) (xy 409.137585 -165.432298)
			(xy 409.174802 -165.473835) (xy 409.205575 -165.520348) (xy 409.229247 -165.570845) (xy 409.245315 -165.624252)
			(xy 409.253435 -165.679428) (xy 409.253944 -165.707314) (xy 409.253435 -165.7352) (xy 409.245315 -165.790376)
			(xy 409.229247 -165.843783) (xy 409.205575 -165.89428) (xy 409.174802 -165.940793) (xy 409.137585 -165.98233)
			(xy 409.094717 -166.018005) (xy 409.047111 -166.047059) (xy 408.995782 -166.068871) (xy 408.941825 -166.082977)
			(xy 408.886388 -166.089077) (xy 408.830654 -166.08704) (xy 408.775811 -166.07691) (xy 408.723027 -166.058903)
			(xy 408.673427 -166.033402) (xy 408.628069 -166.000951) (xy 408.58792 -165.962242) (xy 408.553834 -165.918099)
			(xy 408.526538 -165.869464) (xy 408.506615 -165.817373) (xy 408.494489 -165.762936) (xy 408.490418 -165.707314)
			(xy 403.901462 -165.707314) (xy 403.90191 -165.732968) (xy 403.901415 -165.76022) (xy 403.893662 -165.81417)
			(xy 403.87831 -165.866467) (xy 403.855672 -165.916047) (xy 403.826207 -165.9619) (xy 403.790517 -166.003093)
			(xy 403.749327 -166.038787) (xy 403.703477 -166.068256) (xy 403.653899 -166.090899) (xy 403.601603 -166.106255)
			(xy 403.547654 -166.114013) (xy 403.520402 -166.114476) (xy 403.486112 -166.112952) (xy 403.475952 -166.111936)
			(xy 403.456648 -166.118032) (xy 403.386036 -166.177214) (xy 403.376638 -166.195248) (xy 403.375622 -166.205408)
			(xy 403.37263 -166.233576) (xy 403.359462 -166.288667) (xy 403.338289 -166.341204) (xy 403.309577 -166.39003)
			(xy 403.273957 -166.434072) (xy 403.232214 -166.472359) (xy 403.185266 -166.50405) (xy 403.134147 -166.528447)
			(xy 403.07998 -166.545013) (xy 403.023959 -166.553383) (xy 402.995638 -166.553896) (xy 402.977619 -166.55368)
			(xy 402.941744 -166.550243) (xy 402.92401 -166.547038) (xy 402.914612 -166.54526) (xy 402.895562 -166.54907)
			(xy 402.820378 -166.596822) (xy 402.808948 -166.61257) (xy 402.806662 -166.621968) (xy 402.799299 -166.649022)
			(xy 402.777665 -166.70075) (xy 402.748696 -166.748756) (xy 402.713016 -166.792007) (xy 402.671392 -166.829573)
			(xy 402.624721 -166.860646) (xy 402.574005 -166.884557) (xy 402.520338 -166.900791) (xy 402.464873 -166.908999)
			(xy 402.436838 -166.909496) (xy 402.409586 -166.909009) (xy 402.355635 -166.901257) (xy 402.303337 -166.885905)
			(xy 402.253756 -166.863266) (xy 402.207902 -166.833801) (xy 402.166709 -166.79811) (xy 402.131014 -166.756919)
			(xy 402.101546 -166.711067) (xy 402.078904 -166.661488) (xy 402.063548 -166.609191) (xy 402.055793 -166.55524)
			(xy 402.05533 -166.527988) (xy 392.678412 -166.527988) (xy 392.678412 -168.062148) (xy 392.678862 -168.072215)
			(xy 392.683003 -168.082214) (xy 403.723348 -168.082214) (xy 403.723858 -168.053297) (xy 403.732586 -167.996124)
			(xy 403.749845 -167.940924) (xy 403.775238 -167.888962) (xy 403.808184 -167.841429) (xy 403.847927 -167.799413)
			(xy 403.870414 -167.781224) (xy 403.879163 -167.77365) (xy 403.889353 -167.7529) (xy 403.889972 -167.741346)
			(xy 403.889972 -167.661082) (xy 403.889422 -167.649511) (xy 403.879214 -167.62874) (xy 403.870414 -167.621204)
			(xy 403.847935 -167.603007) (xy 403.808199 -167.560989) (xy 403.775259 -167.513456) (xy 403.74987 -167.461495)
			(xy 403.732613 -167.406299) (xy 403.723883 -167.34913) (xy 403.723348 -167.320214) (xy 403.723894 -167.292154)
			(xy 403.732126 -167.236641) (xy 403.7484 -167.182932) (xy 403.772364 -167.132186) (xy 403.803502 -167.085497)
			(xy 403.841142 -167.043872) (xy 403.884473 -167.008208) (xy 403.90826 -166.993316) (xy 403.917912 -166.987474)
			(xy 403.930104 -166.96944) (xy 403.947122 -166.87165) (xy 403.941534 -166.850568) (xy 403.934422 -166.841678)
			(xy 403.918531 -166.821603) (xy 403.891783 -166.777945) (xy 403.871257 -166.731041) (xy 403.857338 -166.681769)
			(xy 403.850287 -166.631057) (xy 403.84984 -166.605458) (xy 403.850317 -166.578843) (xy 403.857898 -166.526154)
			(xy 403.872898 -166.475081) (xy 403.895014 -166.426662) (xy 403.923794 -166.381882) (xy 403.958653 -166.341653)
			(xy 403.998882 -166.306794) (xy 404.043662 -166.278014) (xy 404.092081 -166.255898) (xy 404.143154 -166.240898)
			(xy 404.195843 -166.233317) (xy 404.222458 -166.23284) (xy 404.24888 -166.233278) (xy 404.301196 -166.240735)
			(xy 404.351934 -166.255505) (xy 404.400078 -166.277293) (xy 404.444663 -166.305661) (xy 404.465028 -166.322502)
			(xy 404.471886 -166.328598) (xy 404.488904 -166.334694) (xy 404.573232 -166.334694) (xy 404.59025 -166.328598)
			(xy 404.597108 -166.322502) (xy 404.617474 -166.305663) (xy 404.66206 -166.277298) (xy 404.710204 -166.255511)
			(xy 404.760941 -166.24074) (xy 404.813256 -166.23328) (xy 404.8661 -166.23328) (xy 404.918415 -166.24074)
			(xy 404.969152 -166.255511) (xy 405.017296 -166.277298) (xy 405.061882 -166.305663) (xy 405.082248 -166.322502)
			(xy 405.089106 -166.328598) (xy 405.106124 -166.334694) (xy 405.190452 -166.334694) (xy 405.20747 -166.328598)
			(xy 405.214328 -166.322502) (xy 405.234683 -166.305651) (xy 405.279276 -166.277298) (xy 405.327423 -166.255521)
			(xy 405.378162 -166.240756) (xy 405.430476 -166.233299) (xy 405.456898 -166.23284) (xy 405.484782 -166.233419)
			(xy 405.539926 -166.241731) (xy 405.593216 -166.258168) (xy 405.643461 -166.282364) (xy 405.689538 -166.313779)
			(xy 405.730419 -166.351711) (xy 405.765189 -166.395311) (xy 405.793073 -166.443607) (xy 405.813447 -166.495519)
			(xy 405.825856 -166.549889) (xy 405.830024 -166.6055) (xy 405.825856 -166.661111) (xy 405.813447 -166.715481)
			(xy 405.793073 -166.767393) (xy 405.765189 -166.815689) (xy 405.730419 -166.859289) (xy 405.689538 -166.897221)
			(xy 405.643461 -166.928636) (xy 405.593216 -166.952832) (xy 405.539926 -166.969269) (xy 405.484782 -166.977581)
			(xy 405.456898 -166.978076) (xy 405.430477 -166.977601) (xy 405.378163 -166.970153) (xy 405.327425 -166.955391)
			(xy 405.279281 -166.933611) (xy 405.234695 -166.905251) (xy 405.214328 -166.888414) (xy 405.20747 -166.882318)
			(xy 405.190452 -166.876222) (xy 405.106124 -166.876222) (xy 405.089106 -166.882318) (xy 405.082248 -166.888414)
			(xy 405.061882 -166.905253) (xy 405.017296 -166.933618) (xy 404.969152 -166.955405) (xy 404.918415 -166.970176)
			(xy 404.8661 -166.977636) (xy 404.813256 -166.977636) (xy 404.760941 -166.970176) (xy 404.710204 -166.955405)
			(xy 404.66206 -166.933618) (xy 404.617474 -166.905253) (xy 404.597108 -166.888414) (xy 404.59025 -166.882318)
			(xy 404.573232 -166.876222) (xy 404.488904 -166.876222) (xy 404.471886 -166.882318) (xy 404.465028 -166.888414)
			(xy 404.454226 -166.897478) (xy 404.431466 -166.914129) (xy 404.419562 -166.921688) (xy 404.40991 -166.92753)
			(xy 404.397972 -166.945818) (xy 404.382732 -167.044116) (xy 404.388574 -167.064944) (xy 404.39594 -167.07358)
			(xy 404.412941 -167.094341) (xy 404.441546 -167.13974) (xy 404.463507 -167.1887) (xy 404.478393 -167.240253)
			(xy 404.485909 -167.293384) (xy 404.486364 -167.320214) (xy 404.485797 -167.349129) (xy 404.47708 -167.406299)
			(xy 404.459833 -167.461497) (xy 404.43445 -167.513459) (xy 404.401514 -167.560994) (xy 404.36178 -167.603013)
			(xy 404.339298 -167.621204) (xy 404.330538 -167.628768) (xy 404.320354 -167.649525) (xy 404.31974 -167.661082)
			(xy 404.31974 -167.741346) (xy 404.320327 -167.752912) (xy 404.330509 -167.773684) (xy 404.339298 -167.781224)
			(xy 404.361793 -167.799402) (xy 404.401527 -167.841424) (xy 404.434465 -167.888962) (xy 404.459851 -167.940926)
			(xy 404.477105 -167.996126) (xy 404.485831 -168.053297) (xy 404.486364 -168.082214) (xy 404.485878 -168.109465)
			(xy 404.478122 -168.163413) (xy 404.462767 -168.215708) (xy 404.440125 -168.265285) (xy 404.410659 -168.311135)
			(xy 404.374968 -168.352326) (xy 404.333777 -168.388017) (xy 404.287927 -168.417483) (xy 404.23835 -168.440125)
			(xy 404.186055 -168.45548) (xy 404.132107 -168.463236) (xy 404.077605 -168.463236) (xy 404.023657 -168.45548)
			(xy 403.971362 -168.440125) (xy 403.921785 -168.417483) (xy 403.875935 -168.388017) (xy 403.834744 -168.352326)
			(xy 403.799053 -168.311135) (xy 403.769587 -168.265285) (xy 403.746945 -168.215708) (xy 403.73159 -168.163413)
			(xy 403.723834 -168.109465) (xy 403.723348 -168.082214) (xy 392.683003 -168.082214) (xy 392.686565 -168.090813)
			(xy 392.693398 -168.098216) (xy 396.72387 -172.128688) (xy 396.731331 -172.135407) (xy 396.749906 -172.142981)
			(xy 396.759938 -172.14342) (xy 397.415258 -172.14342) (xy 397.435271 -172.143899) (xy 397.474525 -172.15173)
			(xy 397.5115 -172.167061) (xy 397.544778 -172.189304) (xy 397.559276 -172.20311) (xy 397.804894 -172.448982)
			(xy 397.827754 -172.456348) (xy 397.839946 -172.454316) (xy 397.85471 -172.452157) (xy 397.884462 -172.449869)
			(xy 397.899382 -172.449744) (xy 397.926631 -172.450295) (xy 397.980573 -172.458048) (xy 398.032864 -172.473398)
			(xy 398.082438 -172.496034) (xy 398.128286 -172.525493) (xy 398.169475 -172.561178) (xy 398.205167 -172.602361)
			(xy 398.234635 -172.648204) (xy 398.257279 -172.697774) (xy 398.272638 -172.750062) (xy 398.2804 -172.804003)
			(xy 398.28089 -172.831252) (xy 398.280237 -172.862815) (xy 398.269847 -172.925081) (xy 398.249359 -172.98479)
			(xy 398.234916 -173.012862) (xy 398.23009 -173.021752) (xy 398.228058 -173.04131) (xy 398.253712 -173.129448)
			(xy 398.266158 -173.144942) (xy 398.275048 -173.150022) (xy 398.282414 -173.154086) (xy 398.292066 -173.159928)
			(xy 398.314164 -173.16196) (xy 398.408652 -173.128432) (xy 398.424654 -173.112938) (xy 398.428718 -173.102524)
			(xy 398.439395 -173.075739) (xy 398.467683 -173.025495) (xy 398.503214 -172.980083) (xy 398.545179 -172.94054)
			(xy 398.592619 -172.907766) (xy 398.644454 -172.88251) (xy 398.6995 -172.865348) (xy 398.756504 -172.85667)
			(xy 398.785334 -172.856144) (xy 398.81258 -172.856728) (xy 398.866517 -172.864488) (xy 398.918801 -172.879844)
			(xy 398.968368 -172.902484) (xy 399.014208 -172.931948) (xy 399.055389 -172.967635) (xy 399.091073 -173.008819)
			(xy 399.120532 -173.054662) (xy 399.143168 -173.10423) (xy 399.158519 -173.156516) (xy 399.166274 -173.210454)
			(xy 399.166274 -173.264946) (xy 399.158519 -173.318884) (xy 399.149183 -173.350682) (xy 399.408142 -173.350682)
			(xy 399.408607 -173.323206) (xy 399.416503 -173.268826) (xy 399.432127 -173.216143) (xy 399.455157 -173.16625)
			(xy 399.485114 -173.120183) (xy 399.502884 -173.099222) (xy 399.50898 -173.09211) (xy 399.51533 -173.075092)
			(xy 399.51533 -172.98924) (xy 399.50898 -172.972222) (xy 399.502884 -172.96511) (xy 399.485141 -172.944131)
			(xy 399.455214 -172.898053) (xy 399.432197 -172.848164) (xy 399.416566 -172.79549) (xy 399.408644 -172.741121)
			(xy 399.408142 -172.71365) (xy 399.408628 -172.686399) (xy 399.416384 -172.632451) (xy 399.431739 -172.580156)
			(xy 399.454381 -172.530579) (xy 399.483847 -172.484729) (xy 399.519538 -172.443538) (xy 399.560729 -172.407847)
			(xy 399.606579 -172.378381) (xy 399.656156 -172.355739) (xy 399.708451 -172.340384) (xy 399.762399 -172.332628)
			(xy 399.816901 -172.332628) (xy 399.870849 -172.340384) (xy 399.923144 -172.355739) (xy 399.972721 -172.378381)
			(xy 400.018571 -172.407847) (xy 400.059762 -172.443538) (xy 400.095453 -172.484729) (xy 400.124919 -172.530579)
			(xy 400.147561 -172.580156) (xy 400.162916 -172.632451) (xy 400.170672 -172.686399) (xy 400.171158 -172.71365)
			(xy 400.170711 -172.741126) (xy 400.162811 -172.795508) (xy 400.147183 -172.848191) (xy 400.124149 -172.898083)
			(xy 400.094188 -172.94415) (xy 400.076416 -172.96511) (xy 400.07032 -172.972222) (xy 400.06397 -172.98924)
			(xy 400.06397 -173.075092) (xy 400.07032 -173.09211) (xy 400.076416 -173.099222) (xy 400.094174 -173.120189)
			(xy 400.124099 -173.16627) (xy 400.147113 -173.216163) (xy 400.16274 -173.268839) (xy 400.170658 -173.32321)
			(xy 400.171158 -173.350682) (xy 400.170672 -173.377933) (xy 400.169039 -173.38929) (xy 400.745958 -173.38929)
			(xy 400.750029 -173.333668) (xy 400.762155 -173.279231) (xy 400.782078 -173.22714) (xy 400.809374 -173.178505)
			(xy 400.84346 -173.134362) (xy 400.883609 -173.095653) (xy 400.928967 -173.063202) (xy 400.978567 -173.037701)
			(xy 401.031351 -173.019694) (xy 401.086194 -173.009564) (xy 401.141928 -173.007527) (xy 401.197365 -173.013627)
			(xy 401.251322 -173.027733) (xy 401.302651 -173.049545) (xy 401.350257 -173.078599) (xy 401.393125 -173.114274)
			(xy 401.430342 -173.155811) (xy 401.461115 -173.202324) (xy 401.484787 -173.252821) (xy 401.500855 -173.306228)
			(xy 401.508975 -173.361404) (xy 401.509484 -173.38929) (xy 401.508975 -173.417176) (xy 401.500855 -173.472352)
			(xy 401.484787 -173.525759) (xy 401.461115 -173.576256) (xy 401.430342 -173.622769) (xy 401.393125 -173.664306)
			(xy 401.350257 -173.699981) (xy 401.302651 -173.729035) (xy 401.251322 -173.750847) (xy 401.197365 -173.764953)
			(xy 401.141928 -173.771053) (xy 401.086194 -173.769016) (xy 401.031351 -173.758886) (xy 400.978567 -173.740879)
			(xy 400.928967 -173.715378) (xy 400.883609 -173.682927) (xy 400.84346 -173.644218) (xy 400.809374 -173.600075)
			(xy 400.782078 -173.55144) (xy 400.762155 -173.499349) (xy 400.750029 -173.444912) (xy 400.745958 -173.38929)
			(xy 400.169039 -173.38929) (xy 400.162916 -173.431881) (xy 400.147561 -173.484176) (xy 400.124919 -173.533753)
			(xy 400.095453 -173.579603) (xy 400.059762 -173.620794) (xy 400.018571 -173.656485) (xy 399.972721 -173.685951)
			(xy 399.923144 -173.708593) (xy 399.870849 -173.723948) (xy 399.816901 -173.731704) (xy 399.762399 -173.731704)
			(xy 399.708451 -173.723948) (xy 399.656156 -173.708593) (xy 399.606579 -173.685951) (xy 399.560729 -173.656485)
			(xy 399.519538 -173.620794) (xy 399.483847 -173.579603) (xy 399.454381 -173.533753) (xy 399.431739 -173.484176)
			(xy 399.416384 -173.431881) (xy 399.408628 -173.377933) (xy 399.408142 -173.350682) (xy 399.149183 -173.350682)
			(xy 399.143168 -173.37117) (xy 399.120532 -173.420738) (xy 399.091073 -173.466581) (xy 399.055389 -173.507765)
			(xy 399.014208 -173.543452) (xy 398.968368 -173.572916) (xy 398.918801 -173.595556) (xy 398.866517 -173.610912)
			(xy 398.81258 -173.618672) (xy 398.785334 -173.61916) (xy 398.760098 -173.618784) (xy 398.710064 -173.612158)
			(xy 398.661343 -173.598979) (xy 398.614792 -173.579477) (xy 398.592802 -173.56709) (xy 398.58315 -173.561248)
			(xy 398.561052 -173.559216) (xy 398.466564 -173.592744) (xy 398.450562 -173.608238) (xy 398.446498 -173.618652)
			(xy 398.435848 -173.645448) (xy 398.407552 -173.695689) (xy 398.372015 -173.741098) (xy 398.330046 -173.780638)
			(xy 398.282602 -173.813409) (xy 398.230765 -173.838664) (xy 398.175717 -173.855826) (xy 398.118713 -173.864505)
			(xy 398.089882 -173.865032) (xy 398.062631 -173.864539) (xy 398.008685 -173.856781) (xy 397.956392 -173.841424)
			(xy 397.906816 -173.818783) (xy 397.860967 -173.789317) (xy 397.819778 -173.753626) (xy 397.784087 -173.712438)
			(xy 397.75462 -173.666589) (xy 397.731978 -173.617014) (xy 397.716621 -173.564721) (xy 397.708861 -173.510775)
			(xy 397.708374 -173.483524) (xy 397.709022 -173.451961) (xy 397.719415 -173.389695) (xy 397.739905 -173.329986)
			(xy 397.754348 -173.301914) (xy 397.759174 -173.293024) (xy 397.761206 -173.273466) (xy 397.735552 -173.185328)
			(xy 397.723106 -173.169834) (xy 397.714216 -173.164754) (xy 397.689114 -173.150207) (xy 397.643231 -173.114704)
			(xy 397.603256 -173.07266) (xy 397.57011 -173.025046) (xy 397.544559 -172.972961) (xy 397.527193 -172.917606)
			(xy 397.518413 -172.860259) (xy 397.517874 -172.831252) (xy 397.517997 -172.816332) (xy 397.520284 -172.786579)
			(xy 397.522446 -172.771816) (xy 397.524478 -172.759624) (xy 397.517112 -172.736764) (xy 397.345916 -172.565568)
			(xy 397.338453 -172.558851) (xy 397.31988 -172.551274) (xy 397.309848 -172.550836) (xy 396.654528 -172.550836)
			(xy 396.634515 -172.55035) (xy 396.595263 -172.542518) (xy 396.558288 -172.527189) (xy 396.525009 -172.504949)
			(xy 396.51051 -172.491146) (xy 392.33094 -168.311576) (xy 392.31715 -168.297081) (xy 392.294977 -168.263785)
			(xy 392.279722 -168.226805) (xy 392.271969 -168.18756) (xy 392.271504 -168.167558) (xy 392.271504 -153.091134)
			(xy 392.271086 -153.081063) (xy 392.263363 -153.062464) (xy 392.256518 -153.055066) (xy 387.114542 -147.913344)
			(xy 387.100694 -147.898881) (xy 387.078438 -147.8656) (xy 387.063111 -147.828613) (xy 387.055305 -147.789345)
			(xy 387.054852 -147.769326) (xy 387.054852 -140.0175) (xy 387.054469 -140.007456) (xy 387.046891 -139.988859)
			(xy 387.04012 -139.981432) (xy 384.940556 -137.881868) (xy 384.933079 -137.875169) (xy 384.914517 -137.867581)
			(xy 384.904488 -137.867136) (xy 380.924562 -137.867136) (xy 380.914516 -137.867502) (xy 380.89592 -137.875093)
			(xy 380.888494 -137.881868) (xy 380.69901 -138.071352) (xy 380.691644 -138.094212) (xy 380.693676 -138.106404)
			(xy 380.69583 -138.121168) (xy 380.698122 -138.15092) (xy 380.698248 -138.16584) (xy 380.697762 -138.193091)
			(xy 380.690006 -138.247039) (xy 380.674651 -138.299334) (xy 380.652009 -138.348911) (xy 380.622543 -138.394761)
			(xy 380.586852 -138.435952) (xy 380.545661 -138.471643) (xy 380.499811 -138.501109) (xy 380.450234 -138.523751)
			(xy 380.397939 -138.539106) (xy 380.393613 -138.539728) (xy 381.147572 -138.539728) (xy 381.151643 -138.484106)
			(xy 381.163769 -138.429669) (xy 381.183692 -138.377578) (xy 381.210988 -138.328943) (xy 381.245074 -138.2848)
			(xy 381.285223 -138.246091) (xy 381.330581 -138.21364) (xy 381.380181 -138.188139) (xy 381.432965 -138.170132)
			(xy 381.487808 -138.160002) (xy 381.543542 -138.157965) (xy 381.598979 -138.164065) (xy 381.652936 -138.178171)
			(xy 381.704265 -138.199983) (xy 381.751871 -138.229037) (xy 381.794739 -138.264712) (xy 381.831956 -138.306249)
			(xy 381.862729 -138.352762) (xy 381.886401 -138.403259) (xy 381.902469 -138.456666) (xy 381.910589 -138.511842)
			(xy 381.911098 -138.539728) (xy 381.910589 -138.567614) (xy 381.902469 -138.62279) (xy 381.886401 -138.676197)
			(xy 381.862729 -138.726694) (xy 381.831956 -138.773207) (xy 381.794739 -138.814744) (xy 381.751871 -138.850419)
			(xy 381.704265 -138.879473) (xy 381.652936 -138.901285) (xy 381.598979 -138.915391) (xy 381.543542 -138.921491)
			(xy 381.487808 -138.919454) (xy 381.432965 -138.909324) (xy 381.380181 -138.891317) (xy 381.330581 -138.865816)
			(xy 381.285223 -138.833365) (xy 381.245074 -138.794656) (xy 381.210988 -138.750513) (xy 381.183692 -138.701878)
			(xy 381.163769 -138.649787) (xy 381.151643 -138.59535) (xy 381.147572 -138.539728) (xy 380.393613 -138.539728)
			(xy 380.343991 -138.546862) (xy 380.289489 -138.546862) (xy 380.235541 -138.539106) (xy 380.183246 -138.523751)
			(xy 380.133669 -138.501109) (xy 380.087819 -138.471643) (xy 380.046628 -138.435952) (xy 380.010937 -138.394761)
			(xy 379.981471 -138.348911) (xy 379.958829 -138.299334) (xy 379.943474 -138.247039) (xy 379.935718 -138.193091)
			(xy 379.935232 -138.16584) (xy 379.935333 -138.15502) (xy 379.936601 -138.133417) (xy 379.937772 -138.12266)
			(xy 379.939042 -138.110214) (xy 379.930152 -138.0871) (xy 379.848872 -138.015472) (xy 379.824742 -138.00963)
			(xy 379.81255 -138.012678) (xy 379.790166 -138.017793) (xy 379.744577 -138.023271) (xy 379.721618 -138.0236)
			(xy 379.694365 -138.023128) (xy 379.640414 -138.015373) (xy 379.588116 -138.000019) (xy 379.538535 -137.977378)
			(xy 379.492682 -137.947911) (xy 379.451489 -137.912218) (xy 379.415795 -137.871026) (xy 379.386327 -137.825173)
			(xy 379.363684 -137.775593) (xy 379.348329 -137.723296) (xy 379.340573 -137.669345) (xy 379.34011 -137.642092)
			(xy 379.34042 -137.619982) (xy 379.345515 -137.576057) (xy 379.35027 -137.554462) (xy 379.353572 -137.541)
			(xy 379.345444 -137.514584) (xy 379.259338 -137.436098) (xy 379.232414 -137.43051) (xy 379.219206 -137.434828)
			(xy 379.189879 -137.443945) (xy 379.129261 -137.45377) (xy 379.098556 -137.454386) (xy 379.071305 -137.453941)
			(xy 379.017359 -137.446179) (xy 378.965067 -137.430819) (xy 378.915492 -137.408174) (xy 378.869645 -137.378705)
			(xy 378.828457 -137.343012) (xy 378.792768 -137.30182) (xy 378.763305 -137.255969) (xy 378.740665 -137.206392)
			(xy 378.725312 -137.154098) (xy 378.717556 -137.100151) (xy 378.424027 -137.100151) (xy 378.756926 -137.43305)
			(xy 378.770782 -137.447505) (xy 378.793034 -137.48079) (xy 378.808358 -137.517779) (xy 378.816163 -137.557049)
			(xy 378.816616 -137.577068) (xy 378.816616 -138.018266) (xy 378.817275 -138.030295) (xy 378.828141 -138.05176)
			(xy 378.837444 -138.059414) (xy 378.857948 -138.074852) (xy 378.895022 -138.110347) (xy 378.927 -138.150493)
			(xy 378.953306 -138.194565) (xy 378.973463 -138.241767) (xy 378.987109 -138.291246) (xy 378.993996 -138.342107)
			(xy 378.994416 -138.36777) (xy 378.993885 -138.395932) (xy 378.985608 -138.451644) (xy 378.96923 -138.505533)
			(xy 378.945106 -138.556429) (xy 378.91376 -138.603224) (xy 378.875875 -138.644902) (xy 378.832274 -138.680556)
			(xy 378.783904 -138.709412) (xy 378.731817 -138.730843) (xy 378.704602 -138.738102) (xy 378.690886 -138.741404)
			(xy 378.671582 -138.760454) (xy 378.643896 -138.859006) (xy 378.641886 -138.867769) (xy 378.643389 -138.885672)
			(xy 378.65098 -138.901955) (xy 378.657104 -138.908536) (xy 378.697236 -138.948922) (xy 378.704627 -138.955774)
			(xy 378.723233 -138.963486) (xy 378.733304 -138.963908) (xy 380.257558 -138.963908) (xy 380.277564 -138.964343)
			(xy 380.31682 -138.972079) (xy 380.353806 -138.987338) (xy 380.387096 -139.009533) (xy 380.401576 -139.023344)
			(xy 380.56439 -139.186158) (xy 384.74726 -139.186158) (xy 384.751331 -139.130536) (xy 384.763457 -139.076099)
			(xy 384.78338 -139.024008) (xy 384.810676 -138.975373) (xy 384.844762 -138.93123) (xy 384.884911 -138.892521)
			(xy 384.930269 -138.86007) (xy 384.979869 -138.834569) (xy 385.032653 -138.816562) (xy 385.087496 -138.806432)
			(xy 385.14323 -138.804395) (xy 385.198667 -138.810495) (xy 385.252624 -138.824601) (xy 385.303953 -138.846413)
			(xy 385.351559 -138.875467) (xy 385.394427 -138.911142) (xy 385.431644 -138.952679) (xy 385.462417 -138.999192)
			(xy 385.486089 -139.049689) (xy 385.502157 -139.103096) (xy 385.510277 -139.158272) (xy 385.510786 -139.186158)
			(xy 385.510277 -139.214044) (xy 385.502157 -139.26922) (xy 385.486089 -139.322627) (xy 385.462417 -139.373124)
			(xy 385.431644 -139.419637) (xy 385.394427 -139.461174) (xy 385.351559 -139.496849) (xy 385.303953 -139.525903)
			(xy 385.252624 -139.547715) (xy 385.198667 -139.561821) (xy 385.14323 -139.567921) (xy 385.087496 -139.565884)
			(xy 385.032653 -139.555754) (xy 384.979869 -139.537747) (xy 384.930269 -139.512246) (xy 384.884911 -139.479795)
			(xy 384.844762 -139.441086) (xy 384.810676 -139.396943) (xy 384.78338 -139.348308) (xy 384.763457 -139.296217)
			(xy 384.751331 -139.24178) (xy 384.74726 -139.186158) (xy 380.56439 -139.186158) (xy 381.093218 -139.714986)
			(xy 382.423668 -139.714986) (xy 382.427739 -139.659364) (xy 382.439865 -139.604927) (xy 382.459788 -139.552836)
			(xy 382.487084 -139.504201) (xy 382.52117 -139.460058) (xy 382.561319 -139.421349) (xy 382.606677 -139.388898)
			(xy 382.656277 -139.363397) (xy 382.709061 -139.34539) (xy 382.763904 -139.33526) (xy 382.819638 -139.333223)
			(xy 382.875075 -139.339323) (xy 382.929032 -139.353429) (xy 382.980361 -139.375241) (xy 383.027967 -139.404295)
			(xy 383.070835 -139.43997) (xy 383.108052 -139.481507) (xy 383.138825 -139.52802) (xy 383.162497 -139.578517)
			(xy 383.178565 -139.631924) (xy 383.186685 -139.6871) (xy 383.187194 -139.714986) (xy 383.186685 -139.742872)
			(xy 383.178565 -139.798048) (xy 383.162497 -139.851455) (xy 383.138825 -139.901952) (xy 383.108052 -139.948465)
			(xy 383.070835 -139.990002) (xy 383.027967 -140.025677) (xy 382.980361 -140.054731) (xy 382.929032 -140.076543)
			(xy 382.875075 -140.090649) (xy 382.819638 -140.096749) (xy 382.763904 -140.094712) (xy 382.709061 -140.084582)
			(xy 382.656277 -140.066575) (xy 382.606677 -140.041074) (xy 382.561319 -140.008623) (xy 382.52117 -139.969914)
			(xy 382.487084 -139.925771) (xy 382.459788 -139.877136) (xy 382.439865 -139.825045) (xy 382.427739 -139.770608)
			(xy 382.423668 -139.714986) (xy 381.093218 -139.714986) (xy 381.58039 -140.202158) (xy 384.767326 -140.202158)
			(xy 384.771397 -140.146536) (xy 384.783523 -140.092099) (xy 384.803446 -140.040008) (xy 384.830742 -139.991373)
			(xy 384.864828 -139.94723) (xy 384.904977 -139.908521) (xy 384.950335 -139.87607) (xy 384.999935 -139.850569)
			(xy 385.052719 -139.832562) (xy 385.107562 -139.822432) (xy 385.163296 -139.820395) (xy 385.218733 -139.826495)
			(xy 385.27269 -139.840601) (xy 385.324019 -139.862413) (xy 385.371625 -139.891467) (xy 385.414493 -139.927142)
			(xy 385.45171 -139.968679) (xy 385.482483 -140.015192) (xy 385.506155 -140.065689) (xy 385.522223 -140.119096)
			(xy 385.530343 -140.174272) (xy 385.530852 -140.202158) (xy 385.530343 -140.230044) (xy 385.522223 -140.28522)
			(xy 385.506155 -140.338627) (xy 385.482483 -140.389124) (xy 385.45171 -140.435637) (xy 385.414493 -140.477174)
			(xy 385.371625 -140.512849) (xy 385.324019 -140.541903) (xy 385.27269 -140.563715) (xy 385.218733 -140.577821)
			(xy 385.163296 -140.583921) (xy 385.107562 -140.581884) (xy 385.052719 -140.571754) (xy 384.999935 -140.553747)
			(xy 384.950335 -140.528246) (xy 384.904977 -140.495795) (xy 384.864828 -140.457086) (xy 384.830742 -140.412943)
			(xy 384.803446 -140.364308) (xy 384.783523 -140.312217) (xy 384.771397 -140.25778) (xy 384.767326 -140.202158)
			(xy 381.58039 -140.202158) (xy 381.696976 -140.318744) (xy 381.710731 -140.333271) (xy 381.732909 -140.366556)
			(xy 381.748174 -140.403526) (xy 381.755939 -140.442763) (xy 381.756412 -140.462762) (xy 381.756412 -140.810488)
			(xy 382.559558 -140.810488) (xy 382.563629 -140.754866) (xy 382.575755 -140.700429) (xy 382.595678 -140.648338)
			(xy 382.622974 -140.599703) (xy 382.65706 -140.55556) (xy 382.697209 -140.516851) (xy 382.742567 -140.4844)
			(xy 382.792167 -140.458899) (xy 382.844951 -140.440892) (xy 382.899794 -140.430762) (xy 382.955528 -140.428725)
			(xy 383.010965 -140.434825) (xy 383.064922 -140.448931) (xy 383.116251 -140.470743) (xy 383.163857 -140.499797)
			(xy 383.206725 -140.535472) (xy 383.243942 -140.577009) (xy 383.274715 -140.623522) (xy 383.298387 -140.674019)
			(xy 383.314455 -140.727426) (xy 383.322575 -140.782602) (xy 383.323084 -140.810488) (xy 383.322575 -140.838374)
			(xy 383.314455 -140.89355) (xy 383.298387 -140.946957) (xy 383.274715 -140.997454) (xy 383.243942 -141.043967)
			(xy 383.206725 -141.085504) (xy 383.163857 -141.121179) (xy 383.116251 -141.150233) (xy 383.064922 -141.172045)
			(xy 383.010965 -141.186151) (xy 382.955528 -141.192251) (xy 382.899794 -141.190214) (xy 382.844951 -141.180084)
			(xy 382.792167 -141.162077) (xy 382.742567 -141.136576) (xy 382.697209 -141.104125) (xy 382.65706 -141.065416)
			(xy 382.622974 -141.021273) (xy 382.595678 -140.972638) (xy 382.575755 -140.920547) (xy 382.563629 -140.86611)
			(xy 382.559558 -140.810488) (xy 381.756412 -140.810488) (xy 381.756412 -141.309852) (xy 385.56006 -141.309852)
			(xy 385.564131 -141.25423) (xy 385.576257 -141.199793) (xy 385.59618 -141.147702) (xy 385.623476 -141.099067)
			(xy 385.657562 -141.054924) (xy 385.697711 -141.016215) (xy 385.743069 -140.983764) (xy 385.792669 -140.958263)
			(xy 385.845453 -140.940256) (xy 385.900296 -140.930126) (xy 385.95603 -140.928089) (xy 386.011467 -140.934189)
			(xy 386.065424 -140.948295) (xy 386.116753 -140.970107) (xy 386.164359 -140.999161) (xy 386.207227 -141.034836)
			(xy 386.244444 -141.076373) (xy 386.275217 -141.122886) (xy 386.298889 -141.173383) (xy 386.314957 -141.22679)
			(xy 386.323077 -141.281966) (xy 386.323586 -141.309852) (xy 386.323077 -141.337738) (xy 386.314957 -141.392914)
			(xy 386.298889 -141.446321) (xy 386.275217 -141.496818) (xy 386.244444 -141.543331) (xy 386.207227 -141.584868)
			(xy 386.164359 -141.620543) (xy 386.116753 -141.649597) (xy 386.065424 -141.671409) (xy 386.011467 -141.685515)
			(xy 385.95603 -141.691615) (xy 385.900296 -141.689578) (xy 385.845453 -141.679448) (xy 385.792669 -141.661441)
			(xy 385.743069 -141.63594) (xy 385.697711 -141.603489) (xy 385.657562 -141.56478) (xy 385.623476 -141.520637)
			(xy 385.59618 -141.472002) (xy 385.576257 -141.419911) (xy 385.564131 -141.365474) (xy 385.56006 -141.309852)
			(xy 381.756412 -141.309852) (xy 381.756412 -142.842742) (xy 381.756812 -142.852814) (xy 381.76455 -142.871412)
			(xy 381.771398 -142.87881) (xy 382.342898 -143.45031) (xy 382.350507 -143.45726) (xy 382.36962 -143.464922)
			(xy 382.390208 -143.464509) (xy 382.399794 -143.460724) (xy 382.50114 -143.41475) (xy 382.517142 -143.387826)
			(xy 382.516126 -143.371824) (xy 382.515364 -143.346678) (xy 382.515982 -143.316694) (xy 382.525393 -143.257467)
			(xy 382.543933 -143.200435) (xy 382.55702 -143.17345) (xy 382.5621 -143.16329) (xy 382.562862 -143.141192)
			(xy 382.523746 -143.048482) (xy 382.50749 -143.03375) (xy 382.496568 -143.030448) (xy 382.470979 -143.022027)
			(xy 382.422288 -142.99898) (xy 382.377323 -142.969314) (xy 382.336976 -142.933619) (xy 382.30205 -142.892605)
			(xy 382.273239 -142.847087) (xy 382.251116 -142.797969) (xy 382.23612 -142.746228) (xy 382.22855 -142.692893)
			(xy 382.22809 -142.665958) (xy 382.228539 -142.638706) (xy 382.236301 -142.584757) (xy 382.251661 -142.532462)
			(xy 382.274307 -142.482884) (xy 382.303778 -142.437034) (xy 382.339473 -142.395845) (xy 382.380666 -142.360154)
			(xy 382.426519 -142.330688) (xy 382.476099 -142.308047) (xy 382.528396 -142.292692) (xy 382.582346 -142.284936)
			(xy 382.609598 -142.28445) (xy 382.626108 -142.284704) (xy 382.637792 -142.285212) (xy 382.659128 -142.276068)
			(xy 382.726438 -142.19682) (xy 382.73228 -142.174214) (xy 382.72974 -142.16253) (xy 382.726046 -142.143376)
			(xy 382.7221 -142.104565) (xy 382.721866 -142.08506) (xy 382.722421 -142.057812) (xy 382.730182 -142.003871)
			(xy 382.745541 -141.951584) (xy 382.768185 -141.902015) (xy 382.797652 -141.856172) (xy 382.833344 -141.81499)
			(xy 382.874533 -141.779307) (xy 382.920381 -141.749848) (xy 382.969955 -141.727215) (xy 383.022245 -141.711866)
			(xy 383.076187 -141.704116) (xy 383.130683 -141.704121) (xy 383.184624 -141.711881) (xy 383.236912 -141.727239)
			(xy 383.286481 -141.749882) (xy 383.332324 -141.779349) (xy 383.373506 -141.81504) (xy 383.40919 -141.856229)
			(xy 383.438649 -141.902077) (xy 383.461284 -141.95165) (xy 383.476633 -142.00394) (xy 383.484384 -142.057882)
			(xy 383.48438 -142.112379) (xy 383.47662 -142.16632) (xy 383.461262 -142.218607) (xy 383.43862 -142.268177)
			(xy 383.409153 -142.31402) (xy 383.373463 -142.355203) (xy 383.332275 -142.390887) (xy 383.286427 -142.420347)
			(xy 383.236854 -142.442982) (xy 383.184564 -142.458332) (xy 383.130622 -142.466084) (xy 383.103374 -142.466568)
			(xy 383.086864 -142.466314) (xy 383.07518 -142.465806) (xy 383.053844 -142.47495) (xy 382.986534 -142.554198)
			(xy 382.980692 -142.576804) (xy 382.983232 -142.588488) (xy 382.986929 -142.607641) (xy 382.990873 -142.646452)
			(xy 382.991106 -142.665958) (xy 382.990505 -142.695943) (xy 382.983157 -142.742158) (xy 385.5245 -142.742158)
			(xy 385.528571 -142.686536) (xy 385.540697 -142.632099) (xy 385.56062 -142.580008) (xy 385.587916 -142.531373)
			(xy 385.622002 -142.48723) (xy 385.662151 -142.448521) (xy 385.707509 -142.41607) (xy 385.757109 -142.390569)
			(xy 385.809893 -142.372562) (xy 385.864736 -142.362432) (xy 385.92047 -142.360395) (xy 385.975907 -142.366495)
			(xy 386.029864 -142.380601) (xy 386.081193 -142.402413) (xy 386.128799 -142.431467) (xy 386.171667 -142.467142)
			(xy 386.208884 -142.508679) (xy 386.239657 -142.555192) (xy 386.263329 -142.605689) (xy 386.279397 -142.659096)
			(xy 386.287517 -142.714272) (xy 386.288026 -142.742158) (xy 386.287517 -142.770044) (xy 386.279397 -142.82522)
			(xy 386.263329 -142.878627) (xy 386.239657 -142.929124) (xy 386.208884 -142.975637) (xy 386.171667 -143.017174)
			(xy 386.128799 -143.052849) (xy 386.081193 -143.081903) (xy 386.029864 -143.103715) (xy 385.975907 -143.117821)
			(xy 385.92047 -143.123921) (xy 385.864736 -143.121884) (xy 385.809893 -143.111754) (xy 385.757109 -143.093747)
			(xy 385.707509 -143.068246) (xy 385.662151 -143.035795) (xy 385.622002 -142.997086) (xy 385.587916 -142.952943)
			(xy 385.56062 -142.904308) (xy 385.540697 -142.852217) (xy 385.528571 -142.79778) (xy 385.5245 -142.742158)
			(xy 382.983157 -142.742158) (xy 382.981088 -142.755171) (xy 382.962541 -142.812202) (xy 382.94945 -142.839186)
			(xy 382.94437 -142.849346) (xy 382.943608 -142.871444) (xy 382.982724 -142.964154) (xy 382.99898 -142.978886)
			(xy 383.009902 -142.982188) (xy 383.035496 -142.990596) (xy 383.084189 -143.013642) (xy 383.129157 -143.043308)
			(xy 383.169505 -143.079004) (xy 383.204431 -143.12002) (xy 383.233242 -143.165541) (xy 383.255363 -143.214661)
			(xy 383.270356 -143.266404) (xy 383.277922 -143.319742) (xy 383.27838 -143.346678) (xy 383.277924 -143.373932)
			(xy 383.270169 -143.427884) (xy 383.254815 -143.480184) (xy 383.232173 -143.529766) (xy 383.202704 -143.57562)
			(xy 383.16701 -143.616814) (xy 383.125816 -143.652508) (xy 383.079961 -143.681976) (xy 383.030378 -143.704617)
			(xy 382.978078 -143.719971) (xy 382.924126 -143.727725) (xy 382.896872 -143.728186) (xy 382.871726 -143.727424)
			(xy 382.855724 -143.726408) (xy 382.8288 -143.74241) (xy 382.782826 -143.843756) (xy 382.779014 -143.853345)
			(xy 382.778538 -143.873949) (xy 382.786257 -143.893058) (xy 382.79324 -143.900652) (xy 391.221976 -152.329134)
			(xy 391.235773 -152.343623) (xy 391.257944 -152.376921) (xy 391.273197 -152.413903) (xy 391.280948 -152.453149)
			(xy 391.281412 -152.473152) (xy 391.281412 -166.493952) (xy 391.280967 -166.513958) (xy 391.273234 -166.553212)
			(xy 391.257977 -166.590198) (xy 391.235785 -166.623489) (xy 391.221976 -166.63797) (xy 386.174234 -171.685458)
			(xy 386.167425 -171.692883) (xy 386.159686 -171.711463) (xy 386.159248 -171.721526) (xy 386.159248 -173.21911)
			(xy 394.24737 -173.21911) (xy 394.247869 -173.190192) (xy 394.256598 -173.133019) (xy 394.273858 -173.077818)
			(xy 394.299253 -173.025856) (xy 394.332202 -172.978323) (xy 394.371948 -172.936308) (xy 394.394436 -172.91812)
			(xy 394.40319 -172.910551) (xy 394.413376 -172.889797) (xy 394.413994 -172.878242) (xy 394.413994 -172.797978)
			(xy 394.413381 -172.786416) (xy 394.403217 -172.765644) (xy 394.394436 -172.7581) (xy 394.37196 -172.7399)
			(xy 394.332223 -172.697883) (xy 394.299282 -172.65035) (xy 394.273892 -172.598391) (xy 394.256634 -172.543194)
			(xy 394.247905 -172.486026) (xy 394.24737 -172.45711) (xy 394.247888 -172.42986) (xy 394.255642 -172.375915)
			(xy 394.270995 -172.323622) (xy 394.293633 -172.274046) (xy 394.323096 -172.228197) (xy 394.358784 -172.187007)
			(xy 394.399971 -172.151316) (xy 394.445818 -172.121849) (xy 394.495392 -172.099206) (xy 394.547683 -172.083849)
			(xy 394.601628 -172.07609) (xy 394.628878 -172.075602) (xy 394.657633 -172.07612) (xy 394.714492 -172.08474)
			(xy 394.769411 -172.101804) (xy 394.821143 -172.126924) (xy 394.868516 -172.15953) (xy 394.910453 -172.198882)
			(xy 394.946002 -172.244087) (xy 394.974358 -172.294119) (xy 394.994877 -172.347843) (xy 395.001496 -172.37583)
			(xy 395.003782 -172.386244) (xy 395.015974 -172.402754) (xy 395.097508 -172.45203) (xy 395.117828 -172.454824)
			(xy 395.128242 -172.451776) (xy 395.153392 -172.445244) (xy 395.204877 -172.438231) (xy 395.230858 -172.437806)
			(xy 395.25811 -172.438294) (xy 395.312061 -172.446046) (xy 395.364359 -172.461397) (xy 395.41394 -172.484036)
			(xy 395.459794 -172.513501) (xy 395.500988 -172.549192) (xy 395.536682 -172.590383) (xy 395.56615 -172.636235)
			(xy 395.588793 -172.685814) (xy 395.604148 -172.738111) (xy 395.611904 -172.792062) (xy 395.612366 -172.819314)
			(xy 395.611926 -172.845003) (xy 395.60503 -172.895915) (xy 395.591363 -172.945442) (xy 395.571175 -172.992687)
			(xy 395.544828 -173.036795) (xy 395.512801 -173.076968) (xy 395.475673 -173.112481) (xy 395.45514 -173.127924)
			(xy 395.445742 -173.134782) (xy 395.43482 -173.154848) (xy 395.430248 -173.257718) (xy 395.439138 -173.2788)
			(xy 395.448028 -173.286674) (xy 395.4681 -173.304875) (xy 395.503432 -173.345953) (xy 395.532592 -173.39162)
			(xy 395.554992 -173.440956) (xy 395.570182 -173.492966) (xy 395.577854 -173.546603) (xy 395.57833 -173.573694)
			(xy 395.57785 -173.601268) (xy 395.569899 -173.65584) (xy 395.554176 -173.708699) (xy 395.531008 -173.758745)
			(xy 395.500879 -173.804935) (xy 395.464415 -173.846307) (xy 395.44371 -173.864524) (xy 395.435587 -173.872122)
			(xy 395.426235 -173.892277) (xy 395.425676 -173.903386) (xy 395.425676 -173.980602) (xy 395.426203 -173.991717)
			(xy 395.435568 -174.011877) (xy 395.44371 -174.019464) (xy 395.464409 -174.037688) (xy 395.50088 -174.079055)
			(xy 395.531013 -174.125242) (xy 395.554181 -174.175287) (xy 395.5699 -174.228147) (xy 395.577843 -174.28272)
			(xy 395.577877 -174.28464) (xy 400.166838 -174.28464) (xy 400.170909 -174.229018) (xy 400.183035 -174.174581)
			(xy 400.202958 -174.12249) (xy 400.230254 -174.073855) (xy 400.26434 -174.029712) (xy 400.304489 -173.991003)
			(xy 400.349847 -173.958552) (xy 400.399447 -173.933051) (xy 400.452231 -173.915044) (xy 400.507074 -173.904914)
			(xy 400.562808 -173.902877) (xy 400.618245 -173.908977) (xy 400.672202 -173.923083) (xy 400.723531 -173.944895)
			(xy 400.771137 -173.973949) (xy 400.814005 -174.009624) (xy 400.851222 -174.051161) (xy 400.881995 -174.097674)
			(xy 400.905667 -174.148171) (xy 400.921735 -174.201578) (xy 400.929855 -174.256754) (xy 400.930364 -174.28464)
			(xy 400.929855 -174.312526) (xy 400.921735 -174.367702) (xy 400.905667 -174.421109) (xy 400.881995 -174.471606)
			(xy 400.851222 -174.518119) (xy 400.814005 -174.559656) (xy 400.771137 -174.595331) (xy 400.723531 -174.624385)
			(xy 400.672202 -174.646197) (xy 400.618245 -174.660303) (xy 400.562808 -174.666403) (xy 400.507074 -174.664366)
			(xy 400.452231 -174.654236) (xy 400.399447 -174.636229) (xy 400.349847 -174.610728) (xy 400.304489 -174.578277)
			(xy 400.26434 -174.539568) (xy 400.230254 -174.495425) (xy 400.202958 -174.44679) (xy 400.183035 -174.394699)
			(xy 400.170909 -174.340262) (xy 400.166838 -174.28464) (xy 395.577877 -174.28464) (xy 395.57833 -174.310294)
			(xy 395.577817 -174.337544) (xy 395.570062 -174.39149) (xy 395.554708 -174.443783) (xy 395.532069 -174.493358)
			(xy 395.502606 -174.539208) (xy 395.466917 -174.580397) (xy 395.42573 -174.616089) (xy 395.379883 -174.645556)
			(xy 395.330309 -174.668199) (xy 395.278017 -174.683556) (xy 395.224072 -174.691315) (xy 395.196822 -174.691802)
			(xy 395.162532 -174.690278) (xy 395.152372 -174.689262) (xy 395.133068 -174.695358) (xy 395.062456 -174.75454)
			(xy 395.053058 -174.772574) (xy 395.052042 -174.782734) (xy 395.049052 -174.810902) (xy 395.035882 -174.865992)
			(xy 395.014706 -174.918527) (xy 394.985993 -174.967352) (xy 394.950373 -175.011393) (xy 394.90863 -175.04968)
			(xy 394.861683 -175.08137) (xy 394.810564 -175.105768) (xy 394.756399 -175.122335) (xy 394.700379 -175.130708)
			(xy 394.672058 -175.131222) (xy 394.644806 -175.130761) (xy 394.590858 -175.122999) (xy 394.538564 -175.10764)
			(xy 394.488988 -175.084995) (xy 394.443138 -175.055525) (xy 394.401949 -175.019831) (xy 394.366258 -174.978639)
			(xy 394.336792 -174.932788) (xy 394.314151 -174.88321) (xy 394.298795 -174.830914) (xy 394.291037 -174.776966)
			(xy 394.29055 -174.749714) (xy 394.291055 -174.721852) (xy 394.299155 -174.666721) (xy 394.315183 -174.613353)
			(xy 394.3388 -174.562882) (xy 394.369504 -174.516381) (xy 394.406643 -174.474838) (xy 394.42771 -174.456598)
			(xy 394.436854 -174.448978) (xy 394.446506 -174.427896) (xy 394.44295 -174.32401) (xy 394.432028 -174.303436)
			(xy 394.422376 -174.296324) (xy 394.401856 -174.280863) (xy 394.36472 -174.245358) (xy 394.332685 -174.20519)
			(xy 394.306333 -174.161085) (xy 394.286139 -174.113842) (xy 394.272469 -174.064316) (xy 394.26557 -174.013403)
			(xy 394.26515 -173.987714) (xy 394.265721 -173.959177) (xy 394.274209 -173.902738) (xy 394.291013 -173.848194)
			(xy 394.315757 -173.796762) (xy 394.347888 -173.749593) (xy 394.38669 -173.707738) (xy 394.40866 -173.689518)
			(xy 394.418058 -173.682152) (xy 394.427964 -173.660562) (xy 394.425678 -173.555914) (xy 394.414502 -173.535086)
			(xy 394.40485 -173.527974) (xy 394.384266 -173.512553) (xy 394.347079 -173.47702) (xy 394.315 -173.436815)
			(xy 394.28861 -173.392667) (xy 394.268388 -173.345375) (xy 394.254699 -173.295795) (xy 394.247791 -173.244827)
			(xy 394.24737 -173.21911) (xy 386.159248 -173.21911) (xy 386.159248 -174.770034) (xy 386.159643 -174.780107)
			(xy 386.167384 -174.798705) (xy 386.174234 -174.806102) (xy 388.025386 -176.657254) (xy 395.399768 -176.657254)
			(xy 395.4003 -176.628337) (xy 395.409022 -176.571166) (xy 395.426276 -176.515966) (xy 395.451665 -176.464004)
			(xy 395.484608 -176.41647) (xy 395.524349 -176.374454) (xy 395.546834 -176.356264) (xy 395.555613 -176.348719)
			(xy 395.565786 -176.327947) (xy 395.566392 -176.316386) (xy 395.566392 -176.236122) (xy 395.565812 -176.224555)
			(xy 395.555624 -176.203784) (xy 395.546834 -176.196244) (xy 395.524379 -176.17802) (xy 395.48464 -176.136008)
			(xy 395.451697 -176.08848) (xy 395.426303 -176.036525) (xy 395.409041 -175.981333) (xy 395.400306 -175.924168)
			(xy 395.399768 -175.895254) (xy 395.400301 -175.86727) (xy 395.408459 -175.811899) (xy 395.424621 -175.758315)
			(xy 395.448442 -175.707669) (xy 395.479408 -175.661048) (xy 395.516856 -175.619454) (xy 395.559981 -175.583779)
			(xy 395.583664 -175.568864) (xy 395.593316 -175.563022) (xy 395.605508 -175.545242) (xy 395.622272 -175.447706)
			(xy 395.616938 -175.426624) (xy 395.609826 -175.417988) (xy 395.594097 -175.39796) (xy 395.567643 -175.354446)
			(xy 395.547359 -175.307735) (xy 395.533624 -175.258697) (xy 395.526693 -175.208246) (xy 395.52626 -175.182784)
			(xy 395.526742 -175.156168) (xy 395.534319 -175.103479) (xy 395.549317 -175.052405) (xy 395.571431 -175.003984)
			(xy 395.60021 -174.959203) (xy 395.635069 -174.918974) (xy 395.675298 -174.884114) (xy 395.720079 -174.855334)
			(xy 395.768499 -174.833219) (xy 395.819573 -174.81822) (xy 395.872262 -174.810642) (xy 395.898878 -174.810166)
			(xy 395.925299 -174.810644) (xy 395.977613 -174.818091) (xy 396.028351 -174.832851) (xy 396.076496 -174.85463)
			(xy 396.121082 -174.882991) (xy 396.141448 -174.899828) (xy 396.148306 -174.905924) (xy 396.165324 -174.91202)
			(xy 396.249652 -174.91202) (xy 396.26667 -174.905924) (xy 396.273528 -174.899828) (xy 396.293894 -174.882989)
			(xy 396.33848 -174.854624) (xy 396.386624 -174.832837) (xy 396.437361 -174.818066) (xy 396.489676 -174.810606)
			(xy 396.54252 -174.810606) (xy 396.594835 -174.818066) (xy 396.645572 -174.832837) (xy 396.693716 -174.854624)
			(xy 396.738302 -174.882989) (xy 396.758668 -174.899828) (xy 396.765526 -174.905924) (xy 396.782544 -174.91202)
			(xy 396.866872 -174.91202) (xy 396.88389 -174.905924) (xy 396.890748 -174.899828) (xy 396.911099 -174.882972)
			(xy 396.955693 -174.854619) (xy 397.003841 -174.832842) (xy 397.054581 -174.818079) (xy 397.106896 -174.810624)
			(xy 397.133318 -174.810166) (xy 397.161201 -174.81072) (xy 397.216343 -174.819034) (xy 397.26963 -174.835473)
			(xy 397.319873 -174.859671) (xy 397.365947 -174.891086) (xy 397.406825 -174.929017) (xy 397.441594 -174.972617)
			(xy 397.469476 -175.020912) (xy 397.489849 -175.072823) (xy 397.502257 -175.12719) (xy 397.506425 -175.1828)
			(xy 397.502257 -175.23841) (xy 397.489849 -175.292777) (xy 397.469476 -175.344688) (xy 397.441594 -175.392983)
			(xy 397.406825 -175.436583) (xy 397.365947 -175.474514) (xy 397.319873 -175.505929) (xy 397.26963 -175.530127)
			(xy 397.216343 -175.546566) (xy 397.161201 -175.55488) (xy 397.133318 -175.555402) (xy 397.106897 -175.554933)
			(xy 397.054582 -175.547486) (xy 397.003843 -175.532723) (xy 396.955699 -175.510942) (xy 396.911113 -175.482579)
			(xy 396.890748 -175.46574) (xy 396.88389 -175.459644) (xy 396.866872 -175.453548) (xy 396.782544 -175.453548)
			(xy 396.765526 -175.459644) (xy 396.758668 -175.46574) (xy 396.738302 -175.482579) (xy 396.693716 -175.510944)
			(xy 396.645572 -175.532731) (xy 396.594835 -175.547502) (xy 396.54252 -175.554962) (xy 396.489676 -175.554962)
			(xy 396.437361 -175.547502) (xy 396.386624 -175.532731) (xy 396.33848 -175.510944) (xy 396.293894 -175.482579)
			(xy 396.273528 -175.46574) (xy 396.26667 -175.459644) (xy 396.249652 -175.453548) (xy 396.165324 -175.453548)
			(xy 396.148306 -175.459644) (xy 396.141448 -175.46574) (xy 396.130876 -175.474582) (xy 396.108628 -175.490856)
			(xy 396.096998 -175.498252) (xy 396.0876 -175.504348) (xy 396.075662 -175.522382) (xy 396.060168 -175.620172)
			(xy 396.06601 -175.641254) (xy 396.073376 -175.649636) (xy 396.090191 -175.670369) (xy 396.118506 -175.715623)
			(xy 396.140232 -175.764384) (xy 396.154944 -175.815698) (xy 396.162355 -175.868563) (xy 396.162784 -175.895254)
			(xy 396.162239 -175.92417) (xy 396.153516 -175.98134) (xy 396.136264 -176.036539) (xy 396.110877 -176.088501)
			(xy 396.077938 -176.136035) (xy 396.038202 -176.178053) (xy 396.015718 -176.196244) (xy 396.006927 -176.203777)
			(xy 395.996763 -176.224558) (xy 395.99616 -176.236122) (xy 395.99616 -176.316386) (xy 395.996718 -176.327956)
			(xy 396.006919 -176.348728) (xy 396.015718 -176.356264) (xy 396.038188 -176.374471) (xy 396.077923 -176.416488)
			(xy 396.110863 -176.46402) (xy 396.136254 -176.515978) (xy 396.153513 -176.571172) (xy 396.162247 -176.628339)
			(xy 396.162784 -176.657254) (xy 396.162298 -176.684505) (xy 396.154542 -176.738453) (xy 396.139187 -176.790748)
			(xy 396.116545 -176.840325) (xy 396.087079 -176.886175) (xy 396.051388 -176.927366) (xy 396.010197 -176.963057)
			(xy 395.964347 -176.992523) (xy 395.91477 -177.015165) (xy 395.862475 -177.03052) (xy 395.808527 -177.038276)
			(xy 395.754025 -177.038276) (xy 395.700077 -177.03052) (xy 395.647782 -177.015165) (xy 395.598205 -176.992523)
			(xy 395.552355 -176.963057) (xy 395.511164 -176.927366) (xy 395.475473 -176.886175) (xy 395.446007 -176.840325)
			(xy 395.423365 -176.790748) (xy 395.40801 -176.738453) (xy 395.400254 -176.684505) (xy 395.399768 -176.657254)
			(xy 388.025386 -176.657254) (xy 389.389874 -178.021742) (xy 389.412734 -178.029108) (xy 389.424926 -178.027076)
			(xy 389.43969 -178.024919) (xy 389.469442 -178.02263) (xy 389.484362 -178.022504) (xy 389.511614 -178.022991)
			(xy 389.565565 -178.030743) (xy 389.617863 -178.046095) (xy 389.667444 -178.068734) (xy 389.713298 -178.098199)
			(xy 389.754491 -178.13389) (xy 389.790186 -178.175081) (xy 389.819654 -178.220933) (xy 389.842296 -178.270512)
			(xy 389.857652 -178.322809) (xy 389.865407 -178.37676) (xy 389.86587 -178.404012) (xy 389.865203 -178.435575)
			(xy 389.854819 -178.49784) (xy 389.834336 -178.557549) (xy 389.819896 -178.585622) (xy 389.81507 -178.594512)
			(xy 389.813038 -178.61407) (xy 389.838692 -178.702208) (xy 389.851138 -178.717702) (xy 389.860028 -178.722782)
			(xy 389.867394 -178.726846) (xy 389.877046 -178.732688) (xy 389.899144 -178.73472) (xy 389.993632 -178.701192)
			(xy 390.009634 -178.685698) (xy 390.013698 -178.675284) (xy 390.024371 -178.648498) (xy 390.052662 -178.598255)
			(xy 390.088195 -178.552845) (xy 390.13016 -178.513303) (xy 390.177601 -178.480531) (xy 390.229435 -178.455275)
			(xy 390.284481 -178.438111) (xy 390.341484 -178.429432) (xy 390.370314 -178.428904) (xy 390.397565 -178.429367)
			(xy 390.451513 -178.437125) (xy 390.503808 -178.452482) (xy 390.553385 -178.475125) (xy 390.599235 -178.504592)
			(xy 390.640425 -178.540285) (xy 390.676116 -178.581476) (xy 390.705582 -178.627327) (xy 390.728223 -178.676905)
			(xy 390.743578 -178.7292) (xy 390.751334 -178.783149) (xy 390.751334 -178.837651) (xy 390.743578 -178.8916)
			(xy 390.734228 -178.923442) (xy 390.993122 -178.923442) (xy 390.993628 -178.895968) (xy 391.001514 -178.841589)
			(xy 391.017129 -178.788907) (xy 391.04015 -178.739014) (xy 391.070098 -178.692944) (xy 391.087864 -178.671982)
			(xy 391.09396 -178.66487) (xy 391.10031 -178.647852) (xy 391.10031 -178.562) (xy 391.09396 -178.544982)
			(xy 391.087864 -178.53787) (xy 391.070099 -178.516909) (xy 391.040176 -178.470826) (xy 391.017164 -178.420932)
			(xy 391.001538 -178.368255) (xy 390.993621 -178.313882) (xy 390.993122 -178.28641) (xy 390.993608 -178.259159)
			(xy 391.001364 -178.205211) (xy 391.016719 -178.152916) (xy 391.039361 -178.103339) (xy 391.068827 -178.057489)
			(xy 391.104518 -178.016298) (xy 391.145709 -177.980607) (xy 391.191559 -177.951141) (xy 391.241136 -177.928499)
			(xy 391.293431 -177.913144) (xy 391.347379 -177.905388) (xy 391.401881 -177.905388) (xy 391.455829 -177.913144)
			(xy 391.508124 -177.928499) (xy 391.557701 -177.951141) (xy 391.603551 -177.980607) (xy 391.644742 -178.016298)
			(xy 391.680433 -178.057489) (xy 391.709899 -178.103339) (xy 391.732541 -178.152916) (xy 391.747896 -178.205211)
			(xy 391.755652 -178.259159) (xy 391.756138 -178.28641) (xy 391.755648 -178.313884) (xy 391.747756 -178.368263)
			(xy 391.732136 -178.420945) (xy 391.709112 -178.470838) (xy 391.679162 -178.516907) (xy 391.661396 -178.53787)
			(xy 391.6553 -178.544982) (xy 391.64895 -178.562) (xy 391.64895 -178.647852) (xy 391.6553 -178.66487)
			(xy 391.661396 -178.671982) (xy 391.679132 -178.692967) (xy 391.709061 -178.739042) (xy 391.732079 -178.788931)
			(xy 391.747712 -178.841603) (xy 391.755635 -178.895971) (xy 391.756138 -178.923442) (xy 391.755652 -178.950693)
			(xy 391.754019 -178.96205) (xy 392.330938 -178.96205) (xy 392.335009 -178.906428) (xy 392.347135 -178.851991)
			(xy 392.367058 -178.7999) (xy 392.394354 -178.751265) (xy 392.42844 -178.707122) (xy 392.468589 -178.668413)
			(xy 392.513947 -178.635962) (xy 392.563547 -178.610461) (xy 392.616331 -178.592454) (xy 392.671174 -178.582324)
			(xy 392.726908 -178.580287) (xy 392.782345 -178.586387) (xy 392.836302 -178.600493) (xy 392.887631 -178.622305)
			(xy 392.935237 -178.651359) (xy 392.978105 -178.687034) (xy 393.015322 -178.728571) (xy 393.046095 -178.775084)
			(xy 393.069767 -178.825581) (xy 393.085835 -178.878988) (xy 393.093955 -178.934164) (xy 393.094464 -178.96205)
			(xy 393.093955 -178.989936) (xy 393.085835 -179.045112) (xy 393.069767 -179.098519) (xy 393.046095 -179.149016)
			(xy 393.015322 -179.195529) (xy 392.978105 -179.237066) (xy 392.935237 -179.272741) (xy 392.887631 -179.301795)
			(xy 392.836302 -179.323607) (xy 392.782345 -179.337713) (xy 392.726908 -179.343813) (xy 392.671174 -179.341776)
			(xy 392.616331 -179.331646) (xy 392.563547 -179.313639) (xy 392.513947 -179.288138) (xy 392.468589 -179.255687)
			(xy 392.42844 -179.216978) (xy 392.394354 -179.172835) (xy 392.367058 -179.1242) (xy 392.347135 -179.072109)
			(xy 392.335009 -179.017672) (xy 392.330938 -178.96205) (xy 391.754019 -178.96205) (xy 391.747896 -179.004641)
			(xy 391.732541 -179.056936) (xy 391.709899 -179.106513) (xy 391.680433 -179.152363) (xy 391.644742 -179.193554)
			(xy 391.603551 -179.229245) (xy 391.557701 -179.258711) (xy 391.508124 -179.281353) (xy 391.455829 -179.296708)
			(xy 391.401881 -179.304464) (xy 391.347379 -179.304464) (xy 391.293431 -179.296708) (xy 391.241136 -179.281353)
			(xy 391.191559 -179.258711) (xy 391.145709 -179.229245) (xy 391.104518 -179.193554) (xy 391.068827 -179.152363)
			(xy 391.039361 -179.106513) (xy 391.016719 -179.056936) (xy 391.001364 -179.004641) (xy 390.993608 -178.950693)
			(xy 390.993122 -178.923442) (xy 390.734228 -178.923442) (xy 390.728223 -178.943895) (xy 390.705582 -178.993473)
			(xy 390.676116 -179.039324) (xy 390.640425 -179.080515) (xy 390.599235 -179.116208) (xy 390.553385 -179.145675)
			(xy 390.503808 -179.168318) (xy 390.451513 -179.183675) (xy 390.397565 -179.191433) (xy 390.370314 -179.19192)
			(xy 390.345079 -179.191514) (xy 390.295045 -179.184898) (xy 390.246325 -179.171728) (xy 390.199773 -179.152234)
			(xy 390.177782 -179.13985) (xy 390.16813 -179.134008) (xy 390.146032 -179.131976) (xy 390.051544 -179.165504)
			(xy 390.035542 -179.180998) (xy 390.031478 -179.191412) (xy 390.02074 -179.21817) (xy 389.992457 -179.26841)
			(xy 389.956933 -179.313819) (xy 389.914977 -179.353362) (xy 389.867546 -179.386137) (xy 389.815721 -179.411399)
			(xy 389.760684 -179.428569) (xy 389.703689 -179.437259) (xy 389.674862 -179.437792) (xy 389.647609 -179.437357)
			(xy 389.593659 -179.429595) (xy 389.541362 -179.414235) (xy 389.491784 -179.391588) (xy 389.445933 -179.362116)
			(xy 389.404742 -179.326419) (xy 389.369051 -179.285224) (xy 389.339586 -179.239369) (xy 389.316946 -179.189787)
			(xy 389.301593 -179.137488) (xy 389.293839 -179.083537) (xy 389.293354 -179.056284) (xy 389.294016 -179.024721)
			(xy 389.304401 -178.962456) (xy 389.324886 -178.902747) (xy 389.339328 -178.874674) (xy 389.344154 -178.865784)
			(xy 389.346186 -178.846226) (xy 389.320532 -178.758088) (xy 389.308086 -178.742594) (xy 389.299196 -178.737514)
			(xy 389.274072 -178.723003) (xy 389.22819 -178.687493) (xy 389.188216 -178.645443) (xy 389.155073 -178.597823)
			(xy 389.129526 -178.545732) (xy 389.112165 -178.490372) (xy 389.10339 -178.433021) (xy 389.102854 -178.404012)
			(xy 389.102973 -178.389092) (xy 389.105263 -178.359339) (xy 389.107426 -178.344576) (xy 389.109458 -178.332384)
			(xy 389.102092 -178.309524) (xy 385.811776 -175.019462) (xy 385.798033 -175.004924) (xy 385.77585 -174.971644)
			(xy 385.760582 -174.934677) (xy 385.752814 -174.895442) (xy 385.75234 -174.875444) (xy 385.75234 -171.616116)
			(xy 385.752779 -171.59611) (xy 385.760517 -171.556856) (xy 385.775775 -171.519871) (xy 385.797967 -171.48658)
			(xy 385.811776 -171.472098) (xy 390.859518 -166.42461) (xy 390.866348 -166.417203) (xy 390.874073 -166.398609)
			(xy 390.874504 -166.388542) (xy 390.874504 -152.578562) (xy 390.874124 -152.568487) (xy 390.866374 -152.549888)
			(xy 390.859518 -152.542494) (xy 381.40894 -143.09217) (xy 381.395147 -143.077677) (xy 381.372975 -143.04438)
			(xy 381.35772 -143.0074) (xy 381.349969 -142.968154) (xy 381.349504 -142.948152) (xy 381.349504 -140.568172)
			(xy 381.349119 -140.558098) (xy 381.341373 -140.539499) (xy 381.334518 -140.532104) (xy 380.188216 -139.385802)
			(xy 380.180804 -139.378977) (xy 380.162214 -139.371248) (xy 380.152148 -139.370816) (xy 378.627894 -139.370816)
			(xy 378.607887 -139.370403) (xy 378.568631 -139.362659) (xy 378.531645 -139.347393) (xy 378.498356 -139.325193)
			(xy 378.483876 -139.31138) (xy 377.136152 -137.963402) (xy 377.113292 -137.956036) (xy 377.1011 -137.958068)
			(xy 377.086336 -137.960221) (xy 377.056584 -137.962513) (xy 377.041664 -137.96264) (xy 377.015502 -137.961624)
			(xy 377.004326 -137.960862) (xy 376.984006 -137.968482) (xy 376.976132 -137.97661) (xy 376.969334 -137.983949)
			(xy 376.961683 -138.00242) (xy 376.96169 -138.022413) (xy 376.969353 -138.040879) (xy 376.976132 -138.048238)
			(xy 377.607576 -138.679682) (xy 377.621349 -138.694193) (xy 377.643524 -138.727484) (xy 377.658784 -138.764459)
			(xy 377.666543 -138.803699) (xy 377.667012 -138.8237) (xy 377.667012 -144.395952) (xy 377.666567 -144.415958)
			(xy 377.658834 -144.455212) (xy 377.643577 -144.492198) (xy 377.621385 -144.525489) (xy 377.607576 -144.53997)
			(xy 377.119345 -145.028158) (xy 381.31826 -145.028158) (xy 381.322331 -144.972536) (xy 381.334457 -144.918099)
			(xy 381.35438 -144.866008) (xy 381.381676 -144.817373) (xy 381.415762 -144.77323) (xy 381.455911 -144.734521)
			(xy 381.501269 -144.70207) (xy 381.550869 -144.676569) (xy 381.603653 -144.658562) (xy 381.658496 -144.648432)
			(xy 381.71423 -144.646395) (xy 381.769667 -144.652495) (xy 381.823624 -144.666601) (xy 381.874953 -144.688413)
			(xy 381.922559 -144.717467) (xy 381.965427 -144.753142) (xy 382.002644 -144.794679) (xy 382.033417 -144.841192)
			(xy 382.057089 -144.891689) (xy 382.073157 -144.945096) (xy 382.081277 -145.000272) (xy 382.081786 -145.028158)
			(xy 382.081277 -145.056044) (xy 382.073157 -145.11122) (xy 382.057089 -145.164627) (xy 382.033417 -145.215124)
			(xy 382.002644 -145.261637) (xy 381.965427 -145.303174) (xy 381.922559 -145.338849) (xy 381.874953 -145.367903)
			(xy 381.823624 -145.389715) (xy 381.769667 -145.403821) (xy 381.71423 -145.409921) (xy 381.658496 -145.407884)
			(xy 381.603653 -145.397754) (xy 381.550869 -145.379747) (xy 381.501269 -145.354246) (xy 381.455911 -145.321795)
			(xy 381.415762 -145.283086) (xy 381.381676 -145.238943) (xy 381.35438 -145.190308) (xy 381.334457 -145.138217)
			(xy 381.322331 -145.08378) (xy 381.31826 -145.028158) (xy 377.119345 -145.028158) (xy 375.690468 -146.456908)
			(xy 378.786388 -146.456908) (xy 378.790459 -146.401286) (xy 378.802585 -146.346849) (xy 378.822508 -146.294758)
			(xy 378.849804 -146.246123) (xy 378.88389 -146.20198) (xy 378.924039 -146.163271) (xy 378.969397 -146.13082)
			(xy 379.018997 -146.105319) (xy 379.071781 -146.087312) (xy 379.126624 -146.077182) (xy 379.182358 -146.075145)
			(xy 379.237795 -146.081245) (xy 379.291752 -146.095351) (xy 379.343081 -146.117163) (xy 379.390687 -146.146217)
			(xy 379.420657 -146.171158) (xy 383.09626 -146.171158) (xy 383.100331 -146.115536) (xy 383.112457 -146.061099)
			(xy 383.13238 -146.009008) (xy 383.159676 -145.960373) (xy 383.193762 -145.91623) (xy 383.233911 -145.877521)
			(xy 383.279269 -145.84507) (xy 383.328869 -145.819569) (xy 383.381653 -145.801562) (xy 383.436496 -145.791432)
			(xy 383.49223 -145.789395) (xy 383.547667 -145.795495) (xy 383.601624 -145.809601) (xy 383.652953 -145.831413)
			(xy 383.700559 -145.860467) (xy 383.743427 -145.896142) (xy 383.780644 -145.937679) (xy 383.811417 -145.984192)
			(xy 383.835089 -146.034689) (xy 383.851157 -146.088096) (xy 383.859277 -146.143272) (xy 383.859786 -146.171158)
			(xy 383.859277 -146.199044) (xy 383.851157 -146.25422) (xy 383.835089 -146.307627) (xy 383.811417 -146.358124)
			(xy 383.780644 -146.404637) (xy 383.743427 -146.446174) (xy 383.700559 -146.481849) (xy 383.652953 -146.510903)
			(xy 383.601624 -146.532715) (xy 383.547667 -146.546821) (xy 383.49223 -146.552921) (xy 383.436496 -146.550884)
			(xy 383.381653 -146.540754) (xy 383.328869 -146.522747) (xy 383.279269 -146.497246) (xy 383.233911 -146.464795)
			(xy 383.193762 -146.426086) (xy 383.159676 -146.381943) (xy 383.13238 -146.333308) (xy 383.112457 -146.281217)
			(xy 383.100331 -146.22678) (xy 383.09626 -146.171158) (xy 379.420657 -146.171158) (xy 379.433555 -146.181892)
			(xy 379.470772 -146.223429) (xy 379.501545 -146.269942) (xy 379.525217 -146.320439) (xy 379.541285 -146.373846)
			(xy 379.549405 -146.429022) (xy 379.549914 -146.456908) (xy 379.549405 -146.484794) (xy 379.541285 -146.53997)
			(xy 379.525217 -146.593377) (xy 379.501545 -146.643874) (xy 379.470772 -146.690387) (xy 379.438275 -146.726656)
			(xy 381.080516 -146.726656) (xy 381.084587 -146.671034) (xy 381.096713 -146.616597) (xy 381.116636 -146.564506)
			(xy 381.143932 -146.515871) (xy 381.178018 -146.471728) (xy 381.218167 -146.433019) (xy 381.263525 -146.400568)
			(xy 381.313125 -146.375067) (xy 381.365909 -146.35706) (xy 381.420752 -146.34693) (xy 381.476486 -146.344893)
			(xy 381.531923 -146.350993) (xy 381.58588 -146.365099) (xy 381.637209 -146.386911) (xy 381.684815 -146.415965)
			(xy 381.727683 -146.45164) (xy 381.7649 -146.493177) (xy 381.795673 -146.53969) (xy 381.819345 -146.590187)
			(xy 381.835413 -146.643594) (xy 381.843533 -146.69877) (xy 381.844042 -146.726656) (xy 381.843533 -146.754542)
			(xy 381.835413 -146.809718) (xy 381.819345 -146.863125) (xy 381.795673 -146.913622) (xy 381.7649 -146.960135)
			(xy 381.727683 -147.001672) (xy 381.684815 -147.037347) (xy 381.637209 -147.066401) (xy 381.58588 -147.088213)
			(xy 381.531923 -147.102319) (xy 381.476486 -147.108419) (xy 381.420752 -147.106382) (xy 381.365909 -147.096252)
			(xy 381.313125 -147.078245) (xy 381.263525 -147.052744) (xy 381.218167 -147.020293) (xy 381.178018 -146.981584)
			(xy 381.143932 -146.937441) (xy 381.116636 -146.888806) (xy 381.096713 -146.836715) (xy 381.084587 -146.782278)
			(xy 381.080516 -146.726656) (xy 379.438275 -146.726656) (xy 379.433555 -146.731924) (xy 379.390687 -146.767599)
			(xy 379.343081 -146.796653) (xy 379.291752 -146.818465) (xy 379.237795 -146.832571) (xy 379.182358 -146.838671)
			(xy 379.126624 -146.836634) (xy 379.071781 -146.826504) (xy 379.018997 -146.808497) (xy 378.969397 -146.782996)
			(xy 378.924039 -146.750545) (xy 378.88389 -146.711836) (xy 378.849804 -146.667693) (xy 378.822508 -146.619058)
			(xy 378.802585 -146.566967) (xy 378.790459 -146.51253) (xy 378.786388 -146.456908) (xy 375.690468 -146.456908)
			(xy 374.7389 -147.408392) (xy 374.73217 -147.415844) (xy 374.731067 -147.418552) (xy 376.64212 -147.418552)
			(xy 376.646191 -147.36293) (xy 376.658317 -147.308493) (xy 376.67824 -147.256402) (xy 376.705536 -147.207767)
			(xy 376.739622 -147.163624) (xy 376.779771 -147.124915) (xy 376.825129 -147.092464) (xy 376.874729 -147.066963)
			(xy 376.927513 -147.048956) (xy 376.982356 -147.038826) (xy 377.03809 -147.036789) (xy 377.093527 -147.042889)
			(xy 377.147484 -147.056995) (xy 377.198813 -147.078807) (xy 377.246419 -147.107861) (xy 377.289287 -147.143536)
			(xy 377.326504 -147.185073) (xy 377.357277 -147.231586) (xy 377.380949 -147.282083) (xy 377.397017 -147.33549)
			(xy 377.405137 -147.390666) (xy 377.405646 -147.418552) (xy 377.405137 -147.446438) (xy 377.398027 -147.494752)
			(xy 378.25045 -147.494752) (xy 378.250936 -147.467501) (xy 378.258692 -147.413553) (xy 378.274047 -147.361258)
			(xy 378.296689 -147.311681) (xy 378.326155 -147.265831) (xy 378.361846 -147.22464) (xy 378.403037 -147.188949)
			(xy 378.448887 -147.159483) (xy 378.498464 -147.136841) (xy 378.550759 -147.121486) (xy 378.604707 -147.11373)
			(xy 378.659209 -147.11373) (xy 378.713157 -147.121486) (xy 378.765452 -147.136841) (xy 378.815029 -147.159483)
			(xy 378.860879 -147.188949) (xy 378.90207 -147.22464) (xy 378.937761 -147.265831) (xy 378.967227 -147.311681)
			(xy 378.989869 -147.361258) (xy 379.005224 -147.413553) (xy 379.01298 -147.467501) (xy 379.013466 -147.494752)
			(xy 379.012966 -147.523678) (xy 379.004279 -147.580874) (xy 378.98705 -147.636101) (xy 378.961676 -147.688091)
			(xy 378.945648 -147.712176) (xy 378.93821 -147.723591) (xy 378.929195 -147.749296) (xy 378.927304 -147.776469)
			(xy 378.932672 -147.803174) (xy 378.944916 -147.827507) (xy 378.963162 -147.847732) (xy 378.98611 -147.862406)
			(xy 378.998988 -147.866862) (xy 379.024571 -147.875301) (xy 379.073263 -147.898344) (xy 379.11823 -147.928006)
			(xy 379.158579 -147.963697) (xy 379.193506 -148.004709) (xy 379.222318 -148.050226) (xy 379.244442 -148.099343)
			(xy 379.259437 -148.151083) (xy 379.267007 -148.204417) (xy 379.267466 -148.231352) (xy 379.26698 -148.258603)
			(xy 379.259224 -148.312551) (xy 379.243869 -148.364846) (xy 379.221227 -148.414423) (xy 379.191761 -148.460273)
			(xy 379.15607 -148.501464) (xy 379.114879 -148.537155) (xy 379.069029 -148.566621) (xy 379.019452 -148.589263)
			(xy 378.967157 -148.604618) (xy 378.913209 -148.612374) (xy 378.858707 -148.612374) (xy 378.804759 -148.604618)
			(xy 378.752464 -148.589263) (xy 378.702887 -148.566621) (xy 378.657037 -148.537155) (xy 378.615846 -148.501464)
			(xy 378.580155 -148.460273) (xy 378.550689 -148.414423) (xy 378.528047 -148.364846) (xy 378.512692 -148.312551)
			(xy 378.504936 -148.258603) (xy 378.50445 -148.231352) (xy 378.504966 -148.202427) (xy 378.513651 -148.145232)
			(xy 378.530876 -148.090006) (xy 378.556244 -148.038015) (xy 378.572268 -148.013928) (xy 378.579693 -148.002505)
			(xy 378.588706 -147.976804) (xy 378.590597 -147.949633) (xy 378.585231 -147.92293) (xy 378.57299 -147.8986)
			(xy 378.554747 -147.878375) (xy 378.531804 -147.863699) (xy 378.518928 -147.859242) (xy 378.49335 -147.85079)
			(xy 378.444657 -147.827749) (xy 378.39969 -147.79809) (xy 378.359341 -147.7624) (xy 378.324413 -147.721389)
			(xy 378.2956 -147.675874) (xy 378.273476 -147.626759) (xy 378.25848 -147.57502) (xy 378.25091 -147.521686)
			(xy 378.25045 -147.494752) (xy 377.398027 -147.494752) (xy 377.397017 -147.501614) (xy 377.380949 -147.555021)
			(xy 377.357277 -147.605518) (xy 377.326504 -147.652031) (xy 377.289287 -147.693568) (xy 377.246419 -147.729243)
			(xy 377.198813 -147.758297) (xy 377.147484 -147.780109) (xy 377.093527 -147.794215) (xy 377.03809 -147.800315)
			(xy 376.982356 -147.798278) (xy 376.927513 -147.788148) (xy 376.874729 -147.770141) (xy 376.825129 -147.74464)
			(xy 376.779771 -147.712189) (xy 376.739622 -147.67348) (xy 376.705536 -147.629337) (xy 376.67824 -147.580702)
			(xy 376.658317 -147.528611) (xy 376.646191 -147.474174) (xy 376.64212 -147.418552) (xy 374.731067 -147.418552)
			(xy 374.724603 -147.434426) (xy 374.724168 -147.44446) (xy 374.724168 -148.372068) (xy 375.095514 -148.372068)
			(xy 375.099585 -148.316446) (xy 375.111711 -148.262009) (xy 375.131634 -148.209918) (xy 375.15893 -148.161283)
			(xy 375.193016 -148.11714) (xy 375.233165 -148.078431) (xy 375.278523 -148.04598) (xy 375.328123 -148.020479)
			(xy 375.380907 -148.002472) (xy 375.43575 -147.992342) (xy 375.491484 -147.990305) (xy 375.546921 -147.996405)
			(xy 375.600878 -148.010511) (xy 375.652207 -148.032323) (xy 375.699813 -148.061377) (xy 375.742681 -148.097052)
			(xy 375.779898 -148.138589) (xy 375.810671 -148.185102) (xy 375.834343 -148.235599) (xy 375.850411 -148.289006)
			(xy 375.858531 -148.344182) (xy 375.85904 -148.372068) (xy 375.858531 -148.399954) (xy 375.850411 -148.45513)
			(xy 375.834343 -148.508537) (xy 375.810671 -148.559034) (xy 375.779898 -148.605547) (xy 375.742681 -148.647084)
			(xy 375.699813 -148.682759) (xy 375.653696 -148.710904) (xy 376.020074 -148.710904) (xy 376.024145 -148.655282)
			(xy 376.036271 -148.600845) (xy 376.056194 -148.548754) (xy 376.08349 -148.500119) (xy 376.117576 -148.455976)
			(xy 376.157725 -148.417267) (xy 376.203083 -148.384816) (xy 376.252683 -148.359315) (xy 376.305467 -148.341308)
			(xy 376.36031 -148.331178) (xy 376.416044 -148.329141) (xy 376.471481 -148.335241) (xy 376.525438 -148.349347)
			(xy 376.576767 -148.371159) (xy 376.624373 -148.400213) (xy 376.667241 -148.435888) (xy 376.704458 -148.477425)
			(xy 376.735231 -148.523938) (xy 376.758903 -148.574435) (xy 376.774971 -148.627842) (xy 376.783091 -148.683018)
			(xy 376.7836 -148.710904) (xy 376.783091 -148.73879) (xy 376.777027 -148.779992) (xy 377.483622 -148.779992)
			(xy 377.487693 -148.72437) (xy 377.499819 -148.669933) (xy 377.519742 -148.617842) (xy 377.547038 -148.569207)
			(xy 377.581124 -148.525064) (xy 377.621273 -148.486355) (xy 377.666631 -148.453904) (xy 377.716231 -148.428403)
			(xy 377.769015 -148.410396) (xy 377.823858 -148.400266) (xy 377.879592 -148.398229) (xy 377.935029 -148.404329)
			(xy 377.988986 -148.418435) (xy 378.040315 -148.440247) (xy 378.087921 -148.469301) (xy 378.130789 -148.504976)
			(xy 378.168006 -148.546513) (xy 378.198779 -148.593026) (xy 378.222451 -148.643523) (xy 378.238519 -148.69693)
			(xy 378.246639 -148.752106) (xy 378.247148 -148.779992) (xy 378.246639 -148.807878) (xy 378.238519 -148.863054)
			(xy 378.222451 -148.916461) (xy 378.198779 -148.966958) (xy 378.168006 -149.013471) (xy 378.130789 -149.055008)
			(xy 378.087921 -149.090683) (xy 378.040315 -149.119737) (xy 377.988986 -149.141549) (xy 377.935029 -149.155655)
			(xy 377.879592 -149.161755) (xy 377.823858 -149.159718) (xy 377.769015 -149.149588) (xy 377.716231 -149.131581)
			(xy 377.666631 -149.10608) (xy 377.621273 -149.073629) (xy 377.581124 -149.03492) (xy 377.547038 -148.990777)
			(xy 377.519742 -148.942142) (xy 377.499819 -148.890051) (xy 377.487693 -148.835614) (xy 377.483622 -148.779992)
			(xy 376.777027 -148.779992) (xy 376.774971 -148.793966) (xy 376.758903 -148.847373) (xy 376.735231 -148.89787)
			(xy 376.704458 -148.944383) (xy 376.667241 -148.98592) (xy 376.624373 -149.021595) (xy 376.576767 -149.050649)
			(xy 376.525438 -149.072461) (xy 376.471481 -149.086567) (xy 376.416044 -149.092667) (xy 376.36031 -149.09063)
			(xy 376.305467 -149.0805) (xy 376.252683 -149.062493) (xy 376.203083 -149.036992) (xy 376.157725 -149.004541)
			(xy 376.117576 -148.965832) (xy 376.08349 -148.921689) (xy 376.056194 -148.873054) (xy 376.036271 -148.820963)
			(xy 376.024145 -148.766526) (xy 376.020074 -148.710904) (xy 375.653696 -148.710904) (xy 375.652207 -148.711813)
			(xy 375.600878 -148.733625) (xy 375.546921 -148.747731) (xy 375.491484 -148.753831) (xy 375.43575 -148.751794)
			(xy 375.380907 -148.741664) (xy 375.328123 -148.723657) (xy 375.278523 -148.698156) (xy 375.233165 -148.665705)
			(xy 375.193016 -148.626996) (xy 375.15893 -148.582853) (xy 375.131634 -148.534218) (xy 375.111711 -148.482127)
			(xy 375.099585 -148.42769) (xy 375.095514 -148.372068) (xy 374.724168 -148.372068) (xy 374.724168 -149.379432)
			(xy 375.095514 -149.379432) (xy 375.099585 -149.32381) (xy 375.111711 -149.269373) (xy 375.131634 -149.217282)
			(xy 375.15893 -149.168647) (xy 375.193016 -149.124504) (xy 375.233165 -149.085795) (xy 375.278523 -149.053344)
			(xy 375.328123 -149.027843) (xy 375.380907 -149.009836) (xy 375.43575 -148.999706) (xy 375.491484 -148.997669)
			(xy 375.546921 -149.003769) (xy 375.600878 -149.017875) (xy 375.652207 -149.039687) (xy 375.699813 -149.068741)
			(xy 375.742681 -149.104416) (xy 375.779898 -149.145953) (xy 375.810671 -149.192466) (xy 375.834343 -149.242963)
			(xy 375.850411 -149.29637) (xy 375.858531 -149.351546) (xy 375.85904 -149.379432) (xy 375.858531 -149.407318)
			(xy 375.850411 -149.462494) (xy 375.834343 -149.515901) (xy 375.810671 -149.566398) (xy 375.779898 -149.612911)
			(xy 375.742681 -149.654448) (xy 375.699813 -149.690123) (xy 375.652207 -149.719177) (xy 375.600878 -149.740989)
			(xy 375.546921 -149.755095) (xy 375.491484 -149.761195) (xy 375.43575 -149.759158) (xy 375.380907 -149.749028)
			(xy 375.328123 -149.731021) (xy 375.278523 -149.70552) (xy 375.233165 -149.673069) (xy 375.193016 -149.63436)
			(xy 375.15893 -149.590217) (xy 375.131634 -149.541582) (xy 375.111711 -149.489491) (xy 375.099585 -149.435054)
			(xy 375.095514 -149.379432) (xy 374.724168 -149.379432) (xy 374.724168 -150.255224) (xy 374.724533 -150.26527)
			(xy 374.732124 -150.283867) (xy 374.7389 -150.291292) (xy 376.235976 -151.788114) (xy 376.249764 -151.802611)
			(xy 376.271936 -151.835907) (xy 376.287192 -151.872886) (xy 376.294946 -151.91213) (xy 376.295412 -151.932132)
			(xy 376.295412 -155.640532) (xy 378.748036 -155.640532) (xy 378.748512 -155.613162) (xy 378.756326 -155.558983)
			(xy 378.771812 -155.50648) (xy 378.794652 -155.456733) (xy 378.824375 -155.410766) (xy 378.842016 -155.389834)
			(xy 378.848112 -155.382722) (xy 378.854462 -155.365704) (xy 378.854462 -155.28036) (xy 378.848112 -155.263342)
			(xy 378.842016 -155.25623) (xy 378.824407 -155.235272) (xy 378.794682 -155.189308) (xy 378.771835 -155.139566)
			(xy 378.756337 -155.087068) (xy 378.748506 -155.032893) (xy 378.748502 -154.978155) (xy 378.756327 -154.923979)
			(xy 378.771818 -154.871479) (xy 378.794659 -154.821734) (xy 378.824378 -154.775767) (xy 378.842016 -154.754834)
			(xy 378.848112 -154.747722) (xy 378.854462 -154.730704) (xy 378.854462 -154.64536) (xy 378.848112 -154.628342)
			(xy 378.842016 -154.62123) (xy 378.824407 -154.600272) (xy 378.794682 -154.554308) (xy 378.771835 -154.504566)
			(xy 378.756337 -154.452068) (xy 378.748506 -154.397893) (xy 378.748502 -154.343155) (xy 378.756327 -154.288979)
			(xy 378.771818 -154.236479) (xy 378.794659 -154.186734) (xy 378.824378 -154.140767) (xy 378.842016 -154.119834)
			(xy 378.848112 -154.112722) (xy 378.854462 -154.095704) (xy 378.854462 -154.01036) (xy 378.848112 -153.993342)
			(xy 378.842016 -153.98623) (xy 378.82438 -153.965295) (xy 378.794667 -153.919324) (xy 378.77183 -153.869577)
			(xy 378.756339 -153.817076) (xy 378.74851 -153.762901) (xy 378.748036 -153.735532) (xy 378.748485 -153.708278)
			(xy 378.756239 -153.654324) (xy 378.771593 -153.602023) (xy 378.794235 -153.55244) (xy 378.823704 -153.506585)
			(xy 378.859399 -153.465391) (xy 378.900595 -153.429697) (xy 378.946451 -153.400229) (xy 378.996035 -153.377589)
			(xy 379.048336 -153.362236) (xy 379.10229 -153.354484) (xy 379.129544 -153.354024) (xy 379.15945 -153.35459)
			(xy 379.218528 -153.363942) (xy 379.275423 -153.382394) (xy 379.328744 -153.409495) (xy 379.377186 -153.444582)
			(xy 379.398784 -153.465276) (xy 379.405896 -153.472388) (xy 379.423168 -153.479754) (xy 379.512576 -153.482548)
			(xy 379.530356 -153.476198) (xy 379.537722 -153.469594) (xy 379.545539 -153.462796) (xy 379.561805 -153.449962)
			(xy 379.570234 -153.44394) (xy 379.579632 -153.437336) (xy 379.590808 -153.418032) (xy 379.599444 -153.317956)
			(xy 379.591824 -153.297128) (xy 379.583696 -153.289) (xy 379.562873 -153.267422) (xy 379.527622 -153.218915)
			(xy 379.500396 -153.165488) (xy 379.481867 -153.10846) (xy 379.47249 -153.049234) (xy 379.471936 -153.019252)
			(xy 379.472424 -152.991882) (xy 379.480235 -152.937704) (xy 379.495719 -152.885201) (xy 379.518556 -152.835453)
			(xy 379.548276 -152.789486) (xy 379.565916 -152.768554) (xy 379.572012 -152.761442) (xy 379.578362 -152.744424)
			(xy 379.578362 -152.65908) (xy 379.572012 -152.642062) (xy 379.565916 -152.63495) (xy 379.548289 -152.614008)
			(xy 379.518575 -152.568038) (xy 379.495737 -152.518293) (xy 379.480243 -152.465795) (xy 379.472411 -152.411621)
			(xy 379.471936 -152.384252) (xy 379.472333 -152.356998) (xy 379.480097 -152.303044) (xy 379.495461 -152.250745)
			(xy 379.518111 -152.201165) (xy 379.547586 -152.155313) (xy 379.583287 -152.114122) (xy 379.624486 -152.078431)
			(xy 379.670346 -152.048967) (xy 379.719932 -152.026329) (xy 379.772234 -152.010978) (xy 379.826189 -152.003227)
			(xy 379.853444 -152.002744) (xy 379.880814 -152.003232) (xy 379.934992 -152.011043) (xy 379.987495 -152.026526)
			(xy 380.037243 -152.049363) (xy 380.08321 -152.079084) (xy 380.104142 -152.096724) (xy 380.111254 -152.10282)
			(xy 380.128272 -152.10917) (xy 380.213616 -152.10917) (xy 380.230634 -152.10282) (xy 380.237746 -152.096724)
			(xy 380.258679 -152.079083) (xy 380.304647 -152.049359) (xy 380.354393 -152.026513) (xy 380.406895 -152.011017)
			(xy 380.461073 -152.003188) (xy 380.515815 -152.003188) (xy 380.569993 -152.011017) (xy 380.622495 -152.026513)
			(xy 380.672241 -152.049359) (xy 380.718209 -152.079083) (xy 380.739142 -152.096724) (xy 380.746254 -152.10282)
			(xy 380.763272 -152.10917) (xy 380.848616 -152.10917) (xy 380.865634 -152.10282) (xy 380.872746 -152.096724)
			(xy 380.893679 -152.079083) (xy 380.939647 -152.049359) (xy 380.989393 -152.026513) (xy 381.041895 -152.011017)
			(xy 381.096073 -152.003188) (xy 381.150815 -152.003188) (xy 381.204993 -152.011017) (xy 381.257495 -152.026513)
			(xy 381.307241 -152.049359) (xy 381.353209 -152.079083) (xy 381.374142 -152.096724) (xy 381.381254 -152.10282)
			(xy 381.398272 -152.10917) (xy 381.483616 -152.10917) (xy 381.500634 -152.10282) (xy 381.507746 -152.096724)
			(xy 381.528691 -152.0791) (xy 381.57466 -152.049385) (xy 381.624404 -152.026546) (xy 381.676902 -152.011052)
			(xy 381.731076 -152.00322) (xy 381.758444 -152.002744) (xy 381.785694 -152.003237) (xy 381.839639 -152.010998)
			(xy 381.891931 -152.026356) (xy 381.941505 -152.048999) (xy 381.987353 -152.078465) (xy 382.028541 -152.114156)
			(xy 382.064232 -152.155344) (xy 382.093699 -152.201191) (xy 382.116342 -152.250765) (xy 382.131701 -152.303057)
			(xy 382.139463 -152.357002) (xy 382.139952 -152.384252) (xy 382.139469 -152.411622) (xy 382.131657 -152.465801)
			(xy 382.116173 -152.518304) (xy 382.093334 -152.568051) (xy 382.063612 -152.614018) (xy 382.045972 -152.63495)
			(xy 382.039876 -152.642062) (xy 382.033526 -152.65908) (xy 382.033526 -152.744424) (xy 382.039876 -152.761442)
			(xy 382.045972 -152.768554) (xy 382.063599 -152.789496) (xy 382.093313 -152.835466) (xy 382.116152 -152.885211)
			(xy 382.131646 -152.937709) (xy 382.139477 -152.991883) (xy 382.139952 -153.019252) (xy 382.139434 -153.048033)
			(xy 382.13078 -153.104939) (xy 382.113677 -153.159901) (xy 382.088512 -153.21167) (xy 382.055856 -153.259071)
			(xy 382.016451 -153.30103) (xy 381.97119 -153.336593) (xy 381.946404 -153.35123) (xy 381.936498 -153.356818)
			(xy 381.923544 -153.37536) (xy 381.906272 -153.47569) (xy 381.912114 -153.49728) (xy 381.919734 -153.50617)
			(xy 381.937187 -153.527084) (xy 381.96664 -153.572906) (xy 381.989282 -153.622449) (xy 382.004654 -153.674706)
			(xy 382.012443 -153.728617) (xy 382.012952 -153.755852) (xy 382.012469 -153.783222) (xy 382.004657 -153.837401)
			(xy 381.989173 -153.889904) (xy 381.966334 -153.939651) (xy 381.936612 -153.985618) (xy 381.918972 -154.00655)
			(xy 381.912876 -154.013662) (xy 381.906526 -154.03068) (xy 381.906526 -154.116024) (xy 381.912876 -154.133042)
			(xy 381.918972 -154.140154) (xy 381.936566 -154.161125) (xy 381.966293 -154.207086) (xy 381.989141 -154.256826)
			(xy 382.004641 -154.309322) (xy 382.012474 -154.363496) (xy 382.012479 -154.418232) (xy 382.004656 -154.472407)
			(xy 381.989166 -154.524906) (xy 381.966327 -154.574651) (xy 381.936609 -154.620617) (xy 381.918972 -154.64155)
			(xy 381.912876 -154.648662) (xy 381.906526 -154.66568) (xy 381.906526 -154.751024) (xy 381.912876 -154.768042)
			(xy 381.918972 -154.775154) (xy 381.936566 -154.796125) (xy 381.966293 -154.842086) (xy 381.989141 -154.891826)
			(xy 382.004641 -154.944322) (xy 382.012474 -154.998496) (xy 382.012479 -155.053232) (xy 382.004656 -155.107407)
			(xy 381.989166 -155.159906) (xy 381.966327 -155.209651) (xy 381.936609 -155.255617) (xy 381.918972 -155.27655)
			(xy 381.912876 -155.283662) (xy 381.906526 -155.30068) (xy 381.906526 -155.386024) (xy 381.912876 -155.403042)
			(xy 381.918972 -155.410154) (xy 381.936599 -155.431096) (xy 381.966313 -155.477066) (xy 381.989152 -155.526811)
			(xy 382.004646 -155.579309) (xy 382.012477 -155.633483) (xy 382.012952 -155.660852) (xy 382.012435 -155.688653)
			(xy 382.004382 -155.743668) (xy 381.988424 -155.79693) (xy 381.9649 -155.84731) (xy 381.934309 -155.89374)
			(xy 381.897299 -155.935234) (xy 381.8763 -155.95346) (xy 381.86815 -155.961065) (xy 381.858649 -155.981196)
			(xy 381.858012 -155.992322) (xy 381.858012 -156.071824) (xy 381.8763 -156.097732) (xy 381.891286 -156.10332)
			(xy 381.918266 -156.113936) (xy 381.968932 -156.142116) (xy 382.014751 -156.177637) (xy 382.054669 -156.21968)
			(xy 382.087768 -156.267279) (xy 382.113284 -156.319338) (xy 382.130631 -156.374657) (xy 382.139409 -156.431964)
			(xy 382.139952 -156.460952) (xy 382.139469 -156.488322) (xy 382.131657 -156.542501) (xy 382.116173 -156.595004)
			(xy 382.093334 -156.644751) (xy 382.063612 -156.690718) (xy 382.045972 -156.71165) (xy 382.039876 -156.718762)
			(xy 382.033526 -156.73578) (xy 382.033526 -156.821124) (xy 382.039876 -156.838142) (xy 382.045972 -156.845254)
			(xy 382.063599 -156.866196) (xy 382.093313 -156.912166) (xy 382.116152 -156.961911) (xy 382.127975 -157.001972)
			(xy 386.91185 -157.001972) (xy 386.912287 -156.974601) (xy 386.92011 -156.92042) (xy 386.935605 -156.867916)
			(xy 386.958454 -156.818169) (xy 386.988185 -156.772204) (xy 387.00583 -156.751274) (xy 387.011926 -156.744162)
			(xy 387.018276 -156.727144) (xy 387.018276 -156.6418) (xy 387.011926 -156.624782) (xy 387.00583 -156.61767)
			(xy 386.988215 -156.596718) (xy 386.958498 -156.550752) (xy 386.935657 -156.501009) (xy 386.920161 -156.448512)
			(xy 386.912327 -156.39434) (xy 386.91185 -156.366972) (xy 386.912354 -156.339204) (xy 386.920393 -156.284252)
			(xy 386.936312 -156.231046) (xy 386.959775 -156.180709) (xy 386.990286 -156.134304) (xy 387.00837 -156.113226)
			(xy 387.01472 -156.106114) (xy 387.021324 -156.088842) (xy 387.021324 -156.002482) (xy 387.01472 -155.98521)
			(xy 387.00837 -155.978098) (xy 386.990305 -155.957004) (xy 386.959797 -155.910601) (xy 386.936331 -155.860268)
			(xy 386.920405 -155.807066) (xy 386.912353 -155.752119) (xy 386.91185 -155.724352) (xy 386.912334 -155.696982)
			(xy 386.920146 -155.642803) (xy 386.93563 -155.5903) (xy 386.958468 -155.540553) (xy 386.98819 -155.494586)
			(xy 387.00583 -155.473654) (xy 387.011926 -155.466542) (xy 387.018276 -155.449524) (xy 387.018276 -155.36418)
			(xy 387.011926 -155.347162) (xy 387.00583 -155.34005) (xy 386.988206 -155.319106) (xy 386.95849 -155.273137)
			(xy 386.935651 -155.223393) (xy 386.920157 -155.170894) (xy 386.912326 -155.11672) (xy 386.91185 -155.089352)
			(xy 386.912358 -155.060613) (xy 386.920986 -155.003785) (xy 386.938041 -154.948895) (xy 386.963136 -154.897183)
			(xy 386.995703 -154.849821) (xy 387.014974 -154.828494) (xy 387.021578 -154.821382) (xy 387.02869 -154.803856)
			(xy 387.02869 -154.714448) (xy 387.021578 -154.696922) (xy 387.014974 -154.68981) (xy 386.995686 -154.668497)
			(xy 386.963121 -154.621132) (xy 386.938031 -154.569417) (xy 386.920985 -154.514523) (xy 386.912368 -154.457692)
			(xy 386.91185 -154.428952) (xy 386.912334 -154.401582) (xy 386.920146 -154.347403) (xy 386.93563 -154.2949)
			(xy 386.958468 -154.245153) (xy 386.98819 -154.199186) (xy 387.00583 -154.178254) (xy 387.011926 -154.171142)
			(xy 387.018276 -154.154124) (xy 387.018276 -154.06878) (xy 387.011926 -154.051762) (xy 387.00583 -154.04465)
			(xy 386.988206 -154.023706) (xy 386.95849 -153.977737) (xy 386.935651 -153.927993) (xy 386.920157 -153.875494)
			(xy 386.912326 -153.82132) (xy 386.91185 -153.793952) (xy 386.912333 -153.766701) (xy 386.920095 -153.712756)
			(xy 386.935454 -153.660464) (xy 386.958098 -153.610889) (xy 386.987565 -153.565041) (xy 387.023257 -153.523852)
			(xy 387.064446 -153.488162) (xy 387.110294 -153.458695) (xy 387.159869 -153.436052) (xy 387.212162 -153.420694)
			(xy 387.266107 -153.412933) (xy 387.293358 -153.412444) (xy 387.320728 -153.412924) (xy 387.374907 -153.420737)
			(xy 387.42741 -153.436222) (xy 387.477157 -153.459061) (xy 387.523124 -153.488783) (xy 387.544056 -153.506424)
			(xy 387.551168 -153.51252) (xy 387.568186 -153.51887) (xy 387.65353 -153.51887) (xy 387.670548 -153.51252)
			(xy 387.67766 -153.506424) (xy 387.698599 -153.488794) (xy 387.74457 -153.45908) (xy 387.794315 -153.436242)
			(xy 387.846815 -153.420749) (xy 387.900989 -153.412919) (xy 387.928358 -153.412444) (xy 387.955606 -153.413017)
			(xy 388.009548 -153.420767) (xy 388.061838 -153.436114) (xy 388.111412 -153.458747) (xy 388.15726 -153.488204)
			(xy 388.19845 -153.523887) (xy 388.234142 -153.565068) (xy 388.26361 -153.610909) (xy 388.286254 -153.660477)
			(xy 388.301614 -153.712764) (xy 388.309376 -153.766704) (xy 388.309866 -153.793952) (xy 388.30938 -153.821322)
			(xy 388.301568 -153.8755) (xy 388.286084 -153.928003) (xy 388.263247 -153.977751) (xy 388.233526 -154.023718)
			(xy 388.215886 -154.04465) (xy 388.20979 -154.051762) (xy 388.20344 -154.06878) (xy 388.20344 -154.154124)
			(xy 388.20979 -154.171142) (xy 388.215886 -154.178254) (xy 388.233515 -154.199194) (xy 388.263229 -154.245165)
			(xy 388.286067 -154.29491) (xy 388.30156 -154.347409) (xy 388.309391 -154.401583) (xy 388.309866 -154.428952)
			(xy 388.309356 -154.457691) (xy 388.300728 -154.514518) (xy 388.283673 -154.569409) (xy 388.258579 -154.62112)
			(xy 388.226013 -154.668483) (xy 388.206742 -154.68981) (xy 388.200138 -154.696922) (xy 388.193026 -154.714448)
			(xy 388.193026 -154.803856) (xy 388.200138 -154.821382) (xy 388.206742 -154.828494) (xy 388.226034 -154.849803)
			(xy 388.258598 -154.897169) (xy 388.283687 -154.948886) (xy 388.300732 -155.003781) (xy 388.309349 -155.060612)
			(xy 388.309866 -155.089352) (xy 388.30938 -155.116722) (xy 388.301568 -155.1709) (xy 388.286084 -155.223403)
			(xy 388.263247 -155.273151) (xy 388.233526 -155.319118) (xy 388.215886 -155.34005) (xy 388.20979 -155.347162)
			(xy 388.20344 -155.36418) (xy 388.20344 -155.449524) (xy 388.20979 -155.466542) (xy 388.215886 -155.473654)
			(xy 388.233515 -155.494594) (xy 388.263229 -155.540565) (xy 388.286067 -155.59031) (xy 388.30156 -155.642809)
			(xy 388.309391 -155.696983) (xy 388.309866 -155.724352) (xy 388.309372 -155.752121) (xy 388.30133 -155.807073)
			(xy 388.285408 -155.860279) (xy 388.261943 -155.910615) (xy 388.231431 -155.95702) (xy 388.213346 -155.978098)
			(xy 388.206996 -155.98521) (xy 388.200392 -156.002482) (xy 388.200392 -156.088842) (xy 388.206996 -156.106114)
			(xy 388.213346 -156.113226) (xy 388.231425 -156.134308) (xy 388.261931 -156.180715) (xy 388.285393 -156.231051)
			(xy 388.301316 -156.284255) (xy 388.309365 -156.339204) (xy 388.309866 -156.366972) (xy 388.309392 -156.394342)
			(xy 388.301577 -156.448521) (xy 388.28609 -156.501024) (xy 388.26325 -156.550771) (xy 388.233527 -156.596738)
			(xy 388.215886 -156.61767) (xy 388.20979 -156.624782) (xy 388.20344 -156.6418) (xy 388.20344 -156.727144)
			(xy 388.20979 -156.744162) (xy 388.215886 -156.751274) (xy 388.233524 -156.772207) (xy 388.263237 -156.818179)
			(xy 388.286073 -156.867926) (xy 388.301564 -156.920427) (xy 388.309392 -156.974603) (xy 388.309866 -157.001972)
			(xy 388.309419 -157.029226) (xy 388.301664 -157.08318) (xy 388.28631 -157.13548) (xy 388.263667 -157.185063)
			(xy 388.234198 -157.230919) (xy 388.198503 -157.272113) (xy 388.157307 -157.307807) (xy 388.111451 -157.337274)
			(xy 388.061867 -157.359915) (xy 388.009566 -157.375267) (xy 387.955612 -157.38302) (xy 387.928358 -157.38348)
			(xy 387.900989 -157.382985) (xy 387.846811 -157.375175) (xy 387.794308 -157.359693) (xy 387.74456 -157.336857)
			(xy 387.698592 -157.307139) (xy 387.67766 -157.2895) (xy 387.670548 -157.283404) (xy 387.65353 -157.277054)
			(xy 387.568186 -157.277054) (xy 387.551168 -157.283404) (xy 387.544056 -157.2895) (xy 387.523114 -157.307126)
			(xy 387.477144 -157.33684) (xy 387.427399 -157.359678) (xy 387.3749 -157.375173) (xy 387.320726 -157.383004)
			(xy 387.293358 -157.38348) (xy 387.266104 -157.383061) (xy 387.212153 -157.375298) (xy 387.159855 -157.359936)
			(xy 387.110276 -157.337288) (xy 387.064424 -157.307815) (xy 387.023234 -157.272117) (xy 386.987543 -157.23092)
			(xy 386.958078 -157.185063) (xy 386.935439 -157.135479) (xy 386.920087 -157.083179) (xy 386.912334 -157.029226)
			(xy 386.91185 -157.001972) (xy 382.127975 -157.001972) (xy 382.131646 -157.014409) (xy 382.139477 -157.068583)
			(xy 382.139952 -157.095952) (xy 382.1394 -157.123202) (xy 382.131651 -157.177147) (xy 382.116303 -157.229441)
			(xy 382.093669 -157.279018) (xy 382.064211 -157.324869) (xy 382.028526 -157.366061) (xy 381.987343 -157.401755)
			(xy 381.941499 -157.431225) (xy 381.891927 -157.453871) (xy 381.839637 -157.469231) (xy 381.785694 -157.476994)
			(xy 381.758444 -157.47746) (xy 381.731074 -157.476978) (xy 381.676895 -157.469165) (xy 381.624392 -157.453681)
			(xy 381.574645 -157.430842) (xy 381.528678 -157.40112) (xy 381.507746 -157.38348) (xy 381.500634 -157.377384)
			(xy 381.483616 -157.371034) (xy 381.398272 -157.371034) (xy 381.381254 -157.377384) (xy 381.374142 -157.38348)
			(xy 381.353209 -157.401121) (xy 381.307241 -157.430845) (xy 381.257495 -157.453691) (xy 381.204993 -157.469187)
			(xy 381.150815 -157.477016) (xy 381.096073 -157.477016) (xy 381.041895 -157.469187) (xy 380.989393 -157.453691)
			(xy 380.939647 -157.430845) (xy 380.893679 -157.401121) (xy 380.872746 -157.38348) (xy 380.865634 -157.377384)
			(xy 380.848616 -157.371034) (xy 380.763272 -157.371034) (xy 380.746254 -157.377384) (xy 380.739142 -157.38348)
			(xy 380.718209 -157.401121) (xy 380.672241 -157.430845) (xy 380.622495 -157.453691) (xy 380.569993 -157.469187)
			(xy 380.515815 -157.477016) (xy 380.461073 -157.477016) (xy 380.406895 -157.469187) (xy 380.354393 -157.453691)
			(xy 380.304647 -157.430845) (xy 380.258679 -157.401121) (xy 380.237746 -157.38348) (xy 380.230634 -157.377384)
			(xy 380.213616 -157.371034) (xy 380.128272 -157.371034) (xy 380.111254 -157.377384) (xy 380.104142 -157.38348)
			(xy 380.083202 -157.40111) (xy 380.037232 -157.430824) (xy 379.987486 -157.453662) (xy 379.934987 -157.469155)
			(xy 379.880813 -157.476985) (xy 379.853444 -157.47746) (xy 379.82354 -157.476843) (xy 379.764464 -157.467504)
			(xy 379.707569 -157.449064) (xy 379.654247 -157.421974) (xy 379.605804 -157.386898) (xy 379.584204 -157.366208)
			(xy 379.577092 -157.359096) (xy 379.55982 -157.35173) (xy 379.470412 -157.348936) (xy 379.452632 -157.355286)
			(xy 379.445266 -157.36189) (xy 379.424251 -157.37974) (xy 379.378064 -157.409851) (xy 379.328024 -157.433002)
			(xy 379.275173 -157.448711) (xy 379.220612 -157.456652) (xy 379.193044 -157.45714) (xy 379.165794 -157.456604)
			(xy 379.111847 -157.448854) (xy 379.059552 -157.433505) (xy 379.009975 -157.41087) (xy 378.964123 -157.381409)
			(xy 378.92293 -157.345723) (xy 378.887236 -157.304538) (xy 378.857767 -157.258692) (xy 378.835122 -157.209119)
			(xy 378.819762 -157.156827) (xy 378.812002 -157.102882) (xy 378.811536 -157.075632) (xy 378.812012 -157.048262)
			(xy 378.819826 -156.994083) (xy 378.835312 -156.94158) (xy 378.858152 -156.891833) (xy 378.887875 -156.845866)
			(xy 378.905516 -156.824934) (xy 378.911612 -156.817822) (xy 378.917962 -156.800804) (xy 378.917962 -156.71546)
			(xy 378.911612 -156.698442) (xy 378.905516 -156.69133) (xy 378.88788 -156.670395) (xy 378.858167 -156.624424)
			(xy 378.83533 -156.574677) (xy 378.819839 -156.522176) (xy 378.81201 -156.468001) (xy 378.811536 -156.440632)
			(xy 378.812066 -156.411956) (xy 378.820635 -156.355248) (xy 378.837599 -156.300463) (xy 378.862576 -156.248836)
			(xy 378.895002 -156.201531) (xy 378.934147 -156.159616) (xy 378.956316 -156.14142) (xy 378.966222 -156.133546)
			(xy 378.976382 -156.110432) (xy 378.967746 -156.000704) (xy 378.95403 -155.979622) (xy 378.942854 -155.973272)
			(xy 378.917936 -155.958648) (xy 378.872393 -155.923103) (xy 378.832729 -155.881098) (xy 378.79985 -155.833593)
			(xy 378.774509 -155.781675) (xy 378.757285 -155.72653) (xy 378.74857 -155.669418) (xy 378.748036 -155.640532)
			(xy 376.295412 -155.640532) (xy 376.295412 -157.498542) (xy 376.295812 -157.508614) (xy 376.30355 -157.527212)
			(xy 376.310398 -157.53461) (xy 381.471056 -162.695058) (xy 386.317994 -162.695058) (xy 386.317994 -162.610362)
			(xy 386.326045 -162.526048) (xy 386.342074 -162.442882) (xy 386.365935 -162.361615) (xy 386.397414 -162.282985)
			(xy 386.436225 -162.207704) (xy 386.482015 -162.136452) (xy 386.534371 -162.069876) (xy 386.592819 -162.008578)
			(xy 386.656829 -161.953113) (xy 386.725821 -161.903984) (xy 386.799171 -161.861635) (xy 386.876214 -161.826451)
			(xy 386.956253 -161.798749) (xy 387.038562 -161.778781) (xy 387.122397 -161.766728) (xy 387.206998 -161.762698)
			(xy 387.291599 -161.766728) (xy 387.375434 -161.778781) (xy 387.457743 -161.798749) (xy 387.537782 -161.826451)
			(xy 387.614825 -161.861635) (xy 387.688175 -161.903984) (xy 387.757167 -161.953113) (xy 387.821177 -162.008578)
			(xy 387.879625 -162.069876) (xy 387.931981 -162.136452) (xy 387.977771 -162.207704) (xy 388.016582 -162.282985)
			(xy 388.048061 -162.361615) (xy 388.071922 -162.442882) (xy 388.087951 -162.526048) (xy 388.096002 -162.610362)
			(xy 388.096506 -162.65271) (xy 388.096002 -162.695058) (xy 388.087951 -162.779372) (xy 388.071922 -162.862538)
			(xy 388.048061 -162.943805) (xy 388.016582 -163.022435) (xy 387.977771 -163.097716) (xy 387.931981 -163.168968)
			(xy 387.879625 -163.235544) (xy 387.821177 -163.296842) (xy 387.757167 -163.352307) (xy 387.688175 -163.401436)
			(xy 387.614825 -163.443785) (xy 387.537782 -163.478969) (xy 387.457743 -163.506671) (xy 387.375434 -163.526639)
			(xy 387.291599 -163.538692) (xy 387.206998 -163.542723) (xy 387.122397 -163.538692) (xy 387.038562 -163.526639)
			(xy 386.956253 -163.506671) (xy 386.876214 -163.478969) (xy 386.799171 -163.443785) (xy 386.725821 -163.401436)
			(xy 386.656829 -163.352307) (xy 386.592819 -163.296842) (xy 386.534371 -163.235544) (xy 386.482015 -163.168968)
			(xy 386.436225 -163.097716) (xy 386.397414 -163.022435) (xy 386.365935 -162.943805) (xy 386.342074 -162.862538)
			(xy 386.326045 -162.779372) (xy 386.317994 -162.695058) (xy 381.471056 -162.695058) (xy 382.542796 -163.766754)
			(xy 382.556559 -163.781274) (xy 382.578735 -163.814562) (xy 382.593997 -163.851534) (xy 382.60176 -163.890772)
			(xy 382.602232 -163.910772) (xy 382.602232 -165.19518) (xy 386.317994 -165.19518) (xy 386.317994 -165.110484)
			(xy 386.326045 -165.02617) (xy 386.342074 -164.943004) (xy 386.365935 -164.861737) (xy 386.397414 -164.783107)
			(xy 386.436225 -164.707826) (xy 386.482015 -164.636574) (xy 386.534371 -164.569998) (xy 386.592819 -164.5087)
			(xy 386.656829 -164.453235) (xy 386.725821 -164.404106) (xy 386.799171 -164.361757) (xy 386.876214 -164.326573)
			(xy 386.956253 -164.298871) (xy 387.038562 -164.278903) (xy 387.122397 -164.26685) (xy 387.206998 -164.26282)
			(xy 387.291599 -164.26685) (xy 387.375434 -164.278903) (xy 387.457743 -164.298871) (xy 387.537782 -164.326573)
			(xy 387.614825 -164.361757) (xy 387.688175 -164.404106) (xy 387.757167 -164.453235) (xy 387.821177 -164.5087)
			(xy 387.879625 -164.569998) (xy 387.931981 -164.636574) (xy 387.977771 -164.707826) (xy 388.016582 -164.783107)
			(xy 388.048061 -164.861737) (xy 388.071922 -164.943004) (xy 388.087951 -165.02617) (xy 388.096002 -165.110484)
			(xy 388.096506 -165.152832) (xy 388.096002 -165.19518) (xy 388.087951 -165.279494) (xy 388.071922 -165.36266)
			(xy 388.048061 -165.443927) (xy 388.016582 -165.522557) (xy 387.977771 -165.597838) (xy 387.931981 -165.66909)
			(xy 387.879625 -165.735666) (xy 387.821177 -165.796964) (xy 387.757167 -165.852429) (xy 387.688175 -165.901558)
			(xy 387.614825 -165.943907) (xy 387.537782 -165.979091) (xy 387.457743 -166.006793) (xy 387.375434 -166.026761)
			(xy 387.291599 -166.038814) (xy 387.206998 -166.042845) (xy 387.122397 -166.038814) (xy 387.038562 -166.026761)
			(xy 386.956253 -166.006793) (xy 386.876214 -165.979091) (xy 386.799171 -165.943907) (xy 386.725821 -165.901558)
			(xy 386.656829 -165.852429) (xy 386.592819 -165.796964) (xy 386.534371 -165.735666) (xy 386.482015 -165.66909)
			(xy 386.436225 -165.597838) (xy 386.397414 -165.522557) (xy 386.365935 -165.443927) (xy 386.342074 -165.36266)
			(xy 386.326045 -165.279494) (xy 386.317994 -165.19518) (xy 382.602232 -165.19518) (xy 382.602232 -177.530252)
			(xy 382.601782 -177.550257) (xy 382.594049 -177.589511) (xy 382.578794 -177.626497) (xy 382.556604 -177.659788)
			(xy 382.542796 -177.67427) (xy 381.96139 -178.255422) (xy 381.954699 -178.262928) (xy 381.947065 -178.281501)
			(xy 381.947081 -178.301583) (xy 381.950468 -178.311048) (xy 381.99314 -178.41214) (xy 382.018794 -178.429158)
			(xy 382.034542 -178.428904) (xy 382.039114 -178.428904) (xy 382.066365 -178.429367) (xy 382.120313 -178.437125)
			(xy 382.172608 -178.452482) (xy 382.222185 -178.475125) (xy 382.268035 -178.504592) (xy 382.309225 -178.540285)
			(xy 382.344916 -178.581476) (xy 382.374382 -178.627327) (xy 382.397023 -178.676905) (xy 382.412378 -178.7292)
			(xy 382.420134 -178.783149) (xy 382.420134 -178.837651) (xy 382.412378 -178.8916) (xy 382.403028 -178.923442)
			(xy 382.661922 -178.923442) (xy 382.662428 -178.895968) (xy 382.670314 -178.841589) (xy 382.685929 -178.788907)
			(xy 382.70895 -178.739014) (xy 382.738898 -178.692944) (xy 382.756664 -178.671982) (xy 382.76276 -178.66487)
			(xy 382.76911 -178.647852) (xy 382.76911 -178.562) (xy 382.76276 -178.544982) (xy 382.756664 -178.53787)
			(xy 382.738899 -178.516909) (xy 382.708976 -178.470826) (xy 382.685964 -178.420932) (xy 382.670338 -178.368255)
			(xy 382.662421 -178.313882) (xy 382.661922 -178.28641) (xy 382.662408 -178.259159) (xy 382.670164 -178.205211)
			(xy 382.685519 -178.152916) (xy 382.708161 -178.103339) (xy 382.737627 -178.057489) (xy 382.773318 -178.016298)
			(xy 382.814509 -177.980607) (xy 382.860359 -177.951141) (xy 382.909936 -177.928499) (xy 382.962231 -177.913144)
			(xy 383.016179 -177.905388) (xy 383.070681 -177.905388) (xy 383.124629 -177.913144) (xy 383.176924 -177.928499)
			(xy 383.226501 -177.951141) (xy 383.272351 -177.980607) (xy 383.313542 -178.016298) (xy 383.349233 -178.057489)
			(xy 383.378699 -178.103339) (xy 383.401341 -178.152916) (xy 383.416696 -178.205211) (xy 383.424452 -178.259159)
			(xy 383.424938 -178.28641) (xy 383.424448 -178.313884) (xy 383.416556 -178.368263) (xy 383.400936 -178.420945)
			(xy 383.377912 -178.470838) (xy 383.347962 -178.516907) (xy 383.330196 -178.53787) (xy 383.3241 -178.544982)
			(xy 383.31775 -178.562) (xy 383.31775 -178.647852) (xy 383.3241 -178.66487) (xy 383.330196 -178.671982)
			(xy 383.347932 -178.692967) (xy 383.377861 -178.739042) (xy 383.400879 -178.788931) (xy 383.416512 -178.841603)
			(xy 383.424435 -178.895971) (xy 383.424938 -178.923442) (xy 383.424452 -178.950693) (xy 383.422819 -178.96205)
			(xy 383.999738 -178.96205) (xy 384.003809 -178.906428) (xy 384.015935 -178.851991) (xy 384.035858 -178.7999)
			(xy 384.063154 -178.751265) (xy 384.09724 -178.707122) (xy 384.137389 -178.668413) (xy 384.182747 -178.635962)
			(xy 384.232347 -178.610461) (xy 384.285131 -178.592454) (xy 384.339974 -178.582324) (xy 384.395708 -178.580287)
			(xy 384.451145 -178.586387) (xy 384.505102 -178.600493) (xy 384.556431 -178.622305) (xy 384.604037 -178.651359)
			(xy 384.646905 -178.687034) (xy 384.684122 -178.728571) (xy 384.714895 -178.775084) (xy 384.738567 -178.825581)
			(xy 384.754635 -178.878988) (xy 384.762755 -178.934164) (xy 384.763264 -178.96205) (xy 384.762755 -178.989936)
			(xy 384.754635 -179.045112) (xy 384.738567 -179.098519) (xy 384.714895 -179.149016) (xy 384.684122 -179.195529)
			(xy 384.646905 -179.237066) (xy 384.604037 -179.272741) (xy 384.556431 -179.301795) (xy 384.505102 -179.323607)
			(xy 384.451145 -179.337713) (xy 384.395708 -179.343813) (xy 384.339974 -179.341776) (xy 384.285131 -179.331646)
			(xy 384.232347 -179.313639) (xy 384.182747 -179.288138) (xy 384.137389 -179.255687) (xy 384.09724 -179.216978)
			(xy 384.063154 -179.172835) (xy 384.035858 -179.1242) (xy 384.015935 -179.072109) (xy 384.003809 -179.017672)
			(xy 383.999738 -178.96205) (xy 383.422819 -178.96205) (xy 383.416696 -179.004641) (xy 383.401341 -179.056936)
			(xy 383.378699 -179.106513) (xy 383.349233 -179.152363) (xy 383.313542 -179.193554) (xy 383.272351 -179.229245)
			(xy 383.226501 -179.258711) (xy 383.176924 -179.281353) (xy 383.124629 -179.296708) (xy 383.070681 -179.304464)
			(xy 383.016179 -179.304464) (xy 382.962231 -179.296708) (xy 382.909936 -179.281353) (xy 382.860359 -179.258711)
			(xy 382.814509 -179.229245) (xy 382.773318 -179.193554) (xy 382.737627 -179.152363) (xy 382.708161 -179.106513)
			(xy 382.685519 -179.056936) (xy 382.670164 -179.004641) (xy 382.662408 -178.950693) (xy 382.661922 -178.923442)
			(xy 382.403028 -178.923442) (xy 382.397023 -178.943895) (xy 382.374382 -178.993473) (xy 382.344916 -179.039324)
			(xy 382.309225 -179.080515) (xy 382.268035 -179.116208) (xy 382.222185 -179.145675) (xy 382.172608 -179.168318)
			(xy 382.120313 -179.183675) (xy 382.066365 -179.191433) (xy 382.039114 -179.19192) (xy 382.013879 -179.191514)
			(xy 381.963845 -179.184898) (xy 381.915125 -179.171728) (xy 381.868573 -179.152234) (xy 381.846582 -179.13985)
			(xy 381.83693 -179.134008) (xy 381.814832 -179.131976) (xy 381.720344 -179.165504) (xy 381.704342 -179.180998)
			(xy 381.700278 -179.191412) (xy 381.68954 -179.21817) (xy 381.661257 -179.26841) (xy 381.625733 -179.313819)
			(xy 381.583777 -179.353362) (xy 381.536346 -179.386137) (xy 381.484521 -179.411399) (xy 381.429484 -179.428569)
			(xy 381.372489 -179.437259) (xy 381.343662 -179.437792) (xy 381.316409 -179.437357) (xy 381.262459 -179.429595)
			(xy 381.210162 -179.414235) (xy 381.160584 -179.391588) (xy 381.114733 -179.362116) (xy 381.073542 -179.326419)
			(xy 381.037851 -179.285224) (xy 381.008386 -179.239369) (xy 380.985746 -179.189787) (xy 380.970393 -179.137488)
			(xy 380.962639 -179.083537) (xy 380.962154 -179.056284) (xy 380.962816 -179.024721) (xy 380.973201 -178.962456)
			(xy 380.993686 -178.902747) (xy 381.008128 -178.874674) (xy 381.012954 -178.865784) (xy 381.014986 -178.846226)
			(xy 380.989332 -178.758088) (xy 380.976886 -178.742594) (xy 380.967996 -178.737514) (xy 380.942872 -178.723003)
			(xy 380.89699 -178.687493) (xy 380.857016 -178.645443) (xy 380.823873 -178.597823) (xy 380.798326 -178.545732)
			(xy 380.780965 -178.490372) (xy 380.77219 -178.433021) (xy 380.771654 -178.404012) (xy 380.772189 -178.376763)
			(xy 380.779943 -178.322819) (xy 380.795295 -178.270527) (xy 380.817932 -178.220953) (xy 380.847393 -178.175104)
			(xy 380.88308 -178.133915) (xy 380.924264 -178.098223) (xy 380.970109 -178.068756) (xy 381.019681 -178.046112)
			(xy 381.07197 -178.030754) (xy 381.125913 -178.022993) (xy 381.153162 -178.022504) (xy 381.179791 -178.022985)
			(xy 381.232532 -178.030387) (xy 381.28373 -178.045055) (xy 381.332391 -178.066701) (xy 381.377567 -178.094906)
			(xy 381.398272 -178.111658) (xy 381.405638 -178.117754) (xy 381.423672 -178.12385) (xy 381.50165 -178.120548)
			(xy 381.511091 -178.119772) (xy 381.528445 -178.112212) (xy 381.535432 -178.105816) (xy 382.180338 -177.46091)
			(xy 382.187171 -177.453505) (xy 382.194894 -177.434909) (xy 382.195324 -177.424842) (xy 382.195324 -164.016182)
			(xy 382.194928 -164.006109) (xy 382.187189 -163.98751) (xy 382.180338 -163.980114) (xy 375.94794 -157.74797)
			(xy 375.934147 -157.733477) (xy 375.911975 -157.70018) (xy 375.89672 -157.6632) (xy 375.888969 -157.623954)
			(xy 375.888504 -157.603952) (xy 375.888504 -152.037542) (xy 375.888082 -152.027472) (xy 375.880362 -152.008873)
			(xy 375.873518 -152.001474) (xy 374.376442 -150.504652) (xy 374.362598 -150.490185) (xy 374.340341 -150.456906)
			(xy 374.325013 -150.41992) (xy 374.317206 -150.380652) (xy 374.316752 -150.360634) (xy 374.316752 -147.33905)
			(xy 374.317255 -147.319038) (xy 374.325082 -147.279787) (xy 374.340406 -147.242812) (xy 374.362641 -147.209532)
			(xy 374.376442 -147.195032) (xy 377.245118 -144.32661) (xy 377.251948 -144.319203) (xy 377.259673 -144.300609)
			(xy 377.260104 -144.290542) (xy 377.260104 -138.92911) (xy 377.259699 -138.919038) (xy 377.251967 -138.900439)
			(xy 377.245118 -138.893042) (xy 376.787156 -138.43508) (xy 376.780292 -138.428815) (xy 376.76335 -138.421222)
			(xy 376.744813 -138.420192) (xy 376.735848 -138.422634) (xy 376.63628 -138.45413) (xy 376.617484 -138.475466)
			(xy 376.615198 -138.489436) (xy 376.609617 -138.518275) (xy 376.590775 -138.57391) (xy 376.563641 -138.626006)
			(xy 376.528854 -138.673336) (xy 376.487234 -138.714784) (xy 376.463814 -138.732514) (xy 376.454408 -138.740109)
			(xy 376.4434 -138.761592) (xy 376.442732 -138.773662) (xy 376.442732 -139.313412) (xy 376.442318 -139.333419)
			(xy 376.434574 -139.372675) (xy 376.419308 -139.409661) (xy 376.397109 -139.44295) (xy 376.383296 -139.45743)
			(xy 375.375678 -140.464794) (xy 375.368845 -140.472199) (xy 375.361122 -140.490795) (xy 375.360692 -140.500862)
			(xy 375.360692 -144.390872) (xy 375.360265 -144.410879) (xy 375.352527 -144.450134) (xy 375.337265 -144.487121)
			(xy 375.315068 -144.52041) (xy 375.301256 -144.53489) (xy 373.897398 -145.938494) (xy 373.890568 -145.945902)
			(xy 373.882842 -145.964495) (xy 373.882412 -145.974562) (xy 373.882412 -151.402542) (xy 373.882812 -151.412614)
			(xy 373.89055 -151.431212) (xy 373.897398 -151.43861) (xy 374.915176 -152.456134) (xy 374.928973 -152.470623)
			(xy 374.951144 -152.503921) (xy 374.966397 -152.540903) (xy 374.974148 -152.580149) (xy 374.974612 -152.600152)
			(xy 374.974612 -162.639178) (xy 376.980954 -162.639178) (xy 376.980954 -162.554482) (xy 376.989005 -162.470168)
			(xy 377.005034 -162.387002) (xy 377.028895 -162.305735) (xy 377.060374 -162.227105) (xy 377.099185 -162.151824)
			(xy 377.144975 -162.080572) (xy 377.197331 -162.013996) (xy 377.255779 -161.952698) (xy 377.319789 -161.897233)
			(xy 377.388781 -161.848104) (xy 377.462131 -161.805755) (xy 377.539174 -161.770571) (xy 377.619213 -161.742869)
			(xy 377.701522 -161.722901) (xy 377.785357 -161.710848) (xy 377.869958 -161.706818) (xy 377.954559 -161.710848)
			(xy 378.038394 -161.722901) (xy 378.120703 -161.742869) (xy 378.200742 -161.770571) (xy 378.277785 -161.805755)
			(xy 378.351135 -161.848104) (xy 378.420127 -161.897233) (xy 378.484137 -161.952698) (xy 378.542585 -162.013996)
			(xy 378.594941 -162.080572) (xy 378.640731 -162.151824) (xy 378.679542 -162.227105) (xy 378.711021 -162.305735)
			(xy 378.734882 -162.387002) (xy 378.750911 -162.470168) (xy 378.758962 -162.554482) (xy 378.759466 -162.59683)
			(xy 378.758962 -162.639178) (xy 378.750911 -162.723492) (xy 378.734882 -162.806658) (xy 378.711021 -162.887925)
			(xy 378.679542 -162.966555) (xy 378.640731 -163.041836) (xy 378.594941 -163.113088) (xy 378.542585 -163.179664)
			(xy 378.484137 -163.240962) (xy 378.420127 -163.296427) (xy 378.351135 -163.345556) (xy 378.277785 -163.387905)
			(xy 378.200742 -163.423089) (xy 378.120703 -163.450791) (xy 378.038394 -163.470759) (xy 377.954559 -163.482812)
			(xy 377.869958 -163.486843) (xy 377.785357 -163.482812) (xy 377.701522 -163.470759) (xy 377.619213 -163.450791)
			(xy 377.539174 -163.423089) (xy 377.462131 -163.387905) (xy 377.388781 -163.345556) (xy 377.319789 -163.296427)
			(xy 377.255779 -163.240962) (xy 377.197331 -163.179664) (xy 377.144975 -163.113088) (xy 377.099185 -163.041836)
			(xy 377.060374 -162.966555) (xy 377.028895 -162.887925) (xy 377.005034 -162.806658) (xy 376.989005 -162.723492)
			(xy 376.980954 -162.639178) (xy 374.974612 -162.639178) (xy 374.974612 -165.1393) (xy 376.980954 -165.1393)
			(xy 376.980954 -165.054604) (xy 376.989005 -164.97029) (xy 377.005034 -164.887124) (xy 377.028895 -164.805857)
			(xy 377.060374 -164.727227) (xy 377.099185 -164.651946) (xy 377.144975 -164.580694) (xy 377.197331 -164.514118)
			(xy 377.255779 -164.45282) (xy 377.319789 -164.397355) (xy 377.388781 -164.348226) (xy 377.462131 -164.305877)
			(xy 377.539174 -164.270693) (xy 377.619213 -164.242991) (xy 377.701522 -164.223023) (xy 377.785357 -164.21097)
			(xy 377.869958 -164.20694) (xy 377.954559 -164.21097) (xy 378.038394 -164.223023) (xy 378.120703 -164.242991)
			(xy 378.200742 -164.270693) (xy 378.277785 -164.305877) (xy 378.351135 -164.348226) (xy 378.420127 -164.397355)
			(xy 378.484137 -164.45282) (xy 378.542585 -164.514118) (xy 378.594941 -164.580694) (xy 378.640731 -164.651946)
			(xy 378.679542 -164.727227) (xy 378.711021 -164.805857) (xy 378.734882 -164.887124) (xy 378.750911 -164.97029)
			(xy 378.758962 -165.054604) (xy 378.759466 -165.096952) (xy 378.758962 -165.1393) (xy 378.750911 -165.223614)
			(xy 378.734882 -165.30678) (xy 378.711021 -165.388047) (xy 378.679542 -165.466677) (xy 378.640731 -165.541958)
			(xy 378.594941 -165.61321) (xy 378.542585 -165.679786) (xy 378.484137 -165.741084) (xy 378.420127 -165.796549)
			(xy 378.351135 -165.845678) (xy 378.277785 -165.888027) (xy 378.200742 -165.923211) (xy 378.120703 -165.950913)
			(xy 378.038394 -165.970881) (xy 377.954559 -165.982934) (xy 377.869958 -165.986965) (xy 377.785357 -165.982934)
			(xy 377.701522 -165.970881) (xy 377.619213 -165.950913) (xy 377.539174 -165.923211) (xy 377.462131 -165.888027)
			(xy 377.388781 -165.845678) (xy 377.319789 -165.796549) (xy 377.255779 -165.741084) (xy 377.197331 -165.679786)
			(xy 377.144975 -165.61321) (xy 377.099185 -165.541958) (xy 377.060374 -165.466677) (xy 377.028895 -165.388047)
			(xy 377.005034 -165.30678) (xy 376.989005 -165.223614) (xy 376.980954 -165.1393) (xy 374.974612 -165.1393)
			(xy 374.974612 -176.383188) (xy 374.974189 -176.403195) (xy 374.966449 -176.44245) (xy 374.951186 -176.479436)
			(xy 374.928988 -176.512726) (xy 374.915176 -176.527206) (xy 373.901716 -177.540412) (xy 373.895024 -177.547894)
			(xy 373.887434 -177.566453) (xy 373.886984 -177.57648) (xy 373.886984 -177.614834) (xy 373.88649 -177.634846)
			(xy 373.878663 -177.674099) (xy 373.863336 -177.711074) (xy 373.841098 -177.744353) (xy 373.827294 -177.758852)
			(xy 373.299736 -178.28641) (xy 374.259094 -178.28641) (xy 374.25958 -178.259159) (xy 374.267336 -178.205211)
			(xy 374.282691 -178.152916) (xy 374.305333 -178.103339) (xy 374.334799 -178.057489) (xy 374.37049 -178.016298)
			(xy 374.411681 -177.980607) (xy 374.457531 -177.951141) (xy 374.507108 -177.928499) (xy 374.559403 -177.913144)
			(xy 374.613351 -177.905388) (xy 374.667853 -177.905388) (xy 374.721801 -177.913144) (xy 374.774096 -177.928499)
			(xy 374.823673 -177.951141) (xy 374.869523 -177.980607) (xy 374.910714 -178.016298) (xy 374.946405 -178.057489)
			(xy 374.975871 -178.103339) (xy 374.998513 -178.152916) (xy 375.013868 -178.205211) (xy 375.021624 -178.259159)
			(xy 375.02211 -178.28641) (xy 375.021586 -178.314084) (xy 375.013594 -178.36885) (xy 374.997766 -178.421886)
			(xy 374.974434 -178.472074) (xy 374.944088 -178.51836) (xy 374.926098 -178.539394) (xy 374.919748 -178.54676)
			(xy 374.913144 -178.564286) (xy 374.914668 -178.652424) (xy 374.922034 -178.66995) (xy 374.928638 -178.676808)
			(xy 374.948251 -178.698239) (xy 374.981448 -178.745911) (xy 375.007042 -178.798061) (xy 375.024442 -178.853486)
			(xy 375.033248 -178.910906) (xy 375.033794 -178.939952) (xy 375.0334 -178.96205) (xy 375.59691 -178.96205)
			(xy 375.600981 -178.906428) (xy 375.613107 -178.851991) (xy 375.63303 -178.7999) (xy 375.660326 -178.751265)
			(xy 375.694412 -178.707122) (xy 375.734561 -178.668413) (xy 375.779919 -178.635962) (xy 375.829519 -178.610461)
			(xy 375.882303 -178.592454) (xy 375.937146 -178.582324) (xy 375.99288 -178.580287) (xy 376.048317 -178.586387)
			(xy 376.102274 -178.600493) (xy 376.153603 -178.622305) (xy 376.201209 -178.651359) (xy 376.244077 -178.687034)
			(xy 376.281294 -178.728571) (xy 376.312067 -178.775084) (xy 376.335739 -178.825581) (xy 376.351807 -178.878988)
			(xy 376.359927 -178.934164) (xy 376.360436 -178.96205) (xy 376.359927 -178.989936) (xy 376.351807 -179.045112)
			(xy 376.335739 -179.098519) (xy 376.312067 -179.149016) (xy 376.281294 -179.195529) (xy 376.244077 -179.237066)
			(xy 376.201209 -179.272741) (xy 376.153603 -179.301795) (xy 376.102274 -179.323607) (xy 376.048317 -179.337713)
			(xy 375.99288 -179.343813) (xy 375.937146 -179.341776) (xy 375.882303 -179.331646) (xy 375.829519 -179.313639)
			(xy 375.779919 -179.288138) (xy 375.734561 -179.255687) (xy 375.694412 -179.216978) (xy 375.660326 -179.172835)
			(xy 375.63303 -179.1242) (xy 375.613107 -179.072109) (xy 375.600981 -179.017672) (xy 375.59691 -178.96205)
			(xy 375.0334 -178.96205) (xy 375.033308 -178.967203) (xy 375.025552 -179.021151) (xy 375.010197 -179.073446)
			(xy 374.987555 -179.123023) (xy 374.958089 -179.168873) (xy 374.922398 -179.210064) (xy 374.881207 -179.245755)
			(xy 374.835357 -179.275221) (xy 374.78578 -179.297863) (xy 374.733485 -179.313218) (xy 374.679537 -179.320974)
			(xy 374.625035 -179.320974) (xy 374.571087 -179.313218) (xy 374.518792 -179.297863) (xy 374.469215 -179.275221)
			(xy 374.423365 -179.245755) (xy 374.382174 -179.210064) (xy 374.346483 -179.168873) (xy 374.317017 -179.123023)
			(xy 374.294375 -179.073446) (xy 374.27902 -179.021151) (xy 374.271264 -178.967203) (xy 374.270778 -178.939952)
			(xy 374.271259 -178.912277) (xy 374.279258 -178.857507) (xy 374.295095 -178.804471) (xy 374.318438 -178.754283)
			(xy 374.348794 -178.707999) (xy 374.36679 -178.686968) (xy 374.37314 -178.679602) (xy 374.379744 -178.662076)
			(xy 374.37822 -178.573938) (xy 374.370854 -178.556412) (xy 374.36425 -178.549554) (xy 374.344616 -178.528141)
			(xy 374.311423 -178.480464) (xy 374.285833 -178.428309) (xy 374.268437 -178.372881) (xy 374.259637 -178.315457)
			(xy 374.259094 -178.28641) (xy 373.299736 -178.28641) (xy 373.238776 -178.34737) (xy 373.222458 -178.362783)
			(xy 373.18452 -178.386753) (xy 373.163592 -178.394868) (xy 373.154712 -178.398596) (xy 373.140305 -178.411346)
			(xy 373.13161 -178.428507) (xy 373.130318 -178.438048) (xy 373.127605 -178.463785) (xy 373.116069 -178.514237)
			(xy 373.09781 -178.562662) (xy 373.085868 -178.585622) (xy 373.081042 -178.594512) (xy 373.07901 -178.61407)
			(xy 373.104664 -178.702208) (xy 373.11711 -178.717702) (xy 373.126 -178.722782) (xy 373.133366 -178.726846)
			(xy 373.143018 -178.732688) (xy 373.165116 -178.73472) (xy 373.259604 -178.701192) (xy 373.275606 -178.685698)
			(xy 373.27967 -178.675284) (xy 373.290366 -178.648508) (xy 373.318654 -178.598266) (xy 373.354184 -178.552857)
			(xy 373.396146 -178.513315) (xy 373.443583 -178.480541) (xy 373.495414 -178.455283) (xy 373.550457 -178.438117)
			(xy 373.607457 -178.429434) (xy 373.636286 -178.428904) (xy 373.66354 -178.429342) (xy 373.717495 -178.437098)
			(xy 373.769796 -178.452453) (xy 373.819379 -178.475095) (xy 373.865236 -178.504564) (xy 373.906431 -178.540259)
			(xy 373.942128 -178.581453) (xy 373.971598 -178.627308) (xy 373.994242 -178.676891) (xy 374.009599 -178.729192)
			(xy 374.017357 -178.783146) (xy 374.017357 -178.837654) (xy 374.009599 -178.891608) (xy 373.994242 -178.943909)
			(xy 373.971598 -178.993492) (xy 373.942128 -179.039347) (xy 373.906431 -179.080541) (xy 373.865236 -179.116236)
			(xy 373.819379 -179.145705) (xy 373.769796 -179.168347) (xy 373.717495 -179.183702) (xy 373.66354 -179.191458)
			(xy 373.636286 -179.19192) (xy 373.611051 -179.191526) (xy 373.561017 -179.184907) (xy 373.512296 -179.171733)
			(xy 373.465745 -179.152235) (xy 373.443754 -179.13985) (xy 373.434102 -179.134008) (xy 373.412004 -179.131976)
			(xy 373.317516 -179.165504) (xy 373.301514 -179.180998) (xy 373.29745 -179.191412) (xy 373.286735 -179.21818)
			(xy 373.25845 -179.268421) (xy 373.222922 -179.31383) (xy 373.180963 -179.353373) (xy 373.133528 -179.386147)
			(xy 373.0817 -179.411407) (xy 373.02666 -179.428575) (xy 372.969662 -179.437261) (xy 372.940834 -179.437792)
			(xy 372.913581 -179.437313) (xy 372.85963 -179.42956) (xy 372.807332 -179.414208) (xy 372.75775 -179.391568)
			(xy 372.711896 -179.362102) (xy 372.670703 -179.32641) (xy 372.635009 -179.285218) (xy 372.605541 -179.239365)
			(xy 372.582899 -179.189785) (xy 372.567544 -179.137488) (xy 372.559788 -179.083537) (xy 372.559326 -179.056284)
			(xy 372.559992 -179.024721) (xy 372.570376 -178.962456) (xy 372.590859 -178.902747) (xy 372.6053 -178.874674)
			(xy 372.610126 -178.865784) (xy 372.612158 -178.846226) (xy 372.586504 -178.758088) (xy 372.574058 -178.742594)
			(xy 372.565168 -178.737514) (xy 372.540061 -178.722975) (xy 372.494175 -178.687473) (xy 372.454197 -178.645429)
			(xy 372.421051 -178.597814) (xy 372.395502 -178.545726) (xy 372.378138 -178.490369) (xy 372.369362 -178.43302)
			(xy 372.368826 -178.404012) (xy 372.369267 -178.376758) (xy 372.377023 -178.322804) (xy 372.392379 -178.270504)
			(xy 372.415023 -178.220922) (xy 372.444493 -178.175067) (xy 372.480189 -178.133873) (xy 372.521385 -178.098179)
			(xy 372.567241 -178.068712) (xy 372.616825 -178.046071) (xy 372.669126 -178.030718) (xy 372.72308 -178.022965)
			(xy 372.750334 -178.022504) (xy 372.768156 -178.022707) (xy 372.803647 -178.026013) (xy 372.8212 -178.029108)
			(xy 372.829779 -178.030385) (xy 372.846917 -178.027797) (xy 372.854728 -178.024028) (xy 372.877177 -178.012736)
			(xy 372.925876 -178.000407) (xy 372.950994 -177.999644) (xy 372.989348 -177.999644) (xy 372.999395 -177.999289)
			(xy 373.017992 -177.991691) (xy 373.025416 -177.984912) (xy 373.464836 -177.545492) (xy 373.47152 -177.538004)
			(xy 373.479116 -177.51945) (xy 373.479568 -177.509424) (xy 373.479568 -177.47107) (xy 373.480079 -177.451059)
			(xy 373.487902 -177.411807) (xy 373.503225 -177.374833) (xy 373.525458 -177.341552) (xy 373.539258 -177.327052)
			(xy 374.552718 -176.313846) (xy 374.559533 -176.306426) (xy 374.567267 -176.287842) (xy 374.567704 -176.277778)
			(xy 374.567704 -152.705562) (xy 374.567324 -152.695487) (xy 374.559574 -152.676888) (xy 374.552718 -152.669494)
			(xy 373.53494 -151.65197) (xy 373.521147 -151.637477) (xy 373.498975 -151.60418) (xy 373.48372 -151.5672)
			(xy 373.475969 -151.527954) (xy 373.475504 -151.507952) (xy 373.475504 -145.869152) (xy 373.475885 -145.849143)
			(xy 373.483638 -145.809885) (xy 373.498913 -145.772899) (xy 373.521123 -145.739612) (xy 373.53494 -145.725134)
			(xy 374.938798 -144.32153) (xy 374.945617 -144.314113) (xy 374.953349 -144.295527) (xy 374.953784 -144.285462)
			(xy 374.953784 -140.395452) (xy 374.954171 -140.375444) (xy 374.961923 -140.336186) (xy 374.977197 -140.299201)
			(xy 374.999404 -140.265913) (xy 375.01322 -140.251434) (xy 376.020838 -139.24407) (xy 376.027689 -139.236679)
			(xy 376.035401 -139.218073) (xy 376.035824 -139.208002) (xy 376.035824 -138.773662) (xy 376.035144 -138.761597)
			(xy 376.024132 -138.740122) (xy 376.014742 -138.732514) (xy 375.994202 -138.717023) (xy 375.957046 -138.681439)
			(xy 375.925002 -138.641191) (xy 375.898649 -138.597007) (xy 375.878463 -138.549686) (xy 375.871232 -138.524996)
			(xy 375.86793 -138.51255) (xy 375.850658 -138.494262) (xy 375.74601 -138.459464) (xy 375.721372 -138.463782)
			(xy 375.711212 -138.471656) (xy 375.691054 -138.486766) (xy 375.647534 -138.512142) (xy 375.60105 -138.531561)
			(xy 375.552411 -138.544683) (xy 375.502467 -138.551281) (xy 375.477278 -138.551666) (xy 375.450023 -138.551265)
			(xy 375.396067 -138.543504) (xy 375.343766 -138.528143) (xy 375.294183 -138.505495) (xy 375.248327 -138.476021)
			(xy 375.207134 -138.440321) (xy 375.171441 -138.399121) (xy 375.141974 -138.353261) (xy 375.119334 -138.303674)
			(xy 375.103982 -138.25137) (xy 375.09623 -138.197413) (xy 375.09577 -138.170158) (xy 375.095894 -138.155238)
			(xy 375.098181 -138.125485) (xy 375.100342 -138.110722) (xy 375.102374 -138.09853) (xy 375.095008 -138.07567)
			(xy 375.05259 -138.033252) (xy 375.045104 -138.026565) (xy 375.026548 -138.018971) (xy 375.016522 -138.01852)
			(xy 372.14175 -138.01852) (xy 372.13219 -138.018935) (xy 372.114366 -138.025844) (xy 372.100307 -138.038797)
			(xy 372.095776 -138.047222) (xy 372.050056 -138.143488) (xy 372.053358 -138.172444) (xy 372.062756 -138.183874)
			(xy 372.078763 -138.204366) (xy 372.105701 -138.248842) (xy 372.126355 -138.296562) (xy 372.140342 -138.346643)
			(xy 372.147404 -138.398159) (xy 372.147846 -138.424158) (xy 372.14736 -138.451409) (xy 372.139604 -138.505357)
			(xy 372.124249 -138.557652) (xy 372.101607 -138.607229) (xy 372.072141 -138.653079) (xy 372.03645 -138.69427)
			(xy 371.995259 -138.729961) (xy 371.949409 -138.759427) (xy 371.899832 -138.782069) (xy 371.847537 -138.797424)
			(xy 371.793589 -138.80518) (xy 371.739087 -138.80518) (xy 371.685139 -138.797424) (xy 371.632844 -138.782069)
			(xy 371.583267 -138.759427) (xy 371.537417 -138.729961) (xy 371.496226 -138.69427) (xy 371.460535 -138.653079)
			(xy 371.431069 -138.607229) (xy 371.408427 -138.557652) (xy 371.393072 -138.505357) (xy 371.385316 -138.451409)
			(xy 371.38483 -138.424158) (xy 371.385271 -138.398158) (xy 371.392323 -138.346639) (xy 371.406304 -138.296554)
			(xy 371.426957 -138.248831) (xy 371.453897 -138.204354) (xy 371.46992 -138.183874) (xy 371.479318 -138.172444)
			(xy 371.48262 -138.143488) (xy 371.4369 -138.047222) (xy 371.432399 -138.03877) (xy 371.418337 -138.025791)
			(xy 371.400496 -138.018871) (xy 371.390926 -138.01852) (xy 369.833652 -138.01852) (xy 369.823606 -138.018885)
			(xy 369.80501 -138.026477) (xy 369.797584 -138.033252) (xy 368.652044 -139.178792) (xy 373.863614 -139.178792)
			(xy 373.867685 -139.12317) (xy 373.879811 -139.068733) (xy 373.899734 -139.016642) (xy 373.92703 -138.968007)
			(xy 373.961116 -138.923864) (xy 374.001265 -138.885155) (xy 374.046623 -138.852704) (xy 374.096223 -138.827203)
			(xy 374.149007 -138.809196) (xy 374.20385 -138.799066) (xy 374.259584 -138.797029) (xy 374.315021 -138.803129)
			(xy 374.368978 -138.817235) (xy 374.420307 -138.839047) (xy 374.467913 -138.868101) (xy 374.510781 -138.903776)
			(xy 374.547998 -138.945313) (xy 374.578771 -138.991826) (xy 374.602443 -139.042323) (xy 374.618511 -139.09573)
			(xy 374.622511 -139.122912) (xy 375.06732 -139.122912) (xy 375.071391 -139.06729) (xy 375.083517 -139.012853)
			(xy 375.10344 -138.960762) (xy 375.130736 -138.912127) (xy 375.164822 -138.867984) (xy 375.204971 -138.829275)
			(xy 375.250329 -138.796824) (xy 375.299929 -138.771323) (xy 375.352713 -138.753316) (xy 375.407556 -138.743186)
			(xy 375.46329 -138.741149) (xy 375.518727 -138.747249) (xy 375.572684 -138.761355) (xy 375.624013 -138.783167)
			(xy 375.671619 -138.812221) (xy 375.714487 -138.847896) (xy 375.751704 -138.889433) (xy 375.782477 -138.935946)
			(xy 375.806149 -138.986443) (xy 375.822217 -139.03985) (xy 375.830337 -139.095026) (xy 375.830846 -139.122912)
			(xy 375.830337 -139.150798) (xy 375.822217 -139.205974) (xy 375.806149 -139.259381) (xy 375.782477 -139.309878)
			(xy 375.751704 -139.356391) (xy 375.714487 -139.397928) (xy 375.671619 -139.433603) (xy 375.624013 -139.462657)
			(xy 375.572684 -139.484469) (xy 375.518727 -139.498575) (xy 375.46329 -139.504675) (xy 375.407556 -139.502638)
			(xy 375.352713 -139.492508) (xy 375.299929 -139.474501) (xy 375.250329 -139.449) (xy 375.204971 -139.416549)
			(xy 375.164822 -139.37784) (xy 375.130736 -139.333697) (xy 375.10344 -139.285062) (xy 375.083517 -139.232971)
			(xy 375.071391 -139.178534) (xy 375.06732 -139.122912) (xy 374.622511 -139.122912) (xy 374.626631 -139.150906)
			(xy 374.62714 -139.178792) (xy 374.626631 -139.206678) (xy 374.618511 -139.261854) (xy 374.602443 -139.315261)
			(xy 374.578771 -139.365758) (xy 374.547998 -139.412271) (xy 374.510781 -139.453808) (xy 374.467913 -139.489483)
			(xy 374.420307 -139.518537) (xy 374.368978 -139.540349) (xy 374.315021 -139.554455) (xy 374.259584 -139.560555)
			(xy 374.20385 -139.558518) (xy 374.149007 -139.548388) (xy 374.096223 -139.530381) (xy 374.046623 -139.50488)
			(xy 374.001265 -139.472429) (xy 373.961116 -139.43372) (xy 373.92703 -139.389577) (xy 373.899734 -139.340942)
			(xy 373.879811 -139.288851) (xy 373.867685 -139.234414) (xy 373.863614 -139.178792) (xy 368.652044 -139.178792)
			(xy 367.815622 -140.015214) (xy 373.57126 -140.015214) (xy 373.575331 -139.959592) (xy 373.587457 -139.905155)
			(xy 373.60738 -139.853064) (xy 373.634676 -139.804429) (xy 373.668762 -139.760286) (xy 373.708911 -139.721577)
			(xy 373.754269 -139.689126) (xy 373.803869 -139.663625) (xy 373.856653 -139.645618) (xy 373.911496 -139.635488)
			(xy 373.96723 -139.633451) (xy 374.022667 -139.639551) (xy 374.076624 -139.653657) (xy 374.127953 -139.675469)
			(xy 374.175559 -139.704523) (xy 374.218427 -139.740198) (xy 374.255644 -139.781735) (xy 374.286417 -139.828248)
			(xy 374.310089 -139.878745) (xy 374.326157 -139.932152) (xy 374.334277 -139.987328) (xy 374.334786 -140.015214)
			(xy 374.334277 -140.0431) (xy 374.326157 -140.098276) (xy 374.310089 -140.151683) (xy 374.286417 -140.20218)
			(xy 374.255644 -140.248693) (xy 374.218427 -140.29023) (xy 374.175559 -140.325905) (xy 374.127953 -140.354959)
			(xy 374.076624 -140.376771) (xy 374.022667 -140.390877) (xy 373.96723 -140.396977) (xy 373.911496 -140.39494)
			(xy 373.856653 -140.38481) (xy 373.803869 -140.366803) (xy 373.754269 -140.341302) (xy 373.708911 -140.308851)
			(xy 373.668762 -140.270142) (xy 373.634676 -140.225999) (xy 373.60738 -140.177364) (xy 373.587457 -140.125273)
			(xy 373.575331 -140.070836) (xy 373.57126 -140.015214) (xy 367.815622 -140.015214) (xy 366.855502 -140.975334)
			(xy 371.09273 -140.975334) (xy 371.093216 -140.948083) (xy 371.100972 -140.894135) (xy 371.116327 -140.84184)
			(xy 371.138969 -140.792263) (xy 371.168435 -140.746413) (xy 371.204126 -140.705222) (xy 371.245317 -140.669531)
			(xy 371.291167 -140.640065) (xy 371.340744 -140.617423) (xy 371.393039 -140.602068) (xy 371.446987 -140.594312)
			(xy 371.501489 -140.594312) (xy 371.555437 -140.602068) (xy 371.607732 -140.617423) (xy 371.657309 -140.640065)
			(xy 371.703159 -140.669531) (xy 371.74435 -140.705222) (xy 371.780041 -140.746413) (xy 371.809507 -140.792263)
			(xy 371.832149 -140.84184) (xy 371.847504 -140.894135) (xy 371.85526 -140.948083) (xy 371.855746 -140.975334)
			(xy 371.855239 -141.004699) (xy 371.846308 -141.062744) (xy 371.837966 -141.090904) (xy 371.834337 -141.103868)
			(xy 371.833141 -141.130748) (xy 371.839019 -141.157005) (xy 371.851561 -141.18081) (xy 371.869893 -141.200504)
			(xy 371.89274 -141.214717) (xy 371.918509 -141.222459) (xy 371.931946 -141.223238) (xy 371.958688 -141.224443)
			(xy 372.011468 -141.233379) (xy 372.062478 -141.24961) (xy 372.110717 -141.272817) (xy 372.155236 -141.302542)
			(xy 372.195159 -141.338202) (xy 372.229702 -141.379096) (xy 372.258186 -141.424419) (xy 372.28005 -141.473281)
			(xy 372.294866 -141.52472) (xy 372.30234 -141.577727) (xy 372.302786 -141.604492) (xy 372.3023 -141.631743)
			(xy 372.294544 -141.685691) (xy 372.279189 -141.737986) (xy 372.256547 -141.787563) (xy 372.227081 -141.833413)
			(xy 372.19139 -141.874604) (xy 372.150199 -141.910295) (xy 372.104349 -141.939761) (xy 372.054772 -141.962403)
			(xy 372.002477 -141.977758) (xy 371.948529 -141.985514) (xy 371.894027 -141.985514) (xy 371.840079 -141.977758)
			(xy 371.787784 -141.962403) (xy 371.738207 -141.939761) (xy 371.692357 -141.910295) (xy 371.651166 -141.874604)
			(xy 371.615475 -141.833413) (xy 371.586009 -141.787563) (xy 371.563367 -141.737986) (xy 371.548012 -141.685691)
			(xy 371.540256 -141.631743) (xy 371.53977 -141.604492) (xy 371.540286 -141.575128) (xy 371.549211 -141.517082)
			(xy 371.55755 -141.488922) (xy 371.561249 -141.475977) (xy 371.562429 -141.449089) (xy 371.556537 -141.422828)
			(xy 371.543983 -141.399022) (xy 371.52564 -141.379326) (xy 371.502786 -141.365112) (xy 371.477011 -141.357369)
			(xy 371.46357 -141.356588) (xy 371.436825 -141.355433) (xy 371.384046 -141.346486) (xy 371.333036 -141.330246)
			(xy 371.284799 -141.307032) (xy 371.240282 -141.277301) (xy 371.200361 -141.241636) (xy 371.165819 -141.200739)
			(xy 371.137336 -141.155413) (xy 371.115471 -141.106549) (xy 371.100655 -141.055108) (xy 371.093178 -141.0021)
			(xy 371.09273 -140.975334) (xy 366.855502 -140.975334) (xy 366.007142 -141.823694) (xy 366.000632 -141.830712)
			(xy 365.993011 -141.84826) (xy 365.992371 -141.86738) (xy 365.995204 -141.876526) (xy 366.030764 -141.976856)
			(xy 366.053624 -141.99489) (xy 366.068102 -141.996668) (xy 366.095824 -142.000155) (xy 366.149916 -142.014141)
			(xy 366.201389 -142.035867) (xy 366.249143 -142.06487) (xy 366.292156 -142.100528) (xy 366.329507 -142.142078)
			(xy 366.360398 -142.188632) (xy 366.384168 -142.239195) (xy 366.400309 -142.292684) (xy 366.408474 -142.347955)
			(xy 366.40897 -142.37589) (xy 366.408535 -142.403144) (xy 366.400779 -142.457098) (xy 366.391659 -142.488158)
			(xy 371.53926 -142.488158) (xy 371.543331 -142.432536) (xy 371.555457 -142.378099) (xy 371.57538 -142.326008)
			(xy 371.602676 -142.277373) (xy 371.636762 -142.23323) (xy 371.676911 -142.194521) (xy 371.722269 -142.16207)
			(xy 371.771869 -142.136569) (xy 371.824653 -142.118562) (xy 371.879496 -142.108432) (xy 371.93523 -142.106395)
			(xy 371.990667 -142.112495) (xy 372.044624 -142.126601) (xy 372.095953 -142.148413) (xy 372.143559 -142.177467)
			(xy 372.186427 -142.213142) (xy 372.223644 -142.254679) (xy 372.254417 -142.301192) (xy 372.278089 -142.351689)
			(xy 372.294157 -142.405096) (xy 372.302277 -142.460272) (xy 372.302786 -142.488158) (xy 372.302277 -142.516044)
			(xy 372.295653 -142.561056) (xy 373.69877 -142.561056) (xy 373.699236 -142.534988) (xy 373.706348 -142.483339)
			(xy 373.72042 -142.433137) (xy 373.74119 -142.385316) (xy 373.768273 -142.340766) (xy 373.801165 -142.300314)
			(xy 373.839253 -142.264712) (xy 373.881831 -142.234623) (xy 373.904764 -142.22222) (xy 373.915178 -142.216886)
			(xy 373.928894 -142.199106) (xy 373.949722 -142.099284) (xy 373.944388 -142.077186) (xy 373.937276 -142.068296)
			(xy 373.921311 -142.047845) (xy 373.894452 -142.003457) (xy 373.87386 -141.955836) (xy 373.859917 -141.905863)
			(xy 373.852878 -141.854461) (xy 373.85244 -141.82852) (xy 373.852894 -141.800916) (xy 373.860837 -141.746283)
			(xy 373.876574 -141.693366) (xy 373.899777 -141.643271) (xy 373.929959 -141.597044) (xy 373.966492 -141.555653)
			(xy 374.008611 -141.519962) (xy 374.031764 -141.504924) (xy 374.042686 -141.498066) (xy 374.055386 -141.475968)
			(xy 374.05818 -141.365732) (xy 374.04675 -141.342872) (xy 374.036082 -141.335506) (xy 374.014869 -141.320146)
			(xy 373.976466 -141.284535) (xy 373.943296 -141.244005) (xy 373.91598 -141.199319) (xy 373.895034 -141.151317)
			(xy 373.88085 -141.100901) (xy 373.873696 -141.049019) (xy 373.873268 -141.022832) (xy 373.873754 -140.995581)
			(xy 373.88151 -140.941633) (xy 373.896865 -140.889338) (xy 373.919507 -140.839761) (xy 373.948973 -140.793911)
			(xy 373.984664 -140.75272) (xy 374.025855 -140.717029) (xy 374.071705 -140.687563) (xy 374.121282 -140.664921)
			(xy 374.173577 -140.649566) (xy 374.227525 -140.64181) (xy 374.282027 -140.64181) (xy 374.335975 -140.649566)
			(xy 374.38827 -140.664921) (xy 374.437847 -140.687563) (xy 374.483697 -140.717029) (xy 374.524888 -140.75272)
			(xy 374.560579 -140.793911) (xy 374.590045 -140.839761) (xy 374.612687 -140.889338) (xy 374.628042 -140.941633)
			(xy 374.635798 -140.995581) (xy 374.636284 -141.022832) (xy 374.635828 -141.050436) (xy 374.62789 -141.105071)
			(xy 374.612156 -141.15799) (xy 374.588955 -141.208086) (xy 374.558771 -141.254313) (xy 374.522237 -141.295703)
			(xy 374.480115 -141.331392) (xy 374.45696 -141.346428) (xy 374.446038 -141.353286) (xy 374.433338 -141.375384)
			(xy 374.430544 -141.48562) (xy 374.441974 -141.50848) (xy 374.452642 -141.515846) (xy 374.473838 -141.531228)
			(xy 374.51224 -141.566837) (xy 374.545411 -141.607363) (xy 374.572728 -141.652045) (xy 374.593677 -141.700043)
			(xy 374.607865 -141.750456) (xy 374.615025 -141.802335) (xy 374.615456 -141.82852) (xy 374.61501 -141.854589)
			(xy 374.6079 -141.906241) (xy 374.593828 -141.956445) (xy 374.573056 -142.004267) (xy 374.54597 -142.048819)
			(xy 374.513074 -142.089271) (xy 374.474981 -142.12487) (xy 374.432398 -142.154956) (xy 374.409462 -142.167356)
			(xy 374.399048 -142.17269) (xy 374.385332 -142.19047) (xy 374.364504 -142.290292) (xy 374.369838 -142.31239)
			(xy 374.37695 -142.32128) (xy 374.392908 -142.341737) (xy 374.419767 -142.386124) (xy 374.44036 -142.433743)
			(xy 374.454305 -142.483714) (xy 374.461346 -142.535116) (xy 374.461786 -142.561056) (xy 374.4613 -142.588307)
			(xy 374.453544 -142.642255) (xy 374.438189 -142.69455) (xy 374.415547 -142.744127) (xy 374.386081 -142.789977)
			(xy 374.35039 -142.831168) (xy 374.309199 -142.866859) (xy 374.263349 -142.896325) (xy 374.213772 -142.918967)
			(xy 374.161477 -142.934322) (xy 374.107529 -142.942078) (xy 374.053027 -142.942078) (xy 373.999079 -142.934322)
			(xy 373.946784 -142.918967) (xy 373.897207 -142.896325) (xy 373.851357 -142.866859) (xy 373.810166 -142.831168)
			(xy 373.774475 -142.789977) (xy 373.745009 -142.744127) (xy 373.722367 -142.69455) (xy 373.707012 -142.642255)
			(xy 373.699256 -142.588307) (xy 373.69877 -142.561056) (xy 372.295653 -142.561056) (xy 372.294157 -142.57122)
			(xy 372.278089 -142.624627) (xy 372.254417 -142.675124) (xy 372.223644 -142.721637) (xy 372.186427 -142.763174)
			(xy 372.143559 -142.798849) (xy 372.095953 -142.827903) (xy 372.044624 -142.849715) (xy 371.990667 -142.863821)
			(xy 371.93523 -142.869921) (xy 371.879496 -142.867884) (xy 371.824653 -142.857754) (xy 371.771869 -142.839747)
			(xy 371.722269 -142.814246) (xy 371.676911 -142.781795) (xy 371.636762 -142.743086) (xy 371.602676 -142.698943)
			(xy 371.57538 -142.650308) (xy 371.555457 -142.598217) (xy 371.543331 -142.54378) (xy 371.53926 -142.488158)
			(xy 366.391659 -142.488158) (xy 366.385422 -142.509399) (xy 366.362778 -142.558982) (xy 366.333307 -142.604837)
			(xy 366.297611 -142.64603) (xy 366.256414 -142.681724) (xy 366.210557 -142.711191) (xy 366.160973 -142.733832)
			(xy 366.108671 -142.749185) (xy 366.054716 -142.756937) (xy 366.027462 -142.757398) (xy 365.999516 -142.757011)
			(xy 365.944221 -142.748873) (xy 365.890707 -142.732748) (xy 365.840121 -142.708981) (xy 365.793547 -142.678082)
			(xy 365.751985 -142.640714) (xy 365.716326 -142.597677) (xy 365.687333 -142.549894) (xy 365.665628 -142.498389)
			(xy 365.651676 -142.444268) (xy 365.64824 -142.41653) (xy 365.646462 -142.402052) (xy 365.628428 -142.379192)
			(xy 365.528098 -142.343632) (xy 365.518964 -142.340801) (xy 365.499863 -142.341511) (xy 365.482327 -142.349117)
			(xy 365.475266 -142.35557) (xy 364.4519 -143.378936) (xy 364.445195 -143.386408) (xy 364.437613 -143.404974)
			(xy 364.437168 -143.415004) (xy 364.437168 -143.504158) (xy 373.57126 -143.504158) (xy 373.575331 -143.448536)
			(xy 373.587457 -143.394099) (xy 373.60738 -143.342008) (xy 373.634676 -143.293373) (xy 373.668762 -143.24923)
			(xy 373.708911 -143.210521) (xy 373.754269 -143.17807) (xy 373.803869 -143.152569) (xy 373.856653 -143.134562)
			(xy 373.911496 -143.124432) (xy 373.96723 -143.122395) (xy 374.022667 -143.128495) (xy 374.076624 -143.142601)
			(xy 374.127953 -143.164413) (xy 374.175559 -143.193467) (xy 374.218427 -143.229142) (xy 374.255644 -143.270679)
			(xy 374.286417 -143.317192) (xy 374.310089 -143.367689) (xy 374.326157 -143.421096) (xy 374.334277 -143.476272)
			(xy 374.334786 -143.504158) (xy 374.334277 -143.532044) (xy 374.326157 -143.58722) (xy 374.310089 -143.640627)
			(xy 374.286417 -143.691124) (xy 374.255644 -143.737637) (xy 374.218427 -143.779174) (xy 374.175559 -143.814849)
			(xy 374.127953 -143.843903) (xy 374.076624 -143.865715) (xy 374.022667 -143.879821) (xy 373.96723 -143.885921)
			(xy 373.911496 -143.883884) (xy 373.856653 -143.873754) (xy 373.803869 -143.855747) (xy 373.754269 -143.830246)
			(xy 373.708911 -143.797795) (xy 373.668762 -143.759086) (xy 373.634676 -143.714943) (xy 373.60738 -143.666308)
			(xy 373.587457 -143.614217) (xy 373.575331 -143.55978) (xy 373.57126 -143.504158) (xy 364.437168 -143.504158)
			(xy 364.437168 -144.520158) (xy 371.53926 -144.520158) (xy 371.543331 -144.464536) (xy 371.555457 -144.410099)
			(xy 371.57538 -144.358008) (xy 371.602676 -144.309373) (xy 371.636762 -144.26523) (xy 371.676911 -144.226521)
			(xy 371.722269 -144.19407) (xy 371.771869 -144.168569) (xy 371.824653 -144.150562) (xy 371.879496 -144.140432)
			(xy 371.93523 -144.138395) (xy 371.990667 -144.144495) (xy 372.044624 -144.158601) (xy 372.095953 -144.180413)
			(xy 372.143559 -144.209467) (xy 372.186427 -144.245142) (xy 372.223644 -144.286679) (xy 372.254417 -144.333192)
			(xy 372.278089 -144.383689) (xy 372.294157 -144.437096) (xy 372.302277 -144.492272) (xy 372.302786 -144.520158)
			(xy 372.302277 -144.548044) (xy 372.294157 -144.60322) (xy 372.278089 -144.656627) (xy 372.254417 -144.707124)
			(xy 372.223644 -144.753637) (xy 372.186427 -144.795174) (xy 372.143559 -144.830849) (xy 372.095953 -144.859903)
			(xy 372.044624 -144.881715) (xy 371.990667 -144.895821) (xy 371.93523 -144.901921) (xy 371.879496 -144.899884)
			(xy 371.824653 -144.889754) (xy 371.771869 -144.871747) (xy 371.722269 -144.846246) (xy 371.676911 -144.813795)
			(xy 371.636762 -144.775086) (xy 371.602676 -144.730943) (xy 371.57538 -144.682308) (xy 371.555457 -144.630217)
			(xy 371.543331 -144.57578) (xy 371.53926 -144.520158) (xy 364.437168 -144.520158) (xy 364.437168 -145.536158)
			(xy 371.53926 -145.536158) (xy 371.543331 -145.480536) (xy 371.555457 -145.426099) (xy 371.57538 -145.374008)
			(xy 371.602676 -145.325373) (xy 371.636762 -145.28123) (xy 371.676911 -145.242521) (xy 371.722269 -145.21007)
			(xy 371.771869 -145.184569) (xy 371.824653 -145.166562) (xy 371.879496 -145.156432) (xy 371.93523 -145.154395)
			(xy 371.990667 -145.160495) (xy 372.044624 -145.174601) (xy 372.095953 -145.196413) (xy 372.143559 -145.225467)
			(xy 372.186427 -145.261142) (xy 372.223644 -145.302679) (xy 372.254417 -145.349192) (xy 372.278089 -145.399689)
			(xy 372.294157 -145.453096) (xy 372.302277 -145.508272) (xy 372.302786 -145.536158) (xy 372.302277 -145.564044)
			(xy 372.294157 -145.61922) (xy 372.278089 -145.672627) (xy 372.254417 -145.723124) (xy 372.223644 -145.769637)
			(xy 372.186427 -145.811174) (xy 372.143559 -145.846849) (xy 372.095953 -145.875903) (xy 372.044624 -145.897715)
			(xy 371.990667 -145.911821) (xy 371.93523 -145.917921) (xy 371.879496 -145.915884) (xy 371.824653 -145.905754)
			(xy 371.771869 -145.887747) (xy 371.722269 -145.862246) (xy 371.676911 -145.829795) (xy 371.636762 -145.791086)
			(xy 371.602676 -145.746943) (xy 371.57538 -145.698308) (xy 371.555457 -145.646217) (xy 371.543331 -145.59178)
			(xy 371.53926 -145.536158) (xy 364.437168 -145.536158) (xy 364.437168 -146.49577) (xy 365.860074 -146.49577)
			(xy 365.864145 -146.440148) (xy 365.876271 -146.385711) (xy 365.896194 -146.33362) (xy 365.92349 -146.284985)
			(xy 365.957576 -146.240842) (xy 365.997725 -146.202133) (xy 366.043083 -146.169682) (xy 366.092683 -146.144181)
			(xy 366.145467 -146.126174) (xy 366.20031 -146.116044) (xy 366.256044 -146.114007) (xy 366.311481 -146.120107)
			(xy 366.365438 -146.134213) (xy 366.416767 -146.156025) (xy 366.464373 -146.185079) (xy 366.507241 -146.220754)
			(xy 366.544458 -146.262291) (xy 366.575231 -146.308804) (xy 366.598903 -146.359301) (xy 366.614971 -146.412708)
			(xy 366.623091 -146.467884) (xy 366.6236 -146.49577) (xy 366.623091 -146.523656) (xy 366.618896 -146.552158)
			(xy 371.53926 -146.552158) (xy 371.543331 -146.496536) (xy 371.555457 -146.442099) (xy 371.57538 -146.390008)
			(xy 371.602676 -146.341373) (xy 371.636762 -146.29723) (xy 371.676911 -146.258521) (xy 371.722269 -146.22607)
			(xy 371.771869 -146.200569) (xy 371.824653 -146.182562) (xy 371.879496 -146.172432) (xy 371.93523 -146.170395)
			(xy 371.990667 -146.176495) (xy 372.044624 -146.190601) (xy 372.095953 -146.212413) (xy 372.143559 -146.241467)
			(xy 372.186427 -146.277142) (xy 372.223644 -146.318679) (xy 372.254417 -146.365192) (xy 372.278089 -146.415689)
			(xy 372.294157 -146.469096) (xy 372.302277 -146.524272) (xy 372.302786 -146.552158) (xy 372.302277 -146.580044)
			(xy 372.294157 -146.63522) (xy 372.278089 -146.688627) (xy 372.254417 -146.739124) (xy 372.223644 -146.785637)
			(xy 372.186427 -146.827174) (xy 372.143559 -146.862849) (xy 372.095953 -146.891903) (xy 372.044624 -146.913715)
			(xy 371.990667 -146.927821) (xy 371.93523 -146.933921) (xy 371.879496 -146.931884) (xy 371.824653 -146.921754)
			(xy 371.771869 -146.903747) (xy 371.722269 -146.878246) (xy 371.676911 -146.845795) (xy 371.636762 -146.807086)
			(xy 371.602676 -146.762943) (xy 371.57538 -146.714308) (xy 371.555457 -146.662217) (xy 371.543331 -146.60778)
			(xy 371.53926 -146.552158) (xy 366.618896 -146.552158) (xy 366.614971 -146.578832) (xy 366.598903 -146.632239)
			(xy 366.575231 -146.682736) (xy 366.544458 -146.729249) (xy 366.507241 -146.770786) (xy 366.464373 -146.806461)
			(xy 366.416767 -146.835515) (xy 366.365438 -146.857327) (xy 366.311481 -146.871433) (xy 366.256044 -146.877533)
			(xy 366.20031 -146.875496) (xy 366.145467 -146.865366) (xy 366.092683 -146.847359) (xy 366.043083 -146.821858)
			(xy 365.997725 -146.789407) (xy 365.957576 -146.750698) (xy 365.92349 -146.706555) (xy 365.896194 -146.65792)
			(xy 365.876271 -146.605829) (xy 365.864145 -146.551392) (xy 365.860074 -146.49577) (xy 364.437168 -146.49577)
			(xy 364.437168 -147.568158) (xy 371.53926 -147.568158) (xy 371.543331 -147.512536) (xy 371.555457 -147.458099)
			(xy 371.57538 -147.406008) (xy 371.602676 -147.357373) (xy 371.636762 -147.31323) (xy 371.676911 -147.274521)
			(xy 371.722269 -147.24207) (xy 371.771869 -147.216569) (xy 371.824653 -147.198562) (xy 371.879496 -147.188432)
			(xy 371.93523 -147.186395) (xy 371.990667 -147.192495) (xy 372.044624 -147.206601) (xy 372.095953 -147.228413)
			(xy 372.143559 -147.257467) (xy 372.186427 -147.293142) (xy 372.223644 -147.334679) (xy 372.254417 -147.381192)
			(xy 372.278089 -147.431689) (xy 372.294157 -147.485096) (xy 372.302277 -147.540272) (xy 372.302786 -147.568158)
			(xy 372.302277 -147.596044) (xy 372.294157 -147.65122) (xy 372.278089 -147.704627) (xy 372.254417 -147.755124)
			(xy 372.223644 -147.801637) (xy 372.186427 -147.843174) (xy 372.143559 -147.878849) (xy 372.095953 -147.907903)
			(xy 372.044624 -147.929715) (xy 371.990667 -147.943821) (xy 371.93523 -147.949921) (xy 371.879496 -147.947884)
			(xy 371.824653 -147.937754) (xy 371.771869 -147.919747) (xy 371.722269 -147.894246) (xy 371.676911 -147.861795)
			(xy 371.636762 -147.823086) (xy 371.602676 -147.778943) (xy 371.57538 -147.730308) (xy 371.555457 -147.678217)
			(xy 371.543331 -147.62378) (xy 371.53926 -147.568158) (xy 364.437168 -147.568158) (xy 364.437168 -154.487118)
			(xy 364.436668 -154.50713) (xy 364.428844 -154.546383) (xy 364.413519 -154.583358) (xy 364.391281 -154.616637)
			(xy 364.377478 -154.631136) (xy 363.297978 -155.710382) (xy 363.29115 -155.717791) (xy 363.283424 -155.736384)
			(xy 363.282992 -155.74645) (xy 363.282992 -157.46831) (xy 365.557825 -157.46831) (xy 365.561553 -157.415059)
			(xy 365.572669 -157.362848) (xy 365.590955 -157.312696) (xy 365.616054 -157.265584) (xy 365.647476 -157.22243)
			(xy 365.684607 -157.184079) (xy 365.70539 -157.167326) (xy 365.714134 -157.159747) (xy 365.724328 -157.139001)
			(xy 365.724948 -157.127448) (xy 365.724948 -157.047184) (xy 365.724405 -157.035612) (xy 365.714193 -157.01484)
			(xy 365.70539 -157.007306) (xy 365.684622 -156.990534) (xy 365.647489 -156.952185) (xy 365.616065 -156.909033)
			(xy 365.590963 -156.861922) (xy 365.572675 -156.811771) (xy 365.561556 -156.75956) (xy 365.557825 -156.70631)
			(xy 365.561553 -156.653059) (xy 365.572669 -156.600848) (xy 365.590955 -156.550696) (xy 365.616054 -156.503584)
			(xy 365.647476 -156.46043) (xy 365.684607 -156.422079) (xy 365.70539 -156.405326) (xy 365.714134 -156.397747)
			(xy 365.724328 -156.377001) (xy 365.724948 -156.365448) (xy 365.724948 -156.285184) (xy 365.724405 -156.273612)
			(xy 365.714193 -156.25284) (xy 365.70539 -156.245306) (xy 365.684622 -156.228534) (xy 365.647489 -156.190185)
			(xy 365.616065 -156.147033) (xy 365.590963 -156.099922) (xy 365.572675 -156.049771) (xy 365.561556 -155.99756)
			(xy 365.557825 -155.94431) (xy 365.561553 -155.891059) (xy 365.572669 -155.838848) (xy 365.590955 -155.788696)
			(xy 365.616054 -155.741584) (xy 365.647476 -155.69843) (xy 365.684607 -155.660079) (xy 365.70539 -155.643326)
			(xy 365.714134 -155.635747) (xy 365.724328 -155.615001) (xy 365.724948 -155.603448) (xy 365.724948 -155.523184)
			(xy 365.724405 -155.511612) (xy 365.714193 -155.49084) (xy 365.70539 -155.483306) (xy 365.684622 -155.466534)
			(xy 365.647489 -155.428185) (xy 365.616065 -155.385033) (xy 365.590963 -155.337922) (xy 365.572675 -155.287771)
			(xy 365.561556 -155.23556) (xy 365.557825 -155.18231) (xy 365.561553 -155.129059) (xy 365.572669 -155.076848)
			(xy 365.590955 -155.026696) (xy 365.616054 -154.979584) (xy 365.647476 -154.93643) (xy 365.684607 -154.898079)
			(xy 365.70539 -154.881326) (xy 365.714134 -154.873747) (xy 365.724328 -154.853001) (xy 365.724948 -154.841448)
			(xy 365.724948 -154.761184) (xy 365.724405 -154.749612) (xy 365.714193 -154.72884) (xy 365.70539 -154.721306)
			(xy 365.682907 -154.703114) (xy 365.643173 -154.661094) (xy 365.610234 -154.613559) (xy 365.584845 -154.561598)
			(xy 365.567589 -154.506401) (xy 365.558859 -154.449232) (xy 365.558324 -154.420316) (xy 365.55877 -154.393062)
			(xy 365.566526 -154.339109) (xy 365.581882 -154.286809) (xy 365.604525 -154.237227) (xy 365.633994 -154.191372)
			(xy 365.669689 -154.150178) (xy 365.710885 -154.114484) (xy 365.756741 -154.085017) (xy 365.806324 -154.062376)
			(xy 365.858625 -154.047023) (xy 365.912578 -154.039269) (xy 365.939832 -154.038808) (xy 365.968747 -154.039372)
			(xy 366.025916 -154.048091) (xy 366.081115 -154.06534) (xy 366.133077 -154.090723) (xy 366.180612 -154.123658)
			(xy 366.222631 -154.163392) (xy 366.240822 -154.185874) (xy 366.248366 -154.194654) (xy 366.269139 -154.204824)
			(xy 366.2807 -154.205432) (xy 366.360964 -154.205432) (xy 366.372533 -154.204865) (xy 366.393305 -154.19467)
			(xy 366.400842 -154.185874) (xy 366.417595 -154.165091) (xy 366.455949 -154.127961) (xy 366.499103 -154.096539)
			(xy 366.546217 -154.07144) (xy 366.596369 -154.053154) (xy 366.64858 -154.042037) (xy 366.701832 -154.038307)
			(xy 366.755084 -154.042037) (xy 366.807295 -154.053154) (xy 366.857447 -154.07144) (xy 366.904561 -154.096539)
			(xy 366.947715 -154.127961) (xy 366.986069 -154.165091) (xy 367.002822 -154.185874) (xy 367.010366 -154.194654)
			(xy 367.031139 -154.204824) (xy 367.0427 -154.205432) (xy 367.122964 -154.205432) (xy 367.134533 -154.204865)
			(xy 367.155305 -154.19467) (xy 367.162842 -154.185874) (xy 367.179595 -154.165091) (xy 367.217949 -154.127961)
			(xy 367.261103 -154.096539) (xy 367.308217 -154.07144) (xy 367.358369 -154.053154) (xy 367.41058 -154.042037)
			(xy 367.463832 -154.038307) (xy 367.517084 -154.042037) (xy 367.569295 -154.053154) (xy 367.619447 -154.07144)
			(xy 367.666561 -154.096539) (xy 367.709715 -154.127961) (xy 367.748069 -154.165091) (xy 367.764822 -154.185874)
			(xy 367.772366 -154.194654) (xy 367.793139 -154.204824) (xy 367.8047 -154.205432) (xy 367.884964 -154.205432)
			(xy 367.896533 -154.204865) (xy 367.917305 -154.19467) (xy 367.924842 -154.185874) (xy 367.941595 -154.165091)
			(xy 367.979949 -154.127961) (xy 368.023103 -154.096539) (xy 368.070217 -154.07144) (xy 368.120369 -154.053154)
			(xy 368.17258 -154.042037) (xy 368.225832 -154.038307) (xy 368.279084 -154.042037) (xy 368.331295 -154.053154)
			(xy 368.381447 -154.07144) (xy 368.428561 -154.096539) (xy 368.471715 -154.127961) (xy 368.510069 -154.165091)
			(xy 368.526822 -154.185874) (xy 368.534366 -154.194654) (xy 368.555139 -154.204824) (xy 368.5667 -154.205432)
			(xy 368.646964 -154.205432) (xy 368.658533 -154.204865) (xy 368.679305 -154.19467) (xy 368.686842 -154.185874)
			(xy 368.703595 -154.165091) (xy 368.741949 -154.127961) (xy 368.785103 -154.096539) (xy 368.832217 -154.07144)
			(xy 368.882369 -154.053154) (xy 368.93458 -154.042037) (xy 368.987832 -154.038307) (xy 369.041084 -154.042037)
			(xy 369.093295 -154.053154) (xy 369.143447 -154.07144) (xy 369.190561 -154.096539) (xy 369.233715 -154.127961)
			(xy 369.272069 -154.165091) (xy 369.288822 -154.185874) (xy 369.296366 -154.194654) (xy 369.317139 -154.204824)
			(xy 369.3287 -154.205432) (xy 369.408964 -154.205432) (xy 369.420533 -154.204865) (xy 369.441305 -154.19467)
			(xy 369.448842 -154.185874) (xy 369.465595 -154.165091) (xy 369.503949 -154.127961) (xy 369.547103 -154.096539)
			(xy 369.594217 -154.07144) (xy 369.644369 -154.053154) (xy 369.69658 -154.042037) (xy 369.749832 -154.038307)
			(xy 369.803084 -154.042037) (xy 369.855295 -154.053154) (xy 369.905447 -154.07144) (xy 369.952561 -154.096539)
			(xy 369.995715 -154.127961) (xy 370.034069 -154.165091) (xy 370.050822 -154.185874) (xy 370.058366 -154.194654)
			(xy 370.079139 -154.204824) (xy 370.0907 -154.205432) (xy 370.170964 -154.205432) (xy 370.182533 -154.204865)
			(xy 370.203305 -154.19467) (xy 370.210842 -154.185874) (xy 370.227595 -154.165091) (xy 370.265949 -154.127961)
			(xy 370.309103 -154.096539) (xy 370.356217 -154.07144) (xy 370.406369 -154.053154) (xy 370.45858 -154.042037)
			(xy 370.511832 -154.038307) (xy 370.565084 -154.042037) (xy 370.617295 -154.053154) (xy 370.667447 -154.07144)
			(xy 370.714561 -154.096539) (xy 370.757715 -154.127961) (xy 370.796069 -154.165091) (xy 370.812822 -154.185874)
			(xy 370.820366 -154.194654) (xy 370.841139 -154.204824) (xy 370.8527 -154.205432) (xy 370.932964 -154.205432)
			(xy 370.944533 -154.204865) (xy 370.965305 -154.19467) (xy 370.972842 -154.185874) (xy 370.989595 -154.165091)
			(xy 371.027949 -154.127961) (xy 371.071103 -154.096539) (xy 371.118217 -154.07144) (xy 371.168369 -154.053154)
			(xy 371.22058 -154.042037) (xy 371.273832 -154.038307) (xy 371.327084 -154.042037) (xy 371.379295 -154.053154)
			(xy 371.429447 -154.07144) (xy 371.476561 -154.096539) (xy 371.519715 -154.127961) (xy 371.558069 -154.165091)
			(xy 371.574822 -154.185874) (xy 371.582366 -154.194654) (xy 371.603139 -154.204824) (xy 371.6147 -154.205432)
			(xy 371.694964 -154.205432) (xy 371.706533 -154.204865) (xy 371.727305 -154.19467) (xy 371.734842 -154.185874)
			(xy 371.751595 -154.165091) (xy 371.789949 -154.127961) (xy 371.833103 -154.096539) (xy 371.880217 -154.07144)
			(xy 371.930369 -154.053154) (xy 371.98258 -154.042037) (xy 372.035832 -154.038307) (xy 372.089084 -154.042037)
			(xy 372.141295 -154.053154) (xy 372.191447 -154.07144) (xy 372.238561 -154.096539) (xy 372.281715 -154.127961)
			(xy 372.320069 -154.165091) (xy 372.336822 -154.185874) (xy 372.344366 -154.194654) (xy 372.365139 -154.204824)
			(xy 372.3767 -154.205432) (xy 372.456964 -154.205432) (xy 372.468533 -154.204865) (xy 372.489305 -154.19467)
			(xy 372.496842 -154.185874) (xy 372.515003 -154.163365) (xy 372.55703 -154.123633) (xy 372.604571 -154.090697)
			(xy 372.656538 -154.065314) (xy 372.711741 -154.048063) (xy 372.768914 -154.03934) (xy 372.797832 -154.038808)
			(xy 372.825085 -154.039248) (xy 372.879035 -154.047009) (xy 372.931332 -154.062369) (xy 372.98091 -154.085015)
			(xy 373.026761 -154.114487) (xy 373.067951 -154.150183) (xy 373.103642 -154.191378) (xy 373.133108 -154.237232)
			(xy 373.155747 -154.286813) (xy 373.171101 -154.339112) (xy 373.178855 -154.393063) (xy 373.17934 -154.420316)
			(xy 373.178784 -154.449232) (xy 373.170066 -154.506402) (xy 373.152817 -154.561601) (xy 373.127432 -154.613564)
			(xy 373.094494 -154.661098) (xy 373.054758 -154.703116) (xy 373.032274 -154.721306) (xy 373.023509 -154.728865)
			(xy 373.013328 -154.749626) (xy 373.012716 -154.761184) (xy 373.012716 -154.841448) (xy 373.013311 -154.853013)
			(xy 373.023488 -154.873784) (xy 373.032274 -154.881326) (xy 373.053071 -154.898062) (xy 373.090199 -154.936418)
			(xy 373.121617 -154.979576) (xy 373.146714 -155.026691) (xy 373.164998 -155.076845) (xy 373.176112 -155.129058)
			(xy 373.17984 -155.18231) (xy 373.17611 -155.235562) (xy 373.164992 -155.287774) (xy 373.146706 -155.337927)
			(xy 373.121607 -155.385041) (xy 373.090186 -155.428197) (xy 373.053057 -155.466552) (xy 373.032274 -155.483306)
			(xy 373.023509 -155.490865) (xy 373.013328 -155.511626) (xy 373.012716 -155.523184) (xy 373.012716 -155.603448)
			(xy 373.013311 -155.615013) (xy 373.023488 -155.635784) (xy 373.032274 -155.643326) (xy 373.053071 -155.660062)
			(xy 373.090199 -155.698418) (xy 373.121617 -155.741576) (xy 373.146714 -155.788691) (xy 373.164998 -155.838845)
			(xy 373.176112 -155.891058) (xy 373.17984 -155.94431) (xy 373.17611 -155.997562) (xy 373.164992 -156.049774)
			(xy 373.146706 -156.099927) (xy 373.121607 -156.147041) (xy 373.090186 -156.190197) (xy 373.053057 -156.228552)
			(xy 373.032274 -156.245306) (xy 373.023509 -156.252865) (xy 373.013328 -156.273626) (xy 373.012716 -156.285184)
			(xy 373.012716 -156.365448) (xy 373.013311 -156.377013) (xy 373.023488 -156.397784) (xy 373.032274 -156.405326)
			(xy 373.053071 -156.422062) (xy 373.090199 -156.460418) (xy 373.121617 -156.503576) (xy 373.146714 -156.550691)
			(xy 373.164998 -156.600845) (xy 373.176112 -156.653058) (xy 373.17984 -156.70631) (xy 373.17611 -156.759562)
			(xy 373.164992 -156.811774) (xy 373.146706 -156.861927) (xy 373.121607 -156.909041) (xy 373.090186 -156.952197)
			(xy 373.053057 -156.990552) (xy 373.032274 -157.007306) (xy 373.023509 -157.014865) (xy 373.013328 -157.035626)
			(xy 373.012716 -157.047184) (xy 373.012716 -157.127448) (xy 373.013311 -157.139013) (xy 373.023488 -157.159784)
			(xy 373.032274 -157.167326) (xy 373.053071 -157.184062) (xy 373.090199 -157.222418) (xy 373.121617 -157.265576)
			(xy 373.146714 -157.312691) (xy 373.164998 -157.362845) (xy 373.176112 -157.415058) (xy 373.17984 -157.46831)
			(xy 373.17611 -157.521562) (xy 373.164992 -157.573774) (xy 373.146706 -157.623927) (xy 373.121607 -157.671041)
			(xy 373.090186 -157.714197) (xy 373.053057 -157.752552) (xy 373.032274 -157.769306) (xy 373.023509 -157.776865)
			(xy 373.013328 -157.797626) (xy 373.012716 -157.809184) (xy 373.012716 -157.889448) (xy 373.013311 -157.901013)
			(xy 373.023488 -157.921784) (xy 373.032274 -157.929326) (xy 373.054765 -157.947509) (xy 373.0945 -157.98953)
			(xy 373.127439 -158.037066) (xy 373.152827 -158.089029) (xy 373.170081 -158.144228) (xy 373.178807 -158.201399)
			(xy 373.17934 -158.230316) (xy 373.178837 -158.257566) (xy 373.171079 -158.311512) (xy 373.155724 -158.363804)
			(xy 373.133083 -158.413379) (xy 373.103618 -158.459228) (xy 373.067929 -158.500417) (xy 373.026741 -158.536109)
			(xy 372.980893 -158.565575) (xy 372.931319 -158.588218) (xy 372.879027 -158.603576) (xy 372.825082 -158.611336)
			(xy 372.797832 -158.611824) (xy 372.768915 -158.611312) (xy 372.711742 -158.602585) (xy 372.656542 -158.585328)
			(xy 372.604579 -158.559936) (xy 372.557046 -158.52699) (xy 372.515031 -158.487245) (xy 372.496842 -158.464758)
			(xy 372.489265 -158.456013) (xy 372.468517 -158.445822) (xy 372.456964 -158.4452) (xy 372.3767 -158.4452)
			(xy 372.365132 -158.44577) (xy 372.344361 -158.455965) (xy 372.336822 -158.464758) (xy 372.320069 -158.485541)
			(xy 372.281715 -158.522671) (xy 372.238561 -158.554093) (xy 372.191447 -158.579192) (xy 372.141295 -158.597478)
			(xy 372.089084 -158.608595) (xy 372.035832 -158.612325) (xy 371.98258 -158.608595) (xy 371.930369 -158.597478)
			(xy 371.880217 -158.579192) (xy 371.833103 -158.554093) (xy 371.789949 -158.522671) (xy 371.751595 -158.485541)
			(xy 371.734842 -158.464758) (xy 371.727265 -158.456013) (xy 371.706517 -158.445822) (xy 371.694964 -158.4452)
			(xy 371.6147 -158.4452) (xy 371.603132 -158.44577) (xy 371.582361 -158.455965) (xy 371.574822 -158.464758)
			(xy 371.556608 -158.487222) (xy 371.514594 -158.526961) (xy 371.467065 -158.559903) (xy 371.415108 -158.585295)
			(xy 371.359914 -158.602555) (xy 371.302747 -158.611287) (xy 371.273832 -158.611824) (xy 371.246985 -158.611383)
			(xy 371.19382 -158.603872) (xy 371.142233 -158.588978) (xy 371.093246 -158.566998) (xy 371.047824 -158.538364)
			(xy 371.006867 -158.503644) (xy 370.971184 -158.463523) (xy 370.941481 -158.418794) (xy 370.918343 -158.370342)
			(xy 370.90985 -158.34487) (xy 370.90477 -158.328868) (xy 370.8781 -158.309056) (xy 370.430298 -158.309056)
			(xy 370.422678 -158.311596) (xy 370.394291 -158.320136) (xy 370.335731 -158.329324) (xy 370.306092 -158.329884)
			(xy 370.276456 -158.329298) (xy 370.217897 -158.320116) (xy 370.189506 -158.311596) (xy 370.181886 -158.309056)
			(xy 369.795298 -158.309056) (xy 369.787678 -158.311596) (xy 369.759291 -158.320136) (xy 369.700731 -158.329324)
			(xy 369.671092 -158.329884) (xy 369.641456 -158.329298) (xy 369.582897 -158.320116) (xy 369.554506 -158.311596)
			(xy 369.546886 -158.309056) (xy 369.160298 -158.309056) (xy 369.152678 -158.311596) (xy 369.124291 -158.320136)
			(xy 369.065731 -158.329324) (xy 369.036092 -158.329884) (xy 369.006456 -158.329298) (xy 368.947897 -158.320116)
			(xy 368.919506 -158.311596) (xy 368.911886 -158.309056) (xy 368.525298 -158.309056) (xy 368.517678 -158.311596)
			(xy 368.489291 -158.320136) (xy 368.430731 -158.329324) (xy 368.401092 -158.329884) (xy 368.371456 -158.329298)
			(xy 368.312897 -158.320116) (xy 368.284506 -158.311596) (xy 368.276886 -158.309056) (xy 367.859564 -158.309056)
			(xy 367.832894 -158.328868) (xy 367.827814 -158.34487) (xy 367.81935 -158.370349) (xy 367.79619 -158.418787)
			(xy 367.766471 -158.463501) (xy 367.730779 -158.50361) (xy 367.689819 -158.538322) (xy 367.6444 -158.566952)
			(xy 367.595417 -158.588935) (xy 367.543837 -158.603838) (xy 367.490677 -158.611365) (xy 367.463832 -158.611824)
			(xy 367.434915 -158.611312) (xy 367.377742 -158.602585) (xy 367.322542 -158.585328) (xy 367.270579 -158.559936)
			(xy 367.223046 -158.52699) (xy 367.181031 -158.487245) (xy 367.162842 -158.464758) (xy 367.155265 -158.456013)
			(xy 367.134517 -158.445822) (xy 367.122964 -158.4452) (xy 367.0427 -158.4452) (xy 367.031132 -158.44577)
			(xy 367.010361 -158.455965) (xy 367.002822 -158.464758) (xy 366.986069 -158.485541) (xy 366.947715 -158.522671)
			(xy 366.904561 -158.554093) (xy 366.857447 -158.579192) (xy 366.807295 -158.597478) (xy 366.755084 -158.608595)
			(xy 366.701832 -158.612325) (xy 366.64858 -158.608595) (xy 366.596369 -158.597478) (xy 366.546217 -158.579192)
			(xy 366.499103 -158.554093) (xy 366.455949 -158.522671) (xy 366.417595 -158.485541) (xy 366.400842 -158.464758)
			(xy 366.393265 -158.456013) (xy 366.372517 -158.445822) (xy 366.360964 -158.4452) (xy 366.2807 -158.4452)
			(xy 366.269132 -158.44577) (xy 366.248361 -158.455965) (xy 366.240822 -158.464758) (xy 366.222608 -158.487222)
			(xy 366.180594 -158.526961) (xy 366.133065 -158.559903) (xy 366.081108 -158.585295) (xy 366.025914 -158.602555)
			(xy 365.968747 -158.611287) (xy 365.939832 -158.611824) (xy 365.912581 -158.611315) (xy 365.858632 -158.603563)
			(xy 365.806336 -158.588212) (xy 365.756757 -158.565574) (xy 365.710905 -158.536111) (xy 365.669712 -158.500422)
			(xy 365.634018 -158.459234) (xy 365.604549 -158.413385) (xy 365.581905 -158.363809) (xy 365.566547 -158.311515)
			(xy 365.558788 -158.257567) (xy 365.558324 -158.230316) (xy 365.558845 -158.201399) (xy 365.567572 -158.144228)
			(xy 365.584829 -158.089028) (xy 365.61022 -158.037067) (xy 365.643164 -157.989533) (xy 365.682904 -157.947516)
			(xy 365.70539 -157.929326) (xy 365.714134 -157.921747) (xy 365.724328 -157.901001) (xy 365.724948 -157.889448)
			(xy 365.724948 -157.809184) (xy 365.724405 -157.797612) (xy 365.714193 -157.77684) (xy 365.70539 -157.769306)
			(xy 365.684622 -157.752534) (xy 365.647489 -157.714185) (xy 365.616065 -157.671033) (xy 365.590963 -157.623922)
			(xy 365.572675 -157.573771) (xy 365.561556 -157.52156) (xy 365.557825 -157.46831) (xy 363.282992 -157.46831)
			(xy 363.282992 -164.53358) (xy 366.362996 -164.53358) (xy 366.363451 -164.506209) (xy 366.371272 -164.45203)
			(xy 366.386764 -164.399527) (xy 366.409608 -164.34978) (xy 366.439334 -164.303814) (xy 366.456976 -164.282882)
			(xy 366.463072 -164.27577) (xy 366.469422 -164.258752) (xy 366.469422 -164.173408) (xy 366.463072 -164.15639)
			(xy 366.456976 -164.149278) (xy 366.439356 -164.12833) (xy 366.409642 -164.082361) (xy 366.386803 -164.032618)
			(xy 366.371307 -163.980121) (xy 366.363473 -163.925948) (xy 366.362996 -163.89858) (xy 366.363459 -163.871328)
			(xy 366.371219 -163.817379) (xy 366.386576 -163.765084) (xy 366.40922 -163.715506) (xy 366.438689 -163.669656)
			(xy 366.474383 -163.628466) (xy 366.515575 -163.592775) (xy 366.561427 -163.563309) (xy 366.611006 -163.540668)
			(xy 366.663303 -163.525313) (xy 366.717252 -163.517557) (xy 366.744504 -163.517072) (xy 366.771875 -163.517518)
			(xy 366.826056 -163.525338) (xy 366.87856 -163.540831) (xy 366.928306 -163.563677) (xy 366.974272 -163.593408)
			(xy 366.995202 -163.611052) (xy 367.002314 -163.617148) (xy 367.019332 -163.623498) (xy 367.104676 -163.623498)
			(xy 367.121694 -163.617148) (xy 367.128806 -163.611052) (xy 367.149732 -163.593405) (xy 367.195705 -163.563692)
			(xy 367.245454 -163.540857) (xy 367.297957 -163.525368) (xy 367.352134 -163.517544) (xy 367.379504 -163.517072)
			(xy 367.408516 -163.517609) (xy 367.465873 -163.526378) (xy 367.521242 -163.543729) (xy 367.573346 -163.569262)
			(xy 367.620984 -163.602388) (xy 367.642394 -163.621974) (xy 367.649506 -163.628832) (xy 367.667286 -163.635944)
			(xy 367.757202 -163.635944) (xy 367.774982 -163.628832) (xy 367.782094 -163.621974) (xy 367.803503 -163.602389)
			(xy 367.851147 -163.569273) (xy 367.903252 -163.543745) (xy 367.958618 -163.526392) (xy 368.015973 -163.517613)
			(xy 368.044984 -163.517072) (xy 368.072355 -163.51753) (xy 368.126535 -163.525347) (xy 368.179039 -163.540837)
			(xy 368.228786 -163.563681) (xy 368.274751 -163.593409) (xy 368.295682 -163.611052) (xy 368.302794 -163.617148)
			(xy 368.319812 -163.623498) (xy 368.405156 -163.623498) (xy 368.422174 -163.617148) (xy 368.429286 -163.611052)
			(xy 368.450219 -163.593411) (xy 368.496187 -163.563687) (xy 368.545933 -163.540841) (xy 368.598435 -163.525345)
			(xy 368.652613 -163.517516) (xy 368.707355 -163.517516) (xy 368.761533 -163.525345) (xy 368.814035 -163.540841)
			(xy 368.863781 -163.563687) (xy 368.909749 -163.593411) (xy 368.930682 -163.611052) (xy 368.937794 -163.617148)
			(xy 368.954812 -163.623498) (xy 369.040156 -163.623498) (xy 369.057174 -163.617148) (xy 369.064286 -163.611052)
			(xy 369.085219 -163.593411) (xy 369.131187 -163.563687) (xy 369.180933 -163.540841) (xy 369.233435 -163.525345)
			(xy 369.287613 -163.517516) (xy 369.342355 -163.517516) (xy 369.396533 -163.525345) (xy 369.449035 -163.540841)
			(xy 369.498781 -163.563687) (xy 369.544749 -163.593411) (xy 369.565682 -163.611052) (xy 369.572794 -163.617148)
			(xy 369.589812 -163.623498) (xy 369.675156 -163.623498) (xy 369.692174 -163.617148) (xy 369.699286 -163.611052)
			(xy 369.720219 -163.593414) (xy 369.766191 -163.5637) (xy 369.815938 -163.540863) (xy 369.868439 -163.525372)
			(xy 369.922615 -163.517545) (xy 369.949984 -163.517072) (xy 369.977558 -163.517558) (xy 370.032129 -163.525508)
			(xy 370.084988 -163.54123) (xy 370.135034 -163.564396) (xy 370.181224 -163.594524) (xy 370.222597 -163.630987)
			(xy 370.240814 -163.651692) (xy 370.248416 -163.659811) (xy 370.268568 -163.669165) (xy 370.279676 -163.669726)
			(xy 370.356892 -163.669726) (xy 370.368007 -163.669193) (xy 370.388167 -163.659832) (xy 370.395754 -163.651692)
			(xy 370.413984 -163.630998) (xy 370.455349 -163.594527) (xy 370.501535 -163.564393) (xy 370.551579 -163.541224)
			(xy 370.604438 -163.525504) (xy 370.65901 -163.51756) (xy 370.686584 -163.517072) (xy 370.713834 -163.517593)
			(xy 370.767779 -163.525347) (xy 370.820072 -163.540699) (xy 370.869648 -163.563337) (xy 370.915497 -163.592799)
			(xy 370.956687 -163.628487) (xy 370.992379 -163.669674) (xy 371.021846 -163.71552) (xy 371.044488 -163.765094)
			(xy 371.059845 -163.817385) (xy 371.067604 -163.87133) (xy 371.068092 -163.89858) (xy 371.067616 -163.92595)
			(xy 371.059801 -163.980129) (xy 371.044314 -164.032632) (xy 371.021475 -164.082379) (xy 370.991752 -164.128346)
			(xy 370.974112 -164.149278) (xy 370.968016 -164.15639) (xy 370.961666 -164.173408) (xy 370.961666 -164.258752)
			(xy 370.968016 -164.27577) (xy 370.974112 -164.282882) (xy 370.991758 -164.303808) (xy 371.021468 -164.349783)
			(xy 371.044303 -164.399532) (xy 371.059792 -164.452034) (xy 371.067619 -164.50621) (xy 371.068092 -164.53358)
			(xy 371.067581 -164.561585) (xy 371.059415 -164.616996) (xy 371.04324 -164.670619) (xy 371.019404 -164.721303)
			(xy 370.988418 -164.76796) (xy 370.970048 -164.789104) (xy 370.963444 -164.79647) (xy 370.95684 -164.813996)
			(xy 370.958364 -164.903404) (xy 370.96573 -164.920676) (xy 370.972588 -164.927788) (xy 370.992762 -164.949287)
			(xy 371.026905 -164.997347) (xy 371.053251 -165.050087) (xy 371.071172 -165.106251) (xy 371.080242 -165.164503)
			(xy 371.080792 -165.19398) (xy 371.080326 -165.221233) (xy 371.072571 -165.275185) (xy 371.057217 -165.327484)
			(xy 371.034576 -165.377065) (xy 371.005108 -165.422919) (xy 370.969415 -165.464112) (xy 370.928222 -165.499806)
			(xy 370.882368 -165.529274) (xy 370.832787 -165.551916) (xy 370.780489 -165.567271) (xy 370.726537 -165.575026)
			(xy 370.699284 -165.575488) (xy 370.671711 -165.574969) (xy 370.617141 -165.567028) (xy 370.564282 -165.551314)
			(xy 370.514235 -165.528154) (xy 370.468044 -165.49803) (xy 370.426671 -165.461571) (xy 370.408454 -165.440868)
			(xy 370.400871 -165.432728) (xy 370.380705 -165.423387) (xy 370.369592 -165.422834) (xy 370.292376 -165.422834)
			(xy 370.281261 -165.423362) (xy 370.261102 -165.432727) (xy 370.253514 -165.440868) (xy 370.235292 -165.461569)
			(xy 370.193926 -165.498042) (xy 370.147739 -165.528176) (xy 370.097693 -165.551344) (xy 370.044832 -165.567062)
			(xy 369.990258 -165.575002) (xy 369.962684 -165.575488) (xy 369.935313 -165.575034) (xy 369.881134 -165.567214)
			(xy 369.82863 -165.551722) (xy 369.778884 -165.528878) (xy 369.732917 -165.49915) (xy 369.711986 -165.481508)
			(xy 369.704874 -165.475412) (xy 369.687856 -165.469062) (xy 369.602512 -165.469062) (xy 369.585494 -165.475412)
			(xy 369.578382 -165.481508) (xy 369.557449 -165.499149) (xy 369.511481 -165.528873) (xy 369.461735 -165.551719)
			(xy 369.409233 -165.567215) (xy 369.355055 -165.575044) (xy 369.300313 -165.575044) (xy 369.246135 -165.567215)
			(xy 369.193633 -165.551719) (xy 369.143887 -165.528873) (xy 369.097919 -165.499149) (xy 369.076986 -165.481508)
			(xy 369.069874 -165.475412) (xy 369.052856 -165.469062) (xy 368.967512 -165.469062) (xy 368.950494 -165.475412)
			(xy 368.943382 -165.481508) (xy 368.922449 -165.499149) (xy 368.876481 -165.528873) (xy 368.826735 -165.551719)
			(xy 368.774233 -165.567215) (xy 368.720055 -165.575044) (xy 368.665313 -165.575044) (xy 368.611135 -165.567215)
			(xy 368.558633 -165.551719) (xy 368.508887 -165.528873) (xy 368.462919 -165.499149) (xy 368.441986 -165.481508)
			(xy 368.434874 -165.475412) (xy 368.417856 -165.469062) (xy 368.332512 -165.469062) (xy 368.315494 -165.475412)
			(xy 368.308382 -165.481508) (xy 368.287431 -165.499123) (xy 368.241463 -165.528838) (xy 368.19172 -165.551679)
			(xy 368.139224 -165.567176) (xy 368.085052 -165.57501) (xy 368.057684 -165.575488) (xy 368.028671 -165.57497)
			(xy 367.971313 -165.566198) (xy 367.915943 -165.548843) (xy 367.86384 -165.523305) (xy 367.816203 -165.490174)
			(xy 367.794794 -165.470586) (xy 367.787682 -165.463728) (xy 367.769902 -165.456616) (xy 367.679986 -165.456616)
			(xy 367.662206 -165.463728) (xy 367.655094 -165.470586) (xy 367.633699 -165.490187) (xy 367.58605 -165.523298)
			(xy 367.533941 -165.548822) (xy 367.478572 -165.566172) (xy 367.421216 -165.574948) (xy 367.392204 -165.575488)
			(xy 367.364834 -165.575023) (xy 367.310654 -165.567205) (xy 367.258151 -165.551716) (xy 367.208404 -165.528874)
			(xy 367.162438 -165.499149) (xy 367.141506 -165.481508) (xy 367.134394 -165.475412) (xy 367.117376 -165.469062)
			(xy 367.032032 -165.469062) (xy 367.015014 -165.475412) (xy 367.007902 -165.481508) (xy 366.986981 -165.499161)
			(xy 366.941005 -165.52887) (xy 366.891255 -165.551704) (xy 366.838752 -165.567191) (xy 366.784574 -165.575016)
			(xy 366.757204 -165.575488) (xy 366.72995 -165.575041) (xy 366.675998 -165.567284) (xy 366.623698 -165.551927)
			(xy 366.574117 -165.529284) (xy 366.528263 -165.499814) (xy 366.48707 -165.464119) (xy 366.451376 -165.422924)
			(xy 366.421908 -165.377069) (xy 366.399267 -165.327487) (xy 366.383913 -165.275187) (xy 366.376158 -165.221234)
			(xy 366.375696 -165.19398) (xy 366.376186 -165.165974) (xy 366.384357 -165.110563) (xy 366.400537 -165.05694)
			(xy 366.424378 -165.006256) (xy 366.455368 -164.959599) (xy 366.47374 -164.938456) (xy 366.480344 -164.93109)
			(xy 366.486948 -164.913564) (xy 366.485424 -164.824156) (xy 366.478058 -164.806884) (xy 366.4712 -164.799772)
			(xy 366.451022 -164.778276) (xy 366.416876 -164.730217) (xy 366.390529 -164.677477) (xy 366.372609 -164.621311)
			(xy 366.363543 -164.563057) (xy 366.362996 -164.53358) (xy 363.282992 -164.53358) (xy 363.282992 -172.01642)
			(xy 363.283383 -172.026494) (xy 363.291125 -172.045093) (xy 363.297978 -172.052488) (xy 364.294674 -173.049184)
			(xy 364.317534 -173.05655) (xy 364.329726 -173.054518) (xy 364.34449 -173.052362) (xy 364.374242 -173.050072)
			(xy 364.389162 -173.049946) (xy 364.41641 -173.050513) (xy 364.470353 -173.058264) (xy 364.522643 -173.073612)
			(xy 364.572217 -173.096245) (xy 364.618065 -173.125703) (xy 364.659255 -173.161386) (xy 364.694947 -173.202567)
			(xy 364.724415 -173.248409) (xy 364.747059 -173.297978) (xy 364.751722 -173.313852) (xy 365.897922 -173.313852)
			(xy 365.898408 -173.286601) (xy 365.906164 -173.232653) (xy 365.921519 -173.180358) (xy 365.944161 -173.130781)
			(xy 365.973627 -173.084931) (xy 366.009318 -173.04374) (xy 366.050509 -173.008049) (xy 366.096359 -172.978583)
			(xy 366.145936 -172.955941) (xy 366.198231 -172.940586) (xy 366.252179 -172.93283) (xy 366.306681 -172.93283)
			(xy 366.360629 -172.940586) (xy 366.412924 -172.955941) (xy 366.462501 -172.978583) (xy 366.508351 -173.008049)
			(xy 366.549542 -173.04374) (xy 366.585233 -173.084931) (xy 366.614699 -173.130781) (xy 366.637341 -173.180358)
			(xy 366.652696 -173.232653) (xy 366.660452 -173.286601) (xy 366.660938 -173.313852) (xy 366.66048 -173.340646)
			(xy 366.65298 -173.393706) (xy 366.638135 -173.445197) (xy 366.616237 -173.494106) (xy 366.587715 -173.539473)
			(xy 366.570768 -173.560232) (xy 366.564672 -173.567344) (xy 366.558576 -173.584362) (xy 366.5601 -173.670214)
			(xy 366.566958 -173.686978) (xy 366.573308 -173.69409) (xy 366.591915 -173.715263) (xy 366.623297 -173.762086)
			(xy 366.647447 -173.813016) (xy 366.663841 -173.866946) (xy 366.672122 -173.922701) (xy 366.672622 -173.950884)
			(xy 366.672136 -173.978135) (xy 366.670503 -173.989492) (xy 367.235738 -173.989492) (xy 367.239809 -173.93387)
			(xy 367.251935 -173.879433) (xy 367.271858 -173.827342) (xy 367.299154 -173.778707) (xy 367.33324 -173.734564)
			(xy 367.373389 -173.695855) (xy 367.418747 -173.663404) (xy 367.468347 -173.637903) (xy 367.521131 -173.619896)
			(xy 367.575974 -173.609766) (xy 367.631708 -173.607729) (xy 367.687145 -173.613829) (xy 367.741102 -173.627935)
			(xy 367.792431 -173.649747) (xy 367.840037 -173.678801) (xy 367.882905 -173.714476) (xy 367.920122 -173.756013)
			(xy 367.950895 -173.802526) (xy 367.974567 -173.853023) (xy 367.990635 -173.90643) (xy 367.998755 -173.961606)
			(xy 367.999264 -173.989492) (xy 367.998755 -174.017378) (xy 367.990635 -174.072554) (xy 367.974567 -174.125961)
			(xy 367.950895 -174.176458) (xy 367.920122 -174.222971) (xy 367.882905 -174.264508) (xy 367.840037 -174.300183)
			(xy 367.792431 -174.329237) (xy 367.741102 -174.351049) (xy 367.687145 -174.365155) (xy 367.631708 -174.371255)
			(xy 367.575974 -174.369218) (xy 367.521131 -174.359088) (xy 367.468347 -174.341081) (xy 367.418747 -174.31558)
			(xy 367.373389 -174.283129) (xy 367.33324 -174.24442) (xy 367.299154 -174.200277) (xy 367.271858 -174.151642)
			(xy 367.251935 -174.099551) (xy 367.239809 -174.045114) (xy 367.235738 -173.989492) (xy 366.670503 -173.989492)
			(xy 366.66438 -174.032083) (xy 366.649025 -174.084378) (xy 366.626383 -174.133955) (xy 366.596917 -174.179805)
			(xy 366.561226 -174.220996) (xy 366.520035 -174.256687) (xy 366.474185 -174.286153) (xy 366.424608 -174.308795)
			(xy 366.372313 -174.32415) (xy 366.318365 -174.331906) (xy 366.263863 -174.331906) (xy 366.209915 -174.32415)
			(xy 366.15762 -174.308795) (xy 366.108043 -174.286153) (xy 366.062193 -174.256687) (xy 366.021002 -174.220996)
			(xy 365.985311 -174.179805) (xy 365.955845 -174.133955) (xy 365.933203 -174.084378) (xy 365.917848 -174.032083)
			(xy 365.910092 -173.978135) (xy 365.909606 -173.950884) (xy 365.91004 -173.924089) (xy 365.917547 -173.871028)
			(xy 365.932399 -173.819538) (xy 365.954302 -173.770629) (xy 365.982828 -173.725262) (xy 365.999776 -173.704504)
			(xy 366.005872 -173.697392) (xy 366.011968 -173.680374) (xy 366.010444 -173.594522) (xy 366.003586 -173.577758)
			(xy 365.997236 -173.570646) (xy 365.978637 -173.549467) (xy 365.947256 -173.502644) (xy 365.923105 -173.451715)
			(xy 365.906709 -173.397788) (xy 365.898424 -173.342035) (xy 365.897922 -173.313852) (xy 364.751722 -173.313852)
			(xy 364.762419 -173.350265) (xy 364.770181 -173.404206) (xy 364.77067 -173.431454) (xy 364.77002 -173.463017)
			(xy 364.759629 -173.525283) (xy 364.73914 -173.584992) (xy 364.724696 -173.613064) (xy 364.71987 -173.621954)
			(xy 364.717838 -173.641512) (xy 364.743492 -173.72965) (xy 364.755938 -173.745144) (xy 364.764828 -173.750224)
			(xy 364.772194 -173.754288) (xy 364.781846 -173.76013) (xy 364.803944 -173.762162) (xy 364.898432 -173.728634)
			(xy 364.914434 -173.71314) (xy 364.918498 -173.702726) (xy 364.929193 -173.675949) (xy 364.957479 -173.625705)
			(xy 364.993008 -173.580294) (xy 365.034969 -173.54075) (xy 365.082407 -173.507976) (xy 365.134239 -173.482718)
			(xy 365.189283 -173.465554) (xy 365.246285 -173.456874) (xy 365.275114 -173.456346) (xy 365.302361 -173.456925)
			(xy 365.356301 -173.464682) (xy 365.408588 -173.480037) (xy 365.458157 -173.502676) (xy 365.504 -173.532139)
			(xy 365.545184 -173.567826) (xy 365.580869 -173.609011) (xy 365.610331 -173.654855) (xy 365.632968 -173.704425)
			(xy 365.648321 -173.756713) (xy 365.656076 -173.810653) (xy 365.656076 -173.865147) (xy 365.648321 -173.919087)
			(xy 365.632968 -173.971375) (xy 365.610331 -174.020945) (xy 365.580869 -174.066789) (xy 365.545184 -174.107974)
			(xy 365.504 -174.143661) (xy 365.458157 -174.173124) (xy 365.408588 -174.195763) (xy 365.356301 -174.211118)
			(xy 365.302361 -174.218875) (xy 365.275114 -174.219362) (xy 365.249879 -174.21895) (xy 365.199846 -174.212335)
			(xy 365.151126 -174.199166) (xy 365.104573 -174.179674) (xy 365.082582 -174.167292) (xy 365.07293 -174.16145)
			(xy 365.050832 -174.159418) (xy 364.956344 -174.192946) (xy 364.940342 -174.20844) (xy 364.936278 -174.218854)
			(xy 364.925562 -174.245622) (xy 364.897274 -174.29586) (xy 364.861745 -174.341267) (xy 364.819786 -174.380808)
			(xy 364.772352 -174.413582) (xy 364.720525 -174.438842) (xy 364.665486 -174.456012) (xy 364.608489 -174.464701)
			(xy 364.579662 -174.465234) (xy 364.552411 -174.464758) (xy 364.498464 -174.456997) (xy 364.446171 -174.441638)
			(xy 364.396595 -174.418994) (xy 364.350746 -174.389526) (xy 364.309557 -174.353834) (xy 364.273866 -174.312644)
			(xy 364.2444 -174.266794) (xy 364.221758 -174.217218) (xy 364.206401 -174.164924) (xy 364.198642 -174.110977)
			(xy 364.198154 -174.083726) (xy 364.198793 -174.052162) (xy 364.209188 -173.989896) (xy 364.229682 -173.930188)
			(xy 364.244128 -173.902116) (xy 364.248954 -173.893226) (xy 364.250986 -173.873668) (xy 364.225332 -173.78553)
			(xy 364.212886 -173.770036) (xy 364.203996 -173.764956) (xy 364.17889 -173.750415) (xy 364.133008 -173.71491)
			(xy 364.093034 -173.672865) (xy 364.059889 -173.62525) (xy 364.034339 -173.573164) (xy 364.016973 -173.517809)
			(xy 364.008193 -173.460462) (xy 364.007654 -173.431454) (xy 364.007778 -173.416534) (xy 364.010065 -173.386781)
			(xy 364.012226 -173.372018) (xy 364.014258 -173.359826) (xy 364.006892 -173.336966) (xy 362.93552 -172.265848)
			(xy 362.921761 -172.251325) (xy 362.899583 -172.218038) (xy 362.88432 -172.181067) (xy 362.876556 -172.14183)
			(xy 362.876084 -172.12183) (xy 362.876084 -155.64104) (xy 362.876525 -155.621034) (xy 362.88426 -155.581779)
			(xy 362.899518 -155.544793) (xy 362.92171 -155.511503) (xy 362.93552 -155.497022) (xy 364.01502 -154.417776)
			(xy 364.021709 -154.410291) (xy 364.029303 -154.391735) (xy 364.029752 -154.381708) (xy 364.029752 -143.309594)
			(xy 364.030282 -143.289584) (xy 364.0381 -143.250333) (xy 364.053417 -143.213359) (xy 364.075644 -143.180077)
			(xy 364.089442 -143.165576) (xy 369.584224 -137.670794) (xy 369.598693 -137.656954) (xy 369.631973 -137.634698)
			(xy 369.668958 -137.61937) (xy 369.708224 -137.61156) (xy 369.728242 -137.611104) (xy 375.121932 -137.611104)
			(xy 375.141944 -137.611603) (xy 375.181197 -137.619429) (xy 375.218172 -137.634754) (xy 375.251451 -137.656991)
			(xy 375.26595 -137.670794) (xy 375.38279 -137.787888) (xy 375.40565 -137.795254) (xy 375.417842 -137.793222)
			(xy 375.432606 -137.791064) (xy 375.462358 -137.788775) (xy 375.477278 -137.78865) (xy 375.504916 -137.78913)
			(xy 375.559612 -137.797126) (xy 375.612583 -137.812924) (xy 375.662724 -137.836194) (xy 375.708985 -137.866451)
			(xy 375.7504 -137.903061) (xy 375.786104 -137.94526) (xy 375.815351 -137.992166) (xy 375.837529 -138.042799)
			(xy 375.845324 -138.06932) (xy 375.848626 -138.081766) (xy 375.865898 -138.100054) (xy 375.970546 -138.134852)
			(xy 375.995184 -138.130534) (xy 376.005344 -138.12266) (xy 376.016336 -138.114309) (xy 376.039348 -138.099056)
			(xy 376.051318 -138.09218) (xy 376.059954 -138.087354) (xy 376.071892 -138.072622) (xy 376.098816 -137.988294)
			(xy 376.097546 -137.969498) (xy 376.093482 -137.960608) (xy 376.08218 -137.935237) (xy 376.066223 -137.88204)
			(xy 376.058166 -137.827088) (xy 376.057668 -137.799318) (xy 376.058195 -137.772068) (xy 376.065948 -137.718123)
			(xy 376.0813 -137.665831) (xy 376.103937 -137.616255) (xy 376.133399 -137.570406) (xy 376.169087 -137.529216)
			(xy 376.210272 -137.493525) (xy 376.256118 -137.464057) (xy 376.305691 -137.441415) (xy 376.357982 -137.426057)
			(xy 376.411926 -137.418298) (xy 376.439176 -137.41781) (xy 376.463206 -137.418166) (xy 376.510884 -137.424213)
			(xy 376.557425 -137.436202) (xy 376.579892 -137.444734) (xy 376.588528 -137.448036) (xy 376.60707 -137.448544)
			(xy 376.688096 -137.41908) (xy 376.702066 -137.407142) (xy 376.706638 -137.39876) (xy 376.713242 -137.386822)
			(xy 376.720354 -137.375138) (xy 376.720608 -137.347706) (xy 376.670062 -137.25906) (xy 376.665332 -137.25147)
			(xy 376.651626 -137.239998) (xy 376.634805 -137.23395) (xy 376.625866 -137.23366) (xy 376.345958 -137.23366)
			(xy 376.325945 -137.233177) (xy 376.286691 -137.225348) (xy 376.249716 -137.210018) (xy 376.216438 -137.187775)
			(xy 376.20194 -137.17397) (xy 375.687336 -136.659112) (xy 375.679873 -136.652396) (xy 375.6613 -136.64482)
			(xy 375.651268 -136.64438) (xy 374.445022 -136.64438) (xy 374.435731 -136.644805) (xy 374.418365 -136.651421)
			(xy 374.404472 -136.663765) (xy 374.39981 -136.671812) (xy 374.351804 -136.765284) (xy 374.353836 -136.793224)
			(xy 374.362472 -136.805162) (xy 374.379286 -136.829614) (xy 374.405956 -136.882622) (xy 374.424101 -136.939118)
			(xy 374.433284 -136.997742) (xy 374.433846 -137.027412) (xy 374.43336 -137.054663) (xy 374.425604 -137.108611)
			(xy 374.410249 -137.160906) (xy 374.387607 -137.210483) (xy 374.358141 -137.256333) (xy 374.32245 -137.297524)
			(xy 374.281259 -137.333215) (xy 374.235409 -137.362681) (xy 374.185832 -137.385323) (xy 374.133537 -137.400678)
			(xy 374.079589 -137.408434) (xy 374.025087 -137.408434) (xy 373.971139 -137.400678) (xy 373.918844 -137.385323)
			(xy 373.869267 -137.362681) (xy 373.823417 -137.333215) (xy 373.782226 -137.297524) (xy 373.746535 -137.256333)
			(xy 373.717069 -137.210483) (xy 373.694427 -137.160906) (xy 373.679072 -137.108611) (xy 373.671316 -137.054663)
			(xy 373.67083 -137.027412) (xy 373.671084 -137.011156) (xy 373.671846 -136.995408) (xy 373.655336 -136.968992)
			(xy 373.554244 -136.924542) (xy 373.544715 -136.92083) (xy 373.524286 -136.920545) (xy 373.505375 -136.928278)
			(xy 373.497856 -136.93521) (xy 373.103902 -137.329164) (xy 373.089396 -137.342942) (xy 373.056104 -137.365117)
			(xy 373.019127 -137.380375) (xy 372.979885 -137.388132) (xy 372.959884 -137.3886) (xy 369.11788 -137.3886)
			(xy 369.107806 -137.388988) (xy 369.089207 -137.396732) (xy 369.081812 -137.403586) (xy 355.68636 -150.799038)
			(xy 355.679662 -150.806516) (xy 355.672074 -150.825078) (xy 355.671628 -150.835106) (xy 355.671628 -152.754768)
			(xy 358.696256 -152.754768) (xy 358.696256 -152.670072) (xy 358.704307 -152.585758) (xy 358.720336 -152.502592)
			(xy 358.744197 -152.421325) (xy 358.775676 -152.342695) (xy 358.814487 -152.267414) (xy 358.860277 -152.196162)
			(xy 358.912633 -152.129586) (xy 358.971081 -152.068288) (xy 359.035091 -152.012823) (xy 359.104083 -151.963694)
			(xy 359.177433 -151.921345) (xy 359.254476 -151.886161) (xy 359.334515 -151.858459) (xy 359.416824 -151.838491)
			(xy 359.500659 -151.826438) (xy 359.58526 -151.822408) (xy 359.669861 -151.826438) (xy 359.753696 -151.838491)
			(xy 359.836005 -151.858459) (xy 359.916044 -151.886161) (xy 359.993087 -151.921345) (xy 360.066437 -151.963694)
			(xy 360.135429 -152.012823) (xy 360.199439 -152.068288) (xy 360.257887 -152.129586) (xy 360.310243 -152.196162)
			(xy 360.356033 -152.267414) (xy 360.394844 -152.342695) (xy 360.426323 -152.421325) (xy 360.450184 -152.502592)
			(xy 360.466213 -152.585758) (xy 360.474264 -152.670072) (xy 360.474768 -152.71242) (xy 360.474264 -152.754768)
			(xy 361.196378 -152.754768) (xy 361.196378 -152.670072) (xy 361.204429 -152.585758) (xy 361.220458 -152.502592)
			(xy 361.244319 -152.421325) (xy 361.275798 -152.342695) (xy 361.314609 -152.267414) (xy 361.360399 -152.196162)
			(xy 361.412755 -152.129586) (xy 361.471203 -152.068288) (xy 361.535213 -152.012823) (xy 361.604205 -151.963694)
			(xy 361.677555 -151.921345) (xy 361.754598 -151.886161) (xy 361.834637 -151.858459) (xy 361.916946 -151.838491)
			(xy 362.000781 -151.826438) (xy 362.085382 -151.822408) (xy 362.169983 -151.826438) (xy 362.253818 -151.838491)
			(xy 362.336127 -151.858459) (xy 362.416166 -151.886161) (xy 362.493209 -151.921345) (xy 362.566559 -151.963694)
			(xy 362.635551 -152.012823) (xy 362.699561 -152.068288) (xy 362.758009 -152.129586) (xy 362.810365 -152.196162)
			(xy 362.856155 -152.267414) (xy 362.894966 -152.342695) (xy 362.926445 -152.421325) (xy 362.950306 -152.502592)
			(xy 362.966335 -152.585758) (xy 362.974386 -152.670072) (xy 362.97489 -152.71242) (xy 362.974386 -152.754768)
			(xy 362.966335 -152.839082) (xy 362.950306 -152.922248) (xy 362.926445 -153.003515) (xy 362.894966 -153.082145)
			(xy 362.856155 -153.157426) (xy 362.810365 -153.228678) (xy 362.758009 -153.295254) (xy 362.699561 -153.356552)
			(xy 362.635551 -153.412017) (xy 362.566559 -153.461146) (xy 362.493209 -153.503495) (xy 362.416166 -153.538679)
			(xy 362.336127 -153.566381) (xy 362.253818 -153.586349) (xy 362.169983 -153.598402) (xy 362.085382 -153.602433)
			(xy 362.000781 -153.598402) (xy 361.916946 -153.586349) (xy 361.834637 -153.566381) (xy 361.754598 -153.538679)
			(xy 361.677555 -153.503495) (xy 361.604205 -153.461146) (xy 361.535213 -153.412017) (xy 361.471203 -153.356552)
			(xy 361.412755 -153.295254) (xy 361.360399 -153.228678) (xy 361.314609 -153.157426) (xy 361.275798 -153.082145)
			(xy 361.244319 -153.003515) (xy 361.220458 -152.922248) (xy 361.204429 -152.839082) (xy 361.196378 -152.754768)
			(xy 360.474264 -152.754768) (xy 360.466213 -152.839082) (xy 360.450184 -152.922248) (xy 360.426323 -153.003515)
			(xy 360.394844 -153.082145) (xy 360.356033 -153.157426) (xy 360.310243 -153.228678) (xy 360.257887 -153.295254)
			(xy 360.199439 -153.356552) (xy 360.135429 -153.412017) (xy 360.066437 -153.461146) (xy 359.993087 -153.503495)
			(xy 359.916044 -153.538679) (xy 359.836005 -153.566381) (xy 359.753696 -153.586349) (xy 359.669861 -153.598402)
			(xy 359.58526 -153.602433) (xy 359.500659 -153.598402) (xy 359.416824 -153.586349) (xy 359.334515 -153.566381)
			(xy 359.254476 -153.538679) (xy 359.177433 -153.503495) (xy 359.104083 -153.461146) (xy 359.035091 -153.412017)
			(xy 358.971081 -153.356552) (xy 358.912633 -153.295254) (xy 358.860277 -153.228678) (xy 358.814487 -153.157426)
			(xy 358.775676 -153.082145) (xy 358.744197 -153.003515) (xy 358.720336 -152.922248) (xy 358.704307 -152.839082)
			(xy 358.696256 -152.754768) (xy 355.671628 -152.754768) (xy 355.671628 -164.409882) (xy 355.671973 -164.41993)
			(xy 355.679579 -164.438526) (xy 355.68636 -164.44595) (xy 356.014274 -164.773864) (xy 356.037134 -164.78123)
			(xy 356.049326 -164.779198) (xy 356.06409 -164.777042) (xy 356.093842 -164.774752) (xy 356.108762 -164.774626)
			(xy 356.136015 -164.775091) (xy 356.189968 -164.782843) (xy 356.242268 -164.798196) (xy 356.29185 -164.820837)
			(xy 356.337705 -164.850304) (xy 356.378899 -164.885998) (xy 356.414593 -164.927192) (xy 356.444061 -164.973046)
			(xy 356.466702 -165.022628) (xy 356.482056 -165.074928) (xy 356.489809 -165.128881) (xy 356.49027 -165.156134)
			(xy 356.489612 -165.187697) (xy 356.479225 -165.249962) (xy 356.458738 -165.309671) (xy 356.444296 -165.337744)
			(xy 356.43947 -165.346634) (xy 356.437438 -165.366192) (xy 356.463092 -165.45433) (xy 356.475538 -165.469824)
			(xy 356.484428 -165.474904) (xy 356.491794 -165.478968) (xy 356.501446 -165.48481) (xy 356.523544 -165.486842)
			(xy 356.618032 -165.453314) (xy 356.634034 -165.43782) (xy 356.638098 -165.427406) (xy 356.648782 -165.400624)
			(xy 356.677071 -165.350381) (xy 356.712601 -165.304971) (xy 356.754565 -165.265428) (xy 356.802004 -165.232654)
			(xy 356.853837 -165.207398) (xy 356.908882 -165.190234) (xy 356.965884 -165.181554) (xy 356.994714 -165.181026)
			(xy 357.021967 -165.181445) (xy 357.075918 -165.189204) (xy 357.128216 -165.204561) (xy 357.177796 -165.227205)
			(xy 357.223648 -165.256675) (xy 357.264841 -165.292369) (xy 357.300534 -165.333563) (xy 357.330001 -165.379417)
			(xy 357.352644 -165.428997) (xy 357.367999 -165.481296) (xy 357.375756 -165.535247) (xy 357.375756 -165.589753)
			(xy 357.367999 -165.643704) (xy 357.358645 -165.675564) (xy 357.617522 -165.675564) (xy 357.617982 -165.648088)
			(xy 357.625879 -165.593707) (xy 357.641505 -165.541025) (xy 357.664536 -165.491132) (xy 357.694494 -165.445065)
			(xy 357.712264 -165.424104) (xy 357.71836 -165.416992) (xy 357.72471 -165.399974) (xy 357.72471 -165.314122)
			(xy 357.71836 -165.297104) (xy 357.712264 -165.289992) (xy 357.69451 -165.269022) (xy 357.664585 -165.222942)
			(xy 357.64157 -165.17305) (xy 357.625942 -165.120375) (xy 357.618023 -165.066004) (xy 357.617522 -165.038532)
			(xy 357.618008 -165.011281) (xy 357.625764 -164.957333) (xy 357.641119 -164.905038) (xy 357.663761 -164.855461)
			(xy 357.693227 -164.809611) (xy 357.728918 -164.76842) (xy 357.770109 -164.732729) (xy 357.815959 -164.703263)
			(xy 357.865536 -164.680621) (xy 357.917831 -164.665266) (xy 357.971779 -164.65751) (xy 358.026281 -164.65751)
			(xy 358.080229 -164.665266) (xy 358.132524 -164.680621) (xy 358.182101 -164.703263) (xy 358.227951 -164.732729)
			(xy 358.269142 -164.76842) (xy 358.304833 -164.809611) (xy 358.334299 -164.855461) (xy 358.356941 -164.905038)
			(xy 358.372296 -164.957333) (xy 358.380052 -165.011281) (xy 358.380538 -165.038532) (xy 358.380062 -165.066007)
			(xy 358.372166 -165.120387) (xy 358.356543 -165.173069) (xy 358.333517 -165.222961) (xy 358.303564 -165.26903)
			(xy 358.285796 -165.289992) (xy 358.2797 -165.297104) (xy 358.27335 -165.314122) (xy 358.27335 -165.399974)
			(xy 358.2797 -165.416992) (xy 358.285796 -165.424104) (xy 358.303542 -165.445081) (xy 358.33347 -165.491158)
			(xy 358.356486 -165.541049) (xy 358.372116 -165.593723) (xy 358.380037 -165.648093) (xy 358.380538 -165.675564)
			(xy 358.380052 -165.702815) (xy 358.372296 -165.756763) (xy 358.356941 -165.809058) (xy 358.334299 -165.858635)
			(xy 358.330831 -165.864032) (xy 358.955338 -165.864032) (xy 358.959409 -165.80841) (xy 358.971535 -165.753973)
			(xy 358.991458 -165.701882) (xy 359.018754 -165.653247) (xy 359.05284 -165.609104) (xy 359.092989 -165.570395)
			(xy 359.138347 -165.537944) (xy 359.187947 -165.512443) (xy 359.240731 -165.494436) (xy 359.295574 -165.484306)
			(xy 359.351308 -165.482269) (xy 359.406745 -165.488369) (xy 359.460702 -165.502475) (xy 359.512031 -165.524287)
			(xy 359.559637 -165.553341) (xy 359.602505 -165.589016) (xy 359.639722 -165.630553) (xy 359.670495 -165.677066)
			(xy 359.694167 -165.727563) (xy 359.710235 -165.78097) (xy 359.718355 -165.836146) (xy 359.718864 -165.864032)
			(xy 359.718355 -165.891918) (xy 359.710235 -165.947094) (xy 359.694167 -166.000501) (xy 359.670495 -166.050998)
			(xy 359.639722 -166.097511) (xy 359.602505 -166.139048) (xy 359.559637 -166.174723) (xy 359.512031 -166.203777)
			(xy 359.460702 -166.225589) (xy 359.406745 -166.239695) (xy 359.351308 -166.245795) (xy 359.295574 -166.243758)
			(xy 359.240731 -166.233628) (xy 359.187947 -166.215621) (xy 359.138347 -166.19012) (xy 359.092989 -166.157669)
			(xy 359.05284 -166.11896) (xy 359.018754 -166.074817) (xy 358.991458 -166.026182) (xy 358.971535 -165.974091)
			(xy 358.959409 -165.919654) (xy 358.955338 -165.864032) (xy 358.330831 -165.864032) (xy 358.304833 -165.904485)
			(xy 358.269142 -165.945676) (xy 358.227951 -165.981367) (xy 358.182101 -166.010833) (xy 358.132524 -166.033475)
			(xy 358.080229 -166.04883) (xy 358.026281 -166.056586) (xy 357.971779 -166.056586) (xy 357.917831 -166.04883)
			(xy 357.865536 -166.033475) (xy 357.815959 -166.010833) (xy 357.770109 -165.981367) (xy 357.728918 -165.945676)
			(xy 357.693227 -165.904485) (xy 357.663761 -165.858635) (xy 357.641119 -165.809058) (xy 357.625764 -165.756763)
			(xy 357.618008 -165.702815) (xy 357.617522 -165.675564) (xy 357.358645 -165.675564) (xy 357.352644 -165.696003)
			(xy 357.330001 -165.745583) (xy 357.300534 -165.791437) (xy 357.264841 -165.832631) (xy 357.223648 -165.868325)
			(xy 357.177796 -165.897795) (xy 357.128216 -165.920439) (xy 357.075918 -165.935796) (xy 357.021967 -165.943555)
			(xy 356.994714 -165.944042) (xy 356.969479 -165.943633) (xy 356.919446 -165.937018) (xy 356.870726 -165.923848)
			(xy 356.824173 -165.904355) (xy 356.802182 -165.891972) (xy 356.79253 -165.88613) (xy 356.770432 -165.884098)
			(xy 356.675944 -165.917626) (xy 356.659942 -165.93312) (xy 356.655878 -165.943534) (xy 356.645152 -165.970297)
			(xy 356.616866 -166.020536) (xy 356.581339 -166.065944) (xy 356.539382 -166.105486) (xy 356.491949 -166.138261)
			(xy 356.440123 -166.163521) (xy 356.385085 -166.180692) (xy 356.328089 -166.189381) (xy 356.299262 -166.189914)
			(xy 356.27201 -166.189458) (xy 356.218062 -166.181696) (xy 356.165767 -166.166336) (xy 356.11619 -166.143691)
			(xy 356.07034 -166.114222) (xy 356.02915 -166.078527) (xy 355.993459 -166.037335) (xy 355.963993 -165.991482)
			(xy 355.941352 -165.941903) (xy 355.925997 -165.889607) (xy 355.91824 -165.835658) (xy 355.917754 -165.808406)
			(xy 355.918386 -165.776842) (xy 355.928784 -165.714576) (xy 355.949281 -165.654867) (xy 355.963728 -165.626796)
			(xy 355.968554 -165.617906) (xy 355.970586 -165.598348) (xy 355.944932 -165.51021) (xy 355.932486 -165.494716)
			(xy 355.923596 -165.489636) (xy 355.898482 -165.475109) (xy 355.8526 -165.439602) (xy 355.812625 -165.397554)
			(xy 355.779482 -165.349937) (xy 355.753933 -165.297849) (xy 355.736569 -165.242491) (xy 355.727791 -165.185142)
			(xy 355.727254 -165.156134) (xy 355.727376 -165.141214) (xy 355.729664 -165.111461) (xy 355.731826 -165.096698)
			(xy 355.733858 -165.084506) (xy 355.726492 -165.061646) (xy 355.323902 -164.65931) (xy 355.310079 -164.644825)
			(xy 355.28782 -164.611551) (xy 355.272487 -164.574571) (xy 355.264671 -164.535308) (xy 355.264212 -164.515292)
			(xy 355.264212 -150.729696) (xy 355.264726 -150.709685) (xy 355.272547 -150.670433) (xy 355.287868 -150.633458)
			(xy 355.310101 -150.600178) (xy 355.323902 -150.585678) (xy 368.868452 -137.041128) (xy 368.882976 -137.02737)
			(xy 368.916262 -137.005192) (xy 368.953233 -136.989928) (xy 368.992471 -136.982164) (xy 369.01247 -136.981692)
			(xy 372.854474 -136.981692) (xy 372.864542 -136.981255) (xy 372.88314 -136.973543) (xy 372.890542 -136.966706)
			(xy 373.56034 -136.296654) (xy 373.574812 -136.282816) (xy 373.608089 -136.260557) (xy 373.645074 -136.245228)
			(xy 373.68434 -136.237418) (xy 373.704358 -136.236964) (xy 375.756678 -136.236964) (xy 375.776691 -136.237447)
			(xy 375.815944 -136.245279) (xy 375.852918 -136.26061) (xy 375.886197 -136.28285) (xy 375.900696 -136.296654)
			(xy 376.4153 -136.811512) (xy 376.422794 -136.818189) (xy 376.441343 -136.82579) (xy 376.451368 -136.826244)
			(xy 377.418092 -136.826244) (xy 377.42536 -136.826362) (xy 377.439852 -136.827505) (xy 377.447048 -136.82853)
			(xy 377.45924 -136.830054) (xy 377.481592 -136.822688) (xy 377.490228 -136.814052) (xy 377.497033 -136.806667)
			(xy 377.504743 -136.788141) (xy 377.504746 -136.768075) (xy 377.497042 -136.749546) (xy 377.490228 -136.74217)
			(xy 376.70105 -135.952992) (xy 376.693573 -135.946293) (xy 376.675011 -135.938705) (xy 376.664982 -135.93826)
			(xy 373.630952 -135.93826) (xy 373.620905 -135.938615) (xy 373.602308 -135.946213) (xy 373.594884 -135.952992)
			(xy 372.864126 -136.684004) (xy 372.849616 -136.697777) (xy 372.816324 -136.719951) (xy 372.779349 -136.735211)
			(xy 372.740109 -136.74297) (xy 372.720108 -136.74344) (xy 368.38128 -136.74344) (xy 368.371208 -136.743844)
			(xy 368.35261 -136.751579) (xy 368.345212 -136.758426) (xy 348.421957 -156.681932) (xy 349.311722 -156.681932)
			(xy 349.312208 -156.654681) (xy 349.319964 -156.600733) (xy 349.335319 -156.548438) (xy 349.357961 -156.498861)
			(xy 349.387427 -156.453011) (xy 349.423118 -156.41182) (xy 349.464309 -156.376129) (xy 349.510159 -156.346663)
			(xy 349.559736 -156.324021) (xy 349.612031 -156.308666) (xy 349.665979 -156.30091) (xy 349.720481 -156.30091)
			(xy 349.774429 -156.308666) (xy 349.826724 -156.324021) (xy 349.876301 -156.346663) (xy 349.922151 -156.376129)
			(xy 349.963342 -156.41182) (xy 349.999033 -156.453011) (xy 350.028499 -156.498861) (xy 350.051141 -156.548438)
			(xy 350.066496 -156.600733) (xy 350.074252 -156.654681) (xy 350.074738 -156.681932) (xy 350.074171 -156.711027)
			(xy 350.065334 -156.768541) (xy 350.047854 -156.824042) (xy 350.022138 -156.876241) (xy 349.988784 -156.923922)
			(xy 349.969074 -156.94533) (xy 349.962216 -156.952696) (xy 349.955104 -156.970476) (xy 349.955612 -157.061154)
			(xy 349.962724 -157.079188) (xy 349.969836 -157.0863) (xy 349.989942 -157.107813) (xy 350.024011 -157.155835)
			(xy 350.050299 -157.20852) (xy 350.068182 -157.264619) (xy 350.077236 -157.322798) (xy 350.077786 -157.352238)
			(xy 350.077691 -157.357572) (xy 350.649538 -157.357572) (xy 350.653609 -157.30195) (xy 350.665735 -157.247513)
			(xy 350.685658 -157.195422) (xy 350.712954 -157.146787) (xy 350.74704 -157.102644) (xy 350.787189 -157.063935)
			(xy 350.832547 -157.031484) (xy 350.882147 -157.005983) (xy 350.934931 -156.987976) (xy 350.989774 -156.977846)
			(xy 351.045508 -156.975809) (xy 351.100945 -156.981909) (xy 351.154902 -156.996015) (xy 351.206231 -157.017827)
			(xy 351.253837 -157.046881) (xy 351.296705 -157.082556) (xy 351.333922 -157.124093) (xy 351.364695 -157.170606)
			(xy 351.388367 -157.221103) (xy 351.404435 -157.27451) (xy 351.412555 -157.329686) (xy 351.413064 -157.357572)
			(xy 351.412555 -157.385458) (xy 351.404435 -157.440634) (xy 351.388367 -157.494041) (xy 351.364695 -157.544538)
			(xy 351.333922 -157.591051) (xy 351.296705 -157.632588) (xy 351.253837 -157.668263) (xy 351.206231 -157.697317)
			(xy 351.154902 -157.719129) (xy 351.100945 -157.733235) (xy 351.045508 -157.739335) (xy 350.989774 -157.737298)
			(xy 350.934931 -157.727168) (xy 350.882147 -157.709161) (xy 350.832547 -157.68366) (xy 350.787189 -157.651209)
			(xy 350.74704 -157.6125) (xy 350.712954 -157.568357) (xy 350.685658 -157.519722) (xy 350.665735 -157.467631)
			(xy 350.653609 -157.413194) (xy 350.649538 -157.357572) (xy 350.077691 -157.357572) (xy 350.0773 -157.379489)
			(xy 350.069544 -157.433437) (xy 350.054189 -157.485732) (xy 350.031547 -157.535309) (xy 350.002081 -157.581159)
			(xy 349.96639 -157.62235) (xy 349.925199 -157.658041) (xy 349.879349 -157.687507) (xy 349.829772 -157.710149)
			(xy 349.777477 -157.725504) (xy 349.723529 -157.73326) (xy 349.669027 -157.73326) (xy 349.615079 -157.725504)
			(xy 349.562784 -157.710149) (xy 349.513207 -157.687507) (xy 349.467357 -157.658041) (xy 349.426166 -157.62235)
			(xy 349.390475 -157.581159) (xy 349.361009 -157.535309) (xy 349.338367 -157.485732) (xy 349.323012 -157.433437)
			(xy 349.315256 -157.379489) (xy 349.31477 -157.352238) (xy 349.315343 -157.323144) (xy 349.324183 -157.265631)
			(xy 349.341663 -157.210131) (xy 349.367376 -157.157932) (xy 349.400726 -157.110249) (xy 349.420434 -157.08884)
			(xy 349.427292 -157.081474) (xy 349.434404 -157.063694) (xy 349.433896 -156.973016) (xy 349.426784 -156.954982)
			(xy 349.419672 -156.94787) (xy 349.399553 -156.926369) (xy 349.365486 -156.878344) (xy 349.3392 -156.825655)
			(xy 349.32132 -156.769554) (xy 349.31227 -156.711373) (xy 349.311722 -156.681932) (xy 348.421957 -156.681932)
			(xy 348.16034 -156.943552) (xy 348.153482 -156.950156) (xy 348.149672 -156.958538) (xy 348.138496 -156.981144)
			(xy 348.13367 -156.990034) (xy 348.131638 -157.009592) (xy 348.157292 -157.09773) (xy 348.169738 -157.113224)
			(xy 348.178628 -157.118304) (xy 348.185994 -157.122368) (xy 348.195646 -157.12821) (xy 348.217744 -157.130242)
			(xy 348.312232 -157.096714) (xy 348.328234 -157.08122) (xy 348.332298 -157.070806) (xy 348.342982 -157.044024)
			(xy 348.371271 -156.993781) (xy 348.406801 -156.948371) (xy 348.448765 -156.908828) (xy 348.496204 -156.876054)
			(xy 348.548037 -156.850798) (xy 348.603082 -156.833634) (xy 348.660084 -156.824954) (xy 348.688914 -156.824426)
			(xy 348.716167 -156.824845) (xy 348.770118 -156.832604) (xy 348.822416 -156.847961) (xy 348.871996 -156.870605)
			(xy 348.917848 -156.900075) (xy 348.959041 -156.935769) (xy 348.994734 -156.976963) (xy 349.024201 -157.022817)
			(xy 349.046844 -157.072397) (xy 349.062199 -157.124696) (xy 349.069956 -157.178647) (xy 349.069956 -157.233153)
			(xy 349.062199 -157.287104) (xy 349.046844 -157.339403) (xy 349.024201 -157.388983) (xy 348.994734 -157.434837)
			(xy 348.959041 -157.476031) (xy 348.917848 -157.511725) (xy 348.871996 -157.541195) (xy 348.822416 -157.563839)
			(xy 348.770118 -157.579196) (xy 348.716167 -157.586955) (xy 348.688914 -157.587442) (xy 348.663679 -157.587033)
			(xy 348.613646 -157.580418) (xy 348.564926 -157.567248) (xy 348.518373 -157.547755) (xy 348.496382 -157.535372)
			(xy 348.48673 -157.52953) (xy 348.464632 -157.527498) (xy 348.370144 -157.561026) (xy 348.354142 -157.57652)
			(xy 348.350078 -157.586934) (xy 348.339352 -157.613697) (xy 348.311066 -157.663936) (xy 348.275539 -157.709344)
			(xy 348.233582 -157.748886) (xy 348.186149 -157.781661) (xy 348.134323 -157.806921) (xy 348.079285 -157.824092)
			(xy 348.022289 -157.832781) (xy 347.993462 -157.833314) (xy 347.96621 -157.832858) (xy 347.912262 -157.825096)
			(xy 347.859967 -157.809736) (xy 347.81039 -157.787091) (xy 347.76454 -157.757622) (xy 347.72335 -157.721927)
			(xy 347.687659 -157.680735) (xy 347.658193 -157.634882) (xy 347.635552 -157.585303) (xy 347.620197 -157.533007)
			(xy 347.61244 -157.479058) (xy 347.611954 -157.451806) (xy 347.612586 -157.420242) (xy 347.622984 -157.357976)
			(xy 347.643481 -157.298267) (xy 347.657928 -157.270196) (xy 347.662754 -157.261306) (xy 347.664786 -157.241748)
			(xy 347.639132 -157.15361) (xy 347.626686 -157.138116) (xy 347.617796 -157.133036) (xy 347.592682 -157.118509)
			(xy 347.5468 -157.083002) (xy 347.506825 -157.040954) (xy 347.473682 -156.993337) (xy 347.448133 -156.941249)
			(xy 347.430769 -156.885891) (xy 347.421991 -156.828542) (xy 347.421454 -156.799534) (xy 339.262466 -156.799534)
			(xy 336.988404 -159.073596) (xy 343.63533 -159.073596) (xy 343.635782 -159.046021) (xy 343.643736 -158.991447)
			(xy 343.659463 -158.938586) (xy 343.682636 -158.88854) (xy 343.712771 -158.842351) (xy 343.749241 -158.800981)
			(xy 343.76995 -158.782766) (xy 343.778087 -158.775181) (xy 343.787429 -158.755016) (xy 343.787984 -158.743904)
			(xy 343.787984 -158.666688) (xy 343.787444 -158.655575) (xy 343.778086 -158.635416) (xy 343.76995 -158.627826)
			(xy 343.749238 -158.609616) (xy 343.71277 -158.568246) (xy 343.68264 -158.522056) (xy 343.659474 -158.472008)
			(xy 343.643757 -158.419146) (xy 343.635816 -158.364572) (xy 343.635817 -158.309423) (xy 343.643759 -158.254849)
			(xy 343.659476 -158.201987) (xy 343.682642 -158.15194) (xy 343.712773 -158.10575) (xy 343.749242 -158.06438)
			(xy 343.76995 -158.046166) (xy 343.778087 -158.038581) (xy 343.787429 -158.018416) (xy 343.787984 -158.007304)
			(xy 343.787984 -157.930088) (xy 343.787444 -157.918975) (xy 343.778086 -157.898816) (xy 343.76995 -157.891226)
			(xy 343.749238 -157.873016) (xy 343.71277 -157.831646) (xy 343.682639 -157.785455) (xy 343.659474 -157.735407)
			(xy 343.643757 -157.682545) (xy 343.635816 -157.627971) (xy 343.63533 -157.600396) (xy 343.635752 -157.573141)
			(xy 343.64351 -157.519187) (xy 343.658869 -157.466886) (xy 343.681514 -157.417303) (xy 343.710986 -157.371448)
			(xy 343.746685 -157.330255) (xy 343.787882 -157.294561) (xy 343.83374 -157.265094) (xy 343.883325 -157.242454)
			(xy 343.935628 -157.227101) (xy 343.989583 -157.219349) (xy 344.016838 -157.218888) (xy 344.044694 -157.219386)
			(xy 344.09981 -157.227514) (xy 344.153161 -157.243564) (xy 344.203613 -157.267195) (xy 344.250097 -157.297905)
			(xy 344.291626 -157.335043) (xy 344.327319 -157.37782) (xy 344.356418 -157.425329) (xy 344.378306 -157.476562)
			(xy 344.3859 -157.503368) (xy 344.388186 -157.512258) (xy 344.398854 -157.527498) (xy 344.470736 -157.57525)
			(xy 344.48877 -157.579314) (xy 344.497914 -157.578044) (xy 344.510931 -157.576375) (xy 344.537115 -157.574595)
			(xy 344.550238 -157.574488) (xy 344.564387 -157.574577) (xy 344.59261 -157.576615) (xy 344.606626 -157.578552)
			(xy 344.616786 -157.580076) (xy 344.636344 -157.57525) (xy 344.710766 -157.51937) (xy 344.720926 -157.501844)
			(xy 344.722196 -157.491684) (xy 344.726294 -157.464532) (xy 344.741264 -157.411701) (xy 344.763653 -157.361562)
			(xy 344.792999 -157.31515) (xy 344.828695 -157.273425) (xy 344.870004 -157.237248) (xy 344.916072 -157.207366)
			(xy 344.965949 -157.184398) (xy 345.018603 -157.168817) (xy 345.072947 -157.160945) (xy 345.100402 -157.160468)
			(xy 345.127652 -157.160976) (xy 345.181598 -157.168732) (xy 345.233891 -157.184086) (xy 345.283466 -157.206726)
			(xy 345.329316 -157.23619) (xy 345.370505 -157.271879) (xy 345.406197 -157.313067) (xy 345.435664 -157.358914)
			(xy 345.458306 -157.408489) (xy 345.473663 -157.460781) (xy 345.481423 -157.514726) (xy 345.48191 -157.541976)
			(xy 345.481424 -157.56955) (xy 345.473475 -157.624122) (xy 345.457754 -157.676981) (xy 345.434588 -157.727027)
			(xy 345.404459 -157.773217) (xy 345.367995 -157.814589) (xy 345.34729 -157.832806) (xy 345.339172 -157.840409)
			(xy 345.329818 -157.86056) (xy 345.329256 -157.871668) (xy 345.329256 -157.948884) (xy 345.329799 -157.959997)
			(xy 345.339153 -157.980157) (xy 345.34729 -157.987746) (xy 345.367976 -158.005984) (xy 345.404449 -158.047347)
			(xy 345.434584 -158.093531) (xy 345.457755 -158.143574) (xy 345.473476 -158.196432) (xy 345.481422 -158.251003)
			(xy 345.481456 -158.252922) (xy 350.070418 -158.252922) (xy 350.074489 -158.1973) (xy 350.086615 -158.142863)
			(xy 350.106538 -158.090772) (xy 350.133834 -158.042137) (xy 350.16792 -157.997994) (xy 350.208069 -157.959285)
			(xy 350.253427 -157.926834) (xy 350.303027 -157.901333) (xy 350.355811 -157.883326) (xy 350.410654 -157.873196)
			(xy 350.466388 -157.871159) (xy 350.521825 -157.877259) (xy 350.575782 -157.891365) (xy 350.627111 -157.913177)
			(xy 350.674717 -157.942231) (xy 350.717585 -157.977906) (xy 350.754802 -158.019443) (xy 350.785575 -158.065956)
			(xy 350.809247 -158.116453) (xy 350.825315 -158.16986) (xy 350.833435 -158.225036) (xy 350.833944 -158.252922)
			(xy 350.833435 -158.280808) (xy 350.825315 -158.335984) (xy 350.809247 -158.389391) (xy 350.785575 -158.439888)
			(xy 350.754802 -158.486401) (xy 350.717585 -158.527938) (xy 350.674717 -158.563613) (xy 350.627111 -158.592667)
			(xy 350.575782 -158.614479) (xy 350.521825 -158.628585) (xy 350.466388 -158.634685) (xy 350.410654 -158.632648)
			(xy 350.355811 -158.622518) (xy 350.303027 -158.604511) (xy 350.253427 -158.57901) (xy 350.208069 -158.546559)
			(xy 350.16792 -158.50785) (xy 350.133834 -158.463707) (xy 350.106538 -158.415072) (xy 350.086615 -158.362981)
			(xy 350.074489 -158.308544) (xy 350.070418 -158.252922) (xy 345.481456 -158.252922) (xy 345.48191 -158.278576)
			(xy 345.481422 -158.305828) (xy 345.473669 -158.359778) (xy 345.458316 -158.412075) (xy 345.435676 -158.461655)
			(xy 345.406211 -158.507508) (xy 345.37052 -158.548701) (xy 345.329329 -158.584395) (xy 345.283478 -158.613864)
			(xy 345.2339 -158.636507) (xy 345.181604 -158.651863) (xy 345.127654 -158.659621) (xy 345.100402 -158.660084)
			(xy 345.066112 -158.65856) (xy 345.055952 -158.657544) (xy 345.036648 -158.66364) (xy 344.966036 -158.722822)
			(xy 344.956638 -158.740856) (xy 344.955622 -158.751016) (xy 344.952637 -158.779185) (xy 344.939468 -158.834276)
			(xy 344.918293 -158.886813) (xy 344.88958 -158.935639) (xy 344.85396 -158.979681) (xy 344.812216 -159.017968)
			(xy 344.765268 -159.049658) (xy 344.714148 -159.074055) (xy 344.659981 -159.090621) (xy 344.60396 -159.098991)
			(xy 344.575638 -159.099504) (xy 344.557619 -159.099288) (xy 344.521744 -159.09585) (xy 344.50401 -159.092646)
			(xy 344.494612 -159.090868) (xy 344.475562 -159.094678) (xy 344.400378 -159.14243) (xy 344.388948 -159.158178)
			(xy 344.386662 -159.167576) (xy 344.379304 -159.194632) (xy 344.357669 -159.246359) (xy 344.328699 -159.294365)
			(xy 344.293018 -159.337616) (xy 344.251394 -159.375182) (xy 344.204722 -159.406254) (xy 344.154006 -159.430165)
			(xy 344.100338 -159.446399) (xy 344.044873 -159.454607) (xy 344.016838 -159.455104) (xy 343.989586 -159.454609)
			(xy 343.935636 -159.446857) (xy 343.883338 -159.431506) (xy 343.833758 -159.408868) (xy 343.787905 -159.379403)
			(xy 343.746711 -159.343713) (xy 343.711017 -159.302523) (xy 343.681549 -159.256672) (xy 343.658906 -159.207094)
			(xy 343.64355 -159.154797) (xy 343.635793 -159.100848) (xy 343.63533 -159.073596) (xy 336.988404 -159.073596)
			(xy 335.428844 -160.633156) (xy 345.303348 -160.633156) (xy 345.303835 -160.605582) (xy 345.311781 -160.551009)
			(xy 345.327501 -160.498149) (xy 345.350667 -160.448103) (xy 345.380796 -160.401913) (xy 345.417262 -160.360542)
			(xy 345.437968 -160.342326) (xy 345.446081 -160.334719) (xy 345.455436 -160.314571) (xy 345.456002 -160.303464)
			(xy 345.456002 -160.226248) (xy 345.455423 -160.21514) (xy 345.446092 -160.194981) (xy 345.437968 -160.187386)
			(xy 345.41724 -160.169193) (xy 345.380773 -160.127819) (xy 345.350644 -160.081626) (xy 345.327481 -160.031574)
			(xy 345.311768 -159.978709) (xy 345.303832 -159.924132) (xy 345.303348 -159.896556) (xy 345.30389 -159.867333)
			(xy 345.312784 -159.809567) (xy 345.330389 -159.753835) (xy 345.356291 -159.701441) (xy 345.389885 -159.653614)
			(xy 345.430382 -159.611472) (xy 345.476836 -159.576003) (xy 345.50223 -159.56153) (xy 345.512644 -159.555942)
			(xy 345.526106 -159.536892) (xy 345.543124 -159.43453) (xy 345.53652 -159.412178) (xy 345.528392 -159.403542)
			(xy 345.509985 -159.382768) (xy 345.478854 -159.336819) (xy 345.454881 -159.286762) (xy 345.438595 -159.233703)
			(xy 345.430355 -159.178817) (xy 345.42984 -159.151066) (xy 345.430325 -159.124451) (xy 345.437904 -159.071763)
			(xy 345.452904 -159.020689) (xy 345.475018 -158.97227) (xy 345.503797 -158.92749) (xy 345.538656 -158.887261)
			(xy 345.578884 -158.852402) (xy 345.623663 -158.823622) (xy 345.672082 -158.801506) (xy 345.723155 -158.786506)
			(xy 345.775843 -158.778925) (xy 345.802458 -158.778448) (xy 345.82888 -158.778884) (xy 345.881196 -158.786341)
			(xy 345.931935 -158.801112) (xy 345.980079 -158.8229) (xy 346.024663 -158.851269) (xy 346.045028 -158.86811)
			(xy 346.051886 -158.874206) (xy 346.068904 -158.880302) (xy 346.153232 -158.880302) (xy 346.17025 -158.874206)
			(xy 346.177108 -158.86811) (xy 346.197474 -158.851271) (xy 346.24206 -158.822906) (xy 346.290204 -158.801119)
			(xy 346.340941 -158.786348) (xy 346.393256 -158.778888) (xy 346.4461 -158.778888) (xy 346.498415 -158.786348)
			(xy 346.549152 -158.801119) (xy 346.597296 -158.822906) (xy 346.641882 -158.851271) (xy 346.662248 -158.86811)
			(xy 346.669106 -158.874206) (xy 346.686124 -158.880302) (xy 346.770452 -158.880302) (xy 346.78747 -158.874206)
			(xy 346.794328 -158.86811) (xy 346.814684 -158.85126) (xy 346.859277 -158.822907) (xy 346.907424 -158.80113)
			(xy 346.958162 -158.786365) (xy 347.010476 -158.778907) (xy 347.036898 -158.778448) (xy 347.064782 -158.779011)
			(xy 347.119928 -158.787323) (xy 347.173219 -158.803761) (xy 347.223465 -158.827958) (xy 347.269543 -158.859373)
			(xy 347.310424 -158.897305) (xy 347.345196 -158.940907) (xy 347.37308 -158.989204) (xy 347.393455 -159.041117)
			(xy 347.405864 -159.095487) (xy 347.410032 -159.1511) (xy 347.405864 -159.206713) (xy 347.393455 -159.261083)
			(xy 347.37308 -159.312996) (xy 347.345196 -159.361293) (xy 347.310424 -159.404895) (xy 347.269543 -159.442827)
			(xy 347.223465 -159.474242) (xy 347.173219 -159.498439) (xy 347.119928 -159.514877) (xy 347.064782 -159.523189)
			(xy 347.036898 -159.523684) (xy 347.010477 -159.523208) (xy 346.958163 -159.515759) (xy 346.907426 -159.500997)
			(xy 346.859281 -159.479218) (xy 346.814695 -159.450858) (xy 346.794328 -159.434022) (xy 346.78747 -159.427926)
			(xy 346.770452 -159.42183) (xy 346.686124 -159.42183) (xy 346.669106 -159.427926) (xy 346.662248 -159.434022)
			(xy 346.641882 -159.450861) (xy 346.597296 -159.479226) (xy 346.549152 -159.501013) (xy 346.498415 -159.515784)
			(xy 346.4461 -159.523244) (xy 346.393256 -159.523244) (xy 346.340941 -159.515784) (xy 346.290204 -159.501013)
			(xy 346.24206 -159.479226) (xy 346.197474 -159.450861) (xy 346.177108 -159.434022) (xy 346.17025 -159.427926)
			(xy 346.153232 -159.42183) (xy 346.068904 -159.42183) (xy 346.051886 -159.427926) (xy 346.045028 -159.434022)
			(xy 346.031089 -159.445692) (xy 346.001317 -159.466557) (xy 345.985592 -159.475678) (xy 345.975178 -159.48152)
			(xy 345.96197 -159.50057) (xy 345.946476 -159.603186) (xy 345.953588 -159.625538) (xy 345.961716 -159.63392)
			(xy 345.981283 -159.655303) (xy 346.01435 -159.702903) (xy 346.039827 -159.754962) (xy 346.057126 -159.810278)
			(xy 346.06585 -159.867576) (xy 346.066364 -159.896556) (xy 346.065881 -159.92413) (xy 346.057933 -159.978703)
			(xy 346.042213 -160.031563) (xy 346.019046 -160.081609) (xy 345.988916 -160.127799) (xy 345.95245 -160.16917)
			(xy 345.931744 -160.187386) (xy 345.923628 -160.19499) (xy 345.914275 -160.215141) (xy 345.91371 -160.226248)
			(xy 345.91371 -160.303464) (xy 345.914279 -160.314574) (xy 345.923616 -160.334733) (xy 345.931744 -160.342326)
			(xy 345.95248 -160.36051) (xy 345.988946 -160.401886) (xy 346.019074 -160.448082) (xy 346.042235 -160.498135)
			(xy 346.057947 -160.551002) (xy 346.065881 -160.60558) (xy 346.066364 -160.633156) (xy 346.065878 -160.660407)
			(xy 346.058122 -160.714355) (xy 346.042767 -160.76665) (xy 346.020125 -160.816227) (xy 345.990659 -160.862077)
			(xy 345.954968 -160.903268) (xy 345.913777 -160.938959) (xy 345.867927 -160.968425) (xy 345.81835 -160.991067)
			(xy 345.766055 -161.006422) (xy 345.712107 -161.014178) (xy 345.657605 -161.014178) (xy 345.603657 -161.006422)
			(xy 345.551362 -160.991067) (xy 345.501785 -160.968425) (xy 345.455935 -160.938959) (xy 345.414744 -160.903268)
			(xy 345.379053 -160.862077) (xy 345.349587 -160.816227) (xy 345.326945 -160.76665) (xy 345.31159 -160.714355)
			(xy 345.303834 -160.660407) (xy 345.303348 -160.633156) (xy 335.428844 -160.633156) (xy 334.321658 -161.740342)
			(xy 334.314292 -161.747454) (xy 334.306672 -161.76625) (xy 334.306672 -166.844218) (xy 335.512662 -166.844218)
			(xy 335.516733 -166.788596) (xy 335.528859 -166.734159) (xy 335.548782 -166.682068) (xy 335.576078 -166.633433)
			(xy 335.610164 -166.58929) (xy 335.650313 -166.550581) (xy 335.695671 -166.51813) (xy 335.745271 -166.492629)
			(xy 335.798055 -166.474622) (xy 335.852898 -166.464492) (xy 335.908632 -166.462455) (xy 335.964069 -166.468555)
			(xy 336.018026 -166.482661) (xy 336.069355 -166.504473) (xy 336.116961 -166.533527) (xy 336.159829 -166.569202)
			(xy 336.197046 -166.610739) (xy 336.227819 -166.657252) (xy 336.251491 -166.707749) (xy 336.267559 -166.761156)
			(xy 336.275679 -166.816332) (xy 336.275877 -166.8272) (xy 336.583526 -166.8272) (xy 336.587597 -166.771578)
			(xy 336.599723 -166.717141) (xy 336.619646 -166.66505) (xy 336.646942 -166.616415) (xy 336.681028 -166.572272)
			(xy 336.721177 -166.533563) (xy 336.766535 -166.501112) (xy 336.816135 -166.475611) (xy 336.868919 -166.457604)
			(xy 336.923762 -166.447474) (xy 336.979496 -166.445437) (xy 337.034933 -166.451537) (xy 337.08889 -166.465643)
			(xy 337.140219 -166.487455) (xy 337.187825 -166.516509) (xy 337.230693 -166.552184) (xy 337.26791 -166.593721)
			(xy 337.298683 -166.640234) (xy 337.322355 -166.690731) (xy 337.338423 -166.744138) (xy 337.346543 -166.799314)
			(xy 337.347052 -166.8272) (xy 337.346543 -166.855086) (xy 337.338423 -166.910262) (xy 337.322355 -166.963669)
			(xy 337.298683 -167.014166) (xy 337.26791 -167.060679) (xy 337.230693 -167.102216) (xy 337.187825 -167.137891)
			(xy 337.140219 -167.166945) (xy 337.08889 -167.188757) (xy 337.034933 -167.202863) (xy 336.979496 -167.208963)
			(xy 336.923762 -167.206926) (xy 336.868919 -167.196796) (xy 336.816135 -167.178789) (xy 336.766535 -167.153288)
			(xy 336.721177 -167.120837) (xy 336.681028 -167.082128) (xy 336.646942 -167.037985) (xy 336.619646 -166.98935)
			(xy 336.599723 -166.937259) (xy 336.587597 -166.882822) (xy 336.583526 -166.8272) (xy 336.275877 -166.8272)
			(xy 336.276188 -166.844218) (xy 336.275679 -166.872104) (xy 336.267559 -166.92728) (xy 336.251491 -166.980687)
			(xy 336.227819 -167.031184) (xy 336.197046 -167.077697) (xy 336.159829 -167.119234) (xy 336.116961 -167.154909)
			(xy 336.069355 -167.183963) (xy 336.018026 -167.205775) (xy 335.964069 -167.219881) (xy 335.908632 -167.225981)
			(xy 335.852898 -167.223944) (xy 335.798055 -167.213814) (xy 335.745271 -167.195807) (xy 335.695671 -167.170306)
			(xy 335.650313 -167.137855) (xy 335.610164 -167.099146) (xy 335.576078 -167.055003) (xy 335.548782 -167.006368)
			(xy 335.528859 -166.954277) (xy 335.516733 -166.89984) (xy 335.512662 -166.844218) (xy 334.306672 -166.844218)
			(xy 334.306672 -168.592246) (xy 334.307136 -168.602121) (xy 334.314584 -168.620415) (xy 334.32115 -168.627806)
			(xy 334.321404 -168.62806) (xy 336.019902 -170.326812) (xy 336.023415 -170.330477) (xy 336.029038 -170.338927)
			(xy 336.031078 -170.343576) (xy 336.041492 -170.369484) (xy 336.048858 -170.37685) (xy 337.824318 -172.15231)
			(xy 340.04377 -172.15231) (xy 340.044297 -172.122832) (xy 340.053366 -172.064577) (xy 340.071291 -172.008411)
			(xy 340.097643 -171.955672) (xy 340.131797 -171.907616) (xy 340.151974 -171.886118) (xy 340.158832 -171.879006)
			(xy 340.166452 -171.860718) (xy 340.166452 -171.769786) (xy 340.158832 -171.751498) (xy 340.151974 -171.744386)
			(xy 340.131798 -171.722888) (xy 340.097653 -171.674829) (xy 340.071306 -171.622089) (xy 340.053386 -171.565924)
			(xy 340.044318 -171.507671) (xy 340.04377 -171.478194) (xy 340.044256 -171.450943) (xy 340.052012 -171.396995)
			(xy 340.067367 -171.3447) (xy 340.090009 -171.295123) (xy 340.119475 -171.249273) (xy 340.155166 -171.208082)
			(xy 340.196357 -171.172391) (xy 340.242207 -171.142925) (xy 340.291784 -171.120283) (xy 340.344079 -171.104928)
			(xy 340.398027 -171.097172) (xy 340.452529 -171.097172) (xy 340.506477 -171.104928) (xy 340.558772 -171.120283)
			(xy 340.608349 -171.142925) (xy 340.654199 -171.172391) (xy 340.69539 -171.208082) (xy 340.731081 -171.249273)
			(xy 340.760547 -171.295123) (xy 340.783189 -171.3447) (xy 340.798544 -171.396995) (xy 340.8063 -171.450943)
			(xy 340.806786 -171.478194) (xy 340.806246 -171.507672) (xy 340.797177 -171.565925) (xy 340.779255 -171.62209)
			(xy 340.752906 -171.674829) (xy 340.718757 -171.722887) (xy 340.698582 -171.744386) (xy 340.691724 -171.751498)
			(xy 340.684104 -171.769786) (xy 340.684104 -171.78909) (xy 349.238824 -171.78909) (xy 349.238824 -166.08171)
			(xy 349.239333 -166.051737) (xy 349.248656 -165.992521) (xy 349.267138 -165.935495) (xy 349.294322 -165.882068)
			(xy 349.329537 -165.833557) (xy 349.35033 -165.811962) (xy 351.535238 -163.627308) (xy 351.542072 -163.619904)
			(xy 351.549794 -163.601308) (xy 351.550224 -163.59124) (xy 351.550224 -160.829752) (xy 351.549791 -160.819683)
			(xy 351.542078 -160.801084) (xy 351.535238 -160.793684) (xy 351.14103 -160.39973) (xy 351.120261 -160.378119)
			(xy 351.085076 -160.329597) (xy 351.05791 -160.276171) (xy 351.039431 -160.219155) (xy 351.030094 -160.15995)
			(xy 351.029524 -160.129982) (xy 351.030022 -160.102072) (xy 351.038158 -160.046847) (xy 351.054253 -159.993397)
			(xy 351.077964 -159.942862) (xy 351.108785 -159.896321) (xy 351.12706 -159.87522) (xy 351.13341 -159.868108)
			(xy 351.140014 -159.850836) (xy 351.140014 -159.763968) (xy 351.13341 -159.746696) (xy 351.12706 -159.739584)
			(xy 351.108736 -159.718477) (xy 351.077829 -159.671907) (xy 351.054051 -159.621323) (xy 351.037912 -159.56781)
			(xy 351.029757 -159.512515) (xy 351.02927 -159.484568) (xy 351.029756 -159.457317) (xy 351.037512 -159.403369)
			(xy 351.052867 -159.351074) (xy 351.075509 -159.301497) (xy 351.104975 -159.255647) (xy 351.140666 -159.214456)
			(xy 351.181857 -159.178765) (xy 351.227707 -159.149299) (xy 351.277284 -159.126657) (xy 351.329579 -159.111302)
			(xy 351.383527 -159.103546) (xy 351.438029 -159.103546) (xy 351.491977 -159.111302) (xy 351.544272 -159.126657)
			(xy 351.593849 -159.149299) (xy 351.639699 -159.178765) (xy 351.68089 -159.214456) (xy 351.716581 -159.255647)
			(xy 351.746047 -159.301497) (xy 351.768689 -159.351074) (xy 351.784044 -159.403369) (xy 351.7918 -159.457317)
			(xy 351.792286 -159.484568) (xy 351.791685 -159.51469) (xy 351.78221 -159.574185) (xy 351.763505 -159.631452)
			(xy 351.736037 -159.685069) (xy 351.700485 -159.733706) (xy 351.67951 -159.755332) (xy 351.672665 -159.762728)
			(xy 351.664948 -159.78133) (xy 351.664524 -159.7914) (xy 351.664524 -159.823404) (xy 351.664941 -159.833474)
			(xy 351.672667 -159.852072) (xy 351.67951 -159.859472) (xy 351.680526 -159.860234) (xy 352.201226 -160.380934)
			(xy 352.22197 -160.402568) (xy 352.25716 -160.451083) (xy 352.284332 -160.504503) (xy 352.302817 -160.561514)
			(xy 352.312159 -160.620715) (xy 352.312732 -160.650682) (xy 352.312732 -163.77031) (xy 352.31222 -163.800283)
			(xy 352.302895 -163.859498) (xy 352.284413 -163.916523) (xy 352.257231 -163.96995) (xy 352.222018 -164.018463)
			(xy 352.201226 -164.040058) (xy 350.016318 -166.224712) (xy 350.009483 -166.232116) (xy 350.001759 -166.250712)
			(xy 350.001332 -166.26078) (xy 350.001332 -167.430196) (xy 351.94113 -167.430196) (xy 351.941582 -167.402621)
			(xy 351.949536 -167.348047) (xy 351.965263 -167.295186) (xy 351.988436 -167.24514) (xy 352.018571 -167.198951)
			(xy 352.055041 -167.157581) (xy 352.07575 -167.139366) (xy 352.083887 -167.131781) (xy 352.093229 -167.111616)
			(xy 352.093784 -167.100504) (xy 352.093784 -167.023288) (xy 352.093244 -167.012175) (xy 352.083886 -166.992016)
			(xy 352.07575 -166.984426) (xy 352.055038 -166.966216) (xy 352.01857 -166.924846) (xy 351.98844 -166.878656)
			(xy 351.965274 -166.828608) (xy 351.949557 -166.775746) (xy 351.941616 -166.721172) (xy 351.941617 -166.666023)
			(xy 351.949559 -166.611449) (xy 351.965276 -166.558587) (xy 351.988442 -166.50854) (xy 352.018573 -166.46235)
			(xy 352.055042 -166.42098) (xy 352.07575 -166.402766) (xy 352.083887 -166.395181) (xy 352.093229 -166.375016)
			(xy 352.093784 -166.363904) (xy 352.093784 -166.286688) (xy 352.093244 -166.275575) (xy 352.083886 -166.255416)
			(xy 352.07575 -166.247826) (xy 352.055038 -166.229616) (xy 352.01857 -166.188246) (xy 351.988439 -166.142055)
			(xy 351.965274 -166.092007) (xy 351.949557 -166.039145) (xy 351.941616 -165.984571) (xy 351.94113 -165.956996)
			(xy 351.941552 -165.929741) (xy 351.94931 -165.875787) (xy 351.964669 -165.823486) (xy 351.987314 -165.773903)
			(xy 352.016786 -165.728048) (xy 352.052485 -165.686855) (xy 352.093682 -165.651161) (xy 352.13954 -165.621694)
			(xy 352.189125 -165.599054) (xy 352.241428 -165.583701) (xy 352.295383 -165.575949) (xy 352.322638 -165.575488)
			(xy 352.350494 -165.575986) (xy 352.40561 -165.584114) (xy 352.458961 -165.600164) (xy 352.509413 -165.623795)
			(xy 352.555897 -165.654505) (xy 352.597426 -165.691643) (xy 352.633119 -165.73442) (xy 352.662218 -165.781929)
			(xy 352.684106 -165.833162) (xy 352.6917 -165.859968) (xy 352.693986 -165.868858) (xy 352.704654 -165.884098)
			(xy 352.776536 -165.93185) (xy 352.79457 -165.935914) (xy 352.803714 -165.934644) (xy 352.816731 -165.932975)
			(xy 352.842915 -165.931195) (xy 352.856038 -165.931088) (xy 352.870187 -165.931177) (xy 352.89841 -165.933215)
			(xy 352.912426 -165.935152) (xy 352.922586 -165.936676) (xy 352.942144 -165.93185) (xy 353.016566 -165.87597)
			(xy 353.026726 -165.858444) (xy 353.027996 -165.848284) (xy 353.032094 -165.821132) (xy 353.047064 -165.768301)
			(xy 353.069453 -165.718162) (xy 353.098799 -165.67175) (xy 353.134495 -165.630025) (xy 353.175804 -165.593848)
			(xy 353.221872 -165.563966) (xy 353.271749 -165.540998) (xy 353.324403 -165.525417) (xy 353.378747 -165.517545)
			(xy 353.406202 -165.517068) (xy 353.433452 -165.517576) (xy 353.487398 -165.525332) (xy 353.539691 -165.540686)
			(xy 353.589266 -165.563326) (xy 353.635116 -165.59279) (xy 353.676305 -165.628479) (xy 353.711997 -165.669667)
			(xy 353.741464 -165.715514) (xy 353.764106 -165.765089) (xy 353.779463 -165.817381) (xy 353.787223 -165.871326)
			(xy 353.78771 -165.898576) (xy 353.787224 -165.92615) (xy 353.779275 -165.980722) (xy 353.763554 -166.033581)
			(xy 353.740388 -166.083627) (xy 353.710259 -166.129817) (xy 353.673795 -166.171189) (xy 353.65309 -166.189406)
			(xy 353.644972 -166.197009) (xy 353.635618 -166.21716) (xy 353.635056 -166.228268) (xy 353.635056 -166.305484)
			(xy 353.635599 -166.316597) (xy 353.644953 -166.336757) (xy 353.65309 -166.344346) (xy 353.673776 -166.362584)
			(xy 353.710249 -166.403947) (xy 353.740384 -166.450131) (xy 353.763555 -166.500174) (xy 353.779276 -166.553032)
			(xy 353.787222 -166.607603) (xy 353.787256 -166.609522) (xy 358.376218 -166.609522) (xy 358.380289 -166.5539)
			(xy 358.392415 -166.499463) (xy 358.412338 -166.447372) (xy 358.439634 -166.398737) (xy 358.47372 -166.354594)
			(xy 358.513869 -166.315885) (xy 358.559227 -166.283434) (xy 358.608827 -166.257933) (xy 358.661611 -166.239926)
			(xy 358.716454 -166.229796) (xy 358.772188 -166.227759) (xy 358.827625 -166.233859) (xy 358.881582 -166.247965)
			(xy 358.932911 -166.269777) (xy 358.980517 -166.298831) (xy 359.023385 -166.334506) (xy 359.060602 -166.376043)
			(xy 359.091375 -166.422556) (xy 359.115047 -166.473053) (xy 359.131115 -166.52646) (xy 359.139235 -166.581636)
			(xy 359.139744 -166.609522) (xy 359.139235 -166.637408) (xy 359.131115 -166.692584) (xy 359.115047 -166.745991)
			(xy 359.091375 -166.796488) (xy 359.060602 -166.843001) (xy 359.023385 -166.884538) (xy 358.980517 -166.920213)
			(xy 358.932911 -166.949267) (xy 358.881582 -166.971079) (xy 358.827625 -166.985185) (xy 358.772188 -166.991285)
			(xy 358.716454 -166.989248) (xy 358.661611 -166.979118) (xy 358.608827 -166.961111) (xy 358.559227 -166.93561)
			(xy 358.513869 -166.903159) (xy 358.47372 -166.86445) (xy 358.439634 -166.820307) (xy 358.412338 -166.771672)
			(xy 358.392415 -166.719581) (xy 358.380289 -166.665144) (xy 358.376218 -166.609522) (xy 353.787256 -166.609522)
			(xy 353.78771 -166.635176) (xy 353.787222 -166.662428) (xy 353.779469 -166.716378) (xy 353.764116 -166.768675)
			(xy 353.741476 -166.818255) (xy 353.712011 -166.864108) (xy 353.67632 -166.905301) (xy 353.635129 -166.940995)
			(xy 353.589278 -166.970464) (xy 353.5397 -166.993107) (xy 353.487404 -167.008463) (xy 353.433454 -167.016221)
			(xy 353.406202 -167.016684) (xy 353.371912 -167.01516) (xy 353.361752 -167.014144) (xy 353.342448 -167.02024)
			(xy 353.271836 -167.079422) (xy 353.262438 -167.097456) (xy 353.261422 -167.107616) (xy 353.258437 -167.135785)
			(xy 353.245268 -167.190876) (xy 353.224093 -167.243413) (xy 353.19538 -167.292239) (xy 353.15976 -167.336281)
			(xy 353.118016 -167.374568) (xy 353.071068 -167.406258) (xy 353.019948 -167.430655) (xy 352.965781 -167.447221)
			(xy 352.90976 -167.455591) (xy 352.881438 -167.456104) (xy 352.863419 -167.455888) (xy 352.827544 -167.45245)
			(xy 352.80981 -167.449246) (xy 352.800412 -167.447468) (xy 352.781362 -167.451278) (xy 352.706178 -167.49903)
			(xy 352.694748 -167.514778) (xy 352.692462 -167.524176) (xy 352.685104 -167.551232) (xy 352.663469 -167.602959)
			(xy 352.634499 -167.650965) (xy 352.598818 -167.694216) (xy 352.557194 -167.731782) (xy 352.510522 -167.762854)
			(xy 352.459806 -167.786765) (xy 352.406138 -167.802999) (xy 352.350673 -167.811207) (xy 352.322638 -167.811704)
			(xy 352.295386 -167.811209) (xy 352.241436 -167.803457) (xy 352.189138 -167.788106) (xy 352.139558 -167.765468)
			(xy 352.093705 -167.736003) (xy 352.052511 -167.700313) (xy 352.016817 -167.659123) (xy 351.987349 -167.613272)
			(xy 351.964706 -167.563694) (xy 351.94935 -167.511397) (xy 351.941593 -167.457448) (xy 351.94113 -167.430196)
			(xy 350.001332 -167.430196) (xy 350.001332 -168.982136) (xy 353.609148 -168.982136) (xy 353.609622 -168.954562)
			(xy 353.61757 -168.899988) (xy 353.633293 -168.847128) (xy 353.656461 -168.797081) (xy 353.686593 -168.750892)
			(xy 353.723061 -168.709521) (xy 353.743768 -168.691306) (xy 353.75189 -168.683707) (xy 353.76124 -168.663552)
			(xy 353.761802 -168.652444) (xy 353.761802 -168.575228) (xy 353.761234 -168.564118) (xy 353.751895 -168.54396)
			(xy 353.743768 -168.536366) (xy 353.723031 -168.518183) (xy 353.686564 -168.476808) (xy 353.656436 -168.430612)
			(xy 353.633275 -168.380558) (xy 353.617564 -168.327691) (xy 353.60963 -168.273112) (xy 353.609148 -168.245536)
			(xy 353.609734 -168.216611) (xy 353.618463 -168.159423) (xy 353.635726 -168.104209) (xy 353.661127 -168.052234)
			(xy 353.694085 -168.00469) (xy 353.733843 -167.962667) (xy 353.77949 -167.927129) (xy 353.804474 -167.912542)
			(xy 353.814634 -167.906954) (xy 353.827842 -167.888158) (xy 353.84486 -167.786812) (xy 353.838256 -167.764968)
			(xy 353.830636 -167.756078) (xy 353.81284 -167.73549) (xy 353.782818 -167.690102) (xy 353.759725 -167.640827)
			(xy 353.744052 -167.588714) (xy 353.736134 -167.534875) (xy 353.73564 -167.507666) (xy 353.736125 -167.481051)
			(xy 353.743704 -167.428363) (xy 353.758704 -167.377289) (xy 353.780818 -167.32887) (xy 353.809597 -167.28409)
			(xy 353.844456 -167.243861) (xy 353.884684 -167.209002) (xy 353.929463 -167.180222) (xy 353.977882 -167.158106)
			(xy 354.028955 -167.143106) (xy 354.081643 -167.135525) (xy 354.108258 -167.135048) (xy 354.13468 -167.135484)
			(xy 354.186996 -167.142941) (xy 354.237735 -167.157712) (xy 354.285879 -167.1795) (xy 354.330463 -167.207869)
			(xy 354.350828 -167.22471) (xy 354.357686 -167.230806) (xy 354.374704 -167.236902) (xy 354.459032 -167.236902)
			(xy 354.47605 -167.230806) (xy 354.482908 -167.22471) (xy 354.503274 -167.207871) (xy 354.54786 -167.179506)
			(xy 354.596004 -167.157719) (xy 354.646741 -167.142948) (xy 354.699056 -167.135488) (xy 354.7519 -167.135488)
			(xy 354.804215 -167.142948) (xy 354.854952 -167.157719) (xy 354.903096 -167.179506) (xy 354.947682 -167.207871)
			(xy 354.968048 -167.22471) (xy 354.974906 -167.230806) (xy 354.991924 -167.236902) (xy 355.076252 -167.236902)
			(xy 355.09327 -167.230806) (xy 355.100128 -167.22471) (xy 355.120484 -167.20786) (xy 355.165077 -167.179507)
			(xy 355.213224 -167.15773) (xy 355.263962 -167.142965) (xy 355.316276 -167.135507) (xy 355.342698 -167.135048)
			(xy 355.370582 -167.135611) (xy 355.425728 -167.143923) (xy 355.479019 -167.160361) (xy 355.529265 -167.184558)
			(xy 355.575343 -167.215973) (xy 355.616224 -167.253905) (xy 355.650996 -167.297507) (xy 355.67888 -167.345804)
			(xy 355.699255 -167.397717) (xy 355.711664 -167.452087) (xy 355.715832 -167.5077) (xy 355.711664 -167.563313)
			(xy 355.699255 -167.617683) (xy 355.67888 -167.669596) (xy 355.650996 -167.717893) (xy 355.616224 -167.761495)
			(xy 355.575343 -167.799427) (xy 355.529265 -167.830842) (xy 355.479019 -167.855039) (xy 355.425728 -167.871477)
			(xy 355.370582 -167.879789) (xy 355.342698 -167.880284) (xy 355.316277 -167.879808) (xy 355.263963 -167.872359)
			(xy 355.213226 -167.857597) (xy 355.165081 -167.835818) (xy 355.120495 -167.807458) (xy 355.100128 -167.790622)
			(xy 355.09327 -167.784526) (xy 355.076252 -167.77843) (xy 354.991924 -167.77843) (xy 354.974906 -167.784526)
			(xy 354.968048 -167.790622) (xy 354.947682 -167.807461) (xy 354.903096 -167.835826) (xy 354.854952 -167.857613)
			(xy 354.804215 -167.872384) (xy 354.7519 -167.879844) (xy 354.699056 -167.879844) (xy 354.646741 -167.872384)
			(xy 354.596004 -167.857613) (xy 354.54786 -167.835826) (xy 354.503274 -167.807461) (xy 354.482908 -167.790622)
			(xy 354.47605 -167.784526) (xy 354.459032 -167.77843) (xy 354.374704 -167.77843) (xy 354.357686 -167.784526)
			(xy 354.350828 -167.790622) (xy 354.337682 -167.801642) (xy 354.309697 -167.821485) (xy 354.294948 -167.830246)
			(xy 354.284788 -167.836088) (xy 354.271834 -167.854884) (xy 354.256594 -167.956484) (xy 354.263198 -167.978328)
			(xy 354.271072 -167.986964) (xy 354.289974 -168.008207) (xy 354.321908 -168.055254) (xy 354.346498 -168.106522)
			(xy 354.363199 -168.160875) (xy 354.371641 -168.217106) (xy 354.372164 -168.245536) (xy 354.371667 -168.27311)
			(xy 354.363722 -168.327682) (xy 354.348005 -168.380541) (xy 354.32484 -168.430588) (xy 354.294713 -168.476778)
			(xy 354.258249 -168.51815) (xy 354.237544 -168.536366) (xy 354.229437 -168.543978) (xy 354.220078 -168.564123)
			(xy 354.21951 -168.575228) (xy 354.21951 -168.652444) (xy 354.22009 -168.663552) (xy 354.22942 -168.683711)
			(xy 354.237544 -168.691306) (xy 354.25827 -168.709501) (xy 354.294737 -168.750874) (xy 354.324866 -168.797068)
			(xy 354.348029 -168.847119) (xy 354.363743 -168.899984) (xy 354.37168 -168.954561) (xy 354.372164 -168.982136)
			(xy 354.371678 -169.009387) (xy 354.363922 -169.063335) (xy 354.348567 -169.11563) (xy 354.325925 -169.165207)
			(xy 354.296459 -169.211057) (xy 354.260768 -169.252248) (xy 354.219577 -169.287939) (xy 354.173727 -169.317405)
			(xy 354.12415 -169.340047) (xy 354.071855 -169.355402) (xy 354.017907 -169.363158) (xy 353.963405 -169.363158)
			(xy 353.909457 -169.355402) (xy 353.857162 -169.340047) (xy 353.807585 -169.317405) (xy 353.761735 -169.287939)
			(xy 353.720544 -169.252248) (xy 353.684853 -169.211057) (xy 353.655387 -169.165207) (xy 353.632745 -169.11563)
			(xy 353.61739 -169.063335) (xy 353.609634 -169.009387) (xy 353.609148 -168.982136) (xy 350.001332 -168.982136)
			(xy 350.001332 -171.61002) (xy 350.001739 -171.620091) (xy 350.009472 -171.63869) (xy 350.016318 -171.646088)
			(xy 352.3742 -174.00397) (xy 352.38161 -174.010798) (xy 352.400201 -174.018526) (xy 352.410268 -174.018956)
			(xy 358.207564 -174.018956) (xy 358.217588 -174.01855) (xy 358.236113 -174.010884) (xy 358.250288 -173.996706)
			(xy 358.257951 -173.97818) (xy 358.258364 -173.968156) (xy 358.258364 -172.91558) (xy 358.258905 -172.885608)
			(xy 358.268219 -172.826393) (xy 358.286692 -172.769367) (xy 358.313869 -172.715939) (xy 358.349079 -172.667427)
			(xy 358.36987 -172.645832) (xy 359.968038 -171.047918) (xy 359.974868 -171.04051) (xy 359.982592 -171.021917)
			(xy 359.983024 -171.01185) (xy 359.983024 -169.313352) (xy 359.982591 -169.303283) (xy 359.974878 -169.284684)
			(xy 359.968038 -169.277284) (xy 359.44683 -168.75633) (xy 359.426061 -168.734719) (xy 359.390876 -168.686197)
			(xy 359.36371 -168.632771) (xy 359.345231 -168.575755) (xy 359.335894 -168.51655) (xy 359.335324 -168.486582)
			(xy 359.335822 -168.458672) (xy 359.343958 -168.403447) (xy 359.360053 -168.349997) (xy 359.383764 -168.299462)
			(xy 359.414585 -168.252921) (xy 359.43286 -168.23182) (xy 359.43921 -168.224708) (xy 359.445814 -168.207436)
			(xy 359.445814 -168.120568) (xy 359.43921 -168.103296) (xy 359.43286 -168.096184) (xy 359.414536 -168.075077)
			(xy 359.383629 -168.028507) (xy 359.359851 -167.977923) (xy 359.343712 -167.92441) (xy 359.335557 -167.869115)
			(xy 359.33507 -167.841168) (xy 359.335556 -167.813917) (xy 359.343312 -167.759969) (xy 359.358667 -167.707674)
			(xy 359.381309 -167.658097) (xy 359.410775 -167.612247) (xy 359.446466 -167.571056) (xy 359.487657 -167.535365)
			(xy 359.533507 -167.505899) (xy 359.583084 -167.483257) (xy 359.635379 -167.467902) (xy 359.689327 -167.460146)
			(xy 359.743829 -167.460146) (xy 359.797777 -167.467902) (xy 359.850072 -167.483257) (xy 359.899649 -167.505899)
			(xy 359.945499 -167.535365) (xy 359.98669 -167.571056) (xy 360.022381 -167.612247) (xy 360.051847 -167.658097)
			(xy 360.074489 -167.707674) (xy 360.089844 -167.759969) (xy 360.0976 -167.813917) (xy 360.098086 -167.841168)
			(xy 360.097485 -167.87129) (xy 360.08801 -167.930785) (xy 360.069305 -167.988052) (xy 360.041837 -168.041669)
			(xy 360.006285 -168.090306) (xy 359.98531 -168.111932) (xy 359.978465 -168.119328) (xy 359.970748 -168.13793)
			(xy 359.970324 -168.148) (xy 359.970324 -168.180004) (xy 359.970741 -168.190074) (xy 359.978467 -168.208672)
			(xy 359.98531 -168.216072) (xy 359.986326 -168.216834) (xy 360.634026 -168.864534) (xy 360.65477 -168.886168)
			(xy 360.68996 -168.934683) (xy 360.717132 -168.988103) (xy 360.735617 -169.045114) (xy 360.744959 -169.104315)
			(xy 360.745532 -169.134282) (xy 360.745532 -171.19092) (xy 360.744963 -171.220891) (xy 360.735652 -171.280103)
			(xy 360.717183 -171.337127) (xy 360.690013 -171.390556) (xy 360.654812 -171.439071) (xy 360.634026 -171.460668)
			(xy 359.035858 -173.058582) (xy 359.029027 -173.065989) (xy 359.021303 -173.084583) (xy 359.020872 -173.09465)
			(xy 359.020872 -175.705516) (xy 360.22153 -175.705516) (xy 360.221996 -175.677941) (xy 360.229947 -175.623368)
			(xy 360.245671 -175.570508) (xy 360.268841 -175.520462) (xy 360.298974 -175.474272) (xy 360.335442 -175.432901)
			(xy 360.35615 -175.414686) (xy 360.364278 -175.407093) (xy 360.373625 -175.386934) (xy 360.374184 -175.375824)
			(xy 360.374184 -175.298608) (xy 360.373632 -175.287496) (xy 360.364283 -175.267337) (xy 360.35615 -175.259746)
			(xy 360.335458 -175.241514) (xy 360.29899 -175.200147) (xy 360.268859 -175.15396) (xy 360.245693 -175.103915)
			(xy 360.229975 -175.051055) (xy 360.222033 -174.996484) (xy 360.222031 -174.941337) (xy 360.229971 -174.886765)
			(xy 360.245686 -174.833905) (xy 360.268849 -174.783859) (xy 360.298978 -174.73767) (xy 360.335443 -174.6963)
			(xy 360.35615 -174.678086) (xy 360.364278 -174.670493) (xy 360.373625 -174.650334) (xy 360.374184 -174.639224)
			(xy 360.374184 -174.562008) (xy 360.373632 -174.550896) (xy 360.364283 -174.530737) (xy 360.35615 -174.523146)
			(xy 360.335448 -174.504925) (xy 360.298979 -174.463557) (xy 360.268847 -174.417369) (xy 360.24568 -174.367323)
			(xy 360.229961 -174.314463) (xy 360.222018 -174.25989) (xy 360.22153 -174.232316) (xy 360.22197 -174.205062)
			(xy 360.229726 -174.151108) (xy 360.245082 -174.098807) (xy 360.267725 -174.049225) (xy 360.297195 -174.00337)
			(xy 360.332892 -173.962176) (xy 360.374087 -173.926482) (xy 360.419944 -173.897015) (xy 360.469528 -173.874374)
			(xy 360.52183 -173.859021) (xy 360.575784 -173.851269) (xy 360.603038 -173.850808) (xy 360.630895 -173.851291)
			(xy 360.686012 -173.85942) (xy 360.739364 -173.875471) (xy 360.789817 -173.899103) (xy 360.836302 -173.929815)
			(xy 360.877831 -173.966955) (xy 360.913523 -174.009735) (xy 360.942621 -174.057246) (xy 360.964507 -174.108481)
			(xy 360.9721 -174.135288) (xy 360.974386 -174.144178) (xy 360.985054 -174.159418) (xy 361.056936 -174.20717)
			(xy 361.07497 -174.211234) (xy 361.084114 -174.209964) (xy 361.097131 -174.208295) (xy 361.123315 -174.206515)
			(xy 361.136438 -174.206408) (xy 361.150587 -174.206497) (xy 361.17881 -174.208534) (xy 361.192826 -174.210472)
			(xy 361.202986 -174.211996) (xy 361.222544 -174.20717) (xy 361.296966 -174.15129) (xy 361.307126 -174.133764)
			(xy 361.308396 -174.123604) (xy 361.312431 -174.096442) (xy 361.327412 -174.04361) (xy 361.349811 -173.993471)
			(xy 361.379165 -173.947061) (xy 361.414869 -173.905337) (xy 361.456184 -173.869162) (xy 361.502258 -173.839283)
			(xy 361.552139 -173.816316) (xy 361.604797 -173.800736) (xy 361.659145 -173.792865) (xy 361.686602 -173.792388)
			(xy 361.713853 -173.792876) (xy 361.767801 -173.800633) (xy 361.820095 -173.815988) (xy 361.869672 -173.838629)
			(xy 361.915522 -173.868095) (xy 361.956712 -173.903786) (xy 361.992404 -173.944976) (xy 362.02187 -173.990826)
			(xy 362.044512 -174.040403) (xy 362.059867 -174.092697) (xy 362.067624 -174.146645) (xy 362.06811 -174.173896)
			(xy 362.067638 -174.20147) (xy 362.059686 -174.256043) (xy 362.043962 -174.308902) (xy 362.020793 -174.358948)
			(xy 361.990662 -174.405138) (xy 361.954196 -174.44651) (xy 361.93349 -174.464726) (xy 361.925363 -174.472321)
			(xy 361.916014 -174.492478) (xy 361.915456 -174.503588) (xy 361.915456 -174.580804) (xy 361.915988 -174.591919)
			(xy 361.92535 -174.612078) (xy 361.93349 -174.619666) (xy 361.954186 -174.637894) (xy 361.990658 -174.679259)
			(xy 362.020792 -174.725445) (xy 362.043961 -174.77549) (xy 362.05968 -174.82835) (xy 362.067623 -174.882922)
			(xy 362.067657 -174.884842) (xy 366.656618 -174.884842) (xy 366.660689 -174.82922) (xy 366.672815 -174.774783)
			(xy 366.692738 -174.722692) (xy 366.720034 -174.674057) (xy 366.75412 -174.629914) (xy 366.794269 -174.591205)
			(xy 366.839627 -174.558754) (xy 366.889227 -174.533253) (xy 366.942011 -174.515246) (xy 366.996854 -174.505116)
			(xy 367.052588 -174.503079) (xy 367.108025 -174.509179) (xy 367.161982 -174.523285) (xy 367.213311 -174.545097)
			(xy 367.260917 -174.574151) (xy 367.303785 -174.609826) (xy 367.341002 -174.651363) (xy 367.371775 -174.697876)
			(xy 367.395447 -174.748373) (xy 367.411515 -174.80178) (xy 367.419635 -174.856956) (xy 367.420144 -174.884842)
			(xy 367.419635 -174.912728) (xy 367.411515 -174.967904) (xy 367.395447 -175.021311) (xy 367.371775 -175.071808)
			(xy 367.341002 -175.118321) (xy 367.303785 -175.159858) (xy 367.260917 -175.195533) (xy 367.213311 -175.224587)
			(xy 367.161982 -175.246399) (xy 367.108025 -175.260505) (xy 367.052588 -175.266605) (xy 366.996854 -175.264568)
			(xy 366.942011 -175.254438) (xy 366.889227 -175.236431) (xy 366.839627 -175.21093) (xy 366.794269 -175.178479)
			(xy 366.75412 -175.13977) (xy 366.720034 -175.095627) (xy 366.692738 -175.046992) (xy 366.672815 -174.994901)
			(xy 366.660689 -174.940464) (xy 366.656618 -174.884842) (xy 362.067657 -174.884842) (xy 362.06811 -174.910496)
			(xy 362.067641 -174.937749) (xy 362.059885 -174.991699) (xy 362.044529 -175.043997) (xy 362.021887 -175.093577)
			(xy 361.99242 -175.13943) (xy 361.956727 -175.180623) (xy 361.915535 -175.216316) (xy 361.869682 -175.245784)
			(xy 361.820103 -175.268427) (xy 361.767805 -175.283783) (xy 361.713855 -175.291541) (xy 361.686602 -175.292004)
			(xy 361.652312 -175.29048) (xy 361.642152 -175.289464) (xy 361.622848 -175.29556) (xy 361.552236 -175.354742)
			(xy 361.542838 -175.372776) (xy 361.541822 -175.382936) (xy 361.538854 -175.411107) (xy 361.525682 -175.466199)
			(xy 361.504505 -175.518735) (xy 361.475789 -175.567561) (xy 361.440167 -175.611602) (xy 361.398421 -175.649889)
			(xy 361.351472 -175.681579) (xy 361.30035 -175.705976) (xy 361.246183 -175.722541) (xy 361.19016 -175.730911)
			(xy 361.161838 -175.731424) (xy 361.143819 -175.731207) (xy 361.107944 -175.72777) (xy 361.09021 -175.724566)
			(xy 361.080812 -175.722788) (xy 361.061762 -175.726598) (xy 360.986578 -175.77435) (xy 360.975148 -175.790098)
			(xy 360.972862 -175.799496) (xy 360.965518 -175.826556) (xy 360.94388 -175.878283) (xy 360.914908 -175.926288)
			(xy 360.879225 -175.969538) (xy 360.837599 -176.007104) (xy 360.790925 -176.038175) (xy 360.740208 -176.062085)
			(xy 360.686539 -176.078319) (xy 360.631073 -176.086527) (xy 360.603038 -176.087024) (xy 360.575787 -176.086509)
			(xy 360.521839 -176.078758) (xy 360.469543 -176.063408) (xy 360.419964 -176.040771) (xy 360.374111 -176.011308)
			(xy 360.332918 -175.97562) (xy 360.297224 -175.934432) (xy 360.267755 -175.888584) (xy 360.245111 -175.839008)
			(xy 360.229753 -175.786714) (xy 360.221994 -175.732767) (xy 360.22153 -175.705516) (xy 359.020872 -175.705516)
			(xy 359.020872 -177.254916) (xy 361.889548 -177.254916) (xy 361.890008 -177.227341) (xy 361.897959 -177.172767)
			(xy 361.913684 -177.119906) (xy 361.936855 -177.06986) (xy 361.96699 -177.023671) (xy 362.00346 -176.982301)
			(xy 362.024168 -176.964086) (xy 362.032299 -176.956496) (xy 362.041644 -176.936334) (xy 362.042202 -176.925224)
			(xy 362.042202 -176.848008) (xy 362.041645 -176.836897) (xy 362.032298 -176.816739) (xy 362.024168 -176.809146)
			(xy 362.003469 -176.790921) (xy 361.967 -176.749555) (xy 361.936867 -176.703367) (xy 361.913699 -176.653322)
			(xy 361.897979 -176.600462) (xy 361.890036 -176.54589) (xy 361.889548 -176.518316) (xy 361.889957 -176.491765)
			(xy 361.897325 -176.439176) (xy 361.911921 -176.388119) (xy 361.933462 -176.339582) (xy 361.961532 -176.294504)
			(xy 361.995586 -176.253759) (xy 362.034966 -176.218135) (xy 362.05668 -176.202848) (xy 362.064808 -176.197006)
			(xy 362.07573 -176.18075) (xy 362.093764 -176.091088) (xy 362.089954 -176.07153) (xy 362.084366 -176.063148)
			(xy 362.070006 -176.040293) (xy 362.047322 -175.991317) (xy 362.031927 -175.939584) (xy 362.024142 -175.886173)
			(xy 362.02366 -175.859186) (xy 362.024144 -175.83257) (xy 362.031721 -175.779881) (xy 362.046719 -175.728807)
			(xy 362.068832 -175.680386) (xy 362.097611 -175.635605) (xy 362.13247 -175.595376) (xy 362.172699 -175.560516)
			(xy 362.217479 -175.531736) (xy 362.265899 -175.509621) (xy 362.316973 -175.494622) (xy 362.369662 -175.487044)
			(xy 362.396278 -175.486568) (xy 362.422699 -175.487046) (xy 362.475013 -175.494492) (xy 362.525751 -175.509253)
			(xy 362.573896 -175.531032) (xy 362.618482 -175.559393) (xy 362.638848 -175.57623) (xy 362.645706 -175.582326)
			(xy 362.662724 -175.588422) (xy 362.747052 -175.588422) (xy 362.76407 -175.582326) (xy 362.770928 -175.57623)
			(xy 362.791294 -175.559391) (xy 362.83588 -175.531026) (xy 362.884024 -175.509239) (xy 362.934761 -175.494468)
			(xy 362.987076 -175.487008) (xy 363.03992 -175.487008) (xy 363.092235 -175.494468) (xy 363.142972 -175.509239)
			(xy 363.191116 -175.531026) (xy 363.235702 -175.559391) (xy 363.256068 -175.57623) (xy 363.262926 -175.582326)
			(xy 363.279944 -175.588422) (xy 363.364272 -175.588422) (xy 363.38129 -175.582326) (xy 363.388148 -175.57623)
			(xy 363.408499 -175.559374) (xy 363.453093 -175.531021) (xy 363.501241 -175.509244) (xy 363.551981 -175.494481)
			(xy 363.604296 -175.487026) (xy 363.630718 -175.486568) (xy 363.658601 -175.487118) (xy 363.713744 -175.495432)
			(xy 363.767031 -175.511871) (xy 363.817274 -175.536069) (xy 363.863349 -175.567484) (xy 363.904227 -175.605416)
			(xy 363.938995 -175.649016) (xy 363.966878 -175.697311) (xy 363.987251 -175.749222) (xy 363.999659 -175.80359)
			(xy 364.003827 -175.8592) (xy 363.999659 -175.91481) (xy 363.987251 -175.969178) (xy 363.966878 -176.021089)
			(xy 363.938995 -176.069384) (xy 363.904227 -176.112984) (xy 363.863349 -176.150916) (xy 363.817274 -176.182331)
			(xy 363.767031 -176.206529) (xy 363.713744 -176.222968) (xy 363.658601 -176.231282) (xy 363.630718 -176.231804)
			(xy 363.604297 -176.231335) (xy 363.551982 -176.223888) (xy 363.501243 -176.209125) (xy 363.453099 -176.187344)
			(xy 363.408514 -176.158981) (xy 363.388148 -176.142142) (xy 363.38129 -176.136046) (xy 363.364272 -176.12995)
			(xy 363.279944 -176.12995) (xy 363.262926 -176.136046) (xy 363.256068 -176.142142) (xy 363.235702 -176.158981)
			(xy 363.191116 -176.187346) (xy 363.142972 -176.209133) (xy 363.092235 -176.223904) (xy 363.03992 -176.231364)
			(xy 362.987076 -176.231364) (xy 362.934761 -176.223904) (xy 362.884024 -176.209133) (xy 362.83588 -176.187346)
			(xy 362.791294 -176.158981) (xy 362.770928 -176.142142) (xy 362.76407 -176.136046) (xy 362.747052 -176.12995)
			(xy 362.662724 -176.12995) (xy 362.645706 -176.136046) (xy 362.638848 -176.142142) (xy 362.61167 -176.163224)
			(xy 362.603288 -176.169066) (xy 362.59262 -176.18583) (xy 362.576618 -176.275746) (xy 362.580682 -176.29505)
			(xy 362.58627 -176.303432) (xy 362.601926 -176.327311) (xy 362.626709 -176.378749) (xy 362.643545 -176.433308)
			(xy 362.652057 -176.489767) (xy 362.652564 -176.518316) (xy 362.652053 -176.545889) (xy 362.644112 -176.60046)
			(xy 362.628396 -176.65332) (xy 362.605235 -176.703366) (xy 362.57511 -176.749557) (xy 362.538648 -176.79093)
			(xy 362.517944 -176.809146) (xy 362.509801 -176.816725) (xy 362.500463 -176.836895) (xy 362.49991 -176.848008)
			(xy 362.49991 -176.925224) (xy 362.500445 -176.936338) (xy 362.509807 -176.956496) (xy 362.517944 -176.964086)
			(xy 362.53866 -176.982291) (xy 362.575128 -177.023662) (xy 362.605259 -177.069854) (xy 362.628423 -177.119903)
			(xy 362.644139 -177.172766) (xy 362.652079 -177.227341) (xy 362.652564 -177.254916) (xy 362.652078 -177.282167)
			(xy 362.644322 -177.336115) (xy 362.628967 -177.38841) (xy 362.606325 -177.437987) (xy 362.576859 -177.483837)
			(xy 362.541168 -177.525028) (xy 362.499977 -177.560719) (xy 362.454127 -177.590185) (xy 362.40455 -177.612827)
			(xy 362.352255 -177.628182) (xy 362.298307 -177.635938) (xy 362.243805 -177.635938) (xy 362.189857 -177.628182)
			(xy 362.137562 -177.612827) (xy 362.087985 -177.590185) (xy 362.042135 -177.560719) (xy 362.000944 -177.525028)
			(xy 361.965253 -177.483837) (xy 361.935787 -177.437987) (xy 361.913145 -177.38841) (xy 361.89779 -177.336115)
			(xy 361.890034 -177.282167) (xy 361.889548 -177.254916) (xy 359.020872 -177.254916) (xy 359.020872 -180.3273)
			(xy 359.021278 -180.337372) (xy 359.02901 -180.35597) (xy 359.035858 -180.363368) (xy 360.92892 -182.25643)
			(xy 360.936316 -182.263276) (xy 360.954918 -182.270991) (xy 360.964988 -182.271416) (xy 367.265204 -182.271416)
			(xy 367.27521 -182.270915) (xy 367.293699 -182.263258) (xy 367.307851 -182.249109) (xy 367.315513 -182.230622)
			(xy 367.316004 -182.220616) (xy 367.316004 -179.372768) (xy 367.316555 -179.342796) (xy 367.325869 -179.283583)
			(xy 367.344341 -179.226558) (xy 367.371515 -179.17313) (xy 367.406721 -179.124616) (xy 367.42751 -179.10302)
			(xy 367.730278 -178.800506) (xy 367.737105 -178.793096) (xy 367.744833 -178.774504) (xy 367.745264 -178.764438)
			(xy 367.745264 -177.070512) (xy 367.744842 -177.060442) (xy 367.73712 -177.041844) (xy 367.730278 -177.034444)
			(xy 367.72723 -177.03165) (xy 367.706471 -177.01003) (xy 367.671284 -176.961511) (xy 367.644116 -176.908087)
			(xy 367.625635 -176.851072) (xy 367.616295 -176.79187) (xy 367.615724 -176.761902) (xy 367.616234 -176.733992)
			(xy 367.624367 -176.678768) (xy 367.640459 -176.625318) (xy 367.664168 -176.574783) (xy 367.694986 -176.528241)
			(xy 367.71326 -176.50714) (xy 367.71961 -176.500028) (xy 367.726214 -176.482756) (xy 367.726214 -176.395888)
			(xy 367.71961 -176.378616) (xy 367.71326 -176.371504) (xy 367.694945 -176.35039) (xy 367.664037 -176.303821)
			(xy 367.640257 -176.253239) (xy 367.624116 -176.199728) (xy 367.615959 -176.144434) (xy 367.61547 -176.116488)
			(xy 367.615956 -176.089237) (xy 367.623712 -176.035289) (xy 367.639067 -175.982994) (xy 367.661709 -175.933417)
			(xy 367.691175 -175.887567) (xy 367.726866 -175.846376) (xy 367.768057 -175.810685) (xy 367.813907 -175.781219)
			(xy 367.863484 -175.758577) (xy 367.915779 -175.743222) (xy 367.969727 -175.735466) (xy 368.024229 -175.735466)
			(xy 368.078177 -175.743222) (xy 368.130472 -175.758577) (xy 368.180049 -175.781219) (xy 368.225899 -175.810685)
			(xy 368.26709 -175.846376) (xy 368.302781 -175.887567) (xy 368.332247 -175.933417) (xy 368.354889 -175.982994)
			(xy 368.370244 -176.035289) (xy 368.378 -176.089237) (xy 368.378486 -176.116488) (xy 368.377897 -176.146611)
			(xy 368.368419 -176.206106) (xy 368.349712 -176.263373) (xy 368.32224 -176.31699) (xy 368.286687 -176.365626)
			(xy 368.26571 -176.387252) (xy 368.2589 -176.394676) (xy 368.251162 -176.413257) (xy 368.250724 -176.42332)
			(xy 368.250724 -176.455324) (xy 368.251131 -176.465395) (xy 368.258864 -176.483993) (xy 368.26571 -176.491392)
			(xy 368.266726 -176.492154) (xy 368.396266 -176.621694) (xy 368.417046 -176.643296) (xy 368.45223 -176.69182)
			(xy 368.479394 -176.745248) (xy 368.49787 -176.802267) (xy 368.507204 -176.861473) (xy 368.507772 -176.891442)
			(xy 368.507772 -178.943508) (xy 368.507276 -178.973482) (xy 368.497949 -179.032698) (xy 368.479465 -179.089724)
			(xy 368.452278 -179.143151) (xy 368.41706 -179.191662) (xy 368.396266 -179.213256) (xy 368.377351 -179.232155)
			(xy 368.583129 -179.232155) (xy 368.583129 -179.177645) (xy 368.590887 -179.123689) (xy 368.606244 -179.071387)
			(xy 368.628889 -179.021803) (xy 368.65836 -178.975946) (xy 368.694057 -178.93475) (xy 368.735254 -178.899054)
			(xy 368.781112 -178.869584) (xy 368.830696 -178.846941) (xy 368.882999 -178.831585) (xy 368.936955 -178.823828)
			(xy 368.96421 -178.823366) (xy 368.975284 -178.823436) (xy 368.997396 -178.824709) (xy 369.008406 -178.825906)
			(xy 369.018312 -178.827176) (xy 369.037108 -178.822096) (xy 369.109244 -178.766978) (xy 369.118896 -178.750468)
			(xy 369.12042 -178.740562) (xy 369.125354 -178.712096) (xy 369.142666 -178.656979) (xy 369.168078 -178.605095)
			(xy 369.201009 -178.557628) (xy 369.24071 -178.515659) (xy 369.263168 -178.497484) (xy 369.271944 -178.489936)
			(xy 369.282117 -178.469166) (xy 369.282726 -178.457606) (xy 369.282726 -178.377342) (xy 369.282157 -178.365773)
			(xy 369.271964 -178.345001) (xy 369.263168 -178.337464) (xy 369.240661 -178.319301) (xy 369.200928 -178.277275)
			(xy 369.167993 -178.229734) (xy 369.142609 -178.177767) (xy 369.125358 -178.122565) (xy 369.116634 -178.065392)
			(xy 369.116102 -178.036474) (xy 369.116588 -178.009223) (xy 369.124344 -177.955275) (xy 369.139699 -177.90298)
			(xy 369.162341 -177.853403) (xy 369.191807 -177.807553) (xy 369.227498 -177.766362) (xy 369.268689 -177.730671)
			(xy 369.314539 -177.701205) (xy 369.364116 -177.678563) (xy 369.416411 -177.663208) (xy 369.470359 -177.655452)
			(xy 369.524861 -177.655452) (xy 369.578809 -177.663208) (xy 369.631104 -177.678563) (xy 369.680681 -177.701205)
			(xy 369.726531 -177.730671) (xy 369.767722 -177.766362) (xy 369.803413 -177.807553) (xy 369.832879 -177.853403)
			(xy 369.855521 -177.90298) (xy 369.870876 -177.955275) (xy 369.878632 -178.009223) (xy 369.879118 -178.036474)
			(xy 369.878612 -178.065392) (xy 369.869885 -178.122565) (xy 369.852627 -178.177765) (xy 369.827233 -178.229728)
			(xy 369.794286 -178.277261) (xy 369.75454 -178.319276) (xy 369.732052 -178.337464) (xy 369.723303 -178.345037)
			(xy 369.713114 -178.365788) (xy 369.712494 -178.377342) (xy 369.712494 -178.457606) (xy 369.713063 -178.469174)
			(xy 369.723259 -178.489945) (xy 369.732052 -178.497484) (xy 369.75586 -178.516753) (xy 369.797577 -178.561593)
			(xy 369.831578 -178.612534) (xy 369.856986 -178.66826) (xy 369.865656 -178.697636) (xy 369.867942 -178.70678)
			(xy 369.879372 -178.72202) (xy 369.953286 -178.768756) (xy 369.971828 -178.772566) (xy 369.981226 -178.770788)
			(xy 369.997726 -178.76805) (xy 370.031049 -178.765125) (xy 370.047774 -178.764946) (xy 370.075022 -178.765502)
			(xy 370.128965 -178.773254) (xy 370.181256 -178.788604) (xy 370.23083 -178.811238) (xy 370.276678 -178.840698)
			(xy 370.317867 -178.876382) (xy 370.353559 -178.917564) (xy 370.383027 -178.963407) (xy 370.405671 -179.012977)
			(xy 370.421031 -179.065264) (xy 370.428793 -179.119206) (xy 370.429282 -179.146454) (xy 370.428791 -179.174028)
			(xy 370.420844 -179.2286) (xy 370.405125 -179.281459) (xy 370.38196 -179.331506) (xy 370.351831 -179.377696)
			(xy 370.315367 -179.419068) (xy 370.294662 -179.437284) (xy 370.286549 -179.444891) (xy 370.277193 -179.465039)
			(xy 370.276628 -179.476146) (xy 370.276628 -179.553362) (xy 370.277193 -179.564472) (xy 370.286533 -179.584632)
			(xy 370.294662 -179.592224) (xy 370.31538 -179.610428) (xy 370.351852 -179.651797) (xy 370.381984 -179.697988)
			(xy 370.405149 -179.748038) (xy 370.420863 -179.800902) (xy 370.428799 -179.855479) (xy 370.428833 -179.8574)
			(xy 375.01779 -179.8574) (xy 375.021861 -179.801778) (xy 375.033987 -179.747341) (xy 375.05391 -179.69525)
			(xy 375.081206 -179.646615) (xy 375.115292 -179.602472) (xy 375.155441 -179.563763) (xy 375.200799 -179.531312)
			(xy 375.250399 -179.505811) (xy 375.303183 -179.487804) (xy 375.358026 -179.477674) (xy 375.41376 -179.475637)
			(xy 375.469197 -179.481737) (xy 375.523154 -179.495843) (xy 375.574483 -179.517655) (xy 375.622089 -179.546709)
			(xy 375.664957 -179.582384) (xy 375.702174 -179.623921) (xy 375.732947 -179.670434) (xy 375.756619 -179.720931)
			(xy 375.772687 -179.774338) (xy 375.780807 -179.829514) (xy 375.781316 -179.8574) (xy 375.780807 -179.885286)
			(xy 375.772687 -179.940462) (xy 375.756619 -179.993869) (xy 375.732947 -180.044366) (xy 375.702174 -180.090879)
			(xy 375.664957 -180.132416) (xy 375.622089 -180.168091) (xy 375.574483 -180.197145) (xy 375.523154 -180.218957)
			(xy 375.469197 -180.233063) (xy 375.41376 -180.239163) (xy 375.358026 -180.237126) (xy 375.303183 -180.226996)
			(xy 375.250399 -180.208989) (xy 375.200799 -180.183488) (xy 375.155441 -180.151037) (xy 375.115292 -180.112328)
			(xy 375.081206 -180.068185) (xy 375.05391 -180.01955) (xy 375.033987 -179.967459) (xy 375.021861 -179.913022)
			(xy 375.01779 -179.8574) (xy 370.428833 -179.8574) (xy 370.429282 -179.883054) (xy 370.428802 -179.910307)
			(xy 370.42105 -179.964259) (xy 370.405699 -180.016558) (xy 370.38306 -180.066139) (xy 370.353594 -180.111994)
			(xy 370.317902 -180.153188) (xy 370.27671 -180.188882) (xy 370.230857 -180.21835) (xy 370.181276 -180.240992)
			(xy 370.128978 -180.256346) (xy 370.075027 -180.2641) (xy 370.047774 -180.264562) (xy 370.013484 -180.263038)
			(xy 370.003324 -180.262022) (xy 369.98402 -180.268118) (xy 369.913408 -180.3273) (xy 369.90401 -180.345334)
			(xy 369.902994 -180.355494) (xy 369.900102 -180.383674) (xy 369.88692 -180.438769) (xy 369.865734 -180.491308)
			(xy 369.837009 -180.540135) (xy 369.801378 -180.584175) (xy 369.759624 -180.622461) (xy 369.712666 -180.654149)
			(xy 369.661538 -180.678543) (xy 369.607363 -180.695105) (xy 369.551335 -180.703471) (xy 369.52301 -180.703982)
			(xy 369.495756 -180.703535) (xy 369.441803 -180.695779) (xy 369.389504 -180.680423) (xy 369.339922 -180.65778)
			(xy 369.294067 -180.62831) (xy 369.252874 -180.592615) (xy 369.21718 -180.55142) (xy 369.187713 -180.505564)
			(xy 369.165071 -180.455981) (xy 369.149718 -180.403681) (xy 369.141964 -180.349728) (xy 369.141502 -180.322474)
			(xy 369.141961 -180.29461) (xy 369.150067 -180.239476) (xy 369.166104 -180.186106) (xy 369.189729 -180.135635)
			(xy 369.220443 -180.089136) (xy 369.25759 -180.047596) (xy 369.278662 -180.029358) (xy 369.287806 -180.021738)
			(xy 369.297458 -180.000656) (xy 369.293902 -179.89677) (xy 369.28298 -179.876196) (xy 369.273328 -179.869084)
			(xy 369.252417 -179.853361) (xy 369.214661 -179.817144) (xy 369.182219 -179.7761) (xy 369.155703 -179.730999)
			(xy 369.135611 -179.682693) (xy 369.128548 -179.657502) (xy 369.126262 -179.648612) (xy 369.115594 -179.633372)
			(xy 369.043712 -179.58562) (xy 369.025678 -179.581556) (xy 369.016534 -179.582826) (xy 369.003518 -179.5845)
			(xy 368.977333 -179.586277) (xy 368.96421 -179.586382) (xy 368.936955 -179.585972) (xy 368.882999 -179.578215)
			(xy 368.830696 -179.562859) (xy 368.781112 -179.540216) (xy 368.735254 -179.510746) (xy 368.694057 -179.47505)
			(xy 368.65836 -179.433854) (xy 368.628889 -179.387997) (xy 368.606244 -179.338413) (xy 368.590887 -179.286111)
			(xy 368.583129 -179.232155) (xy 368.377351 -179.232155) (xy 368.093498 -179.51577) (xy 368.086678 -179.523186)
			(xy 368.078947 -179.541773) (xy 368.078512 -179.551838) (xy 368.078512 -182.141876) (xy 370.14785 -182.141876)
			(xy 370.148351 -182.114302) (xy 370.156294 -182.05973) (xy 370.17201 -182.00687) (xy 370.195174 -181.956824)
			(xy 370.225301 -181.910634) (xy 370.261765 -181.869262) (xy 370.28247 -181.851046) (xy 370.290574 -181.843431)
			(xy 370.299934 -181.823289) (xy 370.300504 -181.812184) (xy 370.300504 -181.734968) (xy 370.299968 -181.723854)
			(xy 370.290607 -181.703696) (xy 370.28247 -181.696106) (xy 370.261753 -181.677902) (xy 370.225284 -181.636531)
			(xy 370.195153 -181.590339) (xy 370.171989 -181.54029) (xy 370.156274 -181.487427) (xy 370.148335 -181.432851)
			(xy 370.14785 -181.405276) (xy 370.148454 -181.37583) (xy 370.157513 -181.317638) (xy 370.175399 -181.261528)
			(xy 370.201686 -181.208827) (xy 370.235752 -181.160788) (xy 370.276789 -181.118547) (xy 370.323824 -181.083106)
			(xy 370.349526 -181.068726) (xy 370.357908 -181.064408) (xy 370.3701 -181.050438) (xy 370.399818 -180.968904)
			(xy 370.399564 -180.950362) (xy 370.396008 -180.941726) (xy 370.387638 -180.919707) (xy 370.375885 -180.87409)
			(xy 370.369955 -180.827357) (xy 370.369592 -180.803804) (xy 370.370038 -180.777186) (xy 370.377614 -180.724491)
			(xy 370.392612 -180.673411) (xy 370.414727 -180.624986) (xy 370.443509 -180.580201) (xy 370.478372 -180.539967)
			(xy 370.518605 -180.505105) (xy 370.563391 -180.476324) (xy 370.611817 -180.45421) (xy 370.662897 -180.439213)
			(xy 370.715592 -180.431637) (xy 370.74221 -180.431186) (xy 370.768632 -180.431641) (xy 370.820947 -180.439092)
			(xy 370.871686 -180.453858) (xy 370.91983 -180.475642) (xy 370.964415 -180.504008) (xy 370.98478 -180.520848)
			(xy 370.991638 -180.526944) (xy 371.008656 -180.53304) (xy 371.092984 -180.53304) (xy 371.110002 -180.526944)
			(xy 371.11686 -180.520848) (xy 371.137226 -180.504009) (xy 371.181812 -180.475644) (xy 371.229956 -180.453857)
			(xy 371.280693 -180.439086) (xy 371.333008 -180.431626) (xy 371.385852 -180.431626) (xy 371.438167 -180.439086)
			(xy 371.488904 -180.453857) (xy 371.537048 -180.475644) (xy 371.581634 -180.504009) (xy 371.602 -180.520848)
			(xy 371.608858 -180.526944) (xy 371.625876 -180.53304) (xy 371.710204 -180.53304) (xy 371.727222 -180.526944)
			(xy 371.73408 -180.520848) (xy 371.754459 -180.504027) (xy 371.799044 -180.475668) (xy 371.847186 -180.453884)
			(xy 371.897919 -180.439113) (xy 371.95023 -180.431649) (xy 371.97665 -180.431186) (xy 372.00454 -180.431669)
			(xy 372.059696 -180.439976) (xy 372.112999 -180.456411) (xy 372.163256 -180.480608) (xy 372.209346 -180.512026)
			(xy 372.250237 -180.549962) (xy 372.285017 -180.59357) (xy 372.312909 -180.641874) (xy 372.327118 -180.678074)
			(xy 376.98553 -180.678074) (xy 376.986036 -180.650501) (xy 376.993979 -180.595929) (xy 377.009695 -180.54307)
			(xy 377.032858 -180.493023) (xy 377.062984 -180.446833) (xy 377.099445 -180.40546) (xy 377.12015 -180.387244)
			(xy 377.128252 -180.379627) (xy 377.137613 -180.359486) (xy 377.138184 -180.348382) (xy 377.138184 -180.271166)
			(xy 377.137656 -180.260051) (xy 377.12829 -180.239893) (xy 377.12015 -180.232304) (xy 377.099416 -180.214118)
			(xy 377.062948 -180.172745) (xy 377.032818 -180.126551) (xy 377.009654 -180.0765) (xy 376.993938 -180.023636)
			(xy 376.985999 -179.969059) (xy 376.986001 -179.913908) (xy 376.993945 -179.859331) (xy 377.009666 -179.806468)
			(xy 377.032834 -179.756419) (xy 377.062969 -179.710229) (xy 377.09944 -179.668858) (xy 377.12015 -179.650644)
			(xy 377.128252 -179.643027) (xy 377.137613 -179.622886) (xy 377.138184 -179.611782) (xy 377.138184 -179.534566)
			(xy 377.137656 -179.523451) (xy 377.12829 -179.503293) (xy 377.12015 -179.495704) (xy 377.099428 -179.477505)
			(xy 377.06296 -179.436133) (xy 377.032831 -179.38994) (xy 377.009667 -179.33989) (xy 376.993953 -179.287025)
			(xy 376.986015 -179.232449) (xy 376.98553 -179.204874) (xy 376.985931 -179.177619) (xy 376.993692 -179.123664)
			(xy 377.009054 -179.071362) (xy 377.031702 -179.021779) (xy 377.061176 -178.975924) (xy 377.096876 -178.934731)
			(xy 377.138076 -178.899038) (xy 377.183936 -178.869571) (xy 377.233522 -178.846931) (xy 377.285826 -178.831579)
			(xy 377.339783 -178.823826) (xy 377.367038 -178.823366) (xy 377.394893 -178.82388) (xy 377.450008 -178.832008)
			(xy 377.503357 -178.848057) (xy 377.553809 -178.871686) (xy 377.600292 -178.902394) (xy 377.641821 -178.93953)
			(xy 377.677514 -178.982305) (xy 377.706615 -179.029811) (xy 377.728505 -179.081041) (xy 377.7361 -179.107846)
			(xy 377.738386 -179.116736) (xy 377.749054 -179.131976) (xy 377.820936 -179.179728) (xy 377.83897 -179.183792)
			(xy 377.848114 -179.182522) (xy 377.861131 -179.180854) (xy 377.887315 -179.179073) (xy 377.900438 -179.178966)
			(xy 377.914587 -179.179056) (xy 377.94281 -179.181093) (xy 377.956826 -179.18303) (xy 377.966986 -179.184554)
			(xy 377.986544 -179.179728) (xy 378.060966 -179.123848) (xy 378.071126 -179.106322) (xy 378.072396 -179.096162)
			(xy 378.076477 -179.069007) (xy 378.09145 -179.016176) (xy 378.113841 -178.966037) (xy 378.143189 -178.919625)
			(xy 378.178888 -178.877901) (xy 378.220198 -178.841724) (xy 378.266268 -178.811843) (xy 378.316146 -178.788875)
			(xy 378.368801 -178.773295) (xy 378.423146 -178.765423) (xy 378.450602 -178.764946) (xy 378.477851 -178.765476)
			(xy 378.531795 -178.773231) (xy 378.584086 -178.788584) (xy 378.63366 -178.811222) (xy 378.679508 -178.840685)
			(xy 378.720697 -178.876371) (xy 378.756389 -178.917556) (xy 378.785856 -178.963401) (xy 378.8085 -179.012973)
			(xy 378.823859 -179.065262) (xy 378.831621 -179.119205) (xy 378.83211 -179.146454) (xy 378.831609 -179.174027)
			(xy 378.823663 -179.228598) (xy 378.807945 -179.281457) (xy 378.784782 -179.331503) (xy 378.754655 -179.377694)
			(xy 378.718194 -179.419067) (xy 378.69749 -179.437284) (xy 378.689382 -179.444896) (xy 378.680022 -179.46504)
			(xy 378.679456 -179.476146) (xy 378.679456 -179.553362) (xy 378.680011 -179.564474) (xy 378.689357 -179.584634)
			(xy 378.69749 -179.592224) (xy 378.718214 -179.610421) (xy 378.754684 -179.651793) (xy 378.784814 -179.697985)
			(xy 378.807978 -179.748036) (xy 378.823692 -179.800901) (xy 378.831627 -179.855478) (xy 378.831661 -179.8574)
			(xy 383.420618 -179.8574) (xy 383.424689 -179.801778) (xy 383.436815 -179.747341) (xy 383.456738 -179.69525)
			(xy 383.484034 -179.646615) (xy 383.51812 -179.602472) (xy 383.558269 -179.563763) (xy 383.603627 -179.531312)
			(xy 383.653227 -179.505811) (xy 383.706011 -179.487804) (xy 383.760854 -179.477674) (xy 383.816588 -179.475637)
			(xy 383.872025 -179.481737) (xy 383.925982 -179.495843) (xy 383.977311 -179.517655) (xy 384.024917 -179.546709)
			(xy 384.067785 -179.582384) (xy 384.105002 -179.623921) (xy 384.135775 -179.670434) (xy 384.159447 -179.720931)
			(xy 384.175515 -179.774338) (xy 384.183635 -179.829514) (xy 384.184144 -179.8574) (xy 384.183635 -179.885286)
			(xy 384.175515 -179.940462) (xy 384.159447 -179.993869) (xy 384.135775 -180.044366) (xy 384.105002 -180.090879)
			(xy 384.067785 -180.132416) (xy 384.024917 -180.168091) (xy 383.977311 -180.197145) (xy 383.925982 -180.218957)
			(xy 383.872025 -180.233063) (xy 383.816588 -180.239163) (xy 383.760854 -180.237126) (xy 383.706011 -180.226996)
			(xy 383.653227 -180.208989) (xy 383.603627 -180.183488) (xy 383.558269 -180.151037) (xy 383.51812 -180.112328)
			(xy 383.484034 -180.068185) (xy 383.456738 -180.01955) (xy 383.436815 -179.967459) (xy 383.424689 -179.913022)
			(xy 383.420618 -179.8574) (xy 378.831661 -179.8574) (xy 378.83211 -179.883054) (xy 378.831602 -179.910306)
			(xy 378.823851 -179.964255) (xy 378.808501 -180.016552) (xy 378.785864 -180.066132) (xy 378.756401 -180.111985)
			(xy 378.720712 -180.153178) (xy 378.679523 -180.188872) (xy 378.633674 -180.218341) (xy 378.584097 -180.240984)
			(xy 378.531802 -180.256341) (xy 378.477854 -180.264098) (xy 378.450602 -180.264562) (xy 378.416312 -180.263038)
			(xy 378.406152 -180.262022) (xy 378.386848 -180.268118) (xy 378.316236 -180.3273) (xy 378.306838 -180.345334)
			(xy 378.305822 -180.355494) (xy 378.302902 -180.383671) (xy 378.289722 -180.438763) (xy 378.268538 -180.4913)
			(xy 378.239816 -180.540125) (xy 378.204187 -180.584165) (xy 378.162437 -180.622451) (xy 378.115483 -180.65414)
			(xy 378.064358 -180.678535) (xy 378.010187 -180.6951) (xy 377.954162 -180.703469) (xy 377.925838 -180.703982)
			(xy 377.907819 -180.703764) (xy 377.871944 -180.700328) (xy 377.85421 -180.697124) (xy 377.844812 -180.695346)
			(xy 377.825762 -180.699156) (xy 377.750578 -180.746908) (xy 377.739148 -180.762656) (xy 377.736862 -180.772054)
			(xy 377.72949 -180.799106) (xy 377.707858 -180.850833) (xy 377.67889 -180.898839) (xy 377.643212 -180.942091)
			(xy 377.601589 -180.979658) (xy 377.554918 -181.010731) (xy 377.504204 -181.034642) (xy 377.450537 -181.050876)
			(xy 377.395072 -181.059085) (xy 377.367038 -181.059582) (xy 377.339785 -181.059109) (xy 377.285833 -181.051357)
			(xy 377.233534 -181.036004) (xy 377.183952 -181.013364) (xy 377.138097 -180.983898) (xy 377.096904 -180.948205)
			(xy 377.061209 -180.907012) (xy 377.031741 -180.861159) (xy 377.0091 -180.811578) (xy 376.993746 -180.759279)
			(xy 376.985992 -180.705327) (xy 376.98553 -180.678074) (xy 372.327118 -180.678074) (xy 372.333289 -180.693797)
			(xy 372.345702 -180.748177) (xy 372.349871 -180.8038) (xy 372.345702 -180.859423) (xy 372.333289 -180.913803)
			(xy 372.312909 -180.965726) (xy 372.285017 -181.01403) (xy 372.250237 -181.057638) (xy 372.209346 -181.095574)
			(xy 372.163256 -181.126992) (xy 372.112999 -181.151189) (xy 372.059696 -181.167624) (xy 372.00454 -181.175931)
			(xy 371.97665 -181.176422) (xy 371.950227 -181.175988) (xy 371.897911 -181.168532) (xy 371.847172 -181.153761)
			(xy 371.799029 -181.131972) (xy 371.754445 -181.103602) (xy 371.73408 -181.08676) (xy 371.727222 -181.080664)
			(xy 371.710204 -181.074568) (xy 371.625876 -181.074568) (xy 371.608858 -181.080664) (xy 371.602 -181.08676)
			(xy 371.581634 -181.103599) (xy 371.537048 -181.131964) (xy 371.488904 -181.153751) (xy 371.438167 -181.168522)
			(xy 371.385852 -181.175982) (xy 371.333008 -181.175982) (xy 371.280693 -181.168522) (xy 371.229956 -181.153751)
			(xy 371.181812 -181.131964) (xy 371.137226 -181.103599) (xy 371.11686 -181.08676) (xy 371.110002 -181.080664)
			(xy 371.092984 -181.074568) (xy 371.008656 -181.074568) (xy 370.991638 -181.080664) (xy 370.98478 -181.08676)
			(xy 370.970662 -181.098517) (xy 370.94051 -181.119513) (xy 370.924582 -181.12867) (xy 370.916454 -181.133242)
			(xy 370.904516 -181.147466) (xy 370.876576 -181.229508) (xy 370.877084 -181.24805) (xy 370.880894 -181.25694)
			(xy 370.89036 -181.280513) (xy 370.903704 -181.329528) (xy 370.910443 -181.379877) (xy 370.910866 -181.405276)
			(xy 370.910396 -181.432851) (xy 370.902446 -181.487424) (xy 370.886722 -181.540284) (xy 370.863553 -181.59033)
			(xy 370.833421 -181.63652) (xy 370.796953 -181.677891) (xy 370.776246 -181.696106) (xy 370.768121 -181.703702)
			(xy 370.758773 -181.723859) (xy 370.758212 -181.734968) (xy 370.758212 -181.812184) (xy 370.758769 -181.823295)
			(xy 370.768115 -181.843454) (xy 370.776246 -181.851046) (xy 370.796943 -181.869272) (xy 370.833413 -181.910639)
			(xy 370.863546 -181.956826) (xy 370.886713 -182.006871) (xy 370.902433 -182.05973) (xy 370.910378 -182.114302)
			(xy 370.910866 -182.141876) (xy 370.91038 -182.169127) (xy 370.902624 -182.223075) (xy 370.887269 -182.27537)
			(xy 370.864627 -182.324947) (xy 370.835161 -182.370797) (xy 370.79947 -182.411988) (xy 370.758279 -182.447679)
			(xy 370.712429 -182.477145) (xy 370.662852 -182.499787) (xy 370.610557 -182.515142) (xy 370.556609 -182.522898)
			(xy 370.502107 -182.522898) (xy 370.448159 -182.515142) (xy 370.395864 -182.499787) (xy 370.346287 -182.477145)
			(xy 370.300437 -182.447679) (xy 370.259246 -182.411988) (xy 370.223555 -182.370797) (xy 370.194089 -182.324947)
			(xy 370.171447 -182.27537) (xy 370.156092 -182.223075) (xy 370.148336 -182.169127) (xy 370.14785 -182.141876)
			(xy 368.078512 -182.141876) (xy 368.078512 -182.4736) (xy 368.078934 -182.48367) (xy 368.086657 -182.502268)
			(xy 368.093498 -182.509668) (xy 368.266726 -182.682642) (xy 368.287474 -182.704273) (xy 368.322664 -182.752788)
			(xy 368.349834 -182.806209) (xy 368.368318 -182.863222) (xy 368.37766 -182.922423) (xy 368.378232 -182.95239)
			(xy 368.378232 -186.33186) (xy 368.37867 -186.341928) (xy 368.386381 -186.360526) (xy 368.393218 -186.367928)
			(xy 369.57 -187.54471) (xy 369.577405 -187.551544) (xy 369.596 -187.559267) (xy 369.606068 -187.559696)
			(xy 376.227086 -187.559696) (xy 376.237158 -187.559291) (xy 376.255758 -187.551559) (xy 376.263154 -187.54471)
			(xy 376.478038 -187.329826) (xy 376.484864 -187.322416) (xy 376.492591 -187.303824) (xy 376.493024 -187.293758)
			(xy 376.493024 -182.429658) (xy 376.492641 -182.419584) (xy 376.484893 -182.400985) (xy 376.478038 -182.39359)
			(xy 376.088402 -182.004208) (xy 376.067618 -181.982611) (xy 376.032436 -181.934085) (xy 376.005273 -181.880655)
			(xy 375.986798 -181.823636) (xy 375.977464 -181.764429) (xy 375.976896 -181.73446) (xy 375.977363 -181.706548)
			(xy 375.985504 -181.651321) (xy 376.001605 -181.59787) (xy 376.025323 -181.547336) (xy 376.056153 -181.500797)
			(xy 376.074432 -181.479698) (xy 376.080782 -181.472586) (xy 376.087386 -181.455314) (xy 376.087386 -181.368446)
			(xy 376.080782 -181.351174) (xy 376.074432 -181.344062) (xy 376.056093 -181.322968) (xy 376.025189 -181.276393)
			(xy 376.001414 -181.225806) (xy 375.985279 -181.172291) (xy 375.977128 -181.116994) (xy 375.976642 -181.089046)
			(xy 375.977128 -181.061795) (xy 375.984884 -181.007847) (xy 376.000239 -180.955552) (xy 376.022881 -180.905975)
			(xy 376.052347 -180.860125) (xy 376.088038 -180.818934) (xy 376.129229 -180.783243) (xy 376.175079 -180.753777)
			(xy 376.224656 -180.731135) (xy 376.276951 -180.71578) (xy 376.330899 -180.708024) (xy 376.385401 -180.708024)
			(xy 376.439349 -180.71578) (xy 376.491644 -180.731135) (xy 376.541221 -180.753777) (xy 376.587071 -180.783243)
			(xy 376.628262 -180.818934) (xy 376.663953 -180.860125) (xy 376.693419 -180.905975) (xy 376.716061 -180.955552)
			(xy 376.731416 -181.007847) (xy 376.739172 -181.061795) (xy 376.739658 -181.089046) (xy 376.739051 -181.119168)
			(xy 376.729578 -181.178663) (xy 376.710876 -181.23593) (xy 376.683408 -181.289548) (xy 376.647857 -181.338184)
			(xy 376.626882 -181.35981) (xy 376.620043 -181.367211) (xy 376.612323 -181.38581) (xy 376.611896 -181.395878)
			(xy 376.611896 -181.427882) (xy 376.612305 -181.437954) (xy 376.620034 -181.456553) (xy 376.626882 -181.46395)
			(xy 376.627898 -181.464712) (xy 377.144026 -181.98084) (xy 377.164773 -182.002472) (xy 377.199963 -182.050987)
			(xy 377.227134 -182.104408) (xy 377.245618 -182.16142) (xy 377.25496 -182.220621) (xy 377.255154 -182.230776)
			(xy 378.653548 -182.230776) (xy 378.654049 -182.203203) (xy 378.661992 -182.148631) (xy 378.677709 -182.095771)
			(xy 378.700872 -182.045724) (xy 378.730999 -181.999534) (xy 378.767463 -181.958162) (xy 378.788168 -181.939946)
			(xy 378.796272 -181.932331) (xy 378.805632 -181.912189) (xy 378.806202 -181.901084) (xy 378.806202 -181.823868)
			(xy 378.805667 -181.812754) (xy 378.796305 -181.792596) (xy 378.788168 -181.785006) (xy 378.76745 -181.766802)
			(xy 378.730982 -181.725431) (xy 378.700851 -181.679239) (xy 378.677687 -181.62919) (xy 378.661972 -181.576327)
			(xy 378.654033 -181.521751) (xy 378.653548 -181.494176) (xy 378.654063 -181.465222) (xy 378.662824 -181.40798)
			(xy 378.680128 -181.352717) (xy 378.705578 -181.3007) (xy 378.738589 -181.253122) (xy 378.778405 -181.211074)
			(xy 378.824113 -181.175519) (xy 378.849128 -181.160928) (xy 378.859542 -181.15534) (xy 378.87275 -181.136544)
			(xy 378.889514 -181.035198) (xy 378.883164 -181.0131) (xy 378.87529 -181.004464) (xy 378.857463 -180.983825)
			(xy 378.827355 -180.938354) (xy 378.804192 -180.888983) (xy 378.788467 -180.836764) (xy 378.780517 -180.782811)
			(xy 378.78004 -180.755544) (xy 378.780575 -180.728929) (xy 378.788144 -180.676241) (xy 378.803135 -180.625165)
			(xy 378.825241 -180.576743) (xy 378.854014 -180.531961) (xy 378.888867 -180.491728) (xy 378.929092 -180.456866)
			(xy 378.973868 -180.428083) (xy 379.022285 -180.405965) (xy 379.073356 -180.390962) (xy 379.126043 -180.383381)
			(xy 379.152658 -180.382926) (xy 379.17908 -180.383368) (xy 379.231396 -180.390824) (xy 379.282134 -180.405594)
			(xy 379.330278 -180.427381) (xy 379.374862 -180.455748) (xy 379.395228 -180.472588) (xy 379.402086 -180.478684)
			(xy 379.419104 -180.48478) (xy 379.503432 -180.48478) (xy 379.52045 -180.478684) (xy 379.527308 -180.472588)
			(xy 379.547674 -180.455749) (xy 379.59226 -180.427384) (xy 379.640404 -180.405597) (xy 379.691141 -180.390826)
			(xy 379.743456 -180.383366) (xy 379.7963 -180.383366) (xy 379.848615 -180.390826) (xy 379.899352 -180.405597)
			(xy 379.947496 -180.427384) (xy 379.992082 -180.455749) (xy 380.012448 -180.472588) (xy 380.019306 -180.478684)
			(xy 380.036324 -180.48478) (xy 380.120652 -180.48478) (xy 380.13767 -180.478684) (xy 380.144528 -180.472588)
			(xy 380.164882 -180.455735) (xy 380.209475 -180.427383) (xy 380.257623 -180.405606) (xy 380.308362 -180.390842)
			(xy 380.360676 -180.383385) (xy 380.387098 -180.382926) (xy 380.414988 -180.383333) (xy 380.470145 -180.391646)
			(xy 380.523448 -180.408088) (xy 380.573704 -180.43229) (xy 380.619792 -180.463712) (xy 380.660682 -180.501652)
			(xy 380.695461 -180.545262) (xy 380.723351 -180.59357) (xy 380.74373 -180.645494) (xy 380.751166 -180.678074)
			(xy 385.31673 -180.678074) (xy 385.317236 -180.650501) (xy 385.325179 -180.595929) (xy 385.340895 -180.54307)
			(xy 385.364058 -180.493023) (xy 385.394184 -180.446833) (xy 385.430645 -180.40546) (xy 385.45135 -180.387244)
			(xy 385.459452 -180.379627) (xy 385.468813 -180.359486) (xy 385.469384 -180.348382) (xy 385.469384 -180.271166)
			(xy 385.468856 -180.260051) (xy 385.45949 -180.239893) (xy 385.45135 -180.232304) (xy 385.430616 -180.214118)
			(xy 385.394148 -180.172745) (xy 385.364018 -180.126551) (xy 385.340854 -180.0765) (xy 385.325138 -180.023636)
			(xy 385.317199 -179.969059) (xy 385.317201 -179.913908) (xy 385.325145 -179.859331) (xy 385.340866 -179.806468)
			(xy 385.364034 -179.756419) (xy 385.394169 -179.710229) (xy 385.43064 -179.668858) (xy 385.45135 -179.650644)
			(xy 385.459452 -179.643027) (xy 385.468813 -179.622886) (xy 385.469384 -179.611782) (xy 385.469384 -179.534566)
			(xy 385.468856 -179.523451) (xy 385.45949 -179.503293) (xy 385.45135 -179.495704) (xy 385.430628 -179.477505)
			(xy 385.39416 -179.436133) (xy 385.364031 -179.38994) (xy 385.340867 -179.33989) (xy 385.325153 -179.287025)
			(xy 385.317215 -179.232449) (xy 385.31673 -179.204874) (xy 385.317131 -179.177619) (xy 385.324892 -179.123664)
			(xy 385.340254 -179.071362) (xy 385.362902 -179.021779) (xy 385.392376 -178.975924) (xy 385.428076 -178.934731)
			(xy 385.469276 -178.899038) (xy 385.515136 -178.869571) (xy 385.564722 -178.846931) (xy 385.617026 -178.831579)
			(xy 385.670983 -178.823826) (xy 385.698238 -178.823366) (xy 385.726093 -178.82388) (xy 385.781208 -178.832008)
			(xy 385.834557 -178.848057) (xy 385.885009 -178.871686) (xy 385.931492 -178.902394) (xy 385.973021 -178.93953)
			(xy 386.008714 -178.982305) (xy 386.037815 -179.029811) (xy 386.059705 -179.081041) (xy 386.0673 -179.107846)
			(xy 386.069586 -179.116736) (xy 386.080254 -179.131976) (xy 386.152136 -179.179728) (xy 386.17017 -179.183792)
			(xy 386.179314 -179.182522) (xy 386.192331 -179.180854) (xy 386.218515 -179.179073) (xy 386.231638 -179.178966)
			(xy 386.245787 -179.179056) (xy 386.27401 -179.181093) (xy 386.288026 -179.18303) (xy 386.298186 -179.184554)
			(xy 386.317744 -179.179728) (xy 386.392166 -179.123848) (xy 386.402326 -179.106322) (xy 386.403596 -179.096162)
			(xy 386.407677 -179.069007) (xy 386.42265 -179.016176) (xy 386.445041 -178.966037) (xy 386.474389 -178.919625)
			(xy 386.510088 -178.877901) (xy 386.551398 -178.841724) (xy 386.597468 -178.811843) (xy 386.647346 -178.788875)
			(xy 386.700001 -178.773295) (xy 386.754346 -178.765423) (xy 386.781802 -178.764946) (xy 386.809051 -178.765476)
			(xy 386.862995 -178.773231) (xy 386.915286 -178.788584) (xy 386.96486 -178.811222) (xy 387.010708 -178.840685)
			(xy 387.051897 -178.876371) (xy 387.087589 -178.917556) (xy 387.117056 -178.963401) (xy 387.1397 -179.012973)
			(xy 387.155059 -179.065262) (xy 387.162821 -179.119205) (xy 387.16331 -179.146454) (xy 387.162809 -179.174027)
			(xy 387.154863 -179.228598) (xy 387.139145 -179.281457) (xy 387.115982 -179.331503) (xy 387.085855 -179.377694)
			(xy 387.049394 -179.419067) (xy 387.02869 -179.437284) (xy 387.020582 -179.444896) (xy 387.011222 -179.46504)
			(xy 387.010656 -179.476146) (xy 387.010656 -179.553362) (xy 387.011211 -179.564474) (xy 387.020557 -179.584634)
			(xy 387.02869 -179.592224) (xy 387.049414 -179.610421) (xy 387.085884 -179.651793) (xy 387.116014 -179.697985)
			(xy 387.139178 -179.748036) (xy 387.154892 -179.800901) (xy 387.162827 -179.855478) (xy 387.162861 -179.8574)
			(xy 391.751818 -179.8574) (xy 391.755889 -179.801778) (xy 391.768015 -179.747341) (xy 391.787938 -179.69525)
			(xy 391.815234 -179.646615) (xy 391.84932 -179.602472) (xy 391.889469 -179.563763) (xy 391.934827 -179.531312)
			(xy 391.984427 -179.505811) (xy 392.037211 -179.487804) (xy 392.092054 -179.477674) (xy 392.147788 -179.475637)
			(xy 392.203225 -179.481737) (xy 392.257182 -179.495843) (xy 392.308511 -179.517655) (xy 392.356117 -179.546709)
			(xy 392.398985 -179.582384) (xy 392.436202 -179.623921) (xy 392.466975 -179.670434) (xy 392.490647 -179.720931)
			(xy 392.506715 -179.774338) (xy 392.514835 -179.829514) (xy 392.515344 -179.8574) (xy 392.514835 -179.885286)
			(xy 392.506715 -179.940462) (xy 392.490647 -179.993869) (xy 392.466975 -180.044366) (xy 392.436202 -180.090879)
			(xy 392.398985 -180.132416) (xy 392.356117 -180.168091) (xy 392.308511 -180.197145) (xy 392.257182 -180.218957)
			(xy 392.203225 -180.233063) (xy 392.147788 -180.239163) (xy 392.092054 -180.237126) (xy 392.037211 -180.226996)
			(xy 391.984427 -180.208989) (xy 391.934827 -180.183488) (xy 391.889469 -180.151037) (xy 391.84932 -180.112328)
			(xy 391.815234 -180.068185) (xy 391.787938 -180.01955) (xy 391.768015 -179.967459) (xy 391.755889 -179.913022)
			(xy 391.751818 -179.8574) (xy 387.162861 -179.8574) (xy 387.16331 -179.883054) (xy 387.162802 -179.910306)
			(xy 387.155051 -179.964255) (xy 387.139701 -180.016552) (xy 387.117064 -180.066132) (xy 387.087601 -180.111985)
			(xy 387.051912 -180.153178) (xy 387.010723 -180.188872) (xy 386.964874 -180.218341) (xy 386.915297 -180.240984)
			(xy 386.863002 -180.256341) (xy 386.809054 -180.264098) (xy 386.781802 -180.264562) (xy 386.747512 -180.263038)
			(xy 386.737352 -180.262022) (xy 386.718048 -180.268118) (xy 386.647436 -180.3273) (xy 386.638038 -180.345334)
			(xy 386.637022 -180.355494) (xy 386.634102 -180.383671) (xy 386.620922 -180.438763) (xy 386.599738 -180.4913)
			(xy 386.571016 -180.540125) (xy 386.535387 -180.584165) (xy 386.493637 -180.622451) (xy 386.446683 -180.65414)
			(xy 386.395558 -180.678535) (xy 386.341387 -180.6951) (xy 386.285362 -180.703469) (xy 386.257038 -180.703982)
			(xy 386.239019 -180.703764) (xy 386.203144 -180.700328) (xy 386.18541 -180.697124) (xy 386.176012 -180.695346)
			(xy 386.156962 -180.699156) (xy 386.081778 -180.746908) (xy 386.070348 -180.762656) (xy 386.068062 -180.772054)
			(xy 386.06069 -180.799106) (xy 386.039058 -180.850833) (xy 386.01009 -180.898839) (xy 385.974412 -180.942091)
			(xy 385.932789 -180.979658) (xy 385.886118 -181.010731) (xy 385.835404 -181.034642) (xy 385.781737 -181.050876)
			(xy 385.726272 -181.059085) (xy 385.698238 -181.059582) (xy 385.670985 -181.059109) (xy 385.617033 -181.051357)
			(xy 385.564734 -181.036004) (xy 385.515152 -181.013364) (xy 385.469297 -180.983898) (xy 385.428104 -180.948205)
			(xy 385.392409 -180.907012) (xy 385.362941 -180.861159) (xy 385.3403 -180.811578) (xy 385.324946 -180.759279)
			(xy 385.317192 -180.705327) (xy 385.31673 -180.678074) (xy 380.751166 -180.678074) (xy 380.756142 -180.699876)
			(xy 380.760311 -180.7555) (xy 380.756142 -180.811124) (xy 380.74373 -180.865506) (xy 380.723351 -180.91743)
			(xy 380.695461 -180.965738) (xy 380.660682 -181.009348) (xy 380.619792 -181.047288) (xy 380.573704 -181.07871)
			(xy 380.523448 -181.102912) (xy 380.470145 -181.119354) (xy 380.414988 -181.127667) (xy 380.387098 -181.128162)
			(xy 380.360677 -181.127691) (xy 380.308363 -181.120242) (xy 380.257625 -181.105479) (xy 380.20948 -181.083699)
			(xy 380.164894 -181.055337) (xy 380.144528 -181.0385) (xy 380.13767 -181.032404) (xy 380.120652 -181.026308)
			(xy 380.036324 -181.026308) (xy 380.019306 -181.032404) (xy 380.012448 -181.0385) (xy 379.992082 -181.055339)
			(xy 379.947496 -181.083704) (xy 379.899352 -181.105491) (xy 379.848615 -181.120262) (xy 379.7963 -181.127722)
			(xy 379.743456 -181.127722) (xy 379.691141 -181.120262) (xy 379.640404 -181.105491) (xy 379.59226 -181.083704)
			(xy 379.547674 -181.055339) (xy 379.527308 -181.0385) (xy 379.52045 -181.032404) (xy 379.503432 -181.026308)
			(xy 379.419104 -181.026308) (xy 379.402086 -181.032404) (xy 379.395228 -181.0385) (xy 379.382014 -181.04952)
			(xy 379.353903 -181.069365) (xy 379.339094 -181.078124) (xy 379.328934 -181.08422) (xy 379.31598 -181.103016)
			(xy 379.300486 -181.204616) (xy 379.30709 -181.22646) (xy 379.315218 -181.235096) (xy 379.334155 -181.256385)
			(xy 379.366166 -181.303519) (xy 379.390819 -181.354885) (xy 379.407566 -181.409345) (xy 379.416035 -181.465688)
			(xy 379.416564 -181.494176) (xy 379.416094 -181.521751) (xy 379.408144 -181.576324) (xy 379.392421 -181.629184)
			(xy 379.369252 -181.67923) (xy 379.339119 -181.72542) (xy 379.302651 -181.766791) (xy 379.281944 -181.785006)
			(xy 379.273819 -181.792602) (xy 379.264471 -181.812759) (xy 379.26391 -181.823868) (xy 379.26391 -181.901084)
			(xy 379.264468 -181.912195) (xy 379.273813 -181.932354) (xy 379.281944 -181.939946) (xy 379.302641 -181.958172)
			(xy 379.339111 -181.999539) (xy 379.369243 -182.045726) (xy 379.392411 -182.095771) (xy 379.408131 -182.14863)
			(xy 379.416076 -182.203202) (xy 379.416564 -182.230776) (xy 379.416078 -182.258027) (xy 379.408322 -182.311975)
			(xy 379.392967 -182.36427) (xy 379.370325 -182.413847) (xy 379.340859 -182.459697) (xy 379.305168 -182.500888)
			(xy 379.263977 -182.536579) (xy 379.218127 -182.566045) (xy 379.16855 -182.588687) (xy 379.116255 -182.604042)
			(xy 379.062307 -182.611798) (xy 379.007805 -182.611798) (xy 378.953857 -182.604042) (xy 378.901562 -182.588687)
			(xy 378.851985 -182.566045) (xy 378.806135 -182.536579) (xy 378.764944 -182.500888) (xy 378.729253 -182.459697)
			(xy 378.699787 -182.413847) (xy 378.677145 -182.36427) (xy 378.66179 -182.311975) (xy 378.654034 -182.258027)
			(xy 378.653548 -182.230776) (xy 377.255154 -182.230776) (xy 377.255532 -182.250588) (xy 377.255532 -187.293758)
			(xy 377.255971 -187.303826) (xy 377.263681 -187.322424) (xy 377.270518 -187.329826) (xy 377.485402 -187.54471)
			(xy 377.492806 -187.551545) (xy 377.511402 -187.559267) (xy 377.52147 -187.559696) (xy 384.373628 -187.559696)
			(xy 384.383703 -187.559313) (xy 384.402302 -187.551566) (xy 384.409696 -187.54471) (xy 384.656838 -187.297568)
			(xy 384.66369 -187.290177) (xy 384.671402 -187.271571) (xy 384.671824 -187.2615) (xy 384.671824 -182.20563)
			(xy 384.671403 -182.19556) (xy 384.663682 -182.176961) (xy 384.656838 -182.169562) (xy 384.49123 -182.004208)
			(xy 384.470451 -181.982606) (xy 384.435267 -181.934082) (xy 384.408103 -181.880654) (xy 384.389626 -181.823635)
			(xy 384.380292 -181.764429) (xy 384.379724 -181.73446) (xy 384.380209 -181.706549) (xy 384.388348 -181.651324)
			(xy 384.404446 -181.597873) (xy 384.42816 -181.547339) (xy 384.458984 -181.500799) (xy 384.47726 -181.479698)
			(xy 384.48361 -181.472586) (xy 384.490214 -181.455314) (xy 384.490214 -181.368446) (xy 384.48361 -181.351174)
			(xy 384.47726 -181.344062) (xy 384.458926 -181.322964) (xy 384.42802 -181.276391) (xy 384.404244 -181.225805)
			(xy 384.388107 -181.17229) (xy 384.379956 -181.116993) (xy 384.37947 -181.089046) (xy 384.379956 -181.061795)
			(xy 384.387712 -181.007847) (xy 384.403067 -180.955552) (xy 384.425709 -180.905975) (xy 384.455175 -180.860125)
			(xy 384.490866 -180.818934) (xy 384.532057 -180.783243) (xy 384.577907 -180.753777) (xy 384.627484 -180.731135)
			(xy 384.679779 -180.71578) (xy 384.733727 -180.708024) (xy 384.788229 -180.708024) (xy 384.842177 -180.71578)
			(xy 384.894472 -180.731135) (xy 384.944049 -180.753777) (xy 384.989899 -180.783243) (xy 385.03109 -180.818934)
			(xy 385.066781 -180.860125) (xy 385.096247 -180.905975) (xy 385.118889 -180.955552) (xy 385.134244 -181.007847)
			(xy 385.142 -181.061795) (xy 385.142486 -181.089046) (xy 385.141871 -181.119167) (xy 385.132399 -181.178661)
			(xy 385.113698 -181.235928) (xy 385.086232 -181.289546) (xy 385.050684 -181.338183) (xy 385.02971 -181.35981)
			(xy 385.022874 -181.367214) (xy 385.015152 -181.38581) (xy 385.014724 -181.395878) (xy 385.014724 -181.427882)
			(xy 385.015152 -181.437951) (xy 385.02287 -181.456549) (xy 385.02971 -181.46395) (xy 385.030726 -181.464712)
			(xy 385.322826 -181.756812) (xy 385.343559 -181.778456) (xy 385.378751 -181.826968) (xy 385.405925 -181.880386)
			(xy 385.424412 -181.937395) (xy 385.433758 -181.996594) (xy 385.434332 -182.02656) (xy 385.434332 -182.230776)
			(xy 386.984748 -182.230776) (xy 386.985249 -182.203203) (xy 386.993192 -182.148631) (xy 387.008909 -182.095771)
			(xy 387.032072 -182.045724) (xy 387.062199 -181.999534) (xy 387.098663 -181.958162) (xy 387.119368 -181.939946)
			(xy 387.127472 -181.932331) (xy 387.136832 -181.912189) (xy 387.137402 -181.901084) (xy 387.137402 -181.823868)
			(xy 387.136867 -181.812754) (xy 387.127505 -181.792596) (xy 387.119368 -181.785006) (xy 387.09865 -181.766802)
			(xy 387.062182 -181.725431) (xy 387.032051 -181.679239) (xy 387.008887 -181.62919) (xy 386.993172 -181.576327)
			(xy 386.985233 -181.521751) (xy 386.984748 -181.494176) (xy 386.985263 -181.465222) (xy 386.994024 -181.40798)
			(xy 387.011328 -181.352717) (xy 387.036778 -181.3007) (xy 387.069789 -181.253122) (xy 387.109605 -181.211074)
			(xy 387.155313 -181.175519) (xy 387.180328 -181.160928) (xy 387.190742 -181.15534) (xy 387.20395 -181.136544)
			(xy 387.220714 -181.035198) (xy 387.214364 -181.0131) (xy 387.20649 -181.004464) (xy 387.188663 -180.983825)
			(xy 387.158555 -180.938354) (xy 387.135392 -180.888983) (xy 387.119667 -180.836764) (xy 387.111717 -180.782811)
			(xy 387.11124 -180.755544) (xy 387.111775 -180.728929) (xy 387.119344 -180.676241) (xy 387.134335 -180.625165)
			(xy 387.156441 -180.576743) (xy 387.185214 -180.531961) (xy 387.220067 -180.491728) (xy 387.260292 -180.456866)
			(xy 387.305068 -180.428083) (xy 387.353485 -180.405965) (xy 387.404556 -180.390962) (xy 387.457243 -180.383381)
			(xy 387.483858 -180.382926) (xy 387.51028 -180.383368) (xy 387.562596 -180.390824) (xy 387.613334 -180.405594)
			(xy 387.661478 -180.427381) (xy 387.706062 -180.455748) (xy 387.726428 -180.472588) (xy 387.733286 -180.478684)
			(xy 387.750304 -180.48478) (xy 387.834632 -180.48478) (xy 387.85165 -180.478684) (xy 387.858508 -180.472588)
			(xy 387.878874 -180.455749) (xy 387.92346 -180.427384) (xy 387.971604 -180.405597) (xy 388.022341 -180.390826)
			(xy 388.074656 -180.383366) (xy 388.1275 -180.383366) (xy 388.179815 -180.390826) (xy 388.230552 -180.405597)
			(xy 388.278696 -180.427384) (xy 388.323282 -180.455749) (xy 388.343648 -180.472588) (xy 388.350506 -180.478684)
			(xy 388.367524 -180.48478) (xy 388.451852 -180.48478) (xy 388.46887 -180.478684) (xy 388.475728 -180.472588)
			(xy 388.496082 -180.455735) (xy 388.540675 -180.427383) (xy 388.588823 -180.405606) (xy 388.639562 -180.390842)
			(xy 388.691876 -180.383385) (xy 388.718298 -180.382926) (xy 388.746188 -180.383333) (xy 388.801345 -180.391646)
			(xy 388.854648 -180.408088) (xy 388.904904 -180.43229) (xy 388.950992 -180.463712) (xy 388.991882 -180.501652)
			(xy 389.026661 -180.545262) (xy 389.054551 -180.59357) (xy 389.07493 -180.645494) (xy 389.087342 -180.699876)
			(xy 389.091511 -180.7555) (xy 389.087342 -180.811124) (xy 389.07493 -180.865506) (xy 389.054551 -180.91743)
			(xy 389.026661 -180.965738) (xy 388.991882 -181.009348) (xy 388.950992 -181.047288) (xy 388.904904 -181.07871)
			(xy 388.854648 -181.102912) (xy 388.801345 -181.119354) (xy 388.746188 -181.127667) (xy 388.718298 -181.128162)
			(xy 388.691877 -181.127691) (xy 388.639563 -181.120242) (xy 388.588825 -181.105479) (xy 388.54068 -181.083699)
			(xy 388.496094 -181.055337) (xy 388.475728 -181.0385) (xy 388.46887 -181.032404) (xy 388.451852 -181.026308)
			(xy 388.367524 -181.026308) (xy 388.350506 -181.032404) (xy 388.343648 -181.0385) (xy 388.323282 -181.055339)
			(xy 388.278696 -181.083704) (xy 388.230552 -181.105491) (xy 388.179815 -181.120262) (xy 388.1275 -181.127722)
			(xy 388.074656 -181.127722) (xy 388.022341 -181.120262) (xy 387.971604 -181.105491) (xy 387.92346 -181.083704)
			(xy 387.878874 -181.055339) (xy 387.858508 -181.0385) (xy 387.85165 -181.032404) (xy 387.834632 -181.026308)
			(xy 387.750304 -181.026308) (xy 387.733286 -181.032404) (xy 387.726428 -181.0385) (xy 387.713214 -181.04952)
			(xy 387.685103 -181.069365) (xy 387.670294 -181.078124) (xy 387.660134 -181.08422) (xy 387.64718 -181.103016)
			(xy 387.631686 -181.204616) (xy 387.63829 -181.22646) (xy 387.646418 -181.235096) (xy 387.665355 -181.256385)
			(xy 387.697366 -181.303519) (xy 387.722019 -181.354885) (xy 387.738766 -181.409345) (xy 387.747235 -181.465688)
			(xy 387.747764 -181.494176) (xy 387.747294 -181.521751) (xy 387.739344 -181.576324) (xy 387.723621 -181.629184)
			(xy 387.700452 -181.67923) (xy 387.670319 -181.72542) (xy 387.633851 -181.766791) (xy 387.613144 -181.785006)
			(xy 387.605019 -181.792602) (xy 387.595671 -181.812759) (xy 387.59511 -181.823868) (xy 387.59511 -181.901084)
			(xy 387.595668 -181.912195) (xy 387.605013 -181.932354) (xy 387.613144 -181.939946) (xy 387.633841 -181.958172)
			(xy 387.670311 -181.999539) (xy 387.700443 -182.045726) (xy 387.723611 -182.095771) (xy 387.739331 -182.14863)
			(xy 387.747276 -182.203202) (xy 387.747764 -182.230776) (xy 387.747278 -182.258027) (xy 387.739522 -182.311975)
			(xy 387.724167 -182.36427) (xy 387.701525 -182.413847) (xy 387.672059 -182.459697) (xy 387.636368 -182.500888)
			(xy 387.595177 -182.536579) (xy 387.549327 -182.566045) (xy 387.49975 -182.588687) (xy 387.447455 -182.604042)
			(xy 387.393507 -182.611798) (xy 387.339005 -182.611798) (xy 387.285057 -182.604042) (xy 387.232762 -182.588687)
			(xy 387.183185 -182.566045) (xy 387.137335 -182.536579) (xy 387.096144 -182.500888) (xy 387.060453 -182.459697)
			(xy 387.030987 -182.413847) (xy 387.008345 -182.36427) (xy 386.99299 -182.311975) (xy 386.985234 -182.258027)
			(xy 386.984748 -182.230776) (xy 385.434332 -182.230776) (xy 385.434332 -187.2615) (xy 385.434749 -187.27157)
			(xy 385.442475 -187.290169) (xy 385.449318 -187.297568) (xy 385.70408 -187.55233) (xy 385.711489 -187.559158)
			(xy 385.730082 -187.566884) (xy 385.740148 -187.567316) (xy 389.91921 -187.567316) (xy 389.929283 -187.566918)
			(xy 389.947882 -187.55918) (xy 389.955278 -187.55233) (xy 390.469882 -187.037472) (xy 390.491481 -187.016672)
			(xy 390.539981 -186.981414) (xy 390.593402 -186.954183) (xy 390.650427 -186.935649) (xy 390.709649 -186.926268)
			(xy 390.73963 -186.925712) (xy 392.901424 -186.925712) (xy 392.911432 -186.925232) (xy 392.929922 -186.917567)
			(xy 392.944074 -186.903412) (xy 392.951734 -186.88492) (xy 392.952224 -186.874912) (xy 392.952224 -182.15483)
			(xy 392.951803 -182.14476) (xy 392.944082 -182.126161) (xy 392.937238 -182.118762) (xy 392.82243 -182.004208)
			(xy 392.801651 -181.982606) (xy 392.766467 -181.934082) (xy 392.739303 -181.880654) (xy 392.720826 -181.823635)
			(xy 392.711492 -181.764429) (xy 392.710924 -181.73446) (xy 392.711409 -181.706549) (xy 392.719548 -181.651324)
			(xy 392.735646 -181.597873) (xy 392.75936 -181.547339) (xy 392.790184 -181.500799) (xy 392.80846 -181.479698)
			(xy 392.81481 -181.472586) (xy 392.821414 -181.455314) (xy 392.821414 -181.368446) (xy 392.81481 -181.351174)
			(xy 392.80846 -181.344062) (xy 392.790126 -181.322964) (xy 392.75922 -181.276391) (xy 392.735444 -181.225805)
			(xy 392.719307 -181.17229) (xy 392.711156 -181.116993) (xy 392.71067 -181.089046) (xy 392.711156 -181.061795)
			(xy 392.718912 -181.007847) (xy 392.734267 -180.955552) (xy 392.756909 -180.905975) (xy 392.786375 -180.860125)
			(xy 392.822066 -180.818934) (xy 392.863257 -180.783243) (xy 392.909107 -180.753777) (xy 392.958684 -180.731135)
			(xy 393.010979 -180.71578) (xy 393.064927 -180.708024) (xy 393.119429 -180.708024) (xy 393.173377 -180.71578)
			(xy 393.225672 -180.731135) (xy 393.275249 -180.753777) (xy 393.321099 -180.783243) (xy 393.36229 -180.818934)
			(xy 393.397981 -180.860125) (xy 393.427447 -180.905975) (xy 393.450089 -180.955552) (xy 393.465444 -181.007847)
			(xy 393.4732 -181.061795) (xy 393.473686 -181.089046) (xy 393.473071 -181.119167) (xy 393.463599 -181.178661)
			(xy 393.444898 -181.235928) (xy 393.417432 -181.289546) (xy 393.381884 -181.338183) (xy 393.36091 -181.35981)
			(xy 393.354074 -181.367214) (xy 393.346352 -181.38581) (xy 393.345924 -181.395878) (xy 393.345924 -181.427882)
			(xy 393.346352 -181.437951) (xy 393.35407 -181.456549) (xy 393.36091 -181.46395) (xy 393.361926 -181.464712)
			(xy 393.603226 -181.706012) (xy 393.623959 -181.727656) (xy 393.659151 -181.776168) (xy 393.686325 -181.829586)
			(xy 393.704812 -181.886595) (xy 393.714158 -181.945794) (xy 393.714732 -181.97576) (xy 393.714732 -186.680348)
			(xy 393.73175 -186.705748) (xy 393.746228 -186.71159) (xy 393.755661 -186.714944) (xy 393.775659 -186.71496)
			(xy 393.794157 -186.707361) (xy 393.8016 -186.700668) (xy 394.66647 -185.835544) (xy 394.688069 -185.814744)
			(xy 394.73657 -185.779488) (xy 394.789991 -185.752257) (xy 394.847015 -185.733722) (xy 394.906237 -185.724341)
			(xy 394.936218 -185.723784) (xy 400.876008 -185.723784) (xy 400.886052 -185.723397) (xy 400.904648 -185.71582)
			(xy 400.912076 -185.709052) (xy 401.370038 -185.25109) (xy 401.37688 -185.243692) (xy 401.384598 -185.225091)
			(xy 401.385024 -185.215022) (xy 401.385024 -176.59985) (xy 401.384592 -176.589781) (xy 401.376878 -176.571182)
			(xy 401.370038 -176.563782) (xy 401.23745 -176.431448) (xy 401.216693 -176.409825) (xy 401.181506 -176.361307)
			(xy 401.154337 -176.307884) (xy 401.135855 -176.25087) (xy 401.126515 -176.191668) (xy 401.125944 -176.1617)
			(xy 401.126448 -176.13379) (xy 401.134582 -176.078565) (xy 401.150675 -176.025115) (xy 401.174385 -175.97458)
			(xy 401.205205 -175.928039) (xy 401.22348 -175.906938) (xy 401.22983 -175.899826) (xy 401.236434 -175.882554)
			(xy 401.236434 -175.795686) (xy 401.22983 -175.778414) (xy 401.22348 -175.771302) (xy 401.205168 -175.750186)
			(xy 401.174258 -175.703618) (xy 401.150478 -175.653037) (xy 401.134336 -175.599526) (xy 401.126179 -175.544232)
			(xy 401.12569 -175.516286) (xy 401.126165 -175.489034) (xy 401.133923 -175.435086) (xy 401.14928 -175.382792)
			(xy 401.171923 -175.333215) (xy 401.20139 -175.287364) (xy 401.237083 -175.246174) (xy 401.278274 -175.210483)
			(xy 401.324125 -175.181017) (xy 401.373703 -175.158376) (xy 401.425998 -175.143021) (xy 401.479946 -175.135264)
			(xy 401.507198 -175.134778) (xy 401.533946 -175.135252) (xy 401.586915 -175.142751) (xy 401.638318 -175.157575)
			(xy 401.687146 -175.179432) (xy 401.732443 -175.207895) (xy 401.77332 -175.242405) (xy 401.808978 -175.282286)
			(xy 401.838715 -175.326757) (xy 401.861951 -175.374944) (xy 401.878228 -175.425905) (xy 401.887229 -175.47864)
			(xy 401.888452 -175.505364) (xy 401.88896 -175.520858) (xy 401.906232 -175.545496) (xy 402.007324 -175.585628)
			(xy 402.016667 -175.588828) (xy 402.036395 -175.588659) (xy 402.054606 -175.581072) (xy 402.061934 -175.574452)
			(xy 402.44395 -175.192182) (xy 402.465579 -175.171432) (xy 402.514095 -175.136242) (xy 402.567516 -175.109071)
			(xy 402.624529 -175.090588) (xy 402.683731 -175.081247) (xy 402.713698 -175.080676) (xy 406.883108 -175.080676)
			(xy 406.893179 -175.080261) (xy 406.911777 -175.072534) (xy 406.919176 -175.06569) (xy 409.955238 -172.029628)
			(xy 409.962064 -172.022217) (xy 409.969791 -172.003626) (xy 409.970224 -171.99356) (xy 409.970224 -168.284144)
			(xy 409.969796 -168.274075) (xy 409.962079 -168.255476) (xy 409.955238 -168.248076) (xy 409.56103 -167.854122)
			(xy 409.540257 -167.832514) (xy 409.505073 -167.783992) (xy 409.477907 -167.730565) (xy 409.459429 -167.673548)
			(xy 409.450093 -167.614343) (xy 409.449524 -167.584374) (xy 409.450018 -167.556463) (xy 409.458154 -167.501238)
			(xy 409.474251 -167.447788) (xy 409.497963 -167.397254) (xy 409.528785 -167.350713) (xy 409.54706 -167.329612)
			(xy 409.55341 -167.3225) (xy 409.560014 -167.305228) (xy 409.560014 -167.21836) (xy 409.55341 -167.201088)
			(xy 409.54706 -167.193976) (xy 409.528732 -167.172872) (xy 409.497826 -167.126301) (xy 409.474048 -167.075717)
			(xy 409.45791 -167.022203) (xy 409.449757 -166.966907) (xy 409.44927 -166.93896) (xy 409.449756 -166.911709)
			(xy 409.457512 -166.857761) (xy 409.472867 -166.805466) (xy 409.495509 -166.755889) (xy 409.524975 -166.710039)
			(xy 409.560666 -166.668848) (xy 409.601857 -166.633157) (xy 409.647707 -166.603691) (xy 409.697284 -166.581049)
			(xy 409.749579 -166.565694) (xy 409.803527 -166.557938) (xy 409.858029 -166.557938) (xy 409.911977 -166.565694)
			(xy 409.964272 -166.581049) (xy 410.013849 -166.603691) (xy 410.059699 -166.633157) (xy 410.10089 -166.668848)
			(xy 410.136581 -166.710039) (xy 410.166047 -166.755889) (xy 410.188689 -166.805466) (xy 410.204044 -166.857761)
			(xy 410.2118 -166.911709) (xy 410.212286 -166.93896) (xy 410.21168 -166.969082) (xy 410.202206 -167.028576)
			(xy 410.183503 -167.085843) (xy 410.156035 -167.139461) (xy 410.120485 -167.188097) (xy 410.09951 -167.209724)
			(xy 410.092668 -167.217123) (xy 410.084949 -167.235723) (xy 410.084524 -167.245792) (xy 410.084524 -167.277796)
			(xy 410.084945 -167.287866) (xy 410.092668 -167.306464) (xy 410.09951 -167.313864) (xy 410.100526 -167.314626)
			(xy 410.621226 -167.835326) (xy 410.641966 -167.856964) (xy 410.677157 -167.905477) (xy 410.704329 -167.958897)
			(xy 410.722815 -168.015907) (xy 410.732159 -168.075107) (xy 410.732732 -168.105074) (xy 410.732732 -171.99356)
			(xy 410.73317 -172.003628) (xy 410.740881 -172.022226) (xy 410.747718 -172.029628) (xy 411.01518 -172.29709)
			(xy 411.022594 -172.303912) (xy 411.041183 -172.311643) (xy 411.051248 -172.312076) (xy 415.491168 -172.312076)
			(xy 415.501236 -172.31164) (xy 415.519834 -172.303927) (xy 415.527236 -172.29709) (xy 418.172138 -169.652188)
			(xy 418.178981 -169.644791) (xy 418.186698 -169.626189) (xy 418.187124 -169.61612) (xy 418.187124 -163.293044)
			(xy 418.186696 -163.282975) (xy 418.178979 -163.264376) (xy 418.172138 -163.256976) (xy 417.94303 -163.028122)
			(xy 417.922257 -163.006514) (xy 417.887073 -162.957992) (xy 417.859907 -162.904565) (xy 417.841429 -162.847548)
			(xy 417.832093 -162.788343) (xy 417.831524 -162.758374) (xy 417.832018 -162.730463) (xy 417.840154 -162.675238)
			(xy 417.856251 -162.621788) (xy 417.879963 -162.571254) (xy 417.910785 -162.524713) (xy 417.92906 -162.503612)
			(xy 417.93541 -162.4965) (xy 417.942014 -162.479228) (xy 417.942014 -162.39236) (xy 417.93541 -162.375088)
			(xy 417.92906 -162.367976) (xy 417.910732 -162.346872) (xy 417.879826 -162.300301) (xy 417.856048 -162.249717)
			(xy 417.83991 -162.196203) (xy 417.831757 -162.140907) (xy 417.83127 -162.11296) (xy 417.831756 -162.085709)
			(xy 417.839512 -162.031761) (xy 417.854867 -161.979466) (xy 417.877509 -161.929889) (xy 417.906975 -161.884039)
			(xy 417.942666 -161.842848) (xy 417.983857 -161.807157) (xy 418.029707 -161.777691) (xy 418.079284 -161.755049)
			(xy 418.131579 -161.739694) (xy 418.185527 -161.731938) (xy 418.240029 -161.731938) (xy 418.293977 -161.739694)
			(xy 418.346272 -161.755049) (xy 418.395849 -161.777691) (xy 418.441699 -161.807157) (xy 418.48289 -161.842848)
			(xy 418.518581 -161.884039) (xy 418.548047 -161.929889) (xy 418.570689 -161.979466) (xy 418.586044 -162.031761)
			(xy 418.5938 -162.085709) (xy 418.594286 -162.11296) (xy 418.59368 -162.143082) (xy 418.584206 -162.202576)
			(xy 418.565503 -162.259843) (xy 418.538035 -162.313461) (xy 418.502485 -162.362097) (xy 418.48151 -162.383724)
			(xy 418.474668 -162.391123) (xy 418.466949 -162.409723) (xy 418.466524 -162.419792) (xy 418.466524 -162.451796)
			(xy 418.466945 -162.461866) (xy 418.474668 -162.480464) (xy 418.48151 -162.487864) (xy 418.482526 -162.488626)
			(xy 418.838126 -162.844226) (xy 418.858866 -162.865864) (xy 418.894057 -162.914377) (xy 418.921229 -162.967797)
			(xy 418.939715 -163.024807) (xy 418.949059 -163.084007) (xy 418.949632 -163.113974) (xy 418.949632 -169.79519)
			(xy 418.949108 -169.825163) (xy 418.939786 -169.884377) (xy 418.921307 -169.941402) (xy 418.894127 -169.994829)
			(xy 418.858917 -170.043342) (xy 418.838126 -170.064938) (xy 415.939986 -172.963078) (xy 415.918351 -172.983821)
			(xy 415.869836 -173.01901) (xy 415.816416 -173.04618) (xy 415.759405 -173.064665) (xy 415.700205 -173.07401)
			(xy 415.670238 -173.074584) (xy 410.872178 -173.074584) (xy 410.842206 -173.07403) (xy 410.782993 -173.064717)
			(xy 410.725968 -173.046246) (xy 410.67254 -173.019072) (xy 410.624026 -172.983867) (xy 410.60243 -172.963078)
			(xy 410.387292 -172.74794) (xy 410.379931 -172.741171) (xy 410.361469 -172.733524) (xy 410.341487 -172.733524)
			(xy 410.323025 -172.741171) (xy 410.315664 -172.74794) (xy 407.331926 -175.731678) (xy 407.310318 -175.75245)
			(xy 407.261795 -175.787635) (xy 407.208368 -175.8148) (xy 407.151351 -175.833278) (xy 407.092147 -175.842615)
			(xy 407.062178 -175.843184) (xy 402.892768 -175.843184) (xy 402.882694 -175.84357) (xy 402.864095 -175.851316)
			(xy 402.8567 -175.85817) (xy 402.283676 -176.431448) (xy 402.25995 -176.4542) (xy 402.206179 -176.492002)
			(xy 402.176742 -176.506632) (xy 402.16328 -176.512982) (xy 402.147532 -176.53762) (xy 402.147532 -185.394092)
			(xy 402.147009 -185.424065) (xy 402.137687 -185.483279) (xy 402.119207 -185.540304) (xy 402.092027 -185.593731)
			(xy 402.056817 -185.642244) (xy 402.036026 -185.66384) (xy 401.324826 -186.37504) (xy 401.303226 -186.395839)
			(xy 401.254726 -186.431096) (xy 401.201305 -186.458327) (xy 401.144281 -186.476862) (xy 401.085058 -186.486243)
			(xy 401.055078 -186.4868) (xy 395.115288 -186.4868) (xy 395.105241 -186.487163) (xy 395.086644 -186.494754)
			(xy 395.07922 -186.501532) (xy 394.633809 -186.947048) (xy 404.034244 -186.947048) (xy 404.034727 -186.919678)
			(xy 404.042539 -186.8655) (xy 404.058024 -186.812996) (xy 404.080862 -186.763249) (xy 404.110584 -186.717282)
			(xy 404.128224 -186.69635) (xy 404.13432 -186.689238) (xy 404.14067 -186.67222) (xy 404.14067 -186.586876)
			(xy 404.13432 -186.569858) (xy 404.128224 -186.562746) (xy 404.11063 -186.541775) (xy 404.080904 -186.495814)
			(xy 404.058056 -186.446074) (xy 404.042556 -186.393578) (xy 404.034723 -186.339404) (xy 404.034718 -186.284668)
			(xy 404.042541 -186.230493) (xy 404.058031 -186.177994) (xy 404.080869 -186.12825) (xy 404.110587 -186.082283)
			(xy 404.128224 -186.06135) (xy 404.13432 -186.054238) (xy 404.14067 -186.03722) (xy 404.14067 -185.951876)
			(xy 404.13432 -185.934858) (xy 404.128224 -185.927746) (xy 404.11063 -185.906775) (xy 404.080904 -185.860814)
			(xy 404.058056 -185.811074) (xy 404.042556 -185.758578) (xy 404.034723 -185.704404) (xy 404.034718 -185.649668)
			(xy 404.042541 -185.595493) (xy 404.058031 -185.542994) (xy 404.080869 -185.49325) (xy 404.110587 -185.447283)
			(xy 404.128224 -185.42635) (xy 404.13432 -185.419238) (xy 404.14067 -185.40222) (xy 404.14067 -185.316876)
			(xy 404.13432 -185.299858) (xy 404.128224 -185.292746) (xy 404.11063 -185.271775) (xy 404.080904 -185.225814)
			(xy 404.058056 -185.176074) (xy 404.042556 -185.123578) (xy 404.034723 -185.069404) (xy 404.034718 -185.014668)
			(xy 404.042541 -184.960493) (xy 404.058031 -184.907994) (xy 404.080869 -184.85825) (xy 404.110587 -184.812283)
			(xy 404.128224 -184.79135) (xy 404.13432 -184.784238) (xy 404.14067 -184.76722) (xy 404.14067 -184.681876)
			(xy 404.13432 -184.664858) (xy 404.128224 -184.657746) (xy 404.11063 -184.636775) (xy 404.080904 -184.590814)
			(xy 404.058056 -184.541074) (xy 404.042556 -184.488578) (xy 404.034723 -184.434404) (xy 404.034718 -184.379668)
			(xy 404.042541 -184.325493) (xy 404.058031 -184.272994) (xy 404.080869 -184.22325) (xy 404.110587 -184.177283)
			(xy 404.128224 -184.15635) (xy 404.13432 -184.149238) (xy 404.14067 -184.13222) (xy 404.14067 -184.046876)
			(xy 404.13432 -184.029858) (xy 404.128224 -184.022746) (xy 404.110597 -184.001804) (xy 404.080882 -183.955835)
			(xy 404.058044 -183.90609) (xy 404.04255 -183.853591) (xy 404.034719 -183.799417) (xy 404.034244 -183.772048)
			(xy 404.034643 -183.746226) (xy 404.041601 -183.695052) (xy 404.055395 -183.645284) (xy 404.075773 -183.597831)
			(xy 404.102365 -183.553559) (xy 404.134683 -183.513276) (xy 404.153116 -183.495188) (xy 404.160482 -183.48833)
			(xy 404.168356 -183.471312) (xy 404.17369 -183.382412) (xy 404.167848 -183.364378) (xy 404.161498 -183.356758)
			(xy 404.144997 -183.336149) (xy 404.117263 -183.291225) (xy 404.095989 -183.242906) (xy 404.081579 -183.192116)
			(xy 404.07431 -183.139824) (xy 404.073868 -183.113426) (xy 404.074333 -183.086056) (xy 404.082148 -183.031876)
			(xy 404.097637 -182.979372) (xy 404.120479 -182.929625) (xy 404.150206 -182.883659) (xy 404.167848 -182.862728)
			(xy 404.173944 -182.855616) (xy 404.180294 -182.838598) (xy 404.180294 -182.753254) (xy 404.173944 -182.736236)
			(xy 404.167848 -182.729124) (xy 404.150232 -182.708171) (xy 404.120504 -182.662207) (xy 404.097656 -182.612464)
			(xy 404.082157 -182.559965) (xy 404.074326 -182.505789) (xy 404.074323 -182.45105) (xy 404.082149 -182.396873)
			(xy 404.097643 -182.344372) (xy 404.120486 -182.294627) (xy 404.150208 -182.24866) (xy 404.167848 -182.227728)
			(xy 404.173944 -182.220616) (xy 404.180294 -182.203598) (xy 404.180294 -182.118254) (xy 404.173944 -182.101236)
			(xy 404.167848 -182.094124) (xy 404.150232 -182.073171) (xy 404.120504 -182.027207) (xy 404.097656 -181.977464)
			(xy 404.082157 -181.924965) (xy 404.074326 -181.870789) (xy 404.074323 -181.81605) (xy 404.082149 -181.761873)
			(xy 404.097643 -181.709372) (xy 404.120486 -181.659627) (xy 404.150208 -181.61366) (xy 404.167848 -181.592728)
			(xy 404.173944 -181.585616) (xy 404.180294 -181.568598) (xy 404.180294 -181.483254) (xy 404.173944 -181.466236)
			(xy 404.167848 -181.459124) (xy 404.150214 -181.438188) (xy 404.1205 -181.392217) (xy 404.097662 -181.34247)
			(xy 404.08217 -181.28997) (xy 404.074342 -181.235795) (xy 404.073868 -181.208426) (xy 404.074379 -181.181175)
			(xy 404.082132 -181.127227) (xy 404.097484 -181.074931) (xy 404.120121 -181.025353) (xy 404.149585 -180.979501)
			(xy 404.185273 -180.938309) (xy 404.226461 -180.902615) (xy 404.272309 -180.873145) (xy 404.321885 -180.850501)
			(xy 404.374178 -180.835143) (xy 404.428125 -180.827383) (xy 404.455376 -180.826918) (xy 404.484853 -180.827468)
			(xy 404.543106 -180.836534) (xy 404.599271 -180.854454) (xy 404.65201 -180.880801) (xy 404.700069 -180.914948)
			(xy 404.721568 -180.935122) (xy 404.728916 -180.941639) (xy 404.747066 -180.949094) (xy 404.756874 -180.9496)
			(xy 404.810214 -180.9496) (xy 404.814278 -180.945028) (xy 404.820692 -180.937574) (xy 404.827887 -180.919294)
			(xy 404.828248 -180.909468) (xy 404.827994 -180.877718) (xy 404.827431 -180.867883) (xy 404.819867 -180.849718)
			(xy 404.813262 -180.842412) (xy 404.792587 -180.820843) (xy 404.757575 -180.772433) (xy 404.73054 -180.719156)
			(xy 404.712144 -180.662314) (xy 404.702839 -180.603298) (xy 404.702264 -180.573426) (xy 404.70275 -180.546175)
			(xy 404.710506 -180.492227) (xy 404.725861 -180.439932) (xy 404.748503 -180.390355) (xy 404.777969 -180.344505)
			(xy 404.81366 -180.303314) (xy 404.854851 -180.267623) (xy 404.900701 -180.238157) (xy 404.950278 -180.215515)
			(xy 405.002573 -180.20016) (xy 405.056521 -180.192404) (xy 405.111023 -180.192404) (xy 405.164971 -180.20016)
			(xy 405.217266 -180.215515) (xy 405.266843 -180.238157) (xy 405.312693 -180.267623) (xy 405.353884 -180.303314)
			(xy 405.389575 -180.344505) (xy 405.419041 -180.390355) (xy 405.441683 -180.439932) (xy 405.457038 -180.492227)
			(xy 405.464794 -180.546175) (xy 405.46528 -180.573426) (xy 405.464827 -180.600396) (xy 405.457217 -180.653797)
			(xy 405.442154 -180.705592) (xy 405.419938 -180.754745) (xy 405.391013 -180.800274) (xy 405.37384 -180.821076)
			(xy 405.367744 -180.828188) (xy 405.361648 -180.845206) (xy 405.36241 -180.930804) (xy 405.369014 -180.947568)
			(xy 405.375364 -180.95468) (xy 405.393471 -180.975739) (xy 405.423972 -181.022152) (xy 405.447429 -181.072495)
			(xy 405.463345 -181.125703) (xy 405.471387 -181.180657) (xy 405.471884 -181.208426) (xy 405.471437 -181.235797)
			(xy 405.463615 -181.289977) (xy 405.448122 -181.342481) (xy 405.425276 -181.392227) (xy 405.395547 -181.438193)
			(xy 405.377904 -181.459124) (xy 405.371808 -181.466236) (xy 405.365458 -181.483254) (xy 405.365458 -181.568598)
			(xy 405.371808 -181.585616) (xy 405.377904 -181.592728) (xy 405.395569 -181.613641) (xy 405.42529 -181.659613)
			(xy 405.448132 -181.709363) (xy 405.463625 -181.761867) (xy 405.471451 -181.816048) (xy 405.471448 -181.870791)
			(xy 405.463617 -181.924971) (xy 405.448118 -181.977474) (xy 405.425271 -182.027222) (xy 405.395545 -182.073191)
			(xy 405.377904 -182.094124) (xy 405.371808 -182.101236) (xy 405.365458 -182.118254) (xy 405.365458 -182.203598)
			(xy 405.371808 -182.220616) (xy 405.377904 -182.227728) (xy 405.395569 -182.248641) (xy 405.42529 -182.294613)
			(xy 405.448132 -182.344363) (xy 405.463625 -182.396867) (xy 405.471451 -182.451048) (xy 405.471448 -182.505791)
			(xy 405.463617 -182.559971) (xy 405.448118 -182.612474) (xy 405.425271 -182.662222) (xy 405.395545 -182.708191)
			(xy 405.377904 -182.729124) (xy 405.371808 -182.736236) (xy 405.365458 -182.753254) (xy 405.365458 -182.838598)
			(xy 405.371808 -182.855616) (xy 405.377904 -182.862728) (xy 405.395523 -182.883676) (xy 405.425238 -182.929644)
			(xy 405.448078 -182.979388) (xy 405.463573 -183.031885) (xy 405.471407 -183.086058) (xy 405.471884 -183.113426)
			(xy 405.47149 -183.139249) (xy 405.464535 -183.190423) (xy 405.450741 -183.240192) (xy 405.430361 -183.287646)
			(xy 405.403768 -183.331918) (xy 405.371447 -183.372199) (xy 405.353012 -183.390286) (xy 405.345646 -183.397144)
			(xy 405.337772 -183.414162) (xy 405.332438 -183.503062) (xy 405.33828 -183.521096) (xy 405.34463 -183.528716)
			(xy 405.361123 -183.549331) (xy 405.388857 -183.594254) (xy 405.410133 -183.642571) (xy 405.424544 -183.69336)
			(xy 405.431816 -183.745651) (xy 405.43226 -183.772048) (xy 405.431773 -183.799418) (xy 405.423962 -183.853596)
			(xy 405.408478 -183.906099) (xy 405.385641 -183.955847) (xy 405.35592 -184.001814) (xy 405.33828 -184.022746)
			(xy 405.332184 -184.029858) (xy 405.325834 -184.046876) (xy 405.325834 -184.13222) (xy 405.332184 -184.149238)
			(xy 405.33828 -184.15635) (xy 405.355967 -184.177245) (xy 405.38569 -184.223219) (xy 405.408532 -184.272972)
			(xy 405.424024 -184.32548) (xy 405.431848 -184.379663) (xy 405.431843 -184.434409) (xy 405.424009 -184.488591)
			(xy 405.408506 -184.541096) (xy 405.385655 -184.590844) (xy 405.355924 -184.636813) (xy 405.33828 -184.657746)
			(xy 405.332184 -184.664858) (xy 405.325834 -184.681876) (xy 405.325834 -184.76722) (xy 405.332184 -184.784238)
			(xy 405.33828 -184.79135) (xy 405.355967 -184.812245) (xy 405.38569 -184.858219) (xy 405.408532 -184.907972)
			(xy 405.424024 -184.96048) (xy 405.431848 -185.014663) (xy 405.431845 -185.042048) (xy 407.445464 -185.042048)
			(xy 407.445943 -185.014678) (xy 407.453755 -184.960499) (xy 407.46924 -184.907995) (xy 407.49208 -184.858248)
			(xy 407.521803 -184.812281) (xy 407.539444 -184.79135) (xy 407.54554 -184.784238) (xy 407.55189 -184.76722)
			(xy 407.55189 -184.681876) (xy 407.54554 -184.664858) (xy 407.539444 -184.657746) (xy 407.52185 -184.636776)
			(xy 407.492122 -184.590815) (xy 407.469272 -184.541075) (xy 407.453772 -184.488578) (xy 407.445938 -184.434405)
			(xy 407.445933 -184.379668) (xy 407.453756 -184.325492) (xy 407.469247 -184.272993) (xy 407.492087 -184.223249)
			(xy 407.521806 -184.177282) (xy 407.539444 -184.15635) (xy 407.54554 -184.149238) (xy 407.55189 -184.13222)
			(xy 407.55189 -184.046876) (xy 407.54554 -184.029858) (xy 407.539444 -184.022746) (xy 407.52182 -184.001802)
			(xy 407.492104 -183.955833) (xy 407.469265 -183.906089) (xy 407.45377 -183.85359) (xy 407.445939 -183.799416)
			(xy 407.445464 -183.772048) (xy 407.446035 -183.743037) (xy 407.454796 -183.685682) (xy 407.472139 -183.630313)
			(xy 407.497665 -183.578209) (xy 407.530784 -183.530569) (xy 407.550366 -183.509158) (xy 407.557224 -183.502046)
			(xy 407.564336 -183.48452) (xy 407.565352 -183.39562) (xy 407.558494 -183.37784) (xy 407.55189 -183.370728)
			(xy 407.533224 -183.349514) (xy 407.501686 -183.30263) (xy 407.477407 -183.251608) (xy 407.460918 -183.197564)
			(xy 407.452581 -183.141678) (xy 407.452068 -183.113426) (xy 407.452533 -183.086056) (xy 407.460348 -183.031876)
			(xy 407.475837 -182.979372) (xy 407.498679 -182.929625) (xy 407.528406 -182.883659) (xy 407.546048 -182.862728)
			(xy 407.552144 -182.855616) (xy 407.558494 -182.838598) (xy 407.558494 -182.753254) (xy 407.552144 -182.736236)
			(xy 407.546048 -182.729124) (xy 407.528432 -182.708171) (xy 407.498704 -182.662207) (xy 407.475856 -182.612464)
			(xy 407.460357 -182.559965) (xy 407.452526 -182.505789) (xy 407.452523 -182.45105) (xy 407.460349 -182.396873)
			(xy 407.475843 -182.344372) (xy 407.498686 -182.294627) (xy 407.528408 -182.24866) (xy 407.546048 -182.227728)
			(xy 407.552144 -182.220616) (xy 407.558494 -182.203598) (xy 407.558494 -182.118254) (xy 407.552144 -182.101236)
			(xy 407.546048 -182.094124) (xy 407.528432 -182.073171) (xy 407.498704 -182.027207) (xy 407.475856 -181.977464)
			(xy 407.460357 -181.924965) (xy 407.452526 -181.870789) (xy 407.452523 -181.81605) (xy 407.460349 -181.761873)
			(xy 407.475843 -181.709372) (xy 407.498686 -181.659627) (xy 407.528408 -181.61366) (xy 407.546048 -181.592728)
			(xy 407.552144 -181.585616) (xy 407.558494 -181.568598) (xy 407.558494 -181.483254) (xy 407.552144 -181.466236)
			(xy 407.546048 -181.459124) (xy 407.528414 -181.438188) (xy 407.4987 -181.392217) (xy 407.475862 -181.34247)
			(xy 407.46037 -181.28997) (xy 407.452542 -181.235795) (xy 407.452068 -181.208426) (xy 407.452518 -181.181291)
			(xy 407.460212 -181.127569) (xy 407.475448 -181.075482) (xy 407.497918 -181.026083) (xy 407.527168 -180.98037)
			(xy 407.544524 -180.959506) (xy 407.55062 -180.952394) (xy 407.556716 -180.935376) (xy 407.556208 -180.850032)
			(xy 407.549858 -180.833014) (xy 407.543508 -180.825902) (xy 407.52563 -180.804865) (xy 407.495432 -180.758651)
			(xy 407.472213 -180.708566) (xy 407.456458 -180.655657) (xy 407.448495 -180.601029) (xy 407.448004 -180.573426)
			(xy 407.44848 -180.546173) (xy 407.456233 -180.492222) (xy 407.471587 -180.439924) (xy 407.494227 -180.390343)
			(xy 407.523693 -180.344489) (xy 407.559386 -180.303296) (xy 407.600578 -180.267602) (xy 407.646431 -180.238134)
			(xy 407.696011 -180.215492) (xy 407.748308 -180.200136) (xy 407.802259 -180.192381) (xy 407.829512 -180.191918)
			(xy 407.856883 -180.192373) (xy 407.911062 -180.200193) (xy 407.963566 -180.215684) (xy 408.013313 -180.238528)
			(xy 408.059279 -180.268256) (xy 408.08021 -180.285898) (xy 408.087322 -180.291994) (xy 408.10434 -180.298344)
			(xy 408.189684 -180.298344) (xy 408.206702 -180.291994) (xy 408.213814 -180.285898) (xy 408.234747 -180.268257)
			(xy 408.280715 -180.238533) (xy 408.330461 -180.215687) (xy 408.382963 -180.200191) (xy 408.437141 -180.192362)
			(xy 408.491883 -180.192362) (xy 408.546061 -180.200191) (xy 408.598563 -180.215687) (xy 408.648309 -180.238533)
			(xy 408.694277 -180.268257) (xy 408.71521 -180.285898) (xy 408.722322 -180.291994) (xy 408.73934 -180.298344)
			(xy 408.824684 -180.298344) (xy 408.841702 -180.291994) (xy 408.848814 -180.285898) (xy 408.869767 -180.268285)
			(xy 408.915734 -180.23857) (xy 408.965476 -180.215729) (xy 409.017972 -180.200231) (xy 409.072144 -180.192396)
			(xy 409.099512 -180.191918) (xy 409.126766 -180.192344) (xy 409.18072 -180.200103) (xy 409.23302 -180.215462)
			(xy 409.282602 -180.238108) (xy 409.328457 -180.267579) (xy 409.36965 -180.303277) (xy 409.405343 -180.344474)
			(xy 409.43481 -180.390331) (xy 409.457451 -180.439915) (xy 409.472805 -180.492217) (xy 409.480559 -180.546172)
			(xy 409.48102 -180.573426) (xy 409.480529 -180.600759) (xy 409.472725 -180.654865) (xy 409.45728 -180.707303)
			(xy 409.43451 -180.757001) (xy 409.404881 -180.802942) (xy 409.387294 -180.82387) (xy 409.38069 -180.831236)
			(xy 409.374594 -180.84927) (xy 409.374655 -180.851048) (xy 412.39821 -180.851048) (xy 412.398702 -180.823679)
			(xy 412.406513 -180.769501) (xy 412.421996 -180.716998) (xy 412.444832 -180.66725) (xy 412.474551 -180.621282)
			(xy 412.49219 -180.60035) (xy 412.498286 -180.593238) (xy 412.504636 -180.57622) (xy 412.504636 -180.490876)
			(xy 412.498286 -180.473858) (xy 412.49219 -180.466746) (xy 412.474598 -180.445774) (xy 412.444874 -180.399812)
			(xy 412.422028 -180.350072) (xy 412.40653 -180.297577) (xy 412.398697 -180.243404) (xy 412.398692 -180.188668)
			(xy 412.406514 -180.134494) (xy 412.422003 -180.081995) (xy 412.444839 -180.032251) (xy 412.474554 -179.986283)
			(xy 412.49219 -179.96535) (xy 412.498286 -179.958238) (xy 412.504636 -179.94122) (xy 412.504636 -179.855876)
			(xy 412.498286 -179.838858) (xy 412.49219 -179.831746) (xy 412.474598 -179.810774) (xy 412.444874 -179.764812)
			(xy 412.422028 -179.715072) (xy 412.40653 -179.662577) (xy 412.398697 -179.608404) (xy 412.398692 -179.553668)
			(xy 412.406514 -179.499494) (xy 412.422003 -179.446995) (xy 412.444839 -179.397251) (xy 412.474554 -179.351283)
			(xy 412.49219 -179.33035) (xy 412.498286 -179.323238) (xy 412.504636 -179.30622) (xy 412.504636 -179.220876)
			(xy 412.498286 -179.203858) (xy 412.49219 -179.196746) (xy 412.474557 -179.175809) (xy 412.444845 -179.129837)
			(xy 412.422008 -179.080091) (xy 412.406515 -179.027592) (xy 412.398685 -178.973417) (xy 412.39821 -178.946048)
			(xy 412.398768 -178.917037) (xy 412.407531 -178.85968) (xy 412.424876 -178.804311) (xy 412.450405 -178.752207)
			(xy 412.483528 -178.704568) (xy 412.503112 -178.683158) (xy 412.50997 -178.676046) (xy 412.517082 -178.65852)
			(xy 412.518098 -178.56962) (xy 412.51124 -178.55184) (xy 412.504636 -178.544728) (xy 412.485962 -178.523521)
			(xy 412.454426 -178.476635) (xy 412.43015 -178.425611) (xy 412.413663 -178.371565) (xy 412.405327 -178.315678)
			(xy 412.404814 -178.287426) (xy 412.405292 -178.260056) (xy 412.413106 -178.205877) (xy 412.428592 -178.153374)
			(xy 412.451432 -178.103627) (xy 412.481154 -178.05766) (xy 412.498794 -178.036728) (xy 412.50489 -178.029616)
			(xy 412.51124 -178.012598) (xy 412.51124 -177.927254) (xy 412.50489 -177.910236) (xy 412.498794 -177.903124)
			(xy 412.48118 -177.88217) (xy 412.451457 -177.836205) (xy 412.428612 -177.786462) (xy 412.413115 -177.733964)
			(xy 412.405285 -177.679789) (xy 412.405282 -177.625051) (xy 412.413107 -177.570875) (xy 412.428598 -177.518375)
			(xy 412.451438 -177.468629) (xy 412.481157 -177.422661) (xy 412.498794 -177.401728) (xy 412.50489 -177.394616)
			(xy 412.51124 -177.377598) (xy 412.51124 -177.292254) (xy 412.50489 -177.275236) (xy 412.498794 -177.268124)
			(xy 412.48118 -177.24717) (xy 412.451457 -177.201205) (xy 412.428612 -177.151462) (xy 412.413115 -177.098964)
			(xy 412.405285 -177.044789) (xy 412.405282 -176.990051) (xy 412.413107 -176.935875) (xy 412.428598 -176.883375)
			(xy 412.451438 -176.833629) (xy 412.481157 -176.787661) (xy 412.498794 -176.766728) (xy 412.50489 -176.759616)
			(xy 412.51124 -176.742598) (xy 412.51124 -176.657254) (xy 412.50489 -176.640236) (xy 412.498794 -176.633124)
			(xy 412.481152 -176.612194) (xy 412.451441 -176.566221) (xy 412.428605 -176.516473) (xy 412.413115 -176.463972)
			(xy 412.405288 -176.409795) (xy 412.404814 -176.382426) (xy 412.405298 -176.355457) (xy 412.412901 -176.302057)
			(xy 412.427957 -176.250263) (xy 412.450166 -176.20111) (xy 412.479085 -176.155579) (xy 412.496254 -176.134776)
			(xy 412.50235 -176.127664) (xy 412.508446 -176.110646) (xy 412.507684 -176.025048) (xy 412.50108 -176.008284)
			(xy 412.49473 -176.001172) (xy 412.476663 -175.98008) (xy 412.446152 -175.933677) (xy 412.422686 -175.883344)
			(xy 412.406761 -175.830142) (xy 412.398711 -175.775193) (xy 412.39821 -175.747426) (xy 412.39868 -175.720173)
			(xy 412.406433 -175.666221) (xy 412.421787 -175.613922) (xy 412.444428 -175.564341) (xy 412.473895 -175.518487)
			(xy 412.509588 -175.477294) (xy 412.550781 -175.4416) (xy 412.596634 -175.412132) (xy 412.646215 -175.38949)
			(xy 412.698514 -175.374135) (xy 412.752465 -175.36638) (xy 412.779718 -175.365918) (xy 412.807089 -175.366369)
			(xy 412.861269 -175.37419) (xy 412.913772 -175.389682) (xy 412.963519 -175.412527) (xy 413.009485 -175.442255)
			(xy 413.030416 -175.459898) (xy 413.037528 -175.465994) (xy 413.054546 -175.472344) (xy 413.13989 -175.472344)
			(xy 413.156908 -175.465994) (xy 413.16402 -175.459898) (xy 413.184971 -175.442283) (xy 413.230939 -175.412567)
			(xy 413.280681 -175.389727) (xy 413.333178 -175.37423) (xy 413.38735 -175.366396) (xy 413.414718 -175.365918)
			(xy 413.441973 -175.366338) (xy 413.495926 -175.374098) (xy 413.548227 -175.389458) (xy 413.597809 -175.412104)
			(xy 413.643663 -175.441577) (xy 413.684856 -175.477275) (xy 413.72055 -175.518472) (xy 413.750017 -175.56433)
			(xy 413.772657 -175.613915) (xy 413.788011 -175.666217) (xy 413.795765 -175.720171) (xy 413.796226 -175.747426)
			(xy 413.795786 -175.774397) (xy 413.788175 -175.827799) (xy 413.773109 -175.879594) (xy 413.75089 -175.928747)
			(xy 413.721961 -175.974275) (xy 413.704786 -175.995076) (xy 413.69869 -176.002188) (xy 413.692594 -176.019206)
			(xy 413.693356 -176.104804) (xy 413.69996 -176.121568) (xy 413.70631 -176.12868) (xy 413.724408 -176.149746)
			(xy 413.754913 -176.196157) (xy 413.778372 -176.246497) (xy 413.79429 -176.299705) (xy 413.802333 -176.354657)
			(xy 413.80283 -176.382426) (xy 413.802396 -176.409798) (xy 413.794573 -176.463979) (xy 413.779078 -176.516483)
			(xy 413.756228 -176.566229) (xy 413.726495 -176.612194) (xy 413.70885 -176.633124) (xy 413.702754 -176.640236)
			(xy 413.696404 -176.657254) (xy 413.696404 -176.742598) (xy 413.702754 -176.759616) (xy 413.70885 -176.766728)
			(xy 413.726517 -176.78764) (xy 413.756243 -176.833611) (xy 413.779088 -176.88336) (xy 413.794583 -176.935866)
			(xy 413.80241 -176.990047) (xy 413.802407 -177.044792) (xy 413.794575 -177.098973) (xy 413.779074 -177.151477)
			(xy 413.756224 -177.201224) (xy 413.726493 -177.247192) (xy 413.70885 -177.268124) (xy 413.702754 -177.275236)
			(xy 413.696404 -177.292254) (xy 413.696404 -177.377598) (xy 413.702754 -177.394616) (xy 413.70885 -177.401728)
			(xy 413.726517 -177.42264) (xy 413.756243 -177.468611) (xy 413.779088 -177.51836) (xy 413.794583 -177.570866)
			(xy 413.80241 -177.625047) (xy 413.802407 -177.679792) (xy 413.794575 -177.733973) (xy 413.779074 -177.786477)
			(xy 413.756224 -177.836224) (xy 413.726493 -177.882192) (xy 413.70885 -177.903124) (xy 413.702754 -177.910236)
			(xy 413.696404 -177.927254) (xy 413.696404 -178.012598) (xy 413.702754 -178.029616) (xy 413.70885 -178.036728)
			(xy 413.726461 -178.057683) (xy 413.756179 -178.103649) (xy 413.779021 -178.15339) (xy 413.794518 -178.205886)
			(xy 413.802353 -178.260058) (xy 413.80283 -178.287426) (xy 413.802306 -178.316438) (xy 413.793534 -178.373796)
			(xy 413.77618 -178.429165) (xy 413.750644 -178.481269) (xy 413.717515 -178.528906) (xy 413.697928 -178.550316)
			(xy 413.69107 -178.557428) (xy 413.683958 -178.574954) (xy 413.682942 -178.663854) (xy 413.6898 -178.681634)
			(xy 413.696404 -178.688746) (xy 413.715056 -178.709972) (xy 413.746597 -178.756852) (xy 413.770879 -178.807871)
			(xy 413.78737 -178.861913) (xy 413.795711 -178.917797) (xy 413.796226 -178.946048) (xy 413.795747 -178.973418)
			(xy 413.787935 -179.027597) (xy 413.77245 -179.080101) (xy 413.749611 -179.129848) (xy 413.719887 -179.175815)
			(xy 413.702246 -179.196746) (xy 413.69615 -179.203858) (xy 413.6898 -179.220876) (xy 413.6898 -179.30622)
			(xy 413.69615 -179.323238) (xy 413.702246 -179.33035) (xy 413.719935 -179.351244) (xy 413.74966 -179.397218)
			(xy 413.772504 -179.44697) (xy 413.787998 -179.499479) (xy 413.795822 -179.553663) (xy 413.795817 -179.608409)
			(xy 413.787982 -179.662592) (xy 413.772479 -179.715097) (xy 413.749625 -179.764846) (xy 413.719891 -179.810814)
			(xy 413.702246 -179.831746) (xy 413.69615 -179.838858) (xy 413.6898 -179.855876) (xy 413.6898 -179.94122)
			(xy 413.69615 -179.958238) (xy 413.702246 -179.96535) (xy 413.719935 -179.986244) (xy 413.74966 -180.032218)
			(xy 413.772504 -180.08197) (xy 413.787998 -180.134479) (xy 413.795822 -180.188663) (xy 413.795817 -180.243409)
			(xy 413.787982 -180.297592) (xy 413.772479 -180.350097) (xy 413.749625 -180.399846) (xy 413.719891 -180.445814)
			(xy 413.702246 -180.466746) (xy 413.69615 -180.473858) (xy 413.6898 -180.490876) (xy 413.6898 -180.57622)
			(xy 413.69615 -180.593238) (xy 413.702246 -180.60035) (xy 413.719867 -180.621297) (xy 413.749583 -180.667265)
			(xy 413.772424 -180.717008) (xy 413.787919 -180.769506) (xy 413.79575 -180.82368) (xy 413.796049 -180.840888)
			(xy 415.76625 -180.840888) (xy 415.766697 -180.813517) (xy 415.774517 -180.759337) (xy 415.79001 -180.706833)
			(xy 415.812857 -180.657086) (xy 415.842586 -180.611121) (xy 415.86023 -180.59019) (xy 415.866326 -180.583078)
			(xy 415.872676 -180.56606) (xy 415.872676 -180.480716) (xy 415.866326 -180.463698) (xy 415.86023 -180.456586)
			(xy 415.842577 -180.435663) (xy 415.812853 -180.389693) (xy 415.790008 -180.339946) (xy 415.774513 -180.287442)
			(xy 415.766685 -180.233262) (xy 415.766686 -180.17852) (xy 415.774516 -180.12434) (xy 415.790014 -180.071837)
			(xy 415.812862 -180.022091) (xy 415.842588 -179.976123) (xy 415.86023 -179.95519) (xy 415.866326 -179.948078)
			(xy 415.872676 -179.93106) (xy 415.872676 -179.845716) (xy 415.866326 -179.828698) (xy 415.86023 -179.821586)
			(xy 415.842577 -179.800663) (xy 415.812853 -179.754693) (xy 415.790008 -179.704946) (xy 415.774513 -179.652442)
			(xy 415.766685 -179.598262) (xy 415.766686 -179.54352) (xy 415.774516 -179.48934) (xy 415.790014 -179.436837)
			(xy 415.812862 -179.387091) (xy 415.842588 -179.341123) (xy 415.86023 -179.32019) (xy 415.866326 -179.313078)
			(xy 415.872676 -179.29606) (xy 415.872676 -179.210716) (xy 415.866326 -179.193698) (xy 415.86023 -179.186586)
			(xy 415.842622 -179.165628) (xy 415.812905 -179.119663) (xy 415.790062 -179.069922) (xy 415.774564 -179.017427)
			(xy 415.766728 -178.963256) (xy 415.76625 -178.935888) (xy 415.766777 -178.906805) (xy 415.775602 -178.849312)
			(xy 415.793047 -178.793823) (xy 415.818707 -178.741622) (xy 415.851989 -178.693918) (xy 415.87166 -178.67249)
			(xy 415.878518 -178.665632) (xy 415.88563 -178.64836) (xy 415.887662 -178.560984) (xy 415.881566 -178.543458)
			(xy 415.875216 -178.536092) (xy 415.857881 -178.515257) (xy 415.828724 -178.469568) (xy 415.806329 -178.420211)
			(xy 415.791147 -178.368181) (xy 415.783485 -178.314526) (xy 415.783014 -178.287426) (xy 415.783492 -178.260056)
			(xy 415.791306 -178.205877) (xy 415.806792 -178.153374) (xy 415.829632 -178.103627) (xy 415.859354 -178.05766)
			(xy 415.876994 -178.036728) (xy 415.88309 -178.029616) (xy 415.88944 -178.012598) (xy 415.88944 -177.927254)
			(xy 415.88309 -177.910236) (xy 415.876994 -177.903124) (xy 415.85938 -177.88217) (xy 415.829657 -177.836205)
			(xy 415.806812 -177.786462) (xy 415.791315 -177.733964) (xy 415.783485 -177.679789) (xy 415.783482 -177.625051)
			(xy 415.791307 -177.570875) (xy 415.806798 -177.518375) (xy 415.829638 -177.468629) (xy 415.859357 -177.422661)
			(xy 415.876994 -177.401728) (xy 415.88309 -177.394616) (xy 415.88944 -177.377598) (xy 415.88944 -177.292254)
			(xy 415.88309 -177.275236) (xy 415.876994 -177.268124) (xy 415.85938 -177.24717) (xy 415.829657 -177.201205)
			(xy 415.806812 -177.151462) (xy 415.791315 -177.098964) (xy 415.783485 -177.044789) (xy 415.783482 -176.990051)
			(xy 415.791307 -176.935875) (xy 415.806798 -176.883375) (xy 415.829638 -176.833629) (xy 415.859357 -176.787661)
			(xy 415.876994 -176.766728) (xy 415.88309 -176.759616) (xy 415.88944 -176.742598) (xy 415.88944 -176.657254)
			(xy 415.88309 -176.640236) (xy 415.876994 -176.633124) (xy 415.859352 -176.612194) (xy 415.829641 -176.566221)
			(xy 415.806805 -176.516473) (xy 415.791315 -176.463972) (xy 415.783488 -176.409795) (xy 415.783014 -176.382426)
			(xy 415.783477 -176.355292) (xy 415.79117 -176.301571) (xy 415.806404 -176.249484) (xy 415.82887 -176.200085)
			(xy 415.858116 -176.154371) (xy 415.87547 -176.133506) (xy 415.881566 -176.126394) (xy 415.887662 -176.109376)
			(xy 415.887154 -176.024032) (xy 415.880804 -176.007014) (xy 415.874454 -175.999902) (xy 415.856568 -175.978872)
			(xy 415.826373 -175.932655) (xy 415.803156 -175.882568) (xy 415.787403 -175.829658) (xy 415.779441 -175.775029)
			(xy 415.77895 -175.747426) (xy 415.779502 -175.720177) (xy 415.787254 -175.666234) (xy 415.802604 -175.613943)
			(xy 415.825239 -175.564369) (xy 415.854699 -175.518521) (xy 415.890383 -175.477331) (xy 415.931566 -175.441639)
			(xy 415.977409 -175.412172) (xy 416.02698 -175.389528) (xy 416.079268 -175.374169) (xy 416.133209 -175.366407)
			(xy 416.160458 -175.365918) (xy 416.187828 -175.366404) (xy 416.242006 -175.374217) (xy 416.294509 -175.389701)
			(xy 416.344256 -175.412538) (xy 416.390224 -175.442259) (xy 416.411156 -175.459898) (xy 416.418268 -175.465994)
			(xy 416.435286 -175.472344) (xy 416.52063 -175.472344) (xy 416.537648 -175.465994) (xy 416.54476 -175.459898)
			(xy 416.565693 -175.442257) (xy 416.611661 -175.412533) (xy 416.661407 -175.389687) (xy 416.713909 -175.374191)
			(xy 416.768087 -175.366362) (xy 416.822829 -175.366362) (xy 416.877007 -175.374191) (xy 416.929509 -175.389687)
			(xy 416.979255 -175.412533) (xy 417.025223 -175.442257) (xy 417.046156 -175.459898) (xy 417.053268 -175.465994)
			(xy 417.070286 -175.472344) (xy 417.15563 -175.472344) (xy 417.172648 -175.465994) (xy 417.17976 -175.459898)
			(xy 417.200696 -175.442264) (xy 417.246668 -175.412551) (xy 417.296414 -175.389715) (xy 417.348914 -175.374222)
			(xy 417.403089 -175.366393) (xy 417.430458 -175.365918) (xy 417.457711 -175.366394) (xy 417.511663 -175.374146)
			(xy 417.563962 -175.389498) (xy 417.613544 -175.412138) (xy 417.659398 -175.441604) (xy 417.700592 -175.477297)
			(xy 417.736286 -175.518489) (xy 417.765754 -175.564342) (xy 417.788396 -175.613923) (xy 417.80375 -175.666222)
			(xy 417.811504 -175.720173) (xy 417.811966 -175.747426) (xy 417.811488 -175.77476) (xy 417.803683 -175.828867)
			(xy 417.788235 -175.881306) (xy 417.765462 -175.931004) (xy 417.735829 -175.976943) (xy 417.71824 -175.99787)
			(xy 417.711636 -176.005236) (xy 417.70554 -176.02327) (xy 417.708588 -176.11217) (xy 417.715954 -176.129442)
			(xy 417.723066 -176.136554) (xy 417.74386 -176.158159) (xy 417.779117 -176.206658) (xy 417.806349 -176.260077)
			(xy 417.824885 -176.317101) (xy 417.834268 -176.376322) (xy 417.834826 -176.406302) (xy 417.834379 -176.433673)
			(xy 417.826559 -176.487854) (xy 417.811067 -176.540358) (xy 417.78822 -176.590104) (xy 417.75849 -176.63607)
			(xy 417.740846 -176.657) (xy 417.73475 -176.664112) (xy 417.7284 -176.68113) (xy 417.7284 -176.766474)
			(xy 417.73475 -176.783492) (xy 417.740846 -176.790604) (xy 417.75849 -176.811535) (xy 417.788217 -176.857502)
			(xy 417.789456 -176.8602) (xy 421.86225 -176.8602) (xy 421.862749 -176.831282) (xy 421.87148 -176.774109)
			(xy 421.88874 -176.718909) (xy 421.914135 -176.666947) (xy 421.947083 -176.619414) (xy 421.986828 -176.577399)
			(xy 422.009316 -176.55921) (xy 422.018072 -176.551642) (xy 422.028258 -176.530888) (xy 422.028874 -176.519332)
			(xy 422.028874 -176.439068) (xy 422.028274 -176.427504) (xy 422.018101 -176.406732) (xy 422.009316 -176.39919)
			(xy 421.986831 -176.381001) (xy 421.947095 -176.338981) (xy 421.914156 -176.291446) (xy 421.888768 -176.239484)
			(xy 421.871512 -176.184286) (xy 421.862784 -176.127116) (xy 421.86225 -176.0982) (xy 421.862736 -176.070949)
			(xy 421.870492 -176.017001) (xy 421.885847 -175.964706) (xy 421.908489 -175.915129) (xy 421.937955 -175.869279)
			(xy 421.973646 -175.828088) (xy 422.014837 -175.792397) (xy 422.060687 -175.762931) (xy 422.110264 -175.740289)
			(xy 422.162559 -175.724934) (xy 422.216507 -175.717178) (xy 422.271009 -175.717178) (xy 422.324957 -175.724934)
			(xy 422.377252 -175.740289) (xy 422.426829 -175.762931) (xy 422.472679 -175.792397) (xy 422.51387 -175.828088)
			(xy 422.549561 -175.869279) (xy 422.579027 -175.915129) (xy 422.601669 -175.964706) (xy 422.617024 -176.017001)
			(xy 422.62478 -176.070949) (xy 422.625266 -176.0982) (xy 422.62476 -176.127118) (xy 422.616031 -176.18429)
			(xy 422.598771 -176.23949) (xy 422.573377 -176.291451) (xy 422.540431 -176.338985) (xy 422.500687 -176.381001)
			(xy 422.4782 -176.39919) (xy 422.469447 -176.406761) (xy 422.459259 -176.427513) (xy 422.458642 -176.439068)
			(xy 422.458642 -176.519332) (xy 422.459237 -176.530897) (xy 422.469413 -176.551669) (xy 422.4782 -176.55921)
			(xy 422.500688 -176.577395) (xy 422.540423 -176.619416) (xy 422.573362 -176.666952) (xy 422.598749 -176.718915)
			(xy 422.616004 -176.774113) (xy 422.624732 -176.831284) (xy 422.625266 -176.8602) (xy 422.62478 -176.887451)
			(xy 422.617024 -176.941399) (xy 422.601669 -176.993694) (xy 422.579027 -177.043271) (xy 422.549561 -177.089121)
			(xy 422.51387 -177.130312) (xy 422.472679 -177.166003) (xy 422.426829 -177.195469) (xy 422.377252 -177.218111)
			(xy 422.324957 -177.233466) (xy 422.271009 -177.241222) (xy 422.216507 -177.241222) (xy 422.162559 -177.233466)
			(xy 422.110264 -177.218111) (xy 422.060687 -177.195469) (xy 422.014837 -177.166003) (xy 421.973646 -177.130312)
			(xy 421.937955 -177.089121) (xy 421.908489 -177.043271) (xy 421.885847 -176.993694) (xy 421.870492 -176.941399)
			(xy 421.862736 -176.887451) (xy 421.86225 -176.8602) (xy 417.789456 -176.8602) (xy 417.811063 -176.907249)
			(xy 417.826561 -176.959751) (xy 417.83439 -177.01393) (xy 417.83439 -177.068673) (xy 417.82656 -177.122852)
			(xy 417.811062 -177.175354) (xy 417.788215 -177.225101) (xy 417.758488 -177.271068) (xy 417.740846 -177.292)
			(xy 417.73475 -177.299112) (xy 417.7284 -177.31613) (xy 417.7284 -177.401474) (xy 417.73475 -177.418492)
			(xy 417.740846 -177.425604) (xy 417.75849 -177.446535) (xy 417.788217 -177.492502) (xy 417.811063 -177.542249)
			(xy 417.826561 -177.594751) (xy 417.83439 -177.64893) (xy 417.83439 -177.703673) (xy 417.82656 -177.757852)
			(xy 417.811062 -177.810354) (xy 417.788215 -177.860101) (xy 417.758488 -177.906068) (xy 417.740846 -177.927)
			(xy 417.73475 -177.934112) (xy 417.7284 -177.95113) (xy 417.7284 -178.036474) (xy 417.73475 -178.053492)
			(xy 417.740846 -178.060604) (xy 417.758492 -178.081531) (xy 417.788205 -178.127504) (xy 417.81104 -178.177253)
			(xy 417.826529 -178.229755) (xy 417.834354 -178.283932) (xy 417.834826 -178.311302) (xy 417.834273 -178.340815)
			(xy 417.825182 -178.399136) (xy 417.807217 -178.455361) (xy 417.780808 -178.508149) (xy 417.746584 -178.55624)
			(xy 417.726368 -178.577748) (xy 417.719764 -178.584606) (xy 417.712398 -178.601116) (xy 417.707572 -178.68646)
			(xy 417.71316 -178.703732) (xy 417.718748 -178.711098) (xy 417.73393 -178.731286) (xy 417.759435 -178.774884)
			(xy 417.778966 -178.821465) (xy 417.792183 -178.870216) (xy 417.798853 -178.920285) (xy 417.799266 -178.94554)
			(xy 417.798773 -178.972909) (xy 417.790963 -179.027088) (xy 417.775481 -179.079591) (xy 417.752645 -179.129338)
			(xy 417.722925 -179.175306) (xy 417.705286 -179.196238) (xy 417.69919 -179.20335) (xy 417.69284 -179.220368)
			(xy 417.69284 -179.305712) (xy 417.69919 -179.32273) (xy 417.705286 -179.329842) (xy 417.722965 -179.350743)
			(xy 417.752688 -179.396717) (xy 417.77553 -179.446468) (xy 417.791022 -179.498975) (xy 417.798847 -179.553158)
			(xy 417.798843 -179.607902) (xy 417.791009 -179.662084) (xy 417.775509 -179.714588) (xy 417.752658 -179.764336)
			(xy 417.722929 -179.810305) (xy 417.705286 -179.831238) (xy 417.69919 -179.83835) (xy 417.69284 -179.855368)
			(xy 417.69284 -179.940712) (xy 417.69919 -179.95773) (xy 417.705286 -179.964842) (xy 417.722965 -179.985743)
			(xy 417.752688 -180.031717) (xy 417.77553 -180.081468) (xy 417.791022 -180.133975) (xy 417.798847 -180.188158)
			(xy 417.798843 -180.242902) (xy 417.791009 -180.297084) (xy 417.775509 -180.349588) (xy 417.752658 -180.399336)
			(xy 417.722929 -180.445305) (xy 417.705286 -180.466238) (xy 417.69919 -180.47335) (xy 417.69284 -180.490368)
			(xy 417.69284 -180.575712) (xy 417.69919 -180.59273) (xy 417.705286 -180.599842) (xy 417.722909 -180.620787)
			(xy 417.752624 -180.666756) (xy 417.775463 -180.7165) (xy 417.790958 -180.768998) (xy 417.79879 -180.823172)
			(xy 417.799266 -180.85054) (xy 417.798882 -180.877796) (xy 417.791119 -180.931752) (xy 417.775755 -180.984054)
			(xy 417.753105 -181.033637) (xy 417.723629 -181.079492) (xy 417.687927 -181.120685) (xy 417.646726 -181.156378)
			(xy 417.600865 -181.185845) (xy 417.551277 -181.208484) (xy 417.498972 -181.223836) (xy 417.445014 -181.231588)
			(xy 417.417758 -181.232048) (xy 417.389811 -181.231583) (xy 417.334518 -181.223411) (xy 417.281008 -181.207262)
			(xy 417.230426 -181.183481) (xy 417.183852 -181.152578) (xy 417.162742 -181.134258) (xy 417.15563 -181.127908)
			(xy 417.138866 -181.121304) (xy 417.053268 -181.120034) (xy 417.03625 -181.12613) (xy 417.029138 -181.132226)
			(xy 417.008385 -181.149181) (xy 416.96302 -181.17771) (xy 416.91411 -181.199611) (xy 416.862617 -181.214454)
			(xy 416.809553 -181.221946) (xy 416.782758 -181.222396) (xy 416.755389 -181.221897) (xy 416.701211 -181.214087)
			(xy 416.648708 -181.198606) (xy 416.598961 -181.175771) (xy 416.552993 -181.146054) (xy 416.53206 -181.128416)
			(xy 416.524948 -181.12232) (xy 416.50793 -181.11597) (xy 416.422586 -181.11597) (xy 416.405568 -181.12232)
			(xy 416.398456 -181.128416) (xy 416.377516 -181.146045) (xy 416.331545 -181.175758) (xy 416.281799 -181.198595)
			(xy 416.229301 -181.214089) (xy 416.175127 -181.22192) (xy 416.147758 -181.222396) (xy 416.120505 -181.221961)
			(xy 416.066555 -181.214199) (xy 416.014259 -181.198838) (xy 415.96468 -181.176191) (xy 415.91883 -181.146719)
			(xy 415.87764 -181.111022) (xy 415.841949 -181.069827) (xy 415.812483 -181.023972) (xy 415.789843 -180.974391)
			(xy 415.77449 -180.922092) (xy 415.766735 -180.868141) (xy 415.76625 -180.840888) (xy 413.796049 -180.840888)
			(xy 413.796226 -180.851048) (xy 413.795767 -180.8783) (xy 413.788004 -180.932247) (xy 413.772644 -180.984541)
			(xy 413.749999 -181.034118) (xy 413.720529 -181.079967) (xy 413.684835 -181.121156) (xy 413.643643 -181.156847)
			(xy 413.597791 -181.186313) (xy 413.548213 -181.208955) (xy 413.495918 -181.224311) (xy 413.44197 -181.232069)
			(xy 413.414718 -181.232556) (xy 413.387348 -181.23209) (xy 413.333168 -181.224274) (xy 413.280665 -181.208785)
			(xy 413.230918 -181.185943) (xy 413.184951 -181.156218) (xy 413.16402 -181.138576) (xy 413.156908 -181.13248)
			(xy 413.13989 -181.12613) (xy 413.054546 -181.12613) (xy 413.037528 -181.13248) (xy 413.030416 -181.138576)
			(xy 413.009486 -181.156217) (xy 412.963513 -181.18593) (xy 412.913765 -181.208766) (xy 412.861264 -181.224256)
			(xy 412.807087 -181.232083) (xy 412.779718 -181.232556) (xy 412.752469 -181.232005) (xy 412.698527 -181.224252)
			(xy 412.646236 -181.208902) (xy 412.596662 -181.186266) (xy 412.550814 -181.156807) (xy 412.509625 -181.121122)
			(xy 412.473933 -181.079939) (xy 412.444465 -181.034096) (xy 412.421821 -180.984526) (xy 412.406462 -180.932238)
			(xy 412.3987 -180.878297) (xy 412.39821 -180.851048) (xy 409.374655 -180.851048) (xy 409.377642 -180.93817)
			(xy 409.385008 -180.955442) (xy 409.39212 -180.962554) (xy 409.412923 -180.98415) (xy 409.448177 -181.032653)
			(xy 409.475406 -181.086074) (xy 409.49394 -181.143099) (xy 409.503322 -181.202321) (xy 409.50388 -181.232302)
			(xy 409.50342 -181.259673) (xy 409.495601 -181.313852) (xy 409.480111 -181.366355) (xy 409.457268 -181.416102)
			(xy 409.427542 -181.462069) (xy 409.4099 -181.483) (xy 409.403804 -181.490112) (xy 409.397454 -181.50713)
			(xy 409.397454 -181.592474) (xy 409.403804 -181.609492) (xy 409.4099 -181.616604) (xy 409.427542 -181.637536)
			(xy 409.457264 -181.683504) (xy 409.480108 -181.733251) (xy 409.495603 -181.785753) (xy 409.503431 -181.839931)
			(xy 409.50343 -181.894672) (xy 409.495602 -181.94885) (xy 409.480107 -182.001352) (xy 409.457263 -182.051098)
			(xy 409.42754 -182.097067) (xy 409.4099 -182.118) (xy 409.403804 -182.125112) (xy 409.397454 -182.14213)
			(xy 409.397454 -182.227474) (xy 409.403804 -182.244492) (xy 409.4099 -182.251604) (xy 409.427542 -182.272536)
			(xy 409.457264 -182.318504) (xy 409.480108 -182.368251) (xy 409.495603 -182.420753) (xy 409.503431 -182.474931)
			(xy 409.50343 -182.529672) (xy 409.495602 -182.58385) (xy 409.480107 -182.636352) (xy 409.457263 -182.686098)
			(xy 409.42754 -182.732067) (xy 409.4099 -182.753) (xy 409.403804 -182.760112) (xy 409.397454 -182.77713)
			(xy 409.397454 -182.862474) (xy 409.403804 -182.879492) (xy 409.4099 -182.886604) (xy 409.427554 -182.907524)
			(xy 409.457264 -182.9535) (xy 409.480097 -183.003251) (xy 409.495584 -183.055754) (xy 409.503408 -183.109932)
			(xy 409.50388 -183.137302) (xy 409.503376 -183.16622) (xy 409.494639 -183.223394) (xy 409.477365 -183.278591)
			(xy 409.451952 -183.330545) (xy 409.418982 -183.378065) (xy 409.399486 -183.39943) (xy 409.393136 -183.406288)
			(xy 409.386024 -183.422798) (xy 409.382722 -183.508396) (xy 409.38831 -183.525668) (xy 409.394152 -183.533034)
			(xy 409.410035 -183.553429) (xy 409.436709 -183.597709) (xy 409.457164 -183.645184) (xy 409.471023 -183.694985)
			(xy 409.478034 -183.746201) (xy 409.47848 -183.772048) (xy 409.478067 -183.799302) (xy 409.470303 -183.853253)
			(xy 409.45494 -183.905551) (xy 409.432292 -183.955131) (xy 409.402818 -184.000982) (xy 409.367119 -184.042172)
			(xy 409.325921 -184.077863) (xy 409.280064 -184.107328) (xy 409.23048 -184.129967) (xy 409.178179 -184.145319)
			(xy 409.124226 -184.153072) (xy 409.096972 -184.153556) (xy 409.067496 -184.152983) (xy 409.009243 -184.143924)
			(xy 408.953078 -184.126009) (xy 408.900339 -184.099667) (xy 408.85228 -184.065524) (xy 408.83078 -184.045352)
			(xy 408.823452 -184.038809) (xy 408.805286 -184.03137) (xy 408.795474 -184.030874) (xy 408.742134 -184.030874)
			(xy 408.735276 -184.03824) (xy 408.728728 -184.045564) (xy 408.721291 -184.063733) (xy 408.720798 -184.073546)
			(xy 408.720798 -184.10555) (xy 408.721268 -184.115366) (xy 408.728724 -184.13353) (xy 408.735276 -184.140856)
			(xy 408.755433 -184.16237) (xy 408.789579 -184.210426) (xy 408.815928 -184.263162) (xy 408.833853 -184.319323)
			(xy 408.842928 -184.377572) (xy 408.84348 -184.407048) (xy 408.843067 -184.434302) (xy 408.835303 -184.488253)
			(xy 408.81994 -184.540551) (xy 408.797292 -184.590131) (xy 408.767818 -184.635982) (xy 408.732119 -184.677172)
			(xy 408.690921 -184.712863) (xy 408.645064 -184.742328) (xy 408.59548 -184.764967) (xy 408.543179 -184.780319)
			(xy 408.489226 -184.788072) (xy 408.461972 -184.788556) (xy 408.432496 -184.787983) (xy 408.374243 -184.778924)
			(xy 408.318078 -184.761009) (xy 408.265339 -184.734667) (xy 408.21728 -184.700524) (xy 408.19578 -184.680352)
			(xy 408.188452 -184.673809) (xy 408.170286 -184.66637) (xy 408.160474 -184.665874) (xy 408.107134 -184.665874)
			(xy 408.100276 -184.67324) (xy 408.093728 -184.680564) (xy 408.086291 -184.698733) (xy 408.085798 -184.708546)
			(xy 408.085798 -184.74055) (xy 408.086268 -184.750366) (xy 408.093724 -184.76853) (xy 408.100276 -184.775856)
			(xy 408.120433 -184.79737) (xy 408.154579 -184.845426) (xy 408.180928 -184.898162) (xy 408.198853 -184.954323)
			(xy 408.207928 -185.012572) (xy 408.20848 -185.042048) (xy 408.207994 -185.069299) (xy 408.200238 -185.123247)
			(xy 408.184883 -185.175542) (xy 408.162241 -185.225119) (xy 408.132775 -185.270969) (xy 408.097084 -185.31216)
			(xy 408.055893 -185.347851) (xy 408.010043 -185.377317) (xy 407.960466 -185.399959) (xy 407.908171 -185.415314)
			(xy 407.854223 -185.42307) (xy 407.799721 -185.42307) (xy 407.745773 -185.415314) (xy 407.693478 -185.399959)
			(xy 407.643901 -185.377317) (xy 407.598051 -185.347851) (xy 407.55686 -185.31216) (xy 407.521169 -185.270969)
			(xy 407.491703 -185.225119) (xy 407.469061 -185.175542) (xy 407.453706 -185.123247) (xy 407.44595 -185.069299)
			(xy 407.445464 -185.042048) (xy 405.431845 -185.042048) (xy 405.431843 -185.069409) (xy 405.424009 -185.123591)
			(xy 405.408506 -185.176096) (xy 405.385655 -185.225844) (xy 405.355924 -185.271813) (xy 405.33828 -185.292746)
			(xy 405.332184 -185.299858) (xy 405.325834 -185.316876) (xy 405.325834 -185.40222) (xy 405.332184 -185.419238)
			(xy 405.33828 -185.42635) (xy 405.355967 -185.447245) (xy 405.38569 -185.493219) (xy 405.408532 -185.542972)
			(xy 405.424024 -185.59548) (xy 405.431848 -185.649663) (xy 405.431843 -185.704409) (xy 405.424009 -185.758591)
			(xy 405.408506 -185.811096) (xy 405.385655 -185.860844) (xy 405.355924 -185.906813) (xy 405.33828 -185.927746)
			(xy 405.332184 -185.934858) (xy 405.325834 -185.951876) (xy 405.325834 -186.03722) (xy 405.332184 -186.054238)
			(xy 405.33828 -186.06135) (xy 405.355967 -186.082245) (xy 405.38569 -186.128219) (xy 405.408532 -186.177972)
			(xy 405.424024 -186.23048) (xy 405.431848 -186.284663) (xy 405.431843 -186.339409) (xy 405.424009 -186.393591)
			(xy 405.408506 -186.446096) (xy 405.385655 -186.495844) (xy 405.355924 -186.541813) (xy 405.33828 -186.562746)
			(xy 405.332184 -186.569858) (xy 405.325834 -186.586876) (xy 405.325834 -186.67222) (xy 405.332184 -186.689238)
			(xy 405.33828 -186.69635) (xy 405.355906 -186.717293) (xy 405.38562 -186.763262) (xy 405.408459 -186.813007)
			(xy 405.423953 -186.865505) (xy 405.431785 -186.91968) (xy 405.43226 -186.947048) (xy 405.431867 -186.974303)
			(xy 405.424102 -187.028256) (xy 405.408739 -187.080556) (xy 405.386089 -187.130136) (xy 405.356613 -187.175989)
			(xy 405.320912 -187.21718) (xy 405.279712 -187.25287) (xy 405.233852 -187.282335) (xy 405.184265 -187.304972)
			(xy 405.131962 -187.320323) (xy 405.078007 -187.328074) (xy 405.050752 -187.328556) (xy 405.023382 -187.32807)
			(xy 404.969204 -187.320259) (xy 404.9167 -187.304775) (xy 404.866953 -187.281937) (xy 404.820986 -187.252216)
			(xy 404.800054 -187.234576) (xy 404.792942 -187.22848) (xy 404.775924 -187.22213) (xy 404.69058 -187.22213)
			(xy 404.673562 -187.22848) (xy 404.66645 -187.234576) (xy 404.645507 -187.252201) (xy 404.599537 -187.281916)
			(xy 404.549793 -187.304755) (xy 404.497294 -187.320249) (xy 404.44312 -187.328081) (xy 404.415752 -187.328556)
			(xy 404.388502 -187.328067) (xy 404.334557 -187.320305) (xy 404.282265 -187.304946) (xy 404.232691 -187.282303)
			(xy 404.186843 -187.252836) (xy 404.145654 -187.217146) (xy 404.109964 -187.175957) (xy 404.080497 -187.130109)
			(xy 404.057854 -187.080535) (xy 404.042495 -187.028243) (xy 404.034733 -186.974298) (xy 404.034244 -186.947048)
			(xy 394.633809 -186.947048) (xy 394.004038 -187.576968) (xy 393.982437 -187.597766) (xy 393.933937 -187.633022)
			(xy 393.880516 -187.660253) (xy 393.823492 -187.678788) (xy 393.76427 -187.688171) (xy 393.73429 -187.688728)
			(xy 390.9187 -187.688728) (xy 390.908657 -187.689116) (xy 390.89006 -187.696692) (xy 390.882632 -187.70346)
			(xy 390.368028 -188.218318) (xy 390.346409 -188.239079) (xy 390.297891 -188.274267) (xy 390.244467 -188.301436)
			(xy 390.187452 -188.319916) (xy 390.128248 -188.329254) (xy 390.09828 -188.329824) (xy 385.561078 -188.329824)
			(xy 385.531107 -188.329259) (xy 385.471894 -188.319947) (xy 385.41487 -188.301478) (xy 385.361442 -188.274307)
			(xy 385.312927 -188.239105) (xy 385.29133 -188.218318) (xy 385.088892 -188.01588) (xy 385.081531 -188.009111)
			(xy 385.063069 -188.001464) (xy 385.043087 -188.001464) (xy 385.024625 -188.009111) (xy 385.017264 -188.01588)
			(xy 384.822446 -188.210698) (xy 384.800832 -188.231464) (xy 384.752311 -188.266649) (xy 384.698885 -188.293815)
			(xy 384.64187 -188.312294) (xy 384.582666 -188.321633) (xy 384.552698 -188.322204) (xy 377.3424 -188.322204)
			(xy 377.312427 -188.321694) (xy 377.253211 -188.31237) (xy 377.196186 -188.293888) (xy 377.142759 -188.266705)
			(xy 377.094247 -188.231491) (xy 377.072652 -188.210698) (xy 376.910092 -188.048138) (xy 376.902731 -188.041369)
			(xy 376.884269 -188.033722) (xy 376.864287 -188.033722) (xy 376.845825 -188.041369) (xy 376.838464 -188.048138)
			(xy 376.675904 -188.210698) (xy 376.654265 -188.231436) (xy 376.60575 -188.266624) (xy 376.552331 -188.293796)
			(xy 376.495321 -188.312282) (xy 376.436122 -188.321629) (xy 376.406156 -188.322204) (xy 369.426998 -188.322204)
			(xy 369.397025 -188.321695) (xy 369.337809 -188.312371) (xy 369.280784 -188.293889) (xy 369.227357 -188.266705)
			(xy 369.178845 -188.231491) (xy 369.15725 -188.210698) (xy 367.72723 -186.780678) (xy 367.706484 -186.759045)
			(xy 367.671296 -186.71053) (xy 367.644125 -186.657109) (xy 367.625641 -186.600097) (xy 367.616297 -186.540897)
			(xy 367.615724 -186.51093) (xy 367.615724 -183.13146) (xy 367.61534 -183.121386) (xy 367.607592 -183.102787)
			(xy 367.600738 -183.095392) (xy 367.554256 -183.04891) (xy 367.546864 -183.042059) (xy 367.528259 -183.034345)
			(xy 367.518188 -183.033924) (xy 360.785918 -183.033924) (xy 360.755946 -183.033397) (xy 360.696731 -183.024076)
			(xy 360.639706 -183.005598) (xy 360.586279 -182.978419) (xy 360.537766 -182.943209) (xy 360.51617 -182.922418)
			(xy 358.36987 -180.776118) (xy 358.349102 -180.754505) (xy 358.313915 -180.705985) (xy 358.286748 -180.652559)
			(xy 358.268269 -180.595543) (xy 358.258933 -180.536338) (xy 358.258364 -180.50637) (xy 358.258364 -174.832264)
			(xy 358.257943 -174.822236) (xy 358.250302 -174.803697) (xy 358.236126 -174.789514) (xy 358.217591 -174.781863)
			(xy 358.207564 -174.781464) (xy 352.231198 -174.781464) (xy 352.201224 -174.780966) (xy 352.142008 -174.771641)
			(xy 352.084982 -174.753156) (xy 352.031555 -174.72597) (xy 351.983044 -174.690752) (xy 351.96145 -174.669958)
			(xy 349.35033 -172.058838) (xy 349.329565 -172.037223) (xy 349.294379 -171.988702) (xy 349.267212 -171.935277)
			(xy 349.248733 -171.878262) (xy 349.239394 -171.819058) (xy 349.238824 -171.78909) (xy 340.684104 -171.78909)
			(xy 340.684104 -171.860718) (xy 340.691724 -171.879006) (xy 340.698582 -171.886118) (xy 340.718769 -171.907605)
			(xy 340.752911 -171.955668) (xy 340.779254 -172.008411) (xy 340.797172 -172.064578) (xy 340.806238 -172.122832)
			(xy 340.806786 -172.15231) (xy 340.8063 -172.179561) (xy 340.798544 -172.233509) (xy 340.783189 -172.285804)
			(xy 340.760547 -172.335381) (xy 340.731081 -172.381231) (xy 340.69539 -172.422422) (xy 340.654199 -172.458113)
			(xy 340.608349 -172.487579) (xy 340.558772 -172.510221) (xy 340.506477 -172.525576) (xy 340.452529 -172.533332)
			(xy 340.398027 -172.533332) (xy 340.344079 -172.525576) (xy 340.291784 -172.510221) (xy 340.242207 -172.487579)
			(xy 340.196357 -172.458113) (xy 340.155166 -172.422422) (xy 340.119475 -172.381231) (xy 340.090009 -172.335381)
			(xy 340.067367 -172.285804) (xy 340.052012 -172.233509) (xy 340.044256 -172.179561) (xy 340.04377 -172.15231)
			(xy 337.824318 -172.15231) (xy 338.79155 -173.119542) (xy 344.660982 -173.119542) (xy 344.661494 -173.092291)
			(xy 344.669245 -173.038342) (xy 344.684596 -172.986046) (xy 344.707232 -172.936466) (xy 344.736695 -172.890613)
			(xy 344.772384 -172.849421) (xy 344.813572 -172.813726) (xy 344.859421 -172.784257) (xy 344.908997 -172.761614)
			(xy 344.961291 -172.746256) (xy 345.015239 -172.738498) (xy 345.04249 -172.738034) (xy 345.06986 -172.738498)
			(xy 345.12404 -172.746315) (xy 345.176543 -172.761804) (xy 345.22629 -172.784646) (xy 345.272257 -172.814372)
			(xy 345.293188 -172.832014) (xy 345.3003 -172.83811) (xy 345.317318 -172.84446) (xy 345.402662 -172.84446)
			(xy 345.41968 -172.83811) (xy 345.426792 -172.832014) (xy 345.447725 -172.814373) (xy 345.493693 -172.784649)
			(xy 345.543439 -172.761803) (xy 345.595941 -172.746307) (xy 345.650119 -172.738478) (xy 345.704861 -172.738478)
			(xy 345.759039 -172.746307) (xy 345.811541 -172.761803) (xy 345.861287 -172.784649) (xy 345.907255 -172.814373)
			(xy 345.928188 -172.832014) (xy 345.9353 -172.83811) (xy 345.952318 -172.84446) (xy 346.037662 -172.84446)
			(xy 346.05468 -172.83811) (xy 346.061792 -172.832014) (xy 346.082718 -172.814367) (xy 346.128692 -172.784656)
			(xy 346.178441 -172.761821) (xy 346.230943 -172.746332) (xy 346.28512 -172.738507) (xy 346.31249 -172.738034)
			(xy 346.339745 -172.738465) (xy 346.393699 -172.746221) (xy 346.446 -172.761578) (xy 346.495583 -172.784223)
			(xy 346.541438 -172.813694) (xy 346.582632 -172.849391) (xy 346.618326 -172.890588) (xy 346.647793 -172.936445)
			(xy 346.670433 -172.98603) (xy 346.685785 -173.038333) (xy 346.693538 -173.092287) (xy 346.693998 -173.119542)
			(xy 348.676722 -173.119542) (xy 348.677194 -173.092289) (xy 348.684946 -173.038337) (xy 348.700299 -172.986037)
			(xy 348.722939 -172.936455) (xy 348.752405 -172.8906) (xy 348.788098 -172.849406) (xy 348.829291 -172.813712)
			(xy 348.875145 -172.784244) (xy 348.924726 -172.761603) (xy 348.977025 -172.746249) (xy 349.030977 -172.738495)
			(xy 349.05823 -172.738034) (xy 349.085601 -172.738474) (xy 349.139782 -172.746297) (xy 349.192286 -172.761792)
			(xy 349.242032 -172.784639) (xy 349.287997 -172.81437) (xy 349.308928 -172.832014) (xy 349.31604 -172.83811)
			(xy 349.333058 -172.84446) (xy 349.418402 -172.84446) (xy 349.43542 -172.83811) (xy 349.442532 -172.832014)
			(xy 349.463481 -172.814396) (xy 349.509449 -172.78468) (xy 349.559192 -172.76184) (xy 349.611689 -172.746344)
			(xy 349.665862 -172.738511) (xy 349.69323 -172.738034) (xy 349.720486 -172.738427) (xy 349.774441 -172.746189)
			(xy 349.826743 -172.761551) (xy 349.876326 -172.7842) (xy 349.922181 -172.813675) (xy 349.963375 -172.849376)
			(xy 349.999068 -172.890577) (xy 350.028534 -172.936437) (xy 350.051174 -172.986025) (xy 350.066526 -173.038329)
			(xy 350.074278 -173.092286) (xy 350.074738 -173.119542) (xy 350.074268 -173.146676) (xy 350.066578 -173.200397)
			(xy 350.051347 -173.252484) (xy 350.028882 -173.301884) (xy 349.999636 -173.347598) (xy 349.982282 -173.368462)
			(xy 349.976186 -173.375574) (xy 349.97009 -173.392592) (xy 349.970598 -173.477936) (xy 349.976948 -173.494954)
			(xy 349.983298 -173.502066) (xy 350.001209 -173.523076) (xy 350.031401 -173.569298) (xy 350.054614 -173.61939)
			(xy 350.070362 -173.672305) (xy 350.078316 -173.726938) (xy 350.078802 -173.754542) (xy 350.078301 -173.781911)
			(xy 350.070492 -173.836089) (xy 350.055011 -173.888591) (xy 350.032177 -173.938339) (xy 350.00246 -173.984307)
			(xy 349.984822 -174.00524) (xy 349.978726 -174.012352) (xy 349.972376 -174.02937) (xy 349.972376 -174.114714)
			(xy 349.978726 -174.131732) (xy 349.984822 -174.138844) (xy 350.002502 -174.159744) (xy 350.032221 -174.205719)
			(xy 350.055061 -174.255471) (xy 350.070552 -174.307977) (xy 350.078376 -174.36216) (xy 350.078371 -174.416904)
			(xy 350.070538 -174.471084) (xy 350.055039 -174.523588) (xy 350.032191 -174.573337) (xy 350.002464 -174.619306)
			(xy 349.984822 -174.64024) (xy 349.978726 -174.647352) (xy 349.972376 -174.66437) (xy 349.972376 -174.749714)
			(xy 349.978726 -174.766732) (xy 349.984822 -174.773844) (xy 350.002502 -174.794744) (xy 350.032221 -174.840719)
			(xy 350.055061 -174.890471) (xy 350.070552 -174.942977) (xy 350.078376 -174.99716) (xy 350.078371 -175.051904)
			(xy 350.070538 -175.106084) (xy 350.055039 -175.158588) (xy 350.032191 -175.208337) (xy 350.002464 -175.254306)
			(xy 349.984822 -175.27524) (xy 349.978726 -175.282352) (xy 349.972376 -175.29937) (xy 349.972376 -175.384714)
			(xy 349.978726 -175.401732) (xy 349.984822 -175.408844) (xy 350.002452 -175.429784) (xy 350.032164 -175.475755)
			(xy 350.055002 -175.5255) (xy 350.070495 -175.577999) (xy 350.078326 -175.632173) (xy 350.078802 -175.659542)
			(xy 350.078284 -175.687972) (xy 350.069834 -175.744201) (xy 350.053128 -175.798551) (xy 350.028537 -175.849818)
			(xy 349.996606 -175.896866) (xy 349.97771 -175.918114) (xy 349.97136 -175.925226) (xy 349.964502 -175.942752)
			(xy 349.964502 -176.031144) (xy 349.97136 -176.04867) (xy 349.97771 -176.055782) (xy 349.996627 -176.077012)
			(xy 350.028557 -176.124063) (xy 350.053144 -176.175335) (xy 350.069842 -176.22969) (xy 350.07828 -176.285923)
			(xy 350.078802 -176.314354) (xy 350.078308 -176.341723) (xy 350.070497 -176.395901) (xy 350.055015 -176.448404)
			(xy 350.032179 -176.498151) (xy 350.00246 -176.544119) (xy 349.984822 -176.565052) (xy 349.978726 -176.572164)
			(xy 349.972376 -176.589182) (xy 349.972376 -176.674526) (xy 349.978726 -176.691544) (xy 349.984822 -176.698656)
			(xy 350.002416 -176.719626) (xy 350.032139 -176.765589) (xy 350.054984 -176.815329) (xy 350.070481 -176.867825)
			(xy 350.078313 -176.921998) (xy 350.078318 -176.976733) (xy 350.070496 -177.030907) (xy 350.055008 -177.083406)
			(xy 350.032172 -177.13315) (xy 350.002457 -177.179118) (xy 349.984822 -177.200052) (xy 349.978726 -177.207164)
			(xy 349.972376 -177.224182) (xy 349.972376 -177.309526) (xy 349.978726 -177.326544) (xy 349.984822 -177.333656)
			(xy 350.002416 -177.354626) (xy 350.032139 -177.400589) (xy 350.054984 -177.450329) (xy 350.070481 -177.502825)
			(xy 350.078313 -177.556998) (xy 350.078318 -177.611733) (xy 350.070496 -177.665907) (xy 350.055008 -177.718406)
			(xy 350.032172 -177.76815) (xy 350.002457 -177.814118) (xy 349.984822 -177.835052) (xy 349.978726 -177.842164)
			(xy 349.972376 -177.859182) (xy 349.972376 -177.944526) (xy 349.978726 -177.961544) (xy 349.984822 -177.968656)
			(xy 350.002416 -177.989626) (xy 350.032139 -178.035589) (xy 350.054984 -178.085329) (xy 350.070481 -178.137825)
			(xy 350.078313 -178.191998) (xy 350.078318 -178.246733) (xy 350.070496 -178.300907) (xy 350.055008 -178.353406)
			(xy 350.032172 -178.40315) (xy 350.002457 -178.449118) (xy 349.984822 -178.470052) (xy 349.978726 -178.477164)
			(xy 349.972376 -178.494182) (xy 349.972376 -178.579526) (xy 349.978726 -178.596544) (xy 349.984822 -178.603656)
			(xy 350.002416 -178.624626) (xy 350.032139 -178.670589) (xy 350.054984 -178.720329) (xy 350.070481 -178.772825)
			(xy 350.078313 -178.826998) (xy 350.078318 -178.881733) (xy 350.070496 -178.935907) (xy 350.055008 -178.988406)
			(xy 350.032172 -179.03815) (xy 350.002457 -179.084118) (xy 349.984822 -179.105052) (xy 349.978726 -179.112164)
			(xy 349.972376 -179.129182) (xy 349.972376 -179.214526) (xy 349.978726 -179.231544) (xy 349.984822 -179.238656)
			(xy 350.002457 -179.259591) (xy 350.032169 -179.305563) (xy 350.055005 -179.35531) (xy 350.070497 -179.40781)
			(xy 350.078327 -179.461985) (xy 350.078802 -179.489354) (xy 350.078302 -179.516606) (xy 350.070551 -179.570556)
			(xy 350.055201 -179.622853) (xy 350.032563 -179.672434) (xy 350.003099 -179.718287) (xy 349.967409 -179.759481)
			(xy 349.92622 -179.795175) (xy 349.880369 -179.824644) (xy 349.830791 -179.847287) (xy 349.778495 -179.862643)
			(xy 349.724546 -179.870399) (xy 349.697294 -179.870862) (xy 349.669923 -179.870409) (xy 349.615743 -179.862589)
			(xy 349.56324 -179.847098) (xy 349.513493 -179.824253) (xy 349.467527 -179.794525) (xy 349.446596 -179.776882)
			(xy 349.439484 -179.770786) (xy 349.422466 -179.764436) (xy 349.337122 -179.764436) (xy 349.320104 -179.770786)
			(xy 349.312992 -179.776882) (xy 349.292071 -179.794536) (xy 349.246096 -179.824246) (xy 349.196345 -179.847079)
			(xy 349.143842 -179.862567) (xy 349.089664 -179.870391) (xy 349.062294 -179.870862) (xy 349.035039 -179.87045)
			(xy 348.981084 -179.862691) (xy 348.928782 -179.847332) (xy 348.879199 -179.824685) (xy 348.833344 -179.795213)
			(xy 348.79215 -179.759513) (xy 348.756456 -179.718315) (xy 348.72699 -179.672455) (xy 348.70435 -179.622869)
			(xy 348.688998 -179.570565) (xy 348.681246 -179.516609) (xy 348.680786 -179.489354) (xy 348.681287 -179.461985)
			(xy 348.689097 -179.407808) (xy 348.704578 -179.355305) (xy 348.727412 -179.305558) (xy 348.757129 -179.259589)
			(xy 348.774766 -179.238656) (xy 348.780862 -179.231544) (xy 348.787212 -179.214526) (xy 348.787212 -179.129182)
			(xy 348.780862 -179.112164) (xy 348.774766 -179.105052) (xy 348.757079 -179.084157) (xy 348.727353 -179.038183)
			(xy 348.704508 -178.988431) (xy 348.689013 -178.935923) (xy 348.681188 -178.881739) (xy 348.681193 -178.826992)
			(xy 348.689028 -178.772809) (xy 348.704532 -178.720304) (xy 348.727386 -178.670556) (xy 348.75712 -178.624588)
			(xy 348.774766 -178.603656) (xy 348.780862 -178.596544) (xy 348.787212 -178.579526) (xy 348.787212 -178.494182)
			(xy 348.780862 -178.477164) (xy 348.774766 -178.470052) (xy 348.757079 -178.449157) (xy 348.727353 -178.403183)
			(xy 348.704508 -178.353431) (xy 348.689013 -178.300923) (xy 348.681188 -178.246739) (xy 348.681193 -178.191992)
			(xy 348.689028 -178.137809) (xy 348.704532 -178.085304) (xy 348.727386 -178.035556) (xy 348.75712 -177.989588)
			(xy 348.774766 -177.968656) (xy 348.780862 -177.961544) (xy 348.787212 -177.944526) (xy 348.787212 -177.859182)
			(xy 348.780862 -177.842164) (xy 348.774766 -177.835052) (xy 348.757079 -177.814157) (xy 348.727353 -177.768183)
			(xy 348.704508 -177.718431) (xy 348.689013 -177.665923) (xy 348.681188 -177.611739) (xy 348.681193 -177.556992)
			(xy 348.689028 -177.502809) (xy 348.704532 -177.450304) (xy 348.727386 -177.400556) (xy 348.75712 -177.354588)
			(xy 348.774766 -177.333656) (xy 348.780862 -177.326544) (xy 348.787212 -177.309526) (xy 348.787212 -177.224182)
			(xy 348.780862 -177.207164) (xy 348.774766 -177.200052) (xy 348.757079 -177.179157) (xy 348.727353 -177.133183)
			(xy 348.704508 -177.083431) (xy 348.689013 -177.030923) (xy 348.681188 -176.976739) (xy 348.681193 -176.921992)
			(xy 348.689028 -176.867809) (xy 348.704532 -176.815304) (xy 348.727386 -176.765556) (xy 348.75712 -176.719588)
			(xy 348.774766 -176.698656) (xy 348.780862 -176.691544) (xy 348.787212 -176.674526) (xy 348.787212 -176.589182)
			(xy 348.780862 -176.572164) (xy 348.774766 -176.565052) (xy 348.757133 -176.544116) (xy 348.727421 -176.498143)
			(xy 348.704585 -176.448397) (xy 348.689092 -176.395897) (xy 348.681262 -176.341723) (xy 348.680786 -176.314354)
			(xy 348.681305 -176.285924) (xy 348.689755 -176.229696) (xy 348.706461 -176.175345) (xy 348.731052 -176.124078)
			(xy 348.762983 -176.07703) (xy 348.781878 -176.055782) (xy 348.788228 -176.04867) (xy 348.795086 -176.031144)
			(xy 348.795086 -175.942752) (xy 348.788228 -175.925226) (xy 348.781878 -175.918114) (xy 348.762957 -175.896887)
			(xy 348.731028 -175.849835) (xy 348.706442 -175.798562) (xy 348.689745 -175.744206) (xy 348.681307 -175.687973)
			(xy 348.680786 -175.659542) (xy 348.68128 -175.632173) (xy 348.689092 -175.577995) (xy 348.704574 -175.525492)
			(xy 348.72741 -175.475745) (xy 348.757128 -175.429777) (xy 348.774766 -175.408844) (xy 348.780862 -175.401732)
			(xy 348.787212 -175.384714) (xy 348.787212 -175.29937) (xy 348.780862 -175.282352) (xy 348.774766 -175.27524)
			(xy 348.757165 -175.254275) (xy 348.727435 -175.208314) (xy 348.704585 -175.158573) (xy 348.689084 -175.106075)
			(xy 348.681251 -175.051901) (xy 348.681246 -174.997163) (xy 348.68907 -174.942986) (xy 348.704563 -174.890486)
			(xy 348.727405 -174.840742) (xy 348.757127 -174.794776) (xy 348.774766 -174.773844) (xy 348.780862 -174.766732)
			(xy 348.787212 -174.749714) (xy 348.787212 -174.66437) (xy 348.780862 -174.647352) (xy 348.774766 -174.64024)
			(xy 348.757165 -174.619275) (xy 348.727435 -174.573314) (xy 348.704585 -174.523573) (xy 348.689084 -174.471075)
			(xy 348.681251 -174.416901) (xy 348.681246 -174.362163) (xy 348.68907 -174.307986) (xy 348.704563 -174.255486)
			(xy 348.727405 -174.205742) (xy 348.757127 -174.159776) (xy 348.774766 -174.138844) (xy 348.780862 -174.131732)
			(xy 348.787212 -174.114714) (xy 348.787212 -174.02937) (xy 348.780862 -174.012352) (xy 348.774766 -174.00524)
			(xy 348.757127 -173.984308) (xy 348.727416 -173.938335) (xy 348.704581 -173.888587) (xy 348.68909 -173.836087)
			(xy 348.681261 -173.781911) (xy 348.680786 -173.754542) (xy 348.681241 -173.727407) (xy 348.688933 -173.673686)
			(xy 348.704168 -173.621598) (xy 348.726637 -173.572199) (xy 348.755886 -173.526486) (xy 348.773242 -173.505622)
			(xy 348.779338 -173.49851) (xy 348.785434 -173.481492) (xy 348.784926 -173.396148) (xy 348.778576 -173.37913)
			(xy 348.772226 -173.372018) (xy 348.754296 -173.351024) (xy 348.724109 -173.304797) (xy 348.700901 -173.254701)
			(xy 348.685157 -173.201782) (xy 348.677207 -173.147147) (xy 348.676722 -173.119542) (xy 346.693998 -173.119542)
			(xy 346.693551 -173.146512) (xy 346.685939 -173.199914) (xy 346.670874 -173.251708) (xy 346.648657 -173.300861)
			(xy 346.619731 -173.34639) (xy 346.602558 -173.367192) (xy 346.596462 -173.374304) (xy 346.590366 -173.391322)
			(xy 346.591128 -173.47692) (xy 346.597732 -173.493684) (xy 346.604082 -173.500796) (xy 346.622136 -173.521899)
			(xy 346.652648 -173.568299) (xy 346.676116 -173.618629) (xy 346.692045 -173.671829) (xy 346.700099 -173.726775)
			(xy 346.700602 -173.754542) (xy 346.700101 -173.781911) (xy 346.692292 -173.836089) (xy 346.676811 -173.888591)
			(xy 346.653977 -173.938339) (xy 346.62426 -173.984307) (xy 346.606622 -174.00524) (xy 346.600526 -174.012352)
			(xy 346.594176 -174.02937) (xy 346.594176 -174.114714) (xy 346.600526 -174.131732) (xy 346.606622 -174.138844)
			(xy 346.624302 -174.159744) (xy 346.654021 -174.205719) (xy 346.676861 -174.255471) (xy 346.692352 -174.307977)
			(xy 346.700176 -174.36216) (xy 346.700171 -174.416904) (xy 346.692338 -174.471084) (xy 346.676839 -174.523588)
			(xy 346.653991 -174.573337) (xy 346.624264 -174.619306) (xy 346.606622 -174.64024) (xy 346.600526 -174.647352)
			(xy 346.594176 -174.66437) (xy 346.594176 -174.749714) (xy 346.600526 -174.766732) (xy 346.606622 -174.773844)
			(xy 346.624302 -174.794744) (xy 346.654021 -174.840719) (xy 346.676861 -174.890471) (xy 346.692352 -174.942977)
			(xy 346.700176 -174.99716) (xy 346.700171 -175.051904) (xy 346.692338 -175.106084) (xy 346.676839 -175.158588)
			(xy 346.653991 -175.208337) (xy 346.624264 -175.254306) (xy 346.606622 -175.27524) (xy 346.600526 -175.282352)
			(xy 346.594176 -175.29937) (xy 346.594176 -175.384714) (xy 346.600526 -175.401732) (xy 346.606622 -175.408844)
			(xy 346.624252 -175.429784) (xy 346.653964 -175.475755) (xy 346.676802 -175.5255) (xy 346.692295 -175.577999)
			(xy 346.700126 -175.632173) (xy 346.700602 -175.659542) (xy 346.700084 -175.687972) (xy 346.691634 -175.744201)
			(xy 346.674928 -175.798551) (xy 346.650337 -175.849818) (xy 346.618406 -175.896866) (xy 346.59951 -175.918114)
			(xy 346.59316 -175.925226) (xy 346.586302 -175.942752) (xy 346.586302 -176.031144) (xy 346.59316 -176.04867)
			(xy 346.59951 -176.055782) (xy 346.618427 -176.077012) (xy 346.650357 -176.124063) (xy 346.674944 -176.175335)
			(xy 346.691642 -176.22969) (xy 346.70008 -176.285923) (xy 346.700602 -176.314354) (xy 346.700108 -176.341723)
			(xy 346.692297 -176.395901) (xy 346.676815 -176.448404) (xy 346.653979 -176.498151) (xy 346.62426 -176.544119)
			(xy 346.606622 -176.565052) (xy 346.600526 -176.572164) (xy 346.594176 -176.589182) (xy 346.594176 -176.674526)
			(xy 346.600526 -176.691544) (xy 346.606622 -176.698656) (xy 346.624216 -176.719626) (xy 346.653939 -176.765589)
			(xy 346.676784 -176.815329) (xy 346.692281 -176.867825) (xy 346.700113 -176.921998) (xy 346.700118 -176.976733)
			(xy 346.692296 -177.030907) (xy 346.676808 -177.083406) (xy 346.653972 -177.13315) (xy 346.624257 -177.179118)
			(xy 346.606622 -177.200052) (xy 346.600526 -177.207164) (xy 346.594176 -177.224182) (xy 346.594176 -177.309526)
			(xy 346.600526 -177.326544) (xy 346.606622 -177.333656) (xy 346.624257 -177.354591) (xy 346.653969 -177.400563)
			(xy 346.676805 -177.45031) (xy 346.692297 -177.50281) (xy 346.700127 -177.556985) (xy 346.700602 -177.584354)
			(xy 346.700116 -177.611605) (xy 346.69236 -177.665553) (xy 346.677005 -177.717848) (xy 346.654363 -177.767425)
			(xy 346.624897 -177.813275) (xy 346.589206 -177.854466) (xy 346.548015 -177.890157) (xy 346.502165 -177.919623)
			(xy 346.452588 -177.942265) (xy 346.400293 -177.95762) (xy 346.346345 -177.965376) (xy 346.291843 -177.965376)
			(xy 346.237895 -177.95762) (xy 346.1856 -177.942265) (xy 346.136023 -177.919623) (xy 346.090173 -177.890157)
			(xy 346.048982 -177.854466) (xy 346.013291 -177.813275) (xy 345.983825 -177.767425) (xy 345.961183 -177.717848)
			(xy 345.945828 -177.665553) (xy 345.938072 -177.611605) (xy 345.937586 -177.584354) (xy 345.938163 -177.554878)
			(xy 345.947224 -177.496627) (xy 345.965138 -177.440462) (xy 345.991479 -177.387723) (xy 346.025619 -177.339663)
			(xy 346.04579 -177.318162) (xy 346.052333 -177.310834) (xy 346.059774 -177.292669) (xy 346.060268 -177.282856)
			(xy 346.060268 -177.229516) (xy 346.052902 -177.222658) (xy 346.045566 -177.216125) (xy 346.027406 -177.20868)
			(xy 346.017596 -177.20818) (xy 345.985592 -177.20818) (xy 345.975779 -177.208677) (xy 345.957615 -177.216115)
			(xy 345.950286 -177.222658) (xy 345.928793 -177.242839) (xy 345.880732 -177.276983) (xy 345.827991 -177.303328)
			(xy 345.771825 -177.321247) (xy 345.713571 -177.330314) (xy 345.684094 -177.330862) (xy 345.656839 -177.33045)
			(xy 345.602884 -177.322691) (xy 345.550582 -177.307332) (xy 345.500999 -177.284685) (xy 345.455144 -177.255213)
			(xy 345.41395 -177.219513) (xy 345.378256 -177.178315) (xy 345.34879 -177.132455) (xy 345.32615 -177.082869)
			(xy 345.310798 -177.030565) (xy 345.303046 -176.976609) (xy 345.302586 -176.949354) (xy 345.303163 -176.919878)
			(xy 345.312224 -176.861627) (xy 345.330138 -176.805462) (xy 345.356479 -176.752723) (xy 345.390619 -176.704663)
			(xy 345.41079 -176.683162) (xy 345.417333 -176.675834) (xy 345.424774 -176.657669) (xy 345.425268 -176.647856)
			(xy 345.425268 -176.594516) (xy 345.417902 -176.587658) (xy 345.410566 -176.581125) (xy 345.392406 -176.57368)
			(xy 345.382596 -176.57318) (xy 345.350592 -176.57318) (xy 345.340779 -176.573677) (xy 345.322615 -176.581115)
			(xy 345.315286 -176.587658) (xy 345.293793 -176.607839) (xy 345.245732 -176.641983) (xy 345.192991 -176.668328)
			(xy 345.136825 -176.686247) (xy 345.078571 -176.695314) (xy 345.049094 -176.695862) (xy 345.021839 -176.69545)
			(xy 344.967884 -176.687691) (xy 344.915582 -176.672332) (xy 344.865999 -176.649685) (xy 344.820144 -176.620213)
			(xy 344.77895 -176.584513) (xy 344.743256 -176.543315) (xy 344.71379 -176.497455) (xy 344.69115 -176.447869)
			(xy 344.675798 -176.395565) (xy 344.668046 -176.341609) (xy 344.667586 -176.314354) (xy 344.668087 -176.286985)
			(xy 344.675897 -176.232808) (xy 344.691378 -176.180305) (xy 344.714212 -176.130558) (xy 344.743929 -176.084589)
			(xy 344.761566 -176.063656) (xy 344.767662 -176.056544) (xy 344.774012 -176.039526) (xy 344.774012 -175.954182)
			(xy 344.767662 -175.937164) (xy 344.761566 -175.930052) (xy 344.743879 -175.909157) (xy 344.714153 -175.863183)
			(xy 344.691308 -175.813431) (xy 344.675813 -175.760923) (xy 344.667988 -175.706739) (xy 344.667993 -175.651992)
			(xy 344.675828 -175.597809) (xy 344.691332 -175.545304) (xy 344.714186 -175.495556) (xy 344.74392 -175.449588)
			(xy 344.761566 -175.428656) (xy 344.767662 -175.421544) (xy 344.774012 -175.404526) (xy 344.774012 -175.319182)
			(xy 344.767662 -175.302164) (xy 344.761566 -175.295052) (xy 344.743879 -175.274157) (xy 344.714153 -175.228183)
			(xy 344.691308 -175.178431) (xy 344.675813 -175.125923) (xy 344.667988 -175.071739) (xy 344.667993 -175.016992)
			(xy 344.675828 -174.962809) (xy 344.691332 -174.910304) (xy 344.714186 -174.860556) (xy 344.74392 -174.814588)
			(xy 344.761566 -174.793656) (xy 344.767662 -174.786544) (xy 344.774012 -174.769526) (xy 344.774012 -174.684182)
			(xy 344.767662 -174.667164) (xy 344.761566 -174.660052) (xy 344.743879 -174.639157) (xy 344.714153 -174.593183)
			(xy 344.691308 -174.543431) (xy 344.675813 -174.490923) (xy 344.667988 -174.436739) (xy 344.667993 -174.381992)
			(xy 344.675828 -174.327809) (xy 344.691332 -174.275304) (xy 344.714186 -174.225556) (xy 344.74392 -174.179588)
			(xy 344.761566 -174.158656) (xy 344.767662 -174.151544) (xy 344.774012 -174.134526) (xy 344.774012 -174.049182)
			(xy 344.767662 -174.032164) (xy 344.761566 -174.025052) (xy 344.743933 -174.004116) (xy 344.714221 -173.958143)
			(xy 344.691385 -173.908397) (xy 344.675892 -173.855897) (xy 344.668062 -173.801723) (xy 344.667586 -173.774354)
			(xy 344.66805 -173.746313) (xy 344.676258 -173.690833) (xy 344.69249 -173.637151) (xy 344.716399 -173.586419)
			(xy 344.747469 -173.539729) (xy 344.765884 -173.518576) (xy 344.772488 -173.511464) (xy 344.779092 -173.493684)
			(xy 344.77833 -173.405546) (xy 344.771218 -173.38802) (xy 344.764614 -173.380908) (xy 344.745242 -173.359576)
			(xy 344.712517 -173.312148) (xy 344.6873 -173.260336) (xy 344.670166 -173.205321) (xy 344.661505 -173.148353)
			(xy 344.660982 -173.119542) (xy 338.79155 -173.119542) (xy 349.70847 -184.036462) (xy 352.88347 -184.036462)
			(xy 352.883955 -184.009092) (xy 352.891766 -183.954913) (xy 352.90725 -183.90241) (xy 352.930087 -183.852662)
			(xy 352.95981 -183.806696) (xy 352.97745 -183.785764) (xy 352.983546 -183.778652) (xy 352.989896 -183.761634)
			(xy 352.989896 -183.67629) (xy 352.983546 -183.659272) (xy 352.97745 -183.65216) (xy 352.959771 -183.631258)
			(xy 352.930046 -183.585285) (xy 352.907202 -183.535534) (xy 352.891707 -183.483027) (xy 352.883882 -183.428844)
			(xy 352.883886 -183.374099) (xy 352.891719 -183.319917) (xy 352.907222 -183.267412) (xy 352.930074 -183.217664)
			(xy 352.959806 -183.171696) (xy 352.97745 -183.150764) (xy 352.983546 -183.143652) (xy 352.989896 -183.126634)
			(xy 352.989896 -183.04129) (xy 352.983546 -183.024272) (xy 352.97745 -183.01716) (xy 352.959771 -182.996258)
			(xy 352.930046 -182.950285) (xy 352.907202 -182.900534) (xy 352.891707 -182.848027) (xy 352.883882 -182.793844)
			(xy 352.883886 -182.739099) (xy 352.891719 -182.684917) (xy 352.907222 -182.632412) (xy 352.930074 -182.582664)
			(xy 352.959806 -182.536696) (xy 352.97745 -182.515764) (xy 352.983546 -182.508652) (xy 352.989896 -182.491634)
			(xy 352.989896 -182.40629) (xy 352.983546 -182.389272) (xy 352.97745 -182.38216) (xy 352.959833 -182.36121)
			(xy 352.930116 -182.315243) (xy 352.907275 -182.2655) (xy 352.891779 -182.213003) (xy 352.883946 -182.15883)
			(xy 352.88347 -182.131462) (xy 352.884003 -182.102829) (xy 352.892542 -182.046205) (xy 352.909453 -181.991494)
			(xy 352.934356 -181.939927) (xy 352.966689 -181.892665) (xy 352.985832 -181.871366) (xy 352.992436 -181.864254)
			(xy 352.999294 -181.846728) (xy 352.999802 -181.758336) (xy 352.992944 -181.740556) (xy 352.98634 -181.733444)
			(xy 352.967563 -181.712232) (xy 352.935865 -181.665281) (xy 352.911464 -181.614157) (xy 352.894894 -181.559986)
			(xy 352.886523 -181.503959) (xy 352.88601 -181.475634) (xy 352.886487 -181.448381) (xy 352.89424 -181.39443)
			(xy 352.909592 -181.342131) (xy 352.932232 -181.29255) (xy 352.961698 -181.246696) (xy 352.997391 -181.205502)
			(xy 353.038583 -181.169808) (xy 353.084436 -181.14034) (xy 353.134016 -181.117698) (xy 353.186314 -181.102343)
			(xy 353.240265 -181.094588) (xy 353.267518 -181.094126) (xy 353.294889 -181.094575) (xy 353.349069 -181.102396)
			(xy 353.401573 -181.117889) (xy 353.451319 -181.140734) (xy 353.497285 -181.170463) (xy 353.518216 -181.188106)
			(xy 353.525328 -181.194202) (xy 353.542346 -181.200552) (xy 353.62769 -181.200552) (xy 353.644708 -181.194202)
			(xy 353.65182 -181.188106) (xy 353.672753 -181.170465) (xy 353.718721 -181.140741) (xy 353.768467 -181.117895)
			(xy 353.820969 -181.102399) (xy 353.875147 -181.09457) (xy 353.929889 -181.09457) (xy 353.984067 -181.102399)
			(xy 354.036569 -181.117895) (xy 354.086315 -181.140741) (xy 354.132283 -181.170465) (xy 354.153216 -181.188106)
			(xy 354.160328 -181.194202) (xy 354.177346 -181.200552) (xy 354.26269 -181.200552) (xy 354.279708 -181.194202)
			(xy 354.28682 -181.188106) (xy 354.307772 -181.170492) (xy 354.353739 -181.140776) (xy 354.403482 -181.117935)
			(xy 354.455978 -181.102438) (xy 354.51015 -181.094604) (xy 354.537518 -181.094126) (xy 354.564773 -181.094538)
			(xy 354.618727 -181.102299) (xy 354.671028 -181.117659) (xy 354.720611 -181.140306) (xy 354.766466 -181.169779)
			(xy 354.807659 -181.205478) (xy 354.843352 -181.246676) (xy 354.872819 -181.292535) (xy 354.89546 -181.34212)
			(xy 354.910813 -181.394423) (xy 354.918565 -181.448379) (xy 354.919026 -181.475634) (xy 356.90175 -181.475634)
			(xy 356.90231 -181.448386) (xy 356.910061 -181.394443) (xy 356.925409 -181.342152) (xy 356.948043 -181.292578)
			(xy 356.977502 -181.246729) (xy 357.013186 -181.20554) (xy 357.054368 -181.169848) (xy 357.100211 -181.14038)
			(xy 357.149781 -181.117736) (xy 357.202068 -181.102377) (xy 357.25601 -181.094615) (xy 357.283258 -181.094126)
			(xy 357.310628 -181.09461) (xy 357.364806 -181.102423) (xy 357.417309 -181.117907) (xy 357.467057 -181.140745)
			(xy 357.513024 -181.170466) (xy 357.533956 -181.188106) (xy 357.541068 -181.194202) (xy 357.558086 -181.200552)
			(xy 357.64343 -181.200552) (xy 357.660448 -181.194202) (xy 357.66756 -181.188106) (xy 357.688497 -181.170473)
			(xy 357.734468 -181.14076) (xy 357.784215 -181.117923) (xy 357.836714 -181.10243) (xy 357.890889 -181.094601)
			(xy 357.918258 -181.094126) (xy 357.945511 -181.094594) (xy 357.999464 -181.102347) (xy 358.051764 -181.117699)
			(xy 358.101346 -181.140339) (xy 358.147201 -181.169806) (xy 358.188395 -181.205499) (xy 358.224089 -181.246693)
			(xy 358.253557 -181.292547) (xy 358.276198 -181.342129) (xy 358.291552 -181.394428) (xy 358.299305 -181.448381)
			(xy 358.299766 -181.475634) (xy 358.299284 -181.502768) (xy 358.291597 -181.556488) (xy 358.276368 -181.608574)
			(xy 358.253905 -181.657974) (xy 358.224663 -181.703689) (xy 358.20731 -181.724554) (xy 358.201214 -181.731666)
			(xy 358.195118 -181.748684) (xy 358.195626 -181.834028) (xy 358.201976 -181.851046) (xy 358.208326 -181.858158)
			(xy 358.226238 -181.879168) (xy 358.256429 -181.92539) (xy 358.279641 -181.975482) (xy 358.295389 -182.028397)
			(xy 358.303344 -182.08303) (xy 358.30383 -182.110634) (xy 358.303401 -182.138006) (xy 358.295577 -182.192187)
			(xy 358.28008 -182.244691) (xy 358.25723 -182.294438) (xy 358.227496 -182.340402) (xy 358.20985 -182.361332)
			(xy 358.203754 -182.368444) (xy 358.197404 -182.385462) (xy 358.197404 -182.470806) (xy 358.203754 -182.487824)
			(xy 358.20985 -182.494936) (xy 358.227525 -182.515841) (xy 358.25725 -182.561813) (xy 358.280095 -182.611564)
			(xy 358.29559 -182.66407) (xy 358.303415 -182.718253) (xy 358.303412 -182.772998) (xy 358.295579 -182.82718)
			(xy 358.280077 -182.879684) (xy 358.257225 -182.929432) (xy 358.227494 -182.9754) (xy 358.20985 -182.996332)
			(xy 358.203754 -183.003444) (xy 358.197404 -183.020462) (xy 358.197404 -183.105806) (xy 358.203754 -183.122824)
			(xy 358.20985 -183.129936) (xy 358.227525 -183.150841) (xy 358.25725 -183.196813) (xy 358.280095 -183.246564)
			(xy 358.29559 -183.29907) (xy 358.303415 -183.353253) (xy 358.303412 -183.407998) (xy 358.295579 -183.46218)
			(xy 358.280077 -183.514684) (xy 358.257225 -183.564432) (xy 358.227494 -183.6104) (xy 358.20985 -183.631332)
			(xy 358.203754 -183.638444) (xy 358.197404 -183.655462) (xy 358.197404 -183.740806) (xy 358.203754 -183.757824)
			(xy 358.20985 -183.764936) (xy 358.227465 -183.785888) (xy 358.257182 -183.831854) (xy 358.280023 -183.881597)
			(xy 358.29552 -183.934093) (xy 358.303353 -183.988266) (xy 358.30383 -184.015634) (xy 358.303325 -184.043343)
			(xy 358.295298 -184.098177) (xy 358.279418 -184.151271) (xy 358.25602 -184.201507) (xy 358.225597 -184.247828)
			(xy 358.207564 -184.268872) (xy 358.201214 -184.276238) (xy 358.19461 -184.29351) (xy 358.195626 -184.380886)
			(xy 358.20223 -184.398158) (xy 358.208834 -184.40527) (xy 358.227749 -184.426502) (xy 358.259679 -184.473552)
			(xy 358.284265 -184.524824) (xy 358.300964 -184.579179) (xy 358.309403 -184.635411) (xy 358.309926 -184.663842)
			(xy 358.309444 -184.691212) (xy 358.301633 -184.745391) (xy 358.286148 -184.797895) (xy 358.26331 -184.847642)
			(xy 358.233587 -184.893609) (xy 358.215946 -184.91454) (xy 358.20985 -184.921652) (xy 358.2035 -184.93867)
			(xy 358.2035 -185.024014) (xy 358.20985 -185.041032) (xy 358.215946 -185.048144) (xy 358.233629 -185.069043)
			(xy 358.263354 -185.115016) (xy 358.286199 -185.164768) (xy 358.301693 -185.217275) (xy 358.309518 -185.271459)
			(xy 358.309514 -185.326205) (xy 358.301679 -185.380387) (xy 358.286176 -185.432892) (xy 358.263324 -185.48264)
			(xy 358.233591 -185.528608) (xy 358.215946 -185.54954) (xy 358.20985 -185.556652) (xy 358.2035 -185.57367)
			(xy 358.2035 -185.659014) (xy 358.20985 -185.676032) (xy 358.215946 -185.683144) (xy 358.233629 -185.704043)
			(xy 358.263354 -185.750016) (xy 358.286199 -185.799768) (xy 358.301693 -185.852275) (xy 358.309518 -185.906459)
			(xy 358.309514 -185.961205) (xy 358.301679 -186.015387) (xy 358.286176 -186.067892) (xy 358.263324 -186.11764)
			(xy 358.233591 -186.163608) (xy 358.215946 -186.18454) (xy 358.20985 -186.191652) (xy 358.2035 -186.20867)
			(xy 358.2035 -186.294014) (xy 358.20985 -186.311032) (xy 358.215946 -186.318144) (xy 358.233629 -186.339043)
			(xy 358.263354 -186.385016) (xy 358.286199 -186.434768) (xy 358.301693 -186.487275) (xy 358.309518 -186.541459)
			(xy 358.309514 -186.596205) (xy 358.301679 -186.650387) (xy 358.286176 -186.702892) (xy 358.263324 -186.75264)
			(xy 358.233591 -186.798608) (xy 358.215946 -186.81954) (xy 358.20985 -186.826652) (xy 358.2035 -186.84367)
			(xy 358.2035 -186.929014) (xy 358.20985 -186.946032) (xy 358.215946 -186.953144) (xy 358.233629 -186.974043)
			(xy 358.263354 -187.020016) (xy 358.286199 -187.069768) (xy 358.301693 -187.122275) (xy 358.309518 -187.176459)
			(xy 358.309514 -187.231205) (xy 358.301679 -187.285387) (xy 358.286176 -187.337892) (xy 358.263324 -187.38764)
			(xy 358.233591 -187.433608) (xy 358.215946 -187.45454) (xy 358.20985 -187.461652) (xy 358.2035 -187.47867)
			(xy 358.2035 -187.564014) (xy 358.20985 -187.581032) (xy 358.215946 -187.588144) (xy 358.233564 -187.609093)
			(xy 358.263281 -187.655061) (xy 358.286122 -187.704804) (xy 358.301618 -187.757301) (xy 358.30945 -187.811474)
			(xy 358.309926 -187.838842) (xy 358.309461 -187.866093) (xy 358.3017 -187.920041) (xy 358.28634 -187.972335)
			(xy 358.263695 -188.021911) (xy 358.234226 -188.067761) (xy 358.198533 -188.10895) (xy 358.157341 -188.144641)
			(xy 358.11149 -188.174107) (xy 358.061913 -188.196748) (xy 358.009618 -188.212105) (xy 357.955669 -188.219863)
			(xy 357.928418 -188.22035) (xy 357.901048 -188.219886) (xy 357.846868 -188.212069) (xy 357.794364 -188.19658)
			(xy 357.744617 -188.173738) (xy 357.698651 -188.144012) (xy 357.67772 -188.12637) (xy 357.670608 -188.120274)
			(xy 357.65359 -188.113924) (xy 357.568246 -188.113924) (xy 357.551228 -188.120274) (xy 357.544116 -188.12637)
			(xy 357.523185 -188.14401) (xy 357.477212 -188.173723) (xy 357.427465 -188.196559) (xy 357.374964 -188.21205)
			(xy 357.320787 -188.219877) (xy 357.293418 -188.22035) (xy 357.266169 -188.219805) (xy 357.212226 -188.212052)
			(xy 357.159935 -188.196701) (xy 357.11036 -188.174065) (xy 357.064512 -188.144605) (xy 357.023323 -188.10892)
			(xy 356.987631 -188.067736) (xy 356.958163 -188.021892) (xy 356.93552 -187.972322) (xy 356.920161 -187.920033)
			(xy 356.912399 -187.866091) (xy 356.91191 -187.838842) (xy 356.912398 -187.811473) (xy 356.92021 -187.757294)
			(xy 356.935694 -187.704791) (xy 356.958531 -187.655044) (xy 356.988251 -187.609076) (xy 357.00589 -187.588144)
			(xy 357.011986 -187.581032) (xy 357.018336 -187.564014) (xy 357.018336 -187.47867) (xy 357.011986 -187.461652)
			(xy 357.00589 -187.45454) (xy 356.988292 -187.433573) (xy 356.958568 -187.38761) (xy 356.935723 -187.33787)
			(xy 356.920225 -187.285373) (xy 356.912393 -187.2312) (xy 356.912389 -187.176463) (xy 356.920211 -187.122289)
			(xy 356.935701 -187.06979) (xy 356.958538 -187.020045) (xy 356.988254 -186.974077) (xy 357.00589 -186.953144)
			(xy 357.011986 -186.946032) (xy 357.018336 -186.929014) (xy 357.018336 -186.84367) (xy 357.011986 -186.826652)
			(xy 357.00589 -186.81954) (xy 356.988292 -186.798573) (xy 356.958568 -186.75261) (xy 356.935723 -186.70287)
			(xy 356.920225 -186.650373) (xy 356.912393 -186.5962) (xy 356.912389 -186.541463) (xy 356.920211 -186.487289)
			(xy 356.935701 -186.43479) (xy 356.958538 -186.385045) (xy 356.988254 -186.339077) (xy 357.00589 -186.318144)
			(xy 357.011986 -186.311032) (xy 357.018336 -186.294014) (xy 357.018336 -186.20867) (xy 357.011986 -186.191652)
			(xy 357.00589 -186.18454) (xy 356.988292 -186.163573) (xy 356.958568 -186.11761) (xy 356.935723 -186.06787)
			(xy 356.920225 -186.015373) (xy 356.912393 -185.9612) (xy 356.912389 -185.906463) (xy 356.920211 -185.852289)
			(xy 356.935701 -185.79979) (xy 356.958538 -185.750045) (xy 356.988254 -185.704077) (xy 357.00589 -185.683144)
			(xy 357.011986 -185.676032) (xy 357.018336 -185.659014) (xy 357.018336 -185.57367) (xy 357.011986 -185.556652)
			(xy 357.00589 -185.54954) (xy 356.988292 -185.528573) (xy 356.958568 -185.48261) (xy 356.935723 -185.43287)
			(xy 356.920225 -185.380373) (xy 356.912393 -185.3262) (xy 356.912389 -185.271463) (xy 356.920211 -185.217289)
			(xy 356.935701 -185.16479) (xy 356.958538 -185.115045) (xy 356.988254 -185.069077) (xy 357.00589 -185.048144)
			(xy 357.011986 -185.041032) (xy 357.018336 -185.024014) (xy 357.018336 -184.93867) (xy 357.011986 -184.921652)
			(xy 357.00589 -184.91454) (xy 356.988255 -184.893605) (xy 356.958543 -184.847633) (xy 356.935706 -184.797886)
			(xy 356.920214 -184.745386) (xy 356.912385 -184.691211) (xy 356.91191 -184.663842) (xy 356.912391 -184.636132)
			(xy 356.920422 -184.581297) (xy 356.936307 -184.528202) (xy 356.959711 -184.477966) (xy 356.99014 -184.431647)
			(xy 357.008176 -184.410604) (xy 357.014526 -184.403238) (xy 357.02113 -184.385966) (xy 357.020114 -184.29859)
			(xy 357.01351 -184.281318) (xy 357.006906 -184.274206) (xy 356.988033 -184.252938) (xy 356.956096 -184.205898)
			(xy 356.931501 -184.154636) (xy 356.914793 -184.100289) (xy 356.906342 -184.044063) (xy 356.905814 -184.015634)
			(xy 356.906297 -183.988264) (xy 356.91411 -183.934086) (xy 356.929595 -183.881583) (xy 356.952433 -183.831836)
			(xy 356.982154 -183.785868) (xy 356.999794 -183.764936) (xy 357.00589 -183.757824) (xy 357.01224 -183.740806)
			(xy 357.01224 -183.655462) (xy 357.00589 -183.638444) (xy 356.999794 -183.631332) (xy 356.982188 -183.610372)
			(xy 356.952464 -183.564408) (xy 356.929619 -183.514666) (xy 356.914122 -183.462168) (xy 356.90629 -183.407994)
			(xy 356.906287 -183.353257) (xy 356.914111 -183.299082) (xy 356.929601 -183.246582) (xy 356.95244 -183.196837)
			(xy 356.982157 -183.150869) (xy 356.999794 -183.129936) (xy 357.00589 -183.122824) (xy 357.01224 -183.105806)
			(xy 357.01224 -183.020462) (xy 357.00589 -183.003444) (xy 356.999794 -182.996332) (xy 356.982188 -182.975372)
			(xy 356.952464 -182.929408) (xy 356.929619 -182.879666) (xy 356.914122 -182.827168) (xy 356.90629 -182.772994)
			(xy 356.906287 -182.718257) (xy 356.914111 -182.664082) (xy 356.929601 -182.611582) (xy 356.95244 -182.561837)
			(xy 356.982157 -182.515869) (xy 356.999794 -182.494936) (xy 357.00589 -182.487824) (xy 357.01224 -182.470806)
			(xy 357.01224 -182.385462) (xy 357.00589 -182.368444) (xy 356.999794 -182.361332) (xy 356.982156 -182.340399)
			(xy 356.952444 -182.294427) (xy 356.929608 -182.244679) (xy 356.914117 -182.192179) (xy 356.906288 -182.138003)
			(xy 356.905814 -182.110634) (xy 356.906282 -182.0835) (xy 356.913973 -182.029779) (xy 356.929206 -181.977693)
			(xy 356.951672 -181.928293) (xy 356.980916 -181.882579) (xy 356.99827 -181.861714) (xy 357.004366 -181.854602)
			(xy 357.010462 -181.837584) (xy 357.009954 -181.75224) (xy 357.003604 -181.735222) (xy 356.997254 -181.72811)
			(xy 356.979371 -181.707077) (xy 356.949176 -181.660861) (xy 356.925959 -181.610775) (xy 356.910204 -181.557865)
			(xy 356.902241 -181.503237) (xy 356.90175 -181.475634) (xy 354.919026 -181.475634) (xy 354.918591 -181.502605)
			(xy 354.910979 -181.556007) (xy 354.895912 -181.607803) (xy 354.873691 -181.656955) (xy 354.844761 -181.702483)
			(xy 354.827586 -181.723284) (xy 354.82149 -181.730396) (xy 354.815394 -181.747414) (xy 354.816156 -181.833012)
			(xy 354.82276 -181.849776) (xy 354.82911 -181.856888) (xy 354.847212 -181.877951) (xy 354.877716 -181.924363)
			(xy 354.901174 -181.974703) (xy 354.917092 -182.027912) (xy 354.925133 -182.082865) (xy 354.92563 -182.110634)
			(xy 354.925201 -182.138006) (xy 354.917377 -182.192187) (xy 354.90188 -182.244691) (xy 354.87903 -182.294438)
			(xy 354.849296 -182.340402) (xy 354.83165 -182.361332) (xy 354.825554 -182.368444) (xy 354.819204 -182.385462)
			(xy 354.819204 -182.470806) (xy 354.825554 -182.487824) (xy 354.83165 -182.494936) (xy 354.849325 -182.515841)
			(xy 354.87905 -182.561813) (xy 354.901895 -182.611564) (xy 354.91739 -182.66407) (xy 354.925215 -182.718253)
			(xy 354.925212 -182.772998) (xy 354.917379 -182.82718) (xy 354.901877 -182.879684) (xy 354.879025 -182.929432)
			(xy 354.849294 -182.9754) (xy 354.83165 -182.996332) (xy 354.825554 -183.003444) (xy 354.819204 -183.020462)
			(xy 354.819204 -183.105806) (xy 354.825554 -183.122824) (xy 354.83165 -183.129936) (xy 354.849325 -183.150841)
			(xy 354.87905 -183.196813) (xy 354.901895 -183.246564) (xy 354.91739 -183.29907) (xy 354.925215 -183.353253)
			(xy 354.925212 -183.407998) (xy 354.917379 -183.46218) (xy 354.901877 -183.514684) (xy 354.879025 -183.564432)
			(xy 354.849294 -183.6104) (xy 354.83165 -183.631332) (xy 354.825554 -183.638444) (xy 354.819204 -183.655462)
			(xy 354.819204 -183.740806) (xy 354.825554 -183.757824) (xy 354.83165 -183.764936) (xy 354.849265 -183.785888)
			(xy 354.878982 -183.831854) (xy 354.901823 -183.881597) (xy 354.91732 -183.934093) (xy 354.925153 -183.988266)
			(xy 354.92563 -184.015634) (xy 354.925125 -184.043343) (xy 354.917098 -184.098177) (xy 354.901218 -184.151271)
			(xy 354.87782 -184.201507) (xy 354.847397 -184.247828) (xy 354.829364 -184.268872) (xy 354.823014 -184.276238)
			(xy 354.81641 -184.29351) (xy 354.817426 -184.380886) (xy 354.82403 -184.398158) (xy 354.830634 -184.40527)
			(xy 354.849549 -184.426502) (xy 354.881479 -184.473552) (xy 354.906065 -184.524824) (xy 354.922764 -184.579179)
			(xy 354.931203 -184.635411) (xy 354.931726 -184.663842) (xy 354.931244 -184.691212) (xy 354.923433 -184.745391)
			(xy 354.907948 -184.797895) (xy 354.88511 -184.847642) (xy 354.855387 -184.893609) (xy 354.837746 -184.91454)
			(xy 354.83165 -184.921652) (xy 354.8253 -184.93867) (xy 354.8253 -185.024014) (xy 354.83165 -185.041032)
			(xy 354.837746 -185.048144) (xy 354.855429 -185.069043) (xy 354.885154 -185.115016) (xy 354.907999 -185.164768)
			(xy 354.923493 -185.217275) (xy 354.931318 -185.271459) (xy 354.931314 -185.326205) (xy 354.923479 -185.380387)
			(xy 354.907976 -185.432892) (xy 354.885124 -185.48264) (xy 354.855391 -185.528608) (xy 354.837746 -185.54954)
			(xy 354.83165 -185.556652) (xy 354.8253 -185.57367) (xy 354.8253 -185.659014) (xy 354.83165 -185.676032)
			(xy 354.837746 -185.683144) (xy 354.855364 -185.704093) (xy 354.885081 -185.750061) (xy 354.907922 -185.799804)
			(xy 354.923418 -185.852301) (xy 354.93125 -185.906474) (xy 354.931726 -185.933842) (xy 354.93124 -185.961093)
			(xy 354.923484 -186.015041) (xy 354.908129 -186.067336) (xy 354.885487 -186.116913) (xy 354.856021 -186.162763)
			(xy 354.82033 -186.203954) (xy 354.779139 -186.239645) (xy 354.733289 -186.269111) (xy 354.683712 -186.291753)
			(xy 354.631417 -186.307108) (xy 354.577469 -186.314864) (xy 354.522967 -186.314864) (xy 354.469019 -186.307108)
			(xy 354.416724 -186.291753) (xy 354.367147 -186.269111) (xy 354.321297 -186.239645) (xy 354.280106 -186.203954)
			(xy 354.244415 -186.162763) (xy 354.214949 -186.116913) (xy 354.192307 -186.067336) (xy 354.176952 -186.015041)
			(xy 354.169196 -185.961093) (xy 354.16871 -185.933842) (xy 354.169273 -185.904365) (xy 354.178336 -185.846113)
			(xy 354.196253 -185.789948) (xy 354.222597 -185.737209) (xy 354.256742 -185.68915) (xy 354.276914 -185.66765)
			(xy 354.283422 -185.660295) (xy 354.290882 -185.64215) (xy 354.291392 -185.632344) (xy 354.291392 -185.579004)
			(xy 354.284026 -185.572146) (xy 354.276683 -185.565622) (xy 354.258529 -185.558172) (xy 354.24872 -185.557668)
			(xy 354.216716 -185.557668) (xy 354.206899 -185.558128) (xy 354.188735 -185.565592) (xy 354.18141 -185.572146)
			(xy 354.159905 -185.592314) (xy 354.111847 -185.62646) (xy 354.059109 -185.652807) (xy 354.002946 -185.67073)
			(xy 353.944695 -185.6798) (xy 353.915218 -185.68035) (xy 353.887969 -185.679805) (xy 353.834026 -185.672052)
			(xy 353.781735 -185.656701) (xy 353.73216 -185.634065) (xy 353.686312 -185.604605) (xy 353.645123 -185.56892)
			(xy 353.609431 -185.527736) (xy 353.579963 -185.481892) (xy 353.55732 -185.432322) (xy 353.541961 -185.380033)
			(xy 353.534199 -185.326091) (xy 353.53371 -185.298842) (xy 353.534273 -185.269365) (xy 353.543336 -185.211113)
			(xy 353.561253 -185.154948) (xy 353.587597 -185.102209) (xy 353.621742 -185.05415) (xy 353.641914 -185.03265)
			(xy 353.648422 -185.025295) (xy 353.655882 -185.00715) (xy 353.656392 -184.997344) (xy 353.656392 -184.944004)
			(xy 353.650804 -184.938924) (xy 353.643346 -184.932375) (xy 353.62491 -184.925065) (xy 353.61499 -184.9247)
			(xy 353.582986 -184.924954) (xy 353.573122 -184.925523) (xy 353.554955 -184.933252) (xy 353.54768 -184.93994)
			(xy 353.526057 -184.960975) (xy 353.477395 -184.996621) (xy 353.423727 -185.024162) (xy 353.366393 -185.042911)
			(xy 353.306823 -185.052401) (xy 353.276662 -185.05297) (xy 353.249408 -185.052557) (xy 353.195456 -185.044795)
			(xy 353.143157 -185.029433) (xy 353.093577 -185.006785) (xy 353.047725 -184.977311) (xy 353.006535 -184.941612)
			(xy 352.970844 -184.900414) (xy 352.941379 -184.854556) (xy 352.918741 -184.804971) (xy 352.903389 -184.75267)
			(xy 352.895637 -184.698716) (xy 352.895154 -184.671462) (xy 352.895604 -184.644797) (xy 352.903045 -184.591989)
			(xy 352.917765 -184.54073) (xy 352.939475 -184.492019) (xy 352.967754 -184.446803) (xy 352.984562 -184.426098)
			(xy 352.990658 -184.418732) (xy 352.996754 -184.401714) (xy 352.994976 -184.31637) (xy 352.988372 -184.299352)
			(xy 352.982022 -184.292494) (xy 352.963583 -184.271317) (xy 352.93244 -184.224596) (xy 352.908474 -184.173819)
			(xy 352.892201 -184.120079) (xy 352.883971 -184.064537) (xy 352.88347 -184.036462) (xy 349.70847 -184.036462)
			(xy 354.82276 -189.150752) (xy 395.017244 -189.150752) (xy 395.017733 -189.123502) (xy 395.025495 -189.069557)
			(xy 395.040854 -189.017265) (xy 395.063497 -188.967691) (xy 395.092964 -188.921843) (xy 395.128654 -188.880654)
			(xy 395.169843 -188.844964) (xy 395.215691 -188.815497) (xy 395.265265 -188.792854) (xy 395.317557 -188.777495)
			(xy 395.371502 -188.769733) (xy 395.398752 -188.769244) (xy 395.426122 -188.769727) (xy 395.4803 -188.777539)
			(xy 395.532804 -188.793024) (xy 395.582551 -188.815862) (xy 395.628518 -188.845584) (xy 395.64945 -188.863224)
			(xy 395.656562 -188.86932) (xy 395.67358 -188.87567) (xy 395.758924 -188.87567) (xy 395.775942 -188.86932)
			(xy 395.783054 -188.863224) (xy 395.803987 -188.845583) (xy 395.849955 -188.815859) (xy 395.899701 -188.793013)
			(xy 395.952203 -188.777517) (xy 396.006381 -188.769688) (xy 396.061123 -188.769688) (xy 396.115301 -188.777517)
			(xy 396.167803 -188.793013) (xy 396.217549 -188.815859) (xy 396.263517 -188.845583) (xy 396.28445 -188.863224)
			(xy 396.291562 -188.86932) (xy 396.30858 -188.87567) (xy 396.393924 -188.87567) (xy 396.410942 -188.86932)
			(xy 396.418054 -188.863224) (xy 396.438996 -188.845597) (xy 396.484965 -188.815882) (xy 396.53471 -188.793044)
			(xy 396.587209 -188.77755) (xy 396.641383 -188.769719) (xy 396.668752 -188.769244) (xy 396.696 -188.769823)
			(xy 396.749942 -188.777571) (xy 396.802232 -188.792918) (xy 396.851806 -188.81555) (xy 396.897654 -188.845007)
			(xy 396.938843 -188.880689) (xy 396.974536 -188.921869) (xy 397.004004 -188.96771) (xy 397.026648 -189.017278)
			(xy 397.042008 -189.069564) (xy 397.04977 -189.123504) (xy 397.05026 -189.150752) (xy 399.032984 -189.150752)
			(xy 399.033433 -189.1235) (xy 399.041196 -189.069551) (xy 399.056557 -189.017256) (xy 399.079203 -188.96768)
			(xy 399.108673 -188.92183) (xy 399.144369 -188.88064) (xy 399.185562 -188.844949) (xy 399.231415 -188.815484)
			(xy 399.280994 -188.792843) (xy 399.33329 -188.777487) (xy 399.38724 -188.76973) (xy 399.414492 -188.769244)
			(xy 399.441863 -188.769704) (xy 399.496042 -188.777522) (xy 399.548546 -188.793012) (xy 399.598293 -188.815855)
			(xy 399.644259 -188.845582) (xy 399.66519 -188.863224) (xy 399.672302 -188.86932) (xy 399.68932 -188.87567)
			(xy 399.774664 -188.87567) (xy 399.791682 -188.86932) (xy 399.798794 -188.863224) (xy 399.819727 -188.845583)
			(xy 399.865695 -188.815859) (xy 399.915441 -188.793013) (xy 399.967943 -188.777517) (xy 400.022121 -188.769688)
			(xy 400.076863 -188.769688) (xy 400.131041 -188.777517) (xy 400.183543 -188.793013) (xy 400.233289 -188.815859)
			(xy 400.279257 -188.845583) (xy 400.30019 -188.863224) (xy 400.307302 -188.86932) (xy 400.32432 -188.87567)
			(xy 400.409664 -188.87567) (xy 400.426682 -188.86932) (xy 400.433794 -188.863224) (xy 400.454721 -188.845578)
			(xy 400.500695 -188.815866) (xy 400.550443 -188.793031) (xy 400.602945 -188.777542) (xy 400.657122 -188.769716)
			(xy 400.684492 -188.769244) (xy 400.711741 -188.769785) (xy 400.765684 -188.777539) (xy 400.817975 -188.792891)
			(xy 400.867549 -188.815528) (xy 400.913397 -188.844989) (xy 400.954586 -188.880674) (xy 400.990278 -188.921858)
			(xy 401.019745 -188.967702) (xy 401.042389 -189.017273) (xy 401.057749 -189.069561) (xy 401.065511 -189.123503)
			(xy 401.066 -189.150752) (xy 401.065529 -189.178086) (xy 401.057721 -189.232193) (xy 401.042271 -189.284632)
			(xy 401.019497 -189.334329) (xy 400.989863 -189.380268) (xy 400.972274 -189.401196) (xy 400.96567 -189.408562)
			(xy 400.959574 -189.426596) (xy 400.962622 -189.515496) (xy 400.969988 -189.532768) (xy 400.9771 -189.53988)
			(xy 400.997912 -189.561467) (xy 401.033165 -189.609972) (xy 401.060393 -189.663396) (xy 401.078925 -189.720423)
			(xy 401.088304 -189.779647) (xy 401.08886 -189.809628) (xy 401.08842 -189.836999) (xy 401.080597 -189.89118)
			(xy 401.065103 -189.943684) (xy 401.042255 -189.99343) (xy 401.012524 -190.039395) (xy 400.99488 -190.060326)
			(xy 400.988784 -190.067438) (xy 400.982434 -190.084456) (xy 400.982434 -190.1698) (xy 400.988784 -190.186818)
			(xy 400.99488 -190.19393) (xy 401.012548 -190.214841) (xy 401.042271 -190.260812) (xy 401.065114 -190.310562)
			(xy 401.080608 -190.363068) (xy 401.088434 -190.417249) (xy 401.088431 -190.471993) (xy 401.080599 -190.526173)
			(xy 401.065099 -190.578677) (xy 401.042251 -190.628425) (xy 401.012522 -190.674393) (xy 400.99488 -190.695326)
			(xy 400.988784 -190.702438) (xy 400.982434 -190.719456) (xy 400.982434 -190.8048) (xy 400.988784 -190.821818)
			(xy 400.99488 -190.82893) (xy 401.012548 -190.849841) (xy 401.042271 -190.895812) (xy 401.065114 -190.945562)
			(xy 401.080608 -190.998068) (xy 401.088434 -191.052249) (xy 401.088431 -191.106993) (xy 401.080599 -191.161173)
			(xy 401.065099 -191.213677) (xy 401.042251 -191.263425) (xy 401.012522 -191.309393) (xy 400.99488 -191.330326)
			(xy 400.988784 -191.337438) (xy 400.982434 -191.354456) (xy 400.982434 -191.4398) (xy 400.988784 -191.456818)
			(xy 400.99488 -191.46393) (xy 401.012497 -191.48488) (xy 401.042213 -191.530848) (xy 401.065053 -191.580591)
			(xy 401.080549 -191.633087) (xy 401.088383 -191.68726) (xy 401.08886 -191.714628) (xy 401.088471 -191.741884)
			(xy 401.080709 -191.79584) (xy 401.065347 -191.848142) (xy 401.042698 -191.897726) (xy 401.013222 -191.943581)
			(xy 400.977521 -191.984775) (xy 400.93632 -192.020468) (xy 400.890459 -192.049934) (xy 400.840871 -192.072574)
			(xy 400.788566 -192.087925) (xy 400.734608 -192.095676) (xy 400.707352 -192.096136) (xy 400.680648 -192.095706)
			(xy 400.627762 -192.088251) (xy 400.576432 -192.073494) (xy 400.527662 -192.051723) (xy 400.482405 -192.023363)
			(xy 400.441545 -191.98897) (xy 400.42338 -191.96939) (xy 400.416144 -191.962107) (xy 400.397544 -191.953459)
			(xy 400.387312 -191.952626) (xy 400.332956 -191.950594) (xy 400.324066 -191.959738) (xy 400.31713 -191.967446)
			(xy 400.309518 -191.98671) (xy 400.309334 -191.997076) (xy 400.310096 -192.029334) (xy 400.310885 -192.039673)
			(xy 400.319677 -192.058429) (xy 400.327114 -192.065656) (xy 400.346701 -192.083813) (xy 400.381094 -192.124674)
			(xy 400.409451 -192.169933) (xy 400.431218 -192.218705) (xy 400.445968 -192.270036) (xy 400.453414 -192.322924)
			(xy 400.45386 -192.349628) (xy 400.453471 -192.376884) (xy 400.445709 -192.43084) (xy 400.430347 -192.483142)
			(xy 400.407698 -192.532726) (xy 400.378222 -192.578581) (xy 400.342521 -192.619775) (xy 400.30132 -192.655468)
			(xy 400.255459 -192.684934) (xy 400.205871 -192.707574) (xy 400.153566 -192.722925) (xy 400.099608 -192.730676)
			(xy 400.072352 -192.731136) (xy 400.042875 -192.730581) (xy 399.984621 -192.721518) (xy 399.928456 -192.7036)
			(xy 399.875717 -192.677254) (xy 399.827659 -192.643106) (xy 399.80616 -192.622932) (xy 399.798841 -192.616378)
			(xy 399.780668 -192.608946) (xy 399.770854 -192.608454) (xy 399.717514 -192.608454) (xy 399.710656 -192.61582)
			(xy 399.704114 -192.623148) (xy 399.696674 -192.641314) (xy 399.696178 -192.651126) (xy 399.696178 -192.68313)
			(xy 399.696664 -192.692944) (xy 399.70411 -192.711108) (xy 399.710656 -192.718436) (xy 399.730847 -192.739919)
			(xy 399.76499 -192.787983) (xy 399.791333 -192.840727) (xy 399.809249 -192.896895) (xy 399.818314 -192.95515)
			(xy 399.81886 -192.984628) (xy 399.818374 -193.011879) (xy 399.810618 -193.065827) (xy 399.795263 -193.118122)
			(xy 399.772621 -193.167699) (xy 399.743155 -193.213549) (xy 399.707464 -193.25474) (xy 399.666273 -193.290431)
			(xy 399.620423 -193.319897) (xy 399.570846 -193.342539) (xy 399.518551 -193.357894) (xy 399.464603 -193.36565)
			(xy 399.410101 -193.36565) (xy 399.356153 -193.357894) (xy 399.303858 -193.342539) (xy 399.254281 -193.319897)
			(xy 399.208431 -193.290431) (xy 399.16724 -193.25474) (xy 399.131549 -193.213549) (xy 399.102083 -193.167699)
			(xy 399.079441 -193.118122) (xy 399.064086 -193.065827) (xy 399.05633 -193.011879) (xy 399.055844 -192.984628)
			(xy 399.056316 -192.957258) (xy 399.064131 -192.903079) (xy 399.079618 -192.850575) (xy 399.102458 -192.800828)
			(xy 399.132183 -192.754861) (xy 399.149824 -192.73393) (xy 399.15592 -192.726818) (xy 399.16227 -192.7098)
			(xy 399.16227 -192.624456) (xy 399.15592 -192.607438) (xy 399.149824 -192.600326) (xy 399.132187 -192.579392)
			(xy 399.102474 -192.53342) (xy 399.079638 -192.483673) (xy 399.064146 -192.431173) (xy 399.056318 -192.376997)
			(xy 399.055844 -192.349628) (xy 399.056294 -192.322058) (xy 399.064231 -192.267491) (xy 399.079943 -192.214636)
			(xy 399.103103 -192.164595) (xy 399.133228 -192.11841) (xy 399.151094 -192.097406) (xy 399.157698 -192.09004)
			(xy 399.164048 -192.07226) (xy 399.161508 -191.98336) (xy 399.154142 -191.965834) (xy 399.14703 -191.958976)
			(xy 399.126553 -191.937383) (xy 399.091827 -191.889064) (xy 399.065027 -191.835937) (xy 399.046804 -191.779292)
			(xy 399.0376 -191.720504) (xy 399.037048 -191.690752) (xy 399.037533 -191.663382) (xy 399.045344 -191.609204)
			(xy 399.060828 -191.5567) (xy 399.083666 -191.506953) (xy 399.113388 -191.460986) (xy 399.131028 -191.440054)
			(xy 399.137124 -191.432942) (xy 399.143474 -191.415924) (xy 399.143474 -191.33058) (xy 399.137124 -191.313562)
			(xy 399.131028 -191.30645) (xy 399.11334 -191.285555) (xy 399.083617 -191.239581) (xy 399.060775 -191.189828)
			(xy 399.045282 -191.137321) (xy 399.037458 -191.083137) (xy 399.037463 -191.028391) (xy 399.045298 -190.974209)
			(xy 399.0608 -190.921704) (xy 399.083652 -190.871956) (xy 399.113384 -190.825987) (xy 399.131028 -190.805054)
			(xy 399.137124 -190.797942) (xy 399.143474 -190.780924) (xy 399.143474 -190.69558) (xy 399.137124 -190.678562)
			(xy 399.131028 -190.67145) (xy 399.11334 -190.650555) (xy 399.083617 -190.604581) (xy 399.060775 -190.554828)
			(xy 399.045282 -190.502321) (xy 399.037458 -190.448137) (xy 399.037463 -190.393391) (xy 399.045298 -190.339209)
			(xy 399.0608 -190.286704) (xy 399.083652 -190.236956) (xy 399.113384 -190.190987) (xy 399.131028 -190.170054)
			(xy 399.137124 -190.162942) (xy 399.143474 -190.145924) (xy 399.143474 -190.06058) (xy 399.137124 -190.043562)
			(xy 399.131028 -190.03645) (xy 399.113403 -190.015506) (xy 399.083688 -189.969537) (xy 399.060849 -189.919793)
			(xy 399.045355 -189.867294) (xy 399.037524 -189.81312) (xy 399.037048 -189.785752) (xy 399.037518 -189.758618)
			(xy 399.045208 -189.704897) (xy 399.06044 -189.65281) (xy 399.082905 -189.603411) (xy 399.11215 -189.557697)
			(xy 399.129504 -189.536832) (xy 399.1356 -189.52972) (xy 399.141696 -189.512702) (xy 399.141188 -189.427358)
			(xy 399.134838 -189.41034) (xy 399.128488 -189.403228) (xy 399.110572 -189.382222) (xy 399.080381 -189.335999)
			(xy 399.057169 -189.285906) (xy 399.041422 -189.23299) (xy 399.033469 -189.178357) (xy 399.032984 -189.150752)
			(xy 397.05026 -189.150752) (xy 397.049769 -189.177721) (xy 397.042169 -189.231121) (xy 397.027115 -189.282915)
			(xy 397.004907 -189.332069) (xy 396.975989 -189.377599) (xy 396.95882 -189.398402) (xy 396.952724 -189.405514)
			(xy 396.946628 -189.422532) (xy 396.94739 -189.50813) (xy 396.953994 -189.524894) (xy 396.960344 -189.532006)
			(xy 396.978413 -189.553096) (xy 397.00892 -189.599501) (xy 397.032385 -189.649835) (xy 397.04831 -189.703037)
			(xy 397.056361 -189.757985) (xy 397.056864 -189.785752) (xy 397.056379 -189.813122) (xy 397.048567 -189.8673)
			(xy 397.033083 -189.919803) (xy 397.010245 -189.969551) (xy 396.980524 -190.015518) (xy 396.962884 -190.03645)
			(xy 396.956788 -190.043562) (xy 396.950438 -190.06058) (xy 396.950438 -190.145924) (xy 396.956788 -190.162942)
			(xy 396.962884 -190.170054) (xy 396.980477 -190.191025) (xy 397.010203 -190.236986) (xy 397.033051 -190.286726)
			(xy 397.04855 -190.339223) (xy 397.056383 -190.393396) (xy 397.056388 -190.448132) (xy 397.048566 -190.502307)
			(xy 397.033076 -190.554806) (xy 397.010238 -190.60455) (xy 396.980521 -190.650517) (xy 396.962884 -190.67145)
			(xy 396.956788 -190.678562) (xy 396.950438 -190.69558) (xy 396.950438 -190.780924) (xy 396.956788 -190.797942)
			(xy 396.962884 -190.805054) (xy 396.980477 -190.826025) (xy 397.010203 -190.871986) (xy 397.033051 -190.921726)
			(xy 397.04855 -190.974223) (xy 397.056383 -191.028396) (xy 397.056388 -191.083132) (xy 397.048566 -191.137307)
			(xy 397.033076 -191.189806) (xy 397.010238 -191.23955) (xy 396.980521 -191.285517) (xy 396.962884 -191.30645)
			(xy 396.956788 -191.313562) (xy 396.950438 -191.33058) (xy 396.950438 -191.415924) (xy 396.956788 -191.432942)
			(xy 396.962884 -191.440054) (xy 396.980513 -191.460995) (xy 397.010226 -191.506965) (xy 397.033065 -191.55671)
			(xy 397.048558 -191.609209) (xy 397.056389 -191.663383) (xy 397.056864 -191.690752) (xy 397.056355 -191.719491)
			(xy 397.047726 -191.776318) (xy 397.030672 -191.831209) (xy 397.005577 -191.88292) (xy 396.973011 -191.930283)
			(xy 396.95374 -191.95161) (xy 396.947136 -191.958722) (xy 396.940024 -191.976248) (xy 396.93977 -192.065402)
			(xy 396.946882 -192.082928) (xy 396.953486 -192.09004) (xy 396.972533 -192.111328) (xy 397.004699 -192.15853)
			(xy 397.029473 -192.209999) (xy 397.046302 -192.264584) (xy 397.054809 -192.321068) (xy 397.05534 -192.349628)
			(xy 397.054905 -192.377) (xy 397.047082 -192.431181) (xy 397.031586 -192.483685) (xy 397.008737 -192.533431)
			(xy 396.979005 -192.579396) (xy 396.96136 -192.600326) (xy 396.955264 -192.607438) (xy 396.948914 -192.624456)
			(xy 396.948914 -192.7098) (xy 396.955264 -192.726818) (xy 396.96136 -192.73393) (xy 396.979029 -192.75484)
			(xy 397.008753 -192.800812) (xy 397.031598 -192.850562) (xy 397.047092 -192.903067) (xy 397.054919 -192.957249)
			(xy 397.054916 -193.011993) (xy 397.047083 -193.066174) (xy 397.031583 -193.118678) (xy 397.008733 -193.168425)
			(xy 396.979003 -193.214393) (xy 396.96136 -193.235326) (xy 396.955264 -193.242438) (xy 396.948914 -193.259456)
			(xy 396.948914 -193.3448) (xy 396.955264 -193.361818) (xy 396.96136 -193.36893) (xy 396.979029 -193.38984)
			(xy 397.008753 -193.435812) (xy 397.031598 -193.485562) (xy 397.047092 -193.538067) (xy 397.054919 -193.592249)
			(xy 397.054916 -193.646993) (xy 397.047083 -193.701174) (xy 397.031583 -193.753678) (xy 397.008733 -193.803425)
			(xy 396.979003 -193.849393) (xy 396.96136 -193.870326) (xy 396.955264 -193.877438) (xy 396.948914 -193.894456)
			(xy 396.948914 -193.9798) (xy 396.955264 -193.996818) (xy 396.96136 -194.00393) (xy 396.979029 -194.02484)
			(xy 397.008753 -194.070812) (xy 397.031598 -194.120562) (xy 397.047092 -194.173067) (xy 397.054919 -194.227249)
			(xy 397.054916 -194.281993) (xy 397.047083 -194.336174) (xy 397.031583 -194.388678) (xy 397.008733 -194.438425)
			(xy 396.979003 -194.484393) (xy 396.96136 -194.505326) (xy 396.955264 -194.512438) (xy 396.948914 -194.529456)
			(xy 396.948914 -194.6148) (xy 396.955264 -194.631818) (xy 396.96136 -194.63893) (xy 396.979029 -194.65984)
			(xy 397.008753 -194.705812) (xy 397.031598 -194.755562) (xy 397.047092 -194.808067) (xy 397.054919 -194.862249)
			(xy 397.054916 -194.916993) (xy 397.047083 -194.971174) (xy 397.031583 -195.023678) (xy 397.008733 -195.073425)
			(xy 396.979003 -195.119393) (xy 396.96136 -195.140326) (xy 396.955264 -195.147438) (xy 396.948914 -195.164456)
			(xy 396.948914 -195.2498) (xy 396.955264 -195.266818) (xy 396.96136 -195.27393) (xy 396.978974 -195.294883)
			(xy 397.008691 -195.340849) (xy 397.031532 -195.390591) (xy 397.047029 -195.443088) (xy 397.054863 -195.49726)
			(xy 397.05534 -195.524628) (xy 397.054848 -195.551878) (xy 397.047089 -195.605824) (xy 397.031732 -195.658117)
			(xy 397.00909 -195.707692) (xy 396.979623 -195.753541) (xy 396.943933 -195.79473) (xy 396.902744 -195.830421)
			(xy 396.856896 -195.859888) (xy 396.807321 -195.88253) (xy 396.755028 -195.897888) (xy 396.701082 -195.905648)
			(xy 396.673832 -195.906136) (xy 396.646462 -195.905667) (xy 396.592282 -195.897852) (xy 396.539778 -195.882365)
			(xy 396.490031 -195.859523) (xy 396.444065 -195.829798) (xy 396.423134 -195.812156) (xy 396.416022 -195.80606)
			(xy 396.399004 -195.79971) (xy 396.31366 -195.79971) (xy 396.296642 -195.80606) (xy 396.28953 -195.812156)
			(xy 396.268597 -195.829797) (xy 396.222629 -195.859521) (xy 396.172883 -195.882367) (xy 396.120381 -195.897863)
			(xy 396.066203 -195.905692) (xy 396.011461 -195.905692) (xy 395.957283 -195.897863) (xy 395.904781 -195.882367)
			(xy 395.855035 -195.859521) (xy 395.809067 -195.829797) (xy 395.788134 -195.812156) (xy 395.781022 -195.80606)
			(xy 395.764004 -195.79971) (xy 395.67866 -195.79971) (xy 395.661642 -195.80606) (xy 395.65453 -195.812156)
			(xy 395.633592 -195.829788) (xy 395.587621 -195.859502) (xy 395.537876 -195.88234) (xy 395.485376 -195.897833)
			(xy 395.431201 -195.905662) (xy 395.403832 -195.906136) (xy 395.376581 -195.905615) (xy 395.322634 -195.897863)
			(xy 395.270339 -195.882513) (xy 395.220761 -195.859876) (xy 395.174909 -195.830414) (xy 395.133716 -195.794726)
			(xy 395.098022 -195.753539) (xy 395.068553 -195.707692) (xy 395.045908 -195.658118) (xy 395.03055 -195.605825)
			(xy 395.022789 -195.551879) (xy 395.022324 -195.524628) (xy 395.022801 -195.497258) (xy 395.030615 -195.443079)
			(xy 395.046101 -195.390576) (xy 395.068941 -195.340829) (xy 395.098664 -195.294862) (xy 395.116304 -195.27393)
			(xy 395.1224 -195.266818) (xy 395.12875 -195.2498) (xy 395.12875 -195.164456) (xy 395.1224 -195.147438)
			(xy 395.116304 -195.140326) (xy 395.098692 -195.119371) (xy 395.068968 -195.073406) (xy 395.046122 -195.023664)
			(xy 395.030624 -194.971165) (xy 395.022794 -194.91699) (xy 395.022791 -194.862252) (xy 395.030615 -194.808076)
			(xy 395.046107 -194.755576) (xy 395.068947 -194.705831) (xy 395.098666 -194.659863) (xy 395.116304 -194.63893)
			(xy 395.1224 -194.631818) (xy 395.12875 -194.6148) (xy 395.12875 -194.529456) (xy 395.1224 -194.512438)
			(xy 395.116304 -194.505326) (xy 395.098692 -194.484371) (xy 395.068968 -194.438406) (xy 395.046122 -194.388664)
			(xy 395.030624 -194.336165) (xy 395.022794 -194.28199) (xy 395.022791 -194.227252) (xy 395.030615 -194.173076)
			(xy 395.046107 -194.120576) (xy 395.068947 -194.070831) (xy 395.098666 -194.024863) (xy 395.116304 -194.00393)
			(xy 395.1224 -193.996818) (xy 395.12875 -193.9798) (xy 395.12875 -193.894456) (xy 395.1224 -193.877438)
			(xy 395.116304 -193.870326) (xy 395.098692 -193.849371) (xy 395.068968 -193.803406) (xy 395.046122 -193.753664)
			(xy 395.030624 -193.701165) (xy 395.022794 -193.64699) (xy 395.022791 -193.592252) (xy 395.030615 -193.538076)
			(xy 395.046107 -193.485576) (xy 395.068947 -193.435831) (xy 395.098666 -193.389863) (xy 395.116304 -193.36893)
			(xy 395.1224 -193.361818) (xy 395.12875 -193.3448) (xy 395.12875 -193.259456) (xy 395.1224 -193.242438)
			(xy 395.116304 -193.235326) (xy 395.098692 -193.214371) (xy 395.068968 -193.168406) (xy 395.046122 -193.118664)
			(xy 395.030624 -193.066165) (xy 395.022794 -193.01199) (xy 395.022791 -192.957252) (xy 395.030615 -192.903076)
			(xy 395.046107 -192.850576) (xy 395.068947 -192.800831) (xy 395.098666 -192.754863) (xy 395.116304 -192.73393)
			(xy 395.1224 -192.726818) (xy 395.12875 -192.7098) (xy 395.12875 -192.624456) (xy 395.1224 -192.607438)
			(xy 395.116304 -192.600326) (xy 395.098692 -192.579371) (xy 395.068968 -192.533406) (xy 395.046122 -192.483664)
			(xy 395.030624 -192.431165) (xy 395.022794 -192.37699) (xy 395.022791 -192.322252) (xy 395.030615 -192.268076)
			(xy 395.046107 -192.215576) (xy 395.068947 -192.165831) (xy 395.098666 -192.119863) (xy 395.116304 -192.09893)
			(xy 395.1224 -192.091818) (xy 395.12875 -192.0748) (xy 395.12875 -191.989456) (xy 395.1224 -191.972438)
			(xy 395.116304 -191.965326) (xy 395.098692 -191.944371) (xy 395.068968 -191.898406) (xy 395.046122 -191.848664)
			(xy 395.030624 -191.796165) (xy 395.022794 -191.74199) (xy 395.022791 -191.687252) (xy 395.030615 -191.633076)
			(xy 395.046107 -191.580576) (xy 395.068947 -191.530831) (xy 395.098666 -191.484863) (xy 395.116304 -191.46393)
			(xy 395.1224 -191.456818) (xy 395.12875 -191.4398) (xy 395.12875 -191.354456) (xy 395.1224 -191.337438)
			(xy 395.116304 -191.330326) (xy 395.098692 -191.309371) (xy 395.068968 -191.263406) (xy 395.046122 -191.213664)
			(xy 395.030624 -191.161165) (xy 395.022794 -191.10699) (xy 395.022791 -191.052252) (xy 395.030615 -190.998076)
			(xy 395.046107 -190.945576) (xy 395.068947 -190.895831) (xy 395.098666 -190.849863) (xy 395.116304 -190.82893)
			(xy 395.1224 -190.821818) (xy 395.12875 -190.8048) (xy 395.12875 -190.719456) (xy 395.1224 -190.702438)
			(xy 395.116304 -190.695326) (xy 395.098692 -190.674371) (xy 395.068968 -190.628406) (xy 395.046122 -190.578664)
			(xy 395.030624 -190.526165) (xy 395.022794 -190.47199) (xy 395.022791 -190.417252) (xy 395.030615 -190.363076)
			(xy 395.046107 -190.310576) (xy 395.068947 -190.260831) (xy 395.098666 -190.214863) (xy 395.116304 -190.19393)
			(xy 395.1224 -190.186818) (xy 395.12875 -190.1698) (xy 395.12875 -190.084456) (xy 395.1224 -190.067438)
			(xy 395.116304 -190.060326) (xy 395.098664 -190.039394) (xy 395.068952 -189.993422) (xy 395.046116 -189.943674)
			(xy 395.030626 -189.891173) (xy 395.022798 -189.836997) (xy 395.022324 -189.809628) (xy 395.022851 -189.781268)
			(xy 395.03124 -189.725173) (xy 395.04785 -189.670941) (xy 395.072315 -189.619771) (xy 395.104095 -189.572791)
			(xy 395.122908 -189.551564) (xy 395.129512 -189.544452) (xy 395.13637 -189.526672) (xy 395.135608 -189.437772)
			(xy 395.128496 -189.420246) (xy 395.121638 -189.413134) (xy 395.102126 -189.39175) (xy 395.069135 -189.344185)
			(xy 395.043718 -189.292177) (xy 395.026459 -189.236924) (xy 395.017756 -189.179696) (xy 395.017244 -189.150752)
			(xy 354.82276 -189.150752) (xy 357.98379 -192.311782) (xy 361.16387 -192.311782) (xy 361.164308 -192.284411)
			(xy 361.17213 -192.23023) (xy 361.187625 -192.177726) (xy 361.210473 -192.127979) (xy 361.240205 -192.082014)
			(xy 361.25785 -192.061084) (xy 361.263946 -192.053972) (xy 361.270296 -192.036954) (xy 361.270296 -191.95161)
			(xy 361.263946 -191.934592) (xy 361.25785 -191.92748) (xy 361.240191 -191.906562) (xy 361.210465 -191.860592)
			(xy 361.187619 -191.810844) (xy 361.172123 -191.758339) (xy 361.164296 -191.704158) (xy 361.164298 -191.649415)
			(xy 361.172129 -191.595234) (xy 361.187629 -191.542731) (xy 361.210478 -191.492984) (xy 361.240207 -191.447016)
			(xy 361.25785 -191.426084) (xy 361.263946 -191.418972) (xy 361.270296 -191.401954) (xy 361.270296 -191.31661)
			(xy 361.263946 -191.299592) (xy 361.25785 -191.29248) (xy 361.240191 -191.271562) (xy 361.210465 -191.225592)
			(xy 361.187619 -191.175844) (xy 361.172123 -191.123339) (xy 361.164296 -191.069158) (xy 361.164298 -191.014415)
			(xy 361.172129 -190.960234) (xy 361.187629 -190.907731) (xy 361.210478 -190.857984) (xy 361.240207 -190.812016)
			(xy 361.25785 -190.791084) (xy 361.263946 -190.783972) (xy 361.270296 -190.766954) (xy 361.270296 -190.68161)
			(xy 361.263946 -190.664592) (xy 361.25785 -190.65748) (xy 361.240243 -190.636522) (xy 361.210524 -190.590557)
			(xy 361.187682 -190.540816) (xy 361.172183 -190.488321) (xy 361.164348 -190.43415) (xy 361.16387 -190.406782)
			(xy 361.164354 -190.378148) (xy 361.172906 -190.321521) (xy 361.189828 -190.26681) (xy 361.214741 -190.215244)
			(xy 361.247085 -190.167983) (xy 361.266232 -190.146686) (xy 361.272836 -190.139574) (xy 361.279694 -190.122048)
			(xy 361.280202 -190.033656) (xy 361.273344 -190.015876) (xy 361.26674 -190.008764) (xy 361.247972 -189.987544)
			(xy 361.216273 -189.940595) (xy 361.19187 -189.889473) (xy 361.175299 -189.835304) (xy 361.166924 -189.779278)
			(xy 361.16641 -189.750954) (xy 361.166835 -189.723701) (xy 361.174598 -189.66975) (xy 361.18996 -189.617453)
			(xy 361.212608 -189.567874) (xy 361.242081 -189.522023) (xy 361.277779 -189.480833) (xy 361.318975 -189.445142)
			(xy 361.364831 -189.415677) (xy 361.414413 -189.393038) (xy 361.466713 -189.377685) (xy 361.520665 -189.369931)
			(xy 361.547918 -189.369446) (xy 361.575289 -189.36989) (xy 361.62947 -189.377712) (xy 361.681973 -189.393205)
			(xy 361.73172 -189.416052) (xy 361.777685 -189.445782) (xy 361.798616 -189.463426) (xy 361.805728 -189.469522)
			(xy 361.822746 -189.475872) (xy 361.90809 -189.475872) (xy 361.925108 -189.469522) (xy 361.93222 -189.463426)
			(xy 361.953153 -189.445785) (xy 361.999121 -189.416061) (xy 362.048867 -189.393215) (xy 362.101369 -189.377719)
			(xy 362.155547 -189.36989) (xy 362.210289 -189.36989) (xy 362.264467 -189.377719) (xy 362.316969 -189.393215)
			(xy 362.366715 -189.416061) (xy 362.412683 -189.445785) (xy 362.433616 -189.463426) (xy 362.440728 -189.469522)
			(xy 362.457746 -189.475872) (xy 362.54309 -189.475872) (xy 362.560108 -189.469522) (xy 362.56722 -189.463426)
			(xy 362.588175 -189.445815) (xy 362.634141 -189.416098) (xy 362.683883 -189.393256) (xy 362.736378 -189.377759)
			(xy 362.79055 -189.369924) (xy 362.817918 -189.369446) (xy 362.845168 -189.369961) (xy 362.899112 -189.377719)
			(xy 362.951403 -189.393074) (xy 363.000978 -189.415714) (xy 363.046826 -189.445178) (xy 363.088014 -189.480866)
			(xy 363.123706 -189.522052) (xy 363.153173 -189.567898) (xy 363.175816 -189.61747) (xy 363.191175 -189.669761)
			(xy 363.198937 -189.723704) (xy 363.199426 -189.750954) (xy 365.18215 -189.750954) (xy 365.182635 -189.723704)
			(xy 365.190397 -189.669758) (xy 365.205755 -189.617466) (xy 365.228399 -189.567891) (xy 365.257866 -189.522043)
			(xy 365.293557 -189.480854) (xy 365.334746 -189.445164) (xy 365.380595 -189.415697) (xy 365.43017 -189.393054)
			(xy 365.482462 -189.377696) (xy 365.536408 -189.369935) (xy 365.563658 -189.369446) (xy 365.591028 -189.369925)
			(xy 365.645207 -189.377738) (xy 365.69771 -189.393224) (xy 365.747457 -189.416063) (xy 365.793424 -189.445785)
			(xy 365.814356 -189.463426) (xy 365.821468 -189.469522) (xy 365.838486 -189.475872) (xy 365.92383 -189.475872)
			(xy 365.940848 -189.469522) (xy 365.94796 -189.463426) (xy 365.9689 -189.445796) (xy 366.01487 -189.416082)
			(xy 366.064616 -189.393244) (xy 366.117115 -189.377751) (xy 366.171289 -189.369921) (xy 366.198658 -189.369446)
			(xy 366.225906 -189.370017) (xy 366.279848 -189.377767) (xy 366.332139 -189.393114) (xy 366.381713 -189.415747)
			(xy 366.427561 -189.445205) (xy 366.46875 -189.480887) (xy 366.504443 -189.522069) (xy 366.533911 -189.56791)
			(xy 366.556555 -189.617479) (xy 366.571915 -189.669766) (xy 366.579677 -189.723706) (xy 366.580166 -189.750954)
			(xy 366.579696 -189.778088) (xy 366.572006 -189.831809) (xy 366.556774 -189.883895) (xy 366.534308 -189.933295)
			(xy 366.505064 -189.979009) (xy 366.48771 -189.999874) (xy 366.481614 -190.006986) (xy 366.475518 -190.024004)
			(xy 366.476026 -190.109348) (xy 366.482376 -190.126366) (xy 366.488726 -190.133478) (xy 366.506647 -190.15448)
			(xy 366.536837 -190.200704) (xy 366.560047 -190.250798) (xy 366.575793 -190.303715) (xy 366.583745 -190.358349)
			(xy 366.58423 -190.385954) (xy 366.583754 -190.413324) (xy 366.575941 -190.467503) (xy 366.560455 -190.520007)
			(xy 366.537615 -190.569754) (xy 366.507891 -190.615721) (xy 366.49025 -190.636652) (xy 366.484154 -190.643764)
			(xy 366.477804 -190.660782) (xy 366.477804 -190.746126) (xy 366.484154 -190.763144) (xy 366.49025 -190.770256)
			(xy 366.507847 -190.791225) (xy 366.537575 -190.837186) (xy 366.560424 -190.886926) (xy 366.575925 -190.939423)
			(xy 366.583759 -190.993597) (xy 366.583764 -191.048334) (xy 366.57594 -191.10251) (xy 366.560449 -191.155009)
			(xy 366.537608 -191.204753) (xy 366.507888 -191.25072) (xy 366.49025 -191.271652) (xy 366.484154 -191.278764)
			(xy 366.477804 -191.295782) (xy 366.477804 -191.381126) (xy 366.484154 -191.398144) (xy 366.49025 -191.405256)
			(xy 366.507874 -191.4262) (xy 366.53759 -191.472169) (xy 366.56043 -191.521913) (xy 366.575924 -191.574412)
			(xy 366.583755 -191.628586) (xy 366.58423 -191.655954) (xy 366.583681 -191.685431) (xy 366.574617 -191.743685)
			(xy 366.556697 -191.79985) (xy 366.530349 -191.85259) (xy 366.496201 -191.900647) (xy 366.476026 -191.922146)
			(xy 366.469469 -191.929463) (xy 366.462039 -191.947637) (xy 366.461548 -191.957452) (xy 366.461548 -192.010792)
			(xy 366.464088 -192.013078) (xy 366.470946 -192.019428) (xy 366.487964 -192.02654) (xy 366.573816 -192.029334)
			(xy 366.591342 -192.023492) (xy 366.598454 -192.017396) (xy 366.61903 -192.000962) (xy 366.663881 -191.973366)
			(xy 366.712104 -191.952208) (xy 366.762781 -191.937893) (xy 366.814947 -191.930693) (xy 366.841278 -191.930274)
			(xy 366.868529 -191.930776) (xy 366.922478 -191.938529) (xy 366.974774 -191.953882) (xy 367.024353 -191.97652)
			(xy 367.070205 -192.005984) (xy 367.111398 -192.041674) (xy 367.147092 -192.082863) (xy 367.176561 -192.128712)
			(xy 367.199204 -192.178288) (xy 367.214562 -192.230583) (xy 367.222321 -192.284531) (xy 367.222786 -192.311782)
			(xy 367.222313 -192.339152) (xy 367.214497 -192.393331) (xy 367.19901 -192.445834) (xy 367.17617 -192.495581)
			(xy 367.146447 -192.541548) (xy 367.128806 -192.56248) (xy 367.12271 -192.569592) (xy 367.11636 -192.58661)
			(xy 367.11636 -192.671954) (xy 367.12271 -192.688972) (xy 367.128806 -192.696084) (xy 367.146428 -192.717032)
			(xy 367.176151 -192.762998) (xy 367.198995 -192.812742) (xy 367.214491 -192.865241) (xy 367.222321 -192.919417)
			(xy 367.222323 -192.974156) (xy 367.214497 -193.028332) (xy 367.199005 -193.080833) (xy 367.176164 -193.130579)
			(xy 367.146444 -193.176547) (xy 367.128806 -193.19748) (xy 367.12271 -193.204592) (xy 367.11636 -193.22161)
			(xy 367.11636 -193.306954) (xy 367.12271 -193.323972) (xy 367.128806 -193.331084) (xy 367.146428 -193.352032)
			(xy 367.176151 -193.397998) (xy 367.198995 -193.447742) (xy 367.214491 -193.500241) (xy 367.222321 -193.554417)
			(xy 367.222323 -193.609156) (xy 367.214497 -193.663332) (xy 367.199005 -193.715833) (xy 367.176164 -193.765579)
			(xy 367.146444 -193.811547) (xy 367.128806 -193.83248) (xy 367.12271 -193.839592) (xy 367.11636 -193.85661)
			(xy 367.11636 -193.941954) (xy 367.12271 -193.958972) (xy 367.128806 -193.966084) (xy 367.146428 -193.987032)
			(xy 367.176151 -194.032998) (xy 367.198995 -194.082742) (xy 367.214491 -194.135241) (xy 367.222321 -194.189417)
			(xy 367.222323 -194.244156) (xy 367.214497 -194.298332) (xy 367.199005 -194.350833) (xy 367.176164 -194.400579)
			(xy 367.146444 -194.446547) (xy 367.128806 -194.46748) (xy 367.12271 -194.474592) (xy 367.11636 -194.49161)
			(xy 367.11636 -194.576954) (xy 367.12271 -194.593972) (xy 367.128806 -194.601084) (xy 367.146428 -194.622032)
			(xy 367.176151 -194.667998) (xy 367.198995 -194.717742) (xy 367.214491 -194.770241) (xy 367.222321 -194.824417)
			(xy 367.222323 -194.879156) (xy 367.214497 -194.933332) (xy 367.199005 -194.985833) (xy 367.176164 -195.035579)
			(xy 367.146444 -195.081547) (xy 367.128806 -195.10248) (xy 367.12271 -195.109592) (xy 367.11636 -195.12661)
			(xy 367.11636 -195.211954) (xy 367.12271 -195.228972) (xy 367.128806 -195.236084) (xy 367.146428 -195.257032)
			(xy 367.176151 -195.302998) (xy 367.198995 -195.352742) (xy 367.214491 -195.405241) (xy 367.222321 -195.459417)
			(xy 367.222323 -195.514156) (xy 367.214497 -195.568332) (xy 367.199005 -195.620833) (xy 367.176164 -195.670579)
			(xy 367.146444 -195.716547) (xy 367.128806 -195.73748) (xy 367.12271 -195.744592) (xy 367.11636 -195.76161)
			(xy 367.11636 -195.846954) (xy 367.12271 -195.863972) (xy 367.128806 -195.871084) (xy 367.146452 -195.89201)
			(xy 367.176163 -195.937985) (xy 367.198997 -195.987734) (xy 367.214487 -196.040236) (xy 367.222313 -196.094412)
			(xy 367.222786 -196.121782) (xy 367.222328 -196.149035) (xy 367.214573 -196.202988) (xy 367.199218 -196.255287)
			(xy 367.176576 -196.304868) (xy 367.147108 -196.350723) (xy 367.111413 -196.391916) (xy 367.07022 -196.42761)
			(xy 367.024365 -196.457078) (xy 366.974783 -196.479719) (xy 366.922484 -196.495074) (xy 366.868531 -196.502828)
			(xy 366.841278 -196.50329) (xy 366.813907 -196.502839) (xy 366.759727 -196.495018) (xy 366.707224 -196.479526)
			(xy 366.657477 -196.45668) (xy 366.611511 -196.426953) (xy 366.59058 -196.40931) (xy 366.583468 -196.403214)
			(xy 366.56645 -196.396864) (xy 366.481106 -196.396864) (xy 366.464088 -196.403214) (xy 366.456976 -196.40931)
			(xy 366.436027 -196.426928) (xy 366.390059 -196.456643) (xy 366.340316 -196.479483) (xy 366.287819 -196.494979)
			(xy 366.233646 -196.502813) (xy 366.206278 -196.50329) (xy 366.179025 -196.502843) (xy 366.125075 -196.495083)
			(xy 366.072779 -196.479724) (xy 366.0232 -196.457079) (xy 365.977349 -196.427609) (xy 365.936159 -196.391913)
			(xy 365.900467 -196.350719) (xy 365.871002 -196.304865) (xy 365.848362 -196.255284) (xy 365.833009 -196.202986)
			(xy 365.825255 -196.149035) (xy 365.82477 -196.121782) (xy 365.825279 -196.092303) (xy 365.834353 -196.034047)
			(xy 365.852282 -195.977882) (xy 365.878638 -195.925143) (xy 365.912795 -195.877087) (xy 365.932974 -195.85559)
			(xy 365.939516 -195.848261) (xy 365.946955 -195.830096) (xy 365.947452 -195.820284) (xy 365.947452 -195.766944)
			(xy 365.940086 -195.760086) (xy 365.932752 -195.75355) (xy 365.914591 -195.746106) (xy 365.90478 -195.745608)
			(xy 365.872776 -195.745608) (xy 365.862961 -195.746089) (xy 365.844797 -195.753537) (xy 365.83747 -195.760086)
			(xy 365.815989 -195.78028) (xy 365.767924 -195.81442) (xy 365.71518 -195.840762) (xy 365.659012 -195.858679)
			(xy 365.600756 -195.867743) (xy 365.571278 -195.86829) (xy 365.544025 -195.867843) (xy 365.490075 -195.860083)
			(xy 365.437779 -195.844724) (xy 365.3882 -195.822079) (xy 365.342349 -195.792609) (xy 365.301159 -195.756913)
			(xy 365.265467 -195.715719) (xy 365.236002 -195.669865) (xy 365.213362 -195.620284) (xy 365.198009 -195.567986)
			(xy 365.190255 -195.514035) (xy 365.18977 -195.486782) (xy 365.190208 -195.459411) (xy 365.19803 -195.40523)
			(xy 365.213525 -195.352726) (xy 365.236373 -195.302979) (xy 365.266105 -195.257014) (xy 365.28375 -195.236084)
			(xy 365.289846 -195.228972) (xy 365.296196 -195.211954) (xy 365.296196 -195.12661) (xy 365.289846 -195.109592)
			(xy 365.28375 -195.10248) (xy 365.266091 -195.081562) (xy 365.236365 -195.035592) (xy 365.213519 -194.985844)
			(xy 365.198023 -194.933339) (xy 365.190196 -194.879158) (xy 365.190198 -194.824415) (xy 365.198029 -194.770234)
			(xy 365.213529 -194.717731) (xy 365.236378 -194.667984) (xy 365.266107 -194.622016) (xy 365.28375 -194.601084)
			(xy 365.289846 -194.593972) (xy 365.296196 -194.576954) (xy 365.296196 -194.49161) (xy 365.289846 -194.474592)
			(xy 365.28375 -194.46748) (xy 365.266091 -194.446562) (xy 365.236365 -194.400592) (xy 365.213519 -194.350844)
			(xy 365.198023 -194.298339) (xy 365.190196 -194.244158) (xy 365.190198 -194.189415) (xy 365.198029 -194.135234)
			(xy 365.213529 -194.082731) (xy 365.236378 -194.032984) (xy 365.266107 -193.987016) (xy 365.28375 -193.966084)
			(xy 365.289846 -193.958972) (xy 365.296196 -193.941954) (xy 365.296196 -193.85661) (xy 365.289846 -193.839592)
			(xy 365.28375 -193.83248) (xy 365.266091 -193.811562) (xy 365.236365 -193.765592) (xy 365.213519 -193.715844)
			(xy 365.198023 -193.663339) (xy 365.190196 -193.609158) (xy 365.190198 -193.554415) (xy 365.198029 -193.500234)
			(xy 365.213529 -193.447731) (xy 365.236378 -193.397984) (xy 365.266107 -193.352016) (xy 365.28375 -193.331084)
			(xy 365.289846 -193.323972) (xy 365.296196 -193.306954) (xy 365.296196 -193.22161) (xy 365.289846 -193.204592)
			(xy 365.28375 -193.19748) (xy 365.266143 -193.176522) (xy 365.236424 -193.130557) (xy 365.213582 -193.080816)
			(xy 365.198083 -193.028321) (xy 365.190248 -192.97415) (xy 365.18977 -192.946782) (xy 365.190317 -192.918496)
			(xy 365.198672 -192.862543) (xy 365.215196 -192.808438) (xy 365.239527 -192.757364) (xy 365.271132 -192.710443)
			(xy 365.289846 -192.689226) (xy 365.296196 -192.682114) (xy 365.303054 -192.664588) (xy 365.302546 -192.576196)
			(xy 365.295688 -192.558416) (xy 365.289084 -192.551304) (xy 365.269864 -192.530013) (xy 365.237402 -192.482726)
			(xy 365.212384 -192.431113) (xy 365.195371 -192.376337) (xy 365.186749 -192.319632) (xy 365.186214 -192.290954)
			(xy 365.186708 -192.263585) (xy 365.194519 -192.209407) (xy 365.210001 -192.156904) (xy 365.232837 -192.107156)
			(xy 365.262555 -192.061188) (xy 365.280194 -192.040256) (xy 365.28629 -192.033144) (xy 365.29264 -192.016126)
			(xy 365.29264 -191.930782) (xy 365.28629 -191.913764) (xy 365.280194 -191.906652) (xy 365.26251 -191.885755)
			(xy 365.232789 -191.83978) (xy 365.209949 -191.790028) (xy 365.194457 -191.737521) (xy 365.186634 -191.683338)
			(xy 365.186639 -191.628593) (xy 365.194472 -191.574412) (xy 365.209973 -191.521907) (xy 365.232823 -191.472159)
			(xy 365.262551 -191.426189) (xy 365.280194 -191.405256) (xy 365.28629 -191.398144) (xy 365.29264 -191.381126)
			(xy 365.29264 -191.295782) (xy 365.28629 -191.278764) (xy 365.280194 -191.271652) (xy 365.26251 -191.250755)
			(xy 365.232789 -191.20478) (xy 365.209949 -191.155028) (xy 365.194457 -191.102521) (xy 365.186634 -191.048338)
			(xy 365.186639 -190.993593) (xy 365.194472 -190.939412) (xy 365.209973 -190.886907) (xy 365.232823 -190.837159)
			(xy 365.262551 -190.791189) (xy 365.280194 -190.770256) (xy 365.28629 -190.763144) (xy 365.29264 -190.746126)
			(xy 365.29264 -190.660782) (xy 365.28629 -190.643764) (xy 365.280194 -190.636652) (xy 365.262565 -190.615712)
			(xy 365.232852 -190.569741) (xy 365.210014 -190.519996) (xy 365.194521 -190.467497) (xy 365.18669 -190.413323)
			(xy 365.186214 -190.385954) (xy 365.186693 -190.35882) (xy 365.194382 -190.3051) (xy 365.209612 -190.253014)
			(xy 365.232075 -190.203614) (xy 365.261318 -190.157899) (xy 365.27867 -190.137034) (xy 365.284766 -190.129922)
			(xy 365.290862 -190.112904) (xy 365.290354 -190.02756) (xy 365.284004 -190.010542) (xy 365.277654 -190.00343)
			(xy 365.259734 -189.982428) (xy 365.229544 -189.936203) (xy 365.206334 -189.886109) (xy 365.190588 -189.833193)
			(xy 365.182635 -189.778559) (xy 365.18215 -189.750954) (xy 363.199426 -189.750954) (xy 363.198944 -189.777923)
			(xy 363.191343 -189.831324) (xy 363.176288 -189.883118) (xy 363.154077 -189.932272) (xy 363.125157 -189.977802)
			(xy 363.107986 -189.998604) (xy 363.10189 -190.005716) (xy 363.095794 -190.022734) (xy 363.096556 -190.108332)
			(xy 363.10316 -190.125096) (xy 363.10951 -190.132208) (xy 363.127574 -190.153302) (xy 363.158084 -190.199705)
			(xy 363.181549 -190.250038) (xy 363.197476 -190.30324) (xy 363.205528 -190.358187) (xy 363.20603 -190.385954)
			(xy 363.205554 -190.413324) (xy 363.197741 -190.467503) (xy 363.182255 -190.520007) (xy 363.159415 -190.569754)
			(xy 363.129691 -190.615721) (xy 363.11205 -190.636652) (xy 363.105954 -190.643764) (xy 363.099604 -190.660782)
			(xy 363.099604 -190.746126) (xy 363.105954 -190.763144) (xy 363.11205 -190.770256) (xy 363.129647 -190.791225)
			(xy 363.159375 -190.837186) (xy 363.182224 -190.886926) (xy 363.197725 -190.939423) (xy 363.205559 -190.993597)
			(xy 363.205564 -191.048334) (xy 363.19774 -191.10251) (xy 363.182249 -191.155009) (xy 363.159408 -191.204753)
			(xy 363.129688 -191.25072) (xy 363.11205 -191.271652) (xy 363.105954 -191.278764) (xy 363.099604 -191.295782)
			(xy 363.099604 -191.381126) (xy 363.105954 -191.398144) (xy 363.11205 -191.405256) (xy 363.129647 -191.426225)
			(xy 363.159375 -191.472186) (xy 363.182224 -191.521926) (xy 363.197725 -191.574423) (xy 363.205559 -191.628597)
			(xy 363.205564 -191.683334) (xy 363.19774 -191.73751) (xy 363.182249 -191.790009) (xy 363.159408 -191.839753)
			(xy 363.129688 -191.88572) (xy 363.11205 -191.906652) (xy 363.105954 -191.913764) (xy 363.099604 -191.930782)
			(xy 363.099604 -192.016126) (xy 363.105954 -192.033144) (xy 363.11205 -192.040256) (xy 363.129674 -192.0612)
			(xy 363.15939 -192.107169) (xy 363.18223 -192.156913) (xy 363.197724 -192.209412) (xy 363.205555 -192.263586)
			(xy 363.20603 -192.290954) (xy 363.205462 -192.319965) (xy 363.1967 -192.377321) (xy 363.179357 -192.432689)
			(xy 363.153831 -192.484793) (xy 363.120711 -192.532433) (xy 363.101128 -192.553844) (xy 363.09427 -192.560956)
			(xy 363.087158 -192.578482) (xy 363.085888 -192.666874) (xy 363.092492 -192.6844) (xy 363.099096 -192.691766)
			(xy 363.117437 -192.712859) (xy 363.148343 -192.759433) (xy 363.172118 -192.81002) (xy 363.188253 -192.863536)
			(xy 363.196402 -192.918834) (xy 363.196886 -192.946782) (xy 363.196413 -192.974152) (xy 363.188597 -193.028331)
			(xy 363.17311 -193.080834) (xy 363.15027 -193.130581) (xy 363.120547 -193.176548) (xy 363.102906 -193.19748)
			(xy 363.09681 -193.204592) (xy 363.09046 -193.22161) (xy 363.09046 -193.306954) (xy 363.09681 -193.323972)
			(xy 363.102906 -193.331084) (xy 363.120552 -193.35201) (xy 363.150263 -193.397985) (xy 363.173097 -193.447734)
			(xy 363.188587 -193.500236) (xy 363.196413 -193.554412) (xy 363.196886 -193.581782) (xy 363.1964 -193.609033)
			(xy 363.188644 -193.662981) (xy 363.173289 -193.715276) (xy 363.150647 -193.764853) (xy 363.121181 -193.810703)
			(xy 363.08549 -193.851894) (xy 363.044299 -193.887585) (xy 362.998449 -193.917051) (xy 362.948872 -193.939693)
			(xy 362.896577 -193.955048) (xy 362.842629 -193.962804) (xy 362.788127 -193.962804) (xy 362.734179 -193.955048)
			(xy 362.681884 -193.939693) (xy 362.632307 -193.917051) (xy 362.586457 -193.887585) (xy 362.545266 -193.851894)
			(xy 362.509575 -193.810703) (xy 362.480109 -193.764853) (xy 362.457467 -193.715276) (xy 362.442112 -193.662981)
			(xy 362.434356 -193.609033) (xy 362.43387 -193.581782) (xy 362.434379 -193.552303) (xy 362.443453 -193.494047)
			(xy 362.461382 -193.437882) (xy 362.487738 -193.385143) (xy 362.521895 -193.337087) (xy 362.542074 -193.31559)
			(xy 362.548616 -193.308261) (xy 362.556055 -193.290096) (xy 362.556552 -193.280284) (xy 362.556552 -193.226944)
			(xy 362.549186 -193.220086) (xy 362.541852 -193.21355) (xy 362.523691 -193.206106) (xy 362.51388 -193.205608)
			(xy 362.481876 -193.205608) (xy 362.472061 -193.206089) (xy 362.453897 -193.213537) (xy 362.44657 -193.220086)
			(xy 362.425089 -193.24028) (xy 362.377024 -193.27442) (xy 362.32428 -193.300762) (xy 362.268112 -193.318679)
			(xy 362.209856 -193.327743) (xy 362.180378 -193.32829) (xy 362.153125 -193.327843) (xy 362.099175 -193.320083)
			(xy 362.046879 -193.304724) (xy 361.9973 -193.282079) (xy 361.951449 -193.252609) (xy 361.910259 -193.216913)
			(xy 361.874567 -193.175719) (xy 361.845102 -193.129865) (xy 361.822462 -193.080284) (xy 361.807109 -193.027986)
			(xy 361.799355 -192.974035) (xy 361.79887 -192.946782) (xy 361.799306 -192.920708) (xy 361.8064 -192.869043)
			(xy 361.820466 -192.818828) (xy 361.841242 -192.770996) (xy 361.868342 -192.726441) (xy 361.901258 -192.685994)
			(xy 361.920028 -192.66789) (xy 361.927239 -192.66057) (xy 361.935614 -192.641823) (xy 361.936284 -192.631568)
			(xy 361.937046 -192.576958) (xy 361.928156 -192.56883) (xy 361.920505 -192.562272) (xy 361.901656 -192.555196)
			(xy 361.89158 -192.555114) (xy 361.859576 -192.55613) (xy 361.849618 -192.556927) (xy 361.831444 -192.565178)
			(xy 361.82427 -192.572132) (xy 361.806179 -192.590915) (xy 361.765726 -192.623827) (xy 361.721168 -192.650923)
			(xy 361.673335 -192.671699) (xy 361.623118 -192.685768) (xy 361.571453 -192.692867) (xy 361.545378 -192.69329)
			(xy 361.518125 -192.692843) (xy 361.464175 -192.685083) (xy 361.411879 -192.669724) (xy 361.3623 -192.647079)
			(xy 361.316449 -192.617609) (xy 361.275259 -192.581913) (xy 361.239567 -192.540719) (xy 361.210102 -192.494865)
			(xy 361.187462 -192.445284) (xy 361.172109 -192.392986) (xy 361.164355 -192.339035) (xy 361.16387 -192.311782)
			(xy 357.98379 -192.311782) (xy 364.203488 -198.53148) (xy 364.210194 -198.538815) (xy 364.217886 -198.557117)
			(xy 364.218474 -198.56704) (xy 364.218474 -198.573644) (xy 364.220506 -198.58101) (xy 364.22246 -198.587407)
			(xy 364.229146 -198.598985) (xy 364.233714 -198.60387) (xy 366.793526 -201.163682) (xy 366.794034 -201.16419)
			(xy 366.801416 -201.170771) (xy 366.819714 -201.178223) (xy 366.829594 -201.178668)
		)
		(stroke
			(width 0)
			(type solid)
		)
		(fill yes)
		(layer "In6.Cu")
		(net "GND")
	)
	(gr_poly
		(pts
			(xy 311.098184 -335.089754) (xy 311.108246 -335.089314) (xy 311.126824 -335.081573) (xy 311.134252 -335.074768)
			(xy 311.744868 -334.464152) (xy 311.751564 -334.456747) (xy 311.75917 -334.43831) (xy 311.7596 -334.428338)
			(xy 311.7596 -330.64704) (xy 311.759854 -330.639166) (xy 311.759854 -329.92314) (xy 311.760387 -329.913301)
			(xy 311.767966 -329.895133) (xy 311.774586 -329.887834) (xy 314.132722 -327.529698) (xy 314.13996 -327.522985)
			(xy 314.158165 -327.515393) (xy 314.168028 -327.514966) (xy 314.884054 -327.514966) (xy 314.891928 -327.514712)
			(xy 344.719656 -327.514712) (xy 344.72753 -327.514966) (xy 348.066868 -327.514966) (xy 348.076931 -327.515403)
			(xy 348.095512 -327.523142) (xy 348.102936 -327.529952) (xy 348.823788 -328.250804) (xy 348.831186 -328.257652)
			(xy 348.849784 -328.26539) (xy 348.859856 -328.26579) (xy 354.593398 -328.26579) (xy 354.603468 -328.265367)
			(xy 354.622072 -328.257652) (xy 354.629466 -328.250804) (xy 354.809044 -328.071226) (xy 354.815885 -328.063826)
			(xy 354.823601 -328.045227) (xy 354.82403 -328.035158) (xy 354.82403 -320.331592) (xy 354.823718 -320.324104)
			(xy 354.819319 -320.309784) (xy 354.815394 -320.303398) (xy 348.628462 -311.043828) (xy 348.622039 -311.035052)
			(xy 348.603635 -311.023506) (xy 348.582106 -311.020583) (xy 348.571566 -311.023254) (xy 348.555564 -311.02808)
			(xy 348.535752 -311.055004) (xy 348.535752 -311.168034) (xy 348.54134 -311.18429) (xy 348.547182 -311.191148)
			(xy 348.568896 -311.218546) (xy 348.605398 -311.278169) (xy 348.63339 -311.34223) (xy 348.652343 -311.409521)
			(xy 348.661901 -311.478773) (xy 348.662498 -311.513728) (xy 348.662032 -311.544458) (xy 348.654621 -311.605469)
			(xy 348.63991 -311.665141) (xy 348.618113 -311.722606) (xy 348.589549 -311.777024) (xy 348.554634 -311.827603)
			(xy 348.513877 -311.873604) (xy 348.467873 -311.914358) (xy 348.417292 -311.949269) (xy 348.362871 -311.977829)
			(xy 348.305405 -311.999621) (xy 348.245731 -312.014328) (xy 348.18472 -312.021735) (xy 348.15399 -312.022236)
			(xy 348.122937 -312.02175) (xy 348.061297 -312.014156) (xy 348.001036 -311.999131) (xy 347.971872 -311.988454)
			(xy 347.962982 -311.985152) (xy 347.94444 -311.985152) (xy 347.863668 -312.015886) (xy 347.849698 -312.028078)
			(xy 347.84538 -312.03646) (xy 347.832984 -312.059372) (xy 347.802913 -312.101908) (xy 347.767335 -312.139958)
			(xy 347.726912 -312.172815) (xy 347.682395 -312.199868) (xy 347.634611 -312.220614) (xy 347.58445 -312.234667)
			(xy 347.532844 -312.241767) (xy 347.506798 -312.2422) (xy 347.479547 -312.241714) (xy 347.425601 -312.233958)
			(xy 347.373308 -312.218603) (xy 347.323732 -312.195962) (xy 347.277882 -312.166496) (xy 347.236693 -312.130805)
			(xy 347.201003 -312.089616) (xy 347.171537 -312.043767) (xy 347.148897 -311.994191) (xy 347.133542 -311.941897)
			(xy 347.125786 -311.887951) (xy 347.125786 -311.833449) (xy 347.133542 -311.779503) (xy 347.148897 -311.727209)
			(xy 347.171537 -311.677633) (xy 347.201003 -311.631784) (xy 347.236693 -311.590595) (xy 347.277882 -311.554904)
			(xy 347.323732 -311.525438) (xy 347.373308 -311.502797) (xy 347.425601 -311.487442) (xy 347.479547 -311.479686)
			(xy 347.506798 -311.479184) (xy 347.517043 -311.479272) (xy 347.537501 -311.480415) (xy 347.547692 -311.48147)
			(xy 347.55709 -311.482486) (xy 347.575124 -311.47766) (xy 347.645482 -311.427368) (xy 347.655642 -311.411874)
			(xy 347.657674 -311.402476) (xy 347.664567 -311.373613) (xy 347.684196 -311.317609) (xy 347.710221 -311.264276)
			(xy 347.742286 -311.214341) (xy 347.760798 -311.191148) (xy 347.766024 -311.184127) (xy 347.771853 -311.167636)
			(xy 347.772228 -311.15889) (xy 347.772228 -311.004966) (xy 347.771917 -310.996209) (xy 347.766072 -310.979705)
			(xy 347.760798 -310.972708) (xy 347.741909 -310.948955) (xy 347.70931 -310.897763) (xy 347.695774 -310.8706)
			(xy 347.691508 -310.862713) (xy 347.678638 -310.850248) (xy 347.670628 -310.846216) (xy 347.643196 -310.834024)
			(xy 347.634972 -310.830704) (xy 347.617307 -310.82929) (xy 347.608652 -310.83123) (xy 347.583692 -310.837739)
			(xy 347.532589 -310.844745) (xy 347.506798 -310.8452) (xy 347.479547 -310.844714) (xy 347.425601 -310.836958)
			(xy 347.373308 -310.821603) (xy 347.323732 -310.798962) (xy 347.277882 -310.769496) (xy 347.236693 -310.733805)
			(xy 347.201003 -310.692616) (xy 347.171537 -310.646767) (xy 347.148897 -310.597191) (xy 347.133542 -310.544897)
			(xy 347.125786 -310.490951) (xy 347.125786 -310.436449) (xy 347.133542 -310.382503) (xy 347.148897 -310.330209)
			(xy 347.171537 -310.280633) (xy 347.201003 -310.234784) (xy 347.236693 -310.193595) (xy 347.277882 -310.157904)
			(xy 347.323732 -310.128438) (xy 347.373308 -310.105797) (xy 347.425601 -310.090442) (xy 347.479547 -310.082686)
			(xy 347.506798 -310.082184) (xy 347.533247 -310.082634) (xy 347.585638 -310.08994) (xy 347.636517 -310.104412)
			(xy 347.684911 -310.125772) (xy 347.72989 -310.153611) (xy 347.770594 -310.187395) (xy 347.788738 -310.206644)
			(xy 347.79497 -310.212868) (xy 347.810557 -310.221045) (xy 347.819218 -310.222646) (xy 347.84919 -310.226964)
			(xy 347.858066 -310.227773) (xy 347.87547 -310.223993) (xy 347.883226 -310.219598) (xy 347.905456 -310.206041)
			(xy 347.952155 -310.183006) (xy 347.976444 -310.173624) (xy 347.986096 -310.170068) (xy 348.001082 -310.155844)
			(xy 348.034356 -310.07939) (xy 348.038084 -310.069788) (xy 348.03833 -310.049213) (xy 348.034864 -310.039512)
			(xy 347.92031 -309.762906) (xy 347.899736 -309.74665) (xy 347.886782 -309.744364) (xy 347.855916 -309.738735)
			(xy 347.795776 -309.720851) (xy 347.738299 -309.69569) (xy 347.684361 -309.663638) (xy 347.634784 -309.625182)
			(xy 347.612208 -309.603394) (xy 347.601794 -309.59298) (xy 347.574108 -309.58663) (xy 347.460316 -309.625238)
			(xy 347.442028 -309.64759) (xy 347.439996 -309.661814) (xy 347.43509 -309.694734) (xy 347.41782 -309.759011)
			(xy 347.39231 -309.820486) (xy 347.358996 -309.878106) (xy 347.318447 -309.930885) (xy 347.271358 -309.977922)
			(xy 347.218533 -310.018412) (xy 347.160876 -310.051661) (xy 347.099373 -310.077103) (xy 347.035076 -310.094301)
			(xy 346.969085 -310.102961) (xy 346.935806 -310.10352) (xy 346.903843 -310.103039) (xy 346.84042 -310.095028)
			(xy 346.778501 -310.079131) (xy 346.719064 -310.055598) (xy 346.663044 -310.024802) (xy 346.611326 -309.987227)
			(xy 346.564725 -309.943466) (xy 346.523977 -309.89421) (xy 346.489723 -309.840235) (xy 346.462504 -309.782393)
			(xy 346.442749 -309.721595) (xy 346.430771 -309.658801) (xy 346.426756 -309.595) (xy 346.430771 -309.531199)
			(xy 346.442749 -309.468405) (xy 346.462504 -309.407607) (xy 346.489723 -309.349765) (xy 346.523977 -309.29579)
			(xy 346.564725 -309.246534) (xy 346.611326 -309.202773) (xy 346.663044 -309.165198) (xy 346.719064 -309.134402)
			(xy 346.778501 -309.110869) (xy 346.84042 -309.094972) (xy 346.903843 -309.086961) (xy 346.935806 -309.086504)
			(xy 346.968995 -309.087042) (xy 347.034808 -309.09568) (xy 347.098938 -309.112808) (xy 347.160293 -309.138135)
			(xy 347.217832 -309.17123) (xy 347.270575 -309.211531) (xy 347.294454 -309.234586) (xy 347.304868 -309.245)
			(xy 347.332554 -309.25135) (xy 347.446346 -309.212742) (xy 347.464634 -309.19039) (xy 347.466666 -309.176166)
			(xy 347.471215 -309.145494) (xy 347.48681 -309.085478) (xy 347.509584 -309.027803) (xy 347.539201 -308.973324)
			(xy 347.556836 -308.94782) (xy 347.564456 -308.937152) (xy 347.56725 -308.91099) (xy 346.856812 -307.195728)
			(xy 346.852151 -307.185872) (xy 346.836227 -307.171012) (xy 346.826078 -307.167026) (xy 346.742512 -307.139086)
			(xy 346.720922 -307.141626) (xy 346.71127 -307.147214) (xy 346.692807 -307.157856) (xy 346.653982 -307.175424)
			(xy 346.6338 -307.182266) (xy 346.62237 -307.185822) (xy 346.605352 -307.202332) (xy 346.570554 -307.300884)
			(xy 346.573348 -307.324252) (xy 346.579698 -307.334412) (xy 346.595386 -307.359254) (xy 346.62158 -307.411848)
			(xy 346.641547 -307.467107) (xy 346.655022 -307.524296) (xy 346.661826 -307.582656) (xy 346.662248 -307.612034)
			(xy 346.661746 -307.643995) (xy 346.653735 -307.707413) (xy 346.637838 -307.769327) (xy 346.614306 -307.82876)
			(xy 346.583512 -307.884775) (xy 346.545939 -307.93649) (xy 346.502182 -307.983087) (xy 346.452929 -308.023832)
			(xy 346.398958 -308.058083) (xy 346.341119 -308.0853) (xy 346.280326 -308.105053) (xy 346.217536 -308.117031)
			(xy 346.15374 -308.121045) (xy 346.089944 -308.117031) (xy 346.027154 -308.105053) (xy 345.966361 -308.0853)
			(xy 345.908522 -308.058083) (xy 345.854551 -308.023832) (xy 345.805298 -307.983087) (xy 345.761541 -307.93649)
			(xy 345.723968 -307.884775) (xy 345.693174 -307.82876) (xy 345.669642 -307.769327) (xy 345.653745 -307.707413)
			(xy 345.645734 -307.643995) (xy 345.645232 -307.612034) (xy 345.645775 -307.578831) (xy 345.654426 -307.512991)
			(xy 345.671574 -307.448837) (xy 345.696926 -307.38746) (xy 345.730051 -307.329906) (xy 345.770386 -307.277152)
			(xy 345.817243 -307.230097) (xy 345.869826 -307.189542) (xy 345.927241 -307.156175) (xy 345.98851 -307.130565)
			(xy 346.052592 -307.113148) (xy 346.085414 -307.108098) (xy 346.097352 -307.106574) (xy 346.11691 -307.093366)
			(xy 346.168726 -307.002434) (xy 346.169996 -306.978812) (xy 346.165424 -306.96789) (xy 346.16136 -306.958238)
			(xy 346.156613 -306.947882) (xy 346.139998 -306.932337) (xy 346.129356 -306.928266) (xy 346.098622 -306.918614)
			(xy 346.087416 -306.915668) (xy 346.064526 -306.91911) (xy 346.05468 -306.925218) (xy 346.029166 -306.942233)
			(xy 345.974841 -306.970691) (xy 345.917486 -306.992404) (xy 345.857935 -307.007056) (xy 345.797054 -307.014436)
			(xy 345.76639 -307.01488) (xy 345.734431 -307.014378) (xy 345.671018 -307.006365) (xy 345.609108 -306.990469)
			(xy 345.549679 -306.966938) (xy 345.493668 -306.936145) (xy 345.441958 -306.898574) (xy 345.395364 -306.854819)
			(xy 345.354622 -306.805569) (xy 345.320374 -306.751601) (xy 345.293159 -306.693767) (xy 345.273408 -306.632977)
			(xy 345.261431 -306.570192) (xy 345.257417 -306.5064) (xy 345.261431 -306.442608) (xy 345.273408 -306.379823)
			(xy 345.293159 -306.319033) (xy 345.320374 -306.261199) (xy 345.354622 -306.207231) (xy 345.395364 -306.157981)
			(xy 345.441958 -306.114226) (xy 345.493668 -306.076655) (xy 345.549679 -306.045862) (xy 345.609108 -306.022331)
			(xy 345.671018 -306.006435) (xy 345.734431 -305.998422) (xy 345.76639 -305.997864) (xy 345.797195 -305.998308)
			(xy 345.858354 -306.005741) (xy 345.918167 -306.020511) (xy 345.975757 -306.042402) (xy 346.030278 -306.071093)
			(xy 346.080932 -306.106163) (xy 346.126976 -306.147098) (xy 346.167735 -306.193298) (xy 346.202611 -306.244086)
			(xy 346.231094 -306.298716) (xy 346.252765 -306.356389) (xy 346.26042 -306.38623) (xy 346.26296 -306.396898)
			(xy 346.276168 -306.413662) (xy 346.361004 -306.460144) (xy 346.382086 -306.461922) (xy 346.392246 -306.458366)
			(xy 346.395548 -306.45735) (xy 346.40647 -306.45354) (xy 346.42298 -306.437792) (xy 346.45473 -306.352956)
			(xy 346.458134 -306.342075) (xy 346.456166 -306.31939) (xy 346.45092 -306.309268) (xy 343.871296 -301.943516)
			(xy 343.855881 -301.916675) (xy 343.830219 -301.860346) (xy 343.810707 -301.801603) (xy 343.797565 -301.741115)
			(xy 343.790945 -301.679571) (xy 343.790524 -301.648622) (xy 343.790524 -296.23131) (xy 343.790997 -296.199552)
			(xy 343.798031 -296.136426) (xy 343.811927 -296.074448) (xy 343.832519 -296.014362) (xy 343.845642 -295.985438)
			(xy 343.850468 -295.975278) (xy 343.850468 -295.90365) (xy 343.850468 -295.869868) (xy 343.850888 -295.839332)
			(xy 343.857503 -295.778619) (xy 343.863676 -295.74871) (xy 343.86393 -295.746678) (xy 343.871267 -295.707192)
			(xy 343.89196 -295.629585) (xy 343.91936 -295.554085) (xy 343.953256 -295.481269) (xy 343.993389 -295.411696)
			(xy 344.039451 -295.345898) (xy 344.09109 -295.28438) (xy 344.1192 -295.255696) (xy 344.129868 -295.244774)
			(xy 344.136714 -295.237376) (xy 344.144444 -295.218777) (xy 344.144854 -295.208706) (xy 344.144854 -294.741854)
			(xy 344.144421 -294.731789) (xy 344.13669 -294.713201) (xy 344.129868 -294.705786) (xy 344.104722 -294.680894)
			(xy 344.079576 -294.656002) (xy 344.072165 -294.649321) (xy 344.053729 -294.641747) (xy 344.043762 -294.64127)
			(xy 344.041222 -294.64127) (xy 344.015966 -294.640779) (xy 343.966143 -294.632468) (xy 343.918368 -294.61607)
			(xy 343.873943 -294.592032) (xy 343.834081 -294.561008) (xy 343.799869 -294.523847) (xy 343.772241 -294.481561)
			(xy 343.75195 -294.435305) (xy 343.739549 -294.386339) (xy 343.735378 -294.336) (xy 343.739549 -294.285661)
			(xy 343.75195 -294.236695) (xy 343.772241 -294.190439) (xy 343.799869 -294.148153) (xy 343.834081 -294.110992)
			(xy 343.873943 -294.079968) (xy 343.918368 -294.05593) (xy 343.966143 -294.039532) (xy 344.015966 -294.031221)
			(xy 344.041222 -294.030654) (xy 344.043762 -294.030654) (xy 344.053548 -294.030205) (xy 344.071701 -294.022887)
			(xy 344.079068 -294.01643) (xy 344.079322 -294.016176) (xy 344.130122 -293.966138) (xy 344.136842 -293.958902)
			(xy 344.144453 -293.940698) (xy 344.144854 -293.930832) (xy 344.144854 -293.121842) (xy 344.144401 -293.111689)
			(xy 344.136532 -293.092967) (xy 344.129614 -293.08552) (xy 344.112088 -293.068248) (xy 344.08237 -293.03853)
			(xy 344.062812 -293.03091) (xy 344.052144 -293.031418) (xy 344.041222 -293.031672) (xy 344.016405 -293.031212)
			(xy 343.967383 -293.023451) (xy 343.920178 -293.008116) (xy 343.875953 -292.985585) (xy 343.835798 -292.956413)
			(xy 343.800701 -292.921319) (xy 343.771526 -292.881165) (xy 343.748992 -292.836942) (xy 343.733654 -292.789739)
			(xy 343.72589 -292.740717) (xy 343.72589 -292.691083) (xy 343.733654 -292.642061) (xy 343.748992 -292.594858)
			(xy 343.771526 -292.550635) (xy 343.800701 -292.510481) (xy 343.835798 -292.475387) (xy 343.875953 -292.446215)
			(xy 343.920178 -292.423684) (xy 343.967383 -292.408349) (xy 344.016405 -292.400588) (xy 344.041222 -292.400228)
			(xy 344.052144 -292.400482) (xy 344.063066 -292.40099) (xy 344.082116 -292.39337) (xy 344.130122 -292.346126)
			(xy 344.13684 -292.33889) (xy 344.144446 -292.320685) (xy 344.144854 -292.31082) (xy 344.144854 -291.876734)
			(xy 344.14446 -291.867543) (xy 344.137942 -291.850357) (xy 344.132154 -291.843206) (xy 344.127074 -291.837364)
			(xy 344.113612 -291.821362) (xy 344.082489 -291.783328) (xy 344.026215 -291.702749) (xy 343.977149 -291.617589)
			(xy 343.935663 -291.52849) (xy 343.902068 -291.436126) (xy 343.888822 -291.3888) (xy 343.886032 -291.379988)
			(xy 343.875227 -291.36501) (xy 343.86774 -291.35959) (xy 343.84628 -291.344852) (xy 343.808057 -291.309512)
			(xy 343.776153 -291.268378) (xy 343.751433 -291.222565) (xy 343.73457 -291.173316) (xy 343.726018 -291.121966)
			(xy 343.7255 -291.095938) (xy 343.72593 -291.07243) (xy 343.732902 -291.025934) (xy 343.746696 -290.980988)
			(xy 343.767007 -290.938586) (xy 343.793386 -290.899668) (xy 343.825248 -290.865095) (xy 343.861888 -290.835634)
			(xy 343.881964 -290.823396) (xy 343.886536 -290.811966) (xy 343.898015 -290.769399) (xy 343.926734 -290.686035)
			(xy 343.961861 -290.605163) (xy 344.003181 -290.527273) (xy 344.050444 -290.452839) (xy 344.103362 -290.382313)
			(xy 344.132154 -290.348924) (xy 344.137925 -290.341765) (xy 344.14443 -290.324581) (xy 344.144854 -290.315396)
			(xy 344.144854 -289.881818) (xy 344.144397 -289.871667) (xy 344.136522 -289.852952) (xy 344.129614 -289.845496)
			(xy 344.112088 -289.828224) (xy 344.08237 -289.798506) (xy 344.062812 -289.790886) (xy 344.052144 -289.791394)
			(xy 344.041222 -289.791648) (xy 344.016407 -289.791188) (xy 343.967388 -289.783428) (xy 343.920187 -289.768094)
			(xy 343.875966 -289.745565) (xy 343.835814 -289.716395) (xy 343.800719 -289.681303) (xy 343.771547 -289.641153)
			(xy 343.749015 -289.596933) (xy 343.733678 -289.549733) (xy 343.725914 -289.500715) (xy 343.725914 -289.451085)
			(xy 343.733678 -289.402067) (xy 343.749015 -289.354867) (xy 343.771547 -289.310647) (xy 343.800719 -289.270497)
			(xy 343.835814 -289.235405) (xy 343.875966 -289.206235) (xy 343.920187 -289.183706) (xy 343.967388 -289.168372)
			(xy 344.016407 -289.160612) (xy 344.041222 -289.160204) (xy 344.052144 -289.160458) (xy 344.063066 -289.160966)
			(xy 344.082116 -289.153346) (xy 344.130122 -289.106102) (xy 344.136836 -289.098864) (xy 344.144434 -289.080659)
			(xy 344.144854 -289.070796) (xy 344.144854 -288.283142) (xy 344.144854 -288.27984) (xy 344.145616 -288.269172)
			(xy 344.138504 -288.249614) (xy 344.072972 -288.180018) (xy 344.053668 -288.171636) (xy 344.043 -288.171636)
			(xy 344.041222 -288.171636) (xy 344.016432 -288.171177) (xy 343.967461 -288.163424) (xy 343.920307 -288.148105)
			(xy 343.876129 -288.125598) (xy 343.836017 -288.096457) (xy 343.800957 -288.0614) (xy 343.771813 -288.021289)
			(xy 343.749303 -287.977114) (xy 343.733981 -287.92996) (xy 343.726225 -287.88099) (xy 343.726225 -287.83141)
			(xy 343.733981 -287.78244) (xy 343.749303 -287.735286) (xy 343.771813 -287.691111) (xy 343.800957 -287.651)
			(xy 343.836017 -287.615943) (xy 343.876129 -287.586802) (xy 343.920307 -287.564295) (xy 343.967461 -287.548976)
			(xy 344.016432 -287.541223) (xy 344.041222 -287.5407) (xy 344.068812 -287.541221) (xy 344.123165 -287.550734)
			(xy 344.175029 -287.569569) (xy 344.19921 -287.582864) (xy 344.206761 -287.586899) (xy 344.22355 -287.590195)
			(xy 344.24049 -287.587787) (xy 344.248232 -287.584134) (xy 344.274648 -287.570164) (xy 344.282694 -287.565561)
			(xy 344.295048 -287.551764) (xy 344.301662 -287.534466) (xy 344.30208 -287.525206) (xy 344.30208 -287.491424)
			(xy 344.301643 -287.48136) (xy 344.293906 -287.462778) (xy 344.287094 -287.455356) (xy 344.050874 -287.219136)
			(xy 344.04403 -287.211737) (xy 344.036307 -287.193138) (xy 344.035888 -287.183068) (xy 344.035888 -286.864298)
			(xy 344.031824 -286.850582) (xy 344.028014 -286.844486) (xy 344.004172 -286.806334) (xy 343.961936 -286.72689)
			(xy 343.926147 -286.64434) (xy 343.911174 -286.601916) (xy 343.909114 -286.596475) (xy 343.902959 -286.586605)
			(xy 343.898982 -286.582358) (xy 343.701878 -286.385254) (xy 343.69503 -286.377857) (xy 343.6873 -286.359258)
			(xy 343.686892 -286.349186) (xy 343.686892 -286.054292) (xy 343.687316 -286.044222) (xy 343.695032 -286.025619)
			(xy 343.701878 -286.018224) (xy 343.826338 -285.893764) (xy 343.833185 -285.886367) (xy 343.840917 -285.867768)
			(xy 343.841324 -285.857696) (xy 343.841324 -285.807658) (xy 343.84057 -285.794995) (xy 343.828432 -285.772756)
			(xy 343.81821 -285.76524) (xy 343.735914 -285.711646) (xy 343.710514 -285.709614) (xy 343.698576 -285.714694)
			(xy 343.678413 -285.723237) (xy 343.636319 -285.735309) (xy 343.592962 -285.741458) (xy 343.571068 -285.741872)
			(xy 343.546256 -285.741383) (xy 343.497244 -285.733615) (xy 343.45005 -285.718277) (xy 343.405837 -285.695745)
			(xy 343.365692 -285.666575) (xy 343.330605 -285.631483) (xy 343.301438 -285.591336) (xy 343.278911 -285.54712)
			(xy 343.263577 -285.499925) (xy 343.255815 -285.450912) (xy 343.255815 -285.401288) (xy 343.263577 -285.352275)
			(xy 343.278911 -285.30508) (xy 343.301438 -285.260864) (xy 343.330605 -285.220717) (xy 343.365692 -285.185625)
			(xy 343.405837 -285.156455) (xy 343.45005 -285.133923) (xy 343.497244 -285.118585) (xy 343.546256 -285.110817)
			(xy 343.571068 -285.110428) (xy 343.595322 -285.110877) (xy 343.643258 -285.118311) (xy 343.689492 -285.132992)
			(xy 343.732935 -285.154576) (xy 343.772563 -285.182553) (xy 343.807443 -285.216265) (xy 343.836753 -285.254917)
			(xy 343.84869 -285.276036) (xy 343.855294 -285.288482) (xy 343.879424 -285.302706) (xy 343.893394 -285.302706)
			(xy 343.903403 -285.302219) (xy 343.921898 -285.294561) (xy 343.936054 -285.280408) (xy 343.943717 -285.261915)
			(xy 343.944194 -285.251906) (xy 343.944194 -285.188406) (xy 343.944616 -285.178335) (xy 343.952328 -285.159728)
			(xy 343.95918 -285.152338) (xy 344.017346 -285.094172) (xy 344.023524 -285.08752) (xy 344.031118 -285.071045)
			(xy 344.032457 -285.052954) (xy 344.0303 -285.044134) (xy 344.00236 -284.945582) (xy 343.982294 -284.926532)
			(xy 343.968832 -284.92323) (xy 343.943219 -284.91666) (xy 343.894483 -284.896154) (xy 343.849848 -284.867811)
			(xy 343.810562 -284.832423) (xy 343.777725 -284.790982) (xy 343.752256 -284.744647) (xy 343.734867 -284.694714)
			(xy 343.726046 -284.642581) (xy 343.7255 -284.616144) (xy 343.725959 -284.591337) (xy 343.733718 -284.542332)
			(xy 343.749051 -284.495146) (xy 343.77158 -284.450942) (xy 343.800751 -284.410808) (xy 343.835844 -284.375735)
			(xy 343.875994 -284.346587) (xy 343.920211 -284.324082) (xy 343.967406 -284.308776) (xy 344.016414 -284.301045)
			(xy 344.041222 -284.300676) (xy 344.068405 -284.301245) (xy 344.121968 -284.310562) (xy 344.173144 -284.328915)
			(xy 344.220419 -284.355762) (xy 344.262397 -284.390311) (xy 344.297838 -284.431539) (xy 344.31224 -284.4546)
			(xy 344.319352 -284.466284) (xy 344.342212 -284.479238) (xy 344.355928 -284.479238) (xy 344.365935 -284.478746)
			(xy 344.384423 -284.471083) (xy 344.398577 -284.456932) (xy 344.406244 -284.438445) (xy 344.406728 -284.428438)
			(xy 344.406728 -284.41396) (xy 344.407159 -284.403894) (xy 344.414887 -284.385302) (xy 344.421714 -284.377892)
			(xy 344.519758 -284.279848) (xy 344.526045 -284.272947) (xy 344.533592 -284.25589) (xy 344.534512 -284.237261)
			(xy 344.53195 -284.228286) (xy 344.499692 -284.128464) (xy 344.477848 -284.109922) (xy 344.463624 -284.107636)
			(xy 344.439986 -284.103455) (xy 344.394324 -284.088651) (xy 344.351541 -284.066884) (xy 344.312691 -284.038692)
			(xy 344.27873 -284.004768) (xy 344.250494 -283.965949) (xy 344.22868 -283.923191) (xy 344.213824 -283.877546)
			(xy 344.206293 -283.830139) (xy 344.205814 -283.806138) (xy 344.206257 -283.782144) (xy 344.21376 -283.734745)
			(xy 344.228585 -283.689103) (xy 344.250369 -283.646344) (xy 344.278574 -283.607519) (xy 344.312506 -283.573584)
			(xy 344.35133 -283.545377) (xy 344.394089 -283.523591) (xy 344.439729 -283.508763) (xy 344.487128 -283.501259)
			(xy 344.511122 -283.50083) (xy 344.534918 -283.501287) (xy 344.581932 -283.508673) (xy 344.627232 -283.523264)
			(xy 344.669719 -283.544706) (xy 344.708366 -283.572479) (xy 344.742236 -283.605912) (xy 344.75674 -283.624782)
			(xy 344.764106 -283.634688) (xy 344.785442 -283.645356) (xy 344.797634 -283.645356) (xy 344.807648 -283.64493)
			(xy 344.826145 -283.637252) (xy 344.840296 -283.62308) (xy 344.847945 -283.60457) (xy 344.848434 -283.594556)
			(xy 344.848434 -283.590492) (xy 344.972132 -283.466794) (xy 344.978327 -283.460049) (xy 344.985885 -283.443381)
			(xy 344.987102 -283.425121) (xy 344.984832 -283.416248) (xy 344.95486 -283.316934) (xy 344.934286 -283.298138)
			(xy 344.92057 -283.295344) (xy 344.895012 -283.289626) (xy 344.846204 -283.270646) (xy 344.801348 -283.243622)
			(xy 344.761756 -283.209344) (xy 344.728589 -283.168817) (xy 344.702819 -283.123229) (xy 344.6852 -283.073913)
			(xy 344.676248 -283.022316) (xy 344.675714 -282.996132) (xy 344.676158 -282.972138) (xy 344.683661 -282.92474)
			(xy 344.698487 -282.879099) (xy 344.720271 -282.83634) (xy 344.748476 -282.797516) (xy 344.782408 -282.763583)
			(xy 344.821232 -282.735376) (xy 344.86399 -282.713591) (xy 344.90963 -282.698763) (xy 344.957028 -282.691259)
			(xy 344.981022 -282.690824) (xy 345.005823 -282.69131) (xy 345.054773 -282.699333) (xy 345.101782 -282.715165)
			(xy 345.145613 -282.738388) (xy 345.185113 -282.768392) (xy 345.20251 -282.786074) (xy 345.209876 -282.793694)
			(xy 345.228164 -282.801822) (xy 345.311476 -282.802838) (xy 345.321648 -282.802538) (xy 345.340508 -282.794937)
			(xy 345.348052 -282.788106) (xy 345.444318 -282.69184) (xy 345.447366 -282.687268) (xy 345.473274 -282.650946)
			(xy 345.481656 -282.640024) (xy 345.485212 -282.613354) (xy 345.442032 -282.506928) (xy 345.42095 -282.490164)
			(xy 345.407234 -282.488386) (xy 345.383344 -282.484428) (xy 345.337135 -282.469957) (xy 345.293787 -282.448378)
			(xy 345.254386 -282.42023) (xy 345.219919 -282.38622) (xy 345.191249 -282.347198) (xy 345.169093 -282.304142)
			(xy 345.154006 -282.25813) (xy 345.146367 -282.210315) (xy 345.146367 -282.161893) (xy 345.154005 -282.114077)
			(xy 345.16909 -282.068065) (xy 345.191245 -282.025008) (xy 345.219914 -281.985986) (xy 345.254381 -281.951974)
			(xy 345.293781 -281.923826) (xy 345.337128 -281.902246) (xy 345.383337 -281.887773) (xy 345.407234 -281.883866)
			(xy 345.42095 -281.882088) (xy 345.442032 -281.865324) (xy 345.485212 -281.758898) (xy 345.481656 -281.732228)
			(xy 345.473274 -281.721306) (xy 345.45017 -281.690315) (xy 345.411679 -281.62328) (xy 345.396566 -281.587702)
			(xy 345.391486 -281.575002) (xy 345.369896 -281.558238) (xy 345.25585 -281.542236) (xy 345.23045 -281.55265)
			(xy 345.222068 -281.563318) (xy 345.207524 -281.581363) (xy 345.173905 -281.613263) (xy 345.135848 -281.639712)
			(xy 345.094229 -281.660101) (xy 345.050006 -281.673961) (xy 345.004194 -281.680973) (xy 344.981022 -281.681428)
			(xy 344.955761 -281.680937) (xy 344.905929 -281.672625) (xy 344.858144 -281.656223) (xy 344.813711 -281.63218)
			(xy 344.773842 -281.601151) (xy 344.739623 -281.563983) (xy 344.71199 -281.521689) (xy 344.691695 -281.475423)
			(xy 344.679292 -281.426448) (xy 344.67512 -281.3761) (xy 344.679292 -281.325752) (xy 344.691695 -281.276777)
			(xy 344.71199 -281.230511) (xy 344.739623 -281.188217) (xy 344.773842 -281.151049) (xy 344.813711 -281.12002)
			(xy 344.858144 -281.095977) (xy 344.905929 -281.079575) (xy 344.955761 -281.071263) (xy 344.981022 -281.070812)
			(xy 345.004195 -281.071245) (xy 345.050006 -281.07826) (xy 345.094229 -281.092126) (xy 345.135844 -281.112523)
			(xy 345.173895 -281.138981) (xy 345.207505 -281.170892) (xy 345.222068 -281.188922) (xy 345.23045 -281.19959)
			(xy 345.25585 -281.210004) (xy 345.369896 -281.194002) (xy 345.391486 -281.177238) (xy 345.396566 -281.164538)
			(xy 345.411646 -281.128943) (xy 345.450139 -281.061904) (xy 345.473274 -281.030934) (xy 345.481656 -281.020012)
			(xy 345.485212 -280.993342) (xy 345.442032 -280.886916) (xy 345.42095 -280.870152) (xy 345.407234 -280.868374)
			(xy 345.383345 -280.864411) (xy 345.337137 -280.849934) (xy 345.29379 -280.828353) (xy 345.254386 -280.800208)
			(xy 345.219913 -280.766204) (xy 345.191231 -280.72719) (xy 345.169059 -280.684142) (xy 345.15395 -280.638137)
			(xy 345.146283 -280.590325) (xy 345.145868 -280.566114) (xy 345.14639 -280.540859) (xy 345.154703 -280.491037)
			(xy 345.171104 -280.443263) (xy 345.195145 -280.39884) (xy 345.226169 -280.35898) (xy 345.263331 -280.32477)
			(xy 345.305617 -280.297144) (xy 345.351873 -280.276854) (xy 345.400838 -280.264454) (xy 345.451176 -280.260283)
			(xy 345.501514 -280.264454) (xy 345.550479 -280.276854) (xy 345.596735 -280.297144) (xy 345.639021 -280.32477)
			(xy 345.676183 -280.35898) (xy 345.707207 -280.39884) (xy 345.731248 -280.443263) (xy 345.747649 -280.491037)
			(xy 345.755962 -280.540859) (xy 345.756484 -280.566114) (xy 345.755829 -280.594813) (xy 345.745084 -280.651196)
			(xy 345.735148 -280.678128) (xy 345.730322 -280.690828) (xy 345.734132 -280.717244) (xy 345.805252 -280.807668)
			(xy 345.830144 -280.817828) (xy 345.843606 -280.815796) (xy 345.86288 -280.81336) (xy 345.901649 -280.810821)
			(xy 345.921076 -280.810716) (xy 346.01023 -280.810716) (xy 346.022552 -280.809926) (xy 346.044336 -280.798386)
			(xy 346.051886 -280.788618) (xy 346.10675 -280.709624) (xy 346.109798 -280.68524) (xy 346.10548 -280.673302)
			(xy 346.096409 -280.647435) (xy 346.086566 -280.593517) (xy 346.085922 -280.566114) (xy 346.086444 -280.540859)
			(xy 346.094757 -280.491037) (xy 346.111158 -280.443263) (xy 346.135199 -280.39884) (xy 346.166223 -280.35898)
			(xy 346.203385 -280.32477) (xy 346.245671 -280.297144) (xy 346.291927 -280.276854) (xy 346.340892 -280.264454)
			(xy 346.39123 -280.260283) (xy 346.441568 -280.264454) (xy 346.490533 -280.276854) (xy 346.536789 -280.297144)
			(xy 346.579075 -280.32477) (xy 346.616237 -280.35898) (xy 346.647261 -280.39884) (xy 346.671302 -280.443263)
			(xy 346.687703 -280.491037) (xy 346.696016 -280.540859) (xy 346.696538 -280.566114) (xy 346.695938 -280.593522)
			(xy 346.686094 -280.647447) (xy 346.67698 -280.673302) (xy 346.672662 -280.68524) (xy 346.67571 -280.709624)
			(xy 346.730574 -280.788618) (xy 346.738142 -280.79837) (xy 346.759912 -280.809919) (xy 346.77223 -280.810716)
			(xy 346.86113 -280.810716) (xy 346.880557 -280.810819) (xy 346.919326 -280.813359) (xy 346.9386 -280.815796)
			(xy 346.952062 -280.817828) (xy 346.976954 -280.807668) (xy 347.048074 -280.717244) (xy 347.051884 -280.690828)
			(xy 347.047058 -280.678128) (xy 347.037141 -280.651191) (xy 347.026407 -280.59481) (xy 347.025722 -280.566114)
			(xy 347.026207 -280.541296) (xy 347.034235 -280.492313) (xy 347.050081 -280.445274) (xy 347.073329 -280.401419)
			(xy 347.103365 -280.361902) (xy 347.139399 -280.327765) (xy 347.180481 -280.299908) (xy 347.225529 -280.279063)
			(xy 347.273355 -280.265781) (xy 347.3227 -280.260412) (xy 347.372263 -280.263096) (xy 347.42074 -280.273763)
			(xy 347.466852 -280.292132) (xy 347.509385 -280.317719) (xy 347.547218 -280.34985) (xy 347.579355 -280.387679)
			(xy 347.604948 -280.430208) (xy 347.623324 -280.476318) (xy 347.633998 -280.524793) (xy 347.63669 -280.574356)
			(xy 347.631327 -280.623702) (xy 347.618052 -280.67153) (xy 347.597214 -280.71658) (xy 347.569362 -280.757666)
			(xy 347.535231 -280.793705) (xy 347.495718 -280.823747) (xy 347.451866 -280.847001) (xy 347.40483 -280.862855)
			(xy 347.355848 -280.87089) (xy 347.33103 -280.871422) (xy 347.318463 -280.87132) (xy 347.293411 -280.869286)
			(xy 347.280992 -280.867358) (xy 347.270112 -280.866131) (xy 347.24902 -280.871922) (xy 347.232227 -280.885937)
			(xy 347.222759 -280.905655) (xy 347.22232 -280.927523) (xy 347.23099 -280.947605) (xy 347.238828 -280.955242)
			(xy 347.263974 -280.979118) (xy 347.271346 -280.986031) (xy 347.289947 -280.993893) (xy 347.300042 -280.994358)
			(xy 348.302326 -280.994358) (xy 348.312413 -280.993865) (xy 348.330996 -280.985995) (xy 348.338394 -280.979118)
			(xy 348.36354 -280.955242) (xy 348.371365 -280.947555) (xy 348.380152 -280.92748) (xy 348.37977 -280.905571)
			(xy 348.370289 -280.885815) (xy 348.353434 -280.871811) (xy 348.332276 -280.866109) (xy 348.321376 -280.867358)
			(xy 348.308894 -280.869291) (xy 348.283715 -280.871323) (xy 348.271084 -280.871422) (xy 348.246262 -280.870935)
			(xy 348.197273 -280.862901) (xy 348.150228 -280.847047) (xy 348.106368 -280.823791) (xy 348.066849 -280.793746)
			(xy 348.032711 -280.757703) (xy 348.004853 -280.716612) (xy 347.98401 -280.671555) (xy 347.970732 -280.62372)
			(xy 347.965367 -280.574367) (xy 347.968057 -280.524796) (xy 347.978731 -280.476313) (xy 347.997109 -280.430196)
			(xy 348.022705 -280.387659) (xy 348.054846 -280.349824) (xy 348.092684 -280.317687) (xy 348.135223 -280.292095)
			(xy 348.181342 -280.273722) (xy 348.229826 -280.263053) (xy 348.279397 -280.260368) (xy 348.328749 -280.265737)
			(xy 348.376583 -280.279021) (xy 348.421638 -280.299868) (xy 348.462726 -280.327729) (xy 348.498766 -280.361871)
			(xy 348.528807 -280.401394) (xy 348.552059 -280.445256) (xy 348.567908 -280.492302) (xy 348.575937 -280.541292)
			(xy 348.576392 -280.566114) (xy 348.575737 -280.594813) (xy 348.564992 -280.651196) (xy 348.555056 -280.678128)
			(xy 348.55023 -280.690828) (xy 348.55404 -280.717244) (xy 348.62516 -280.807668) (xy 348.650052 -280.817828)
			(xy 348.663514 -280.81605) (xy 348.682847 -280.813545) (xy 348.721744 -280.810875) (xy 348.741238 -280.810716)
			(xy 348.830138 -280.810716) (xy 348.842459 -280.809925) (xy 348.86424 -280.798383) (xy 348.871794 -280.788618)
			(xy 348.926658 -280.709624) (xy 348.929706 -280.68524) (xy 348.925388 -280.673302) (xy 348.916317 -280.647435)
			(xy 348.906474 -280.593517) (xy 348.90583 -280.566114) (xy 348.906352 -280.540859) (xy 348.914665 -280.491037)
			(xy 348.931066 -280.443263) (xy 348.955107 -280.39884) (xy 348.986131 -280.35898) (xy 349.023293 -280.32477)
			(xy 349.065579 -280.297144) (xy 349.111835 -280.276854) (xy 349.1608 -280.264454) (xy 349.211138 -280.260283)
			(xy 349.261476 -280.264454) (xy 349.310441 -280.276854) (xy 349.356697 -280.297144) (xy 349.398983 -280.32477)
			(xy 349.436145 -280.35898) (xy 349.467169 -280.39884) (xy 349.49121 -280.443263) (xy 349.507611 -280.491037)
			(xy 349.515924 -280.540859) (xy 349.516446 -280.566114) (xy 349.515846 -280.593522) (xy 349.506002 -280.647447)
			(xy 349.496888 -280.673302) (xy 349.49257 -280.68524) (xy 349.495618 -280.709624) (xy 349.550482 -280.788618)
			(xy 349.55805 -280.798368) (xy 349.579821 -280.809915) (xy 349.592138 -280.810716) (xy 349.681038 -280.810716)
			(xy 349.700532 -280.810875) (xy 349.739429 -280.813544) (xy 349.758762 -280.81605) (xy 349.772224 -280.817828)
			(xy 349.797116 -280.807668) (xy 349.868236 -280.717244) (xy 349.872046 -280.690828) (xy 349.86722 -280.678128)
			(xy 349.857305 -280.651191) (xy 349.846571 -280.59481) (xy 349.845884 -280.566114) (xy 349.846406 -280.540859)
			(xy 349.854719 -280.491037) (xy 349.87112 -280.443263) (xy 349.895161 -280.39884) (xy 349.926185 -280.35898)
			(xy 349.963347 -280.32477) (xy 350.005633 -280.297144) (xy 350.051889 -280.276854) (xy 350.100854 -280.264454)
			(xy 350.151192 -280.260283) (xy 350.20153 -280.264454) (xy 350.250495 -280.276854) (xy 350.296751 -280.297144)
			(xy 350.339037 -280.32477) (xy 350.376199 -280.35898) (xy 350.407223 -280.39884) (xy 350.431264 -280.443263)
			(xy 350.447665 -280.491037) (xy 350.455978 -280.540859) (xy 350.4565 -280.566114) (xy 350.785442 -280.566114)
			(xy 350.789402 -280.51706) (xy 350.801179 -280.469276) (xy 350.82047 -280.424) (xy 350.846773 -280.382404)
			(xy 350.879408 -280.345567) (xy 350.917529 -280.314442) (xy 350.96015 -280.289835) (xy 351.006166 -280.272383)
			(xy 351.054385 -280.262539) (xy 351.10356 -280.260558) (xy 351.152415 -280.26649) (xy 351.199686 -280.280182)
			(xy 351.244148 -280.30128) (xy 351.284651 -280.329236) (xy 351.320144 -280.363328) (xy 351.349709 -280.402672)
			(xy 351.37258 -280.446249) (xy 351.388164 -280.49293) (xy 351.396059 -280.541507) (xy 351.396554 -280.566114)
			(xy 351.725242 -280.566114) (xy 351.729202 -280.51706) (xy 351.740979 -280.469276) (xy 351.76027 -280.424)
			(xy 351.786573 -280.382404) (xy 351.819208 -280.345567) (xy 351.857329 -280.314442) (xy 351.89995 -280.289835)
			(xy 351.945966 -280.272383) (xy 351.994185 -280.262539) (xy 352.04336 -280.260558) (xy 352.092215 -280.26649)
			(xy 352.139486 -280.280182) (xy 352.183948 -280.30128) (xy 352.224451 -280.329236) (xy 352.259944 -280.363328)
			(xy 352.289509 -280.402672) (xy 352.31238 -280.446249) (xy 352.327964 -280.49293) (xy 352.335859 -280.541507)
			(xy 352.336354 -280.566114) (xy 352.665296 -280.566114) (xy 352.669256 -280.51706) (xy 352.681033 -280.469276)
			(xy 352.700324 -280.424) (xy 352.726627 -280.382404) (xy 352.759262 -280.345567) (xy 352.797383 -280.314442)
			(xy 352.840004 -280.289835) (xy 352.88602 -280.272383) (xy 352.934239 -280.262539) (xy 352.983414 -280.260558)
			(xy 353.032269 -280.26649) (xy 353.07954 -280.280182) (xy 353.124002 -280.30128) (xy 353.164505 -280.329236)
			(xy 353.199998 -280.363328) (xy 353.229563 -280.402672) (xy 353.252434 -280.446249) (xy 353.268018 -280.49293)
			(xy 353.275913 -280.541507) (xy 353.276408 -280.566114) (xy 353.60535 -280.566114) (xy 353.60931 -280.51706)
			(xy 353.621087 -280.469276) (xy 353.640378 -280.424) (xy 353.666681 -280.382404) (xy 353.699316 -280.345567)
			(xy 353.737437 -280.314442) (xy 353.780058 -280.289835) (xy 353.826074 -280.272383) (xy 353.874293 -280.262539)
			(xy 353.923468 -280.260558) (xy 353.972323 -280.26649) (xy 354.019594 -280.280182) (xy 354.064056 -280.30128)
			(xy 354.104559 -280.329236) (xy 354.140052 -280.363328) (xy 354.169617 -280.402672) (xy 354.192488 -280.446249)
			(xy 354.208072 -280.49293) (xy 354.215967 -280.541507) (xy 354.216462 -280.566114) (xy 354.545404 -280.566114)
			(xy 354.549364 -280.51706) (xy 354.561141 -280.469276) (xy 354.580432 -280.424) (xy 354.606735 -280.382404)
			(xy 354.63937 -280.345567) (xy 354.677491 -280.314442) (xy 354.720112 -280.289835) (xy 354.766128 -280.272383)
			(xy 354.814347 -280.262539) (xy 354.863522 -280.260558) (xy 354.912377 -280.26649) (xy 354.959648 -280.280182)
			(xy 355.00411 -280.30128) (xy 355.044613 -280.329236) (xy 355.080106 -280.363328) (xy 355.109671 -280.402672)
			(xy 355.132542 -280.446249) (xy 355.148126 -280.49293) (xy 355.156021 -280.541507) (xy 355.156516 -280.566114)
			(xy 355.485204 -280.566114) (xy 355.489164 -280.51706) (xy 355.500941 -280.469276) (xy 355.520232 -280.424)
			(xy 355.546535 -280.382404) (xy 355.57917 -280.345567) (xy 355.617291 -280.314442) (xy 355.659912 -280.289835)
			(xy 355.705928 -280.272383) (xy 355.754147 -280.262539) (xy 355.803322 -280.260558) (xy 355.852177 -280.26649)
			(xy 355.899448 -280.280182) (xy 355.94391 -280.30128) (xy 355.984413 -280.329236) (xy 356.019906 -280.363328)
			(xy 356.049471 -280.402672) (xy 356.072342 -280.446249) (xy 356.087926 -280.49293) (xy 356.095821 -280.541507)
			(xy 356.096316 -280.566114) (xy 358.305366 -280.566114) (xy 358.309326 -280.51706) (xy 358.321103 -280.469276)
			(xy 358.340394 -280.424) (xy 358.366697 -280.382404) (xy 358.399332 -280.345567) (xy 358.437453 -280.314442)
			(xy 358.480074 -280.289835) (xy 358.52609 -280.272383) (xy 358.574309 -280.262539) (xy 358.623484 -280.260558)
			(xy 358.672339 -280.26649) (xy 358.71961 -280.280182) (xy 358.764072 -280.30128) (xy 358.804575 -280.329236)
			(xy 358.840068 -280.363328) (xy 358.869633 -280.402672) (xy 358.892504 -280.446249) (xy 358.908088 -280.49293)
			(xy 358.915983 -280.541507) (xy 358.916478 -280.566114) (xy 361.118924 -280.566114) (xy 361.122884 -280.51706)
			(xy 361.134661 -280.469276) (xy 361.153952 -280.424) (xy 361.180255 -280.382404) (xy 361.21289 -280.345567)
			(xy 361.251011 -280.314442) (xy 361.293632 -280.289835) (xy 361.339648 -280.272383) (xy 361.387867 -280.262539)
			(xy 361.437042 -280.260558) (xy 361.485897 -280.26649) (xy 361.533168 -280.280182) (xy 361.57763 -280.30128)
			(xy 361.618133 -280.329236) (xy 361.653626 -280.363328) (xy 361.683191 -280.402672) (xy 361.706062 -280.446249)
			(xy 361.721646 -280.49293) (xy 361.729541 -280.541507) (xy 361.730036 -280.566114) (xy 363.939086 -280.566114)
			(xy 363.943046 -280.51706) (xy 363.954823 -280.469276) (xy 363.974114 -280.424) (xy 364.000417 -280.382404)
			(xy 364.033052 -280.345567) (xy 364.071173 -280.314442) (xy 364.113794 -280.289835) (xy 364.15981 -280.272383)
			(xy 364.208029 -280.262539) (xy 364.257204 -280.260558) (xy 364.306059 -280.26649) (xy 364.35333 -280.280182)
			(xy 364.397792 -280.30128) (xy 364.438295 -280.329236) (xy 364.473788 -280.363328) (xy 364.503353 -280.402672)
			(xy 364.526224 -280.446249) (xy 364.541808 -280.49293) (xy 364.549703 -280.541507) (xy 364.550198 -280.566114)
			(xy 364.878886 -280.566114) (xy 364.882846 -280.51706) (xy 364.894623 -280.469276) (xy 364.913914 -280.424)
			(xy 364.940217 -280.382404) (xy 364.972852 -280.345567) (xy 365.010973 -280.314442) (xy 365.053594 -280.289835)
			(xy 365.09961 -280.272383) (xy 365.147829 -280.262539) (xy 365.197004 -280.260558) (xy 365.245859 -280.26649)
			(xy 365.29313 -280.280182) (xy 365.337592 -280.30128) (xy 365.378095 -280.329236) (xy 365.413588 -280.363328)
			(xy 365.443153 -280.402672) (xy 365.466024 -280.446249) (xy 365.481608 -280.49293) (xy 365.489503 -280.541507)
			(xy 365.489998 -280.566114) (xy 365.81894 -280.566114) (xy 365.8229 -280.51706) (xy 365.834677 -280.469276)
			(xy 365.853968 -280.424) (xy 365.880271 -280.382404) (xy 365.912906 -280.345567) (xy 365.951027 -280.314442)
			(xy 365.993648 -280.289835) (xy 366.039664 -280.272383) (xy 366.087883 -280.262539) (xy 366.137058 -280.260558)
			(xy 366.185913 -280.26649) (xy 366.233184 -280.280182) (xy 366.277646 -280.30128) (xy 366.318149 -280.329236)
			(xy 366.353642 -280.363328) (xy 366.383207 -280.402672) (xy 366.406078 -280.446249) (xy 366.421662 -280.49293)
			(xy 366.429557 -280.541507) (xy 366.430052 -280.566114) (xy 366.758994 -280.566114) (xy 366.762954 -280.51706)
			(xy 366.774731 -280.469276) (xy 366.794022 -280.424) (xy 366.820325 -280.382404) (xy 366.85296 -280.345567)
			(xy 366.891081 -280.314442) (xy 366.933702 -280.289835) (xy 366.979718 -280.272383) (xy 367.027937 -280.262539)
			(xy 367.077112 -280.260558) (xy 367.125967 -280.26649) (xy 367.173238 -280.280182) (xy 367.2177 -280.30128)
			(xy 367.258203 -280.329236) (xy 367.293696 -280.363328) (xy 367.323261 -280.402672) (xy 367.346132 -280.446249)
			(xy 367.361716 -280.49293) (xy 367.369611 -280.541507) (xy 367.370106 -280.566114) (xy 367.699048 -280.566114)
			(xy 367.703008 -280.51706) (xy 367.714785 -280.469276) (xy 367.734076 -280.424) (xy 367.760379 -280.382404)
			(xy 367.793014 -280.345567) (xy 367.831135 -280.314442) (xy 367.873756 -280.289835) (xy 367.919772 -280.272383)
			(xy 367.967991 -280.262539) (xy 368.017166 -280.260558) (xy 368.066021 -280.26649) (xy 368.113292 -280.280182)
			(xy 368.157754 -280.30128) (xy 368.198257 -280.329236) (xy 368.23375 -280.363328) (xy 368.263315 -280.402672)
			(xy 368.286186 -280.446249) (xy 368.30177 -280.49293) (xy 368.309665 -280.541507) (xy 368.31016 -280.566114)
			(xy 368.639102 -280.566114) (xy 368.643062 -280.51706) (xy 368.654839 -280.469276) (xy 368.67413 -280.424)
			(xy 368.700433 -280.382404) (xy 368.733068 -280.345567) (xy 368.771189 -280.314442) (xy 368.81381 -280.289835)
			(xy 368.859826 -280.272383) (xy 368.908045 -280.262539) (xy 368.95722 -280.260558) (xy 369.006075 -280.26649)
			(xy 369.053346 -280.280182) (xy 369.097808 -280.30128) (xy 369.138311 -280.329236) (xy 369.173804 -280.363328)
			(xy 369.203369 -280.402672) (xy 369.22624 -280.446249) (xy 369.241824 -280.49293) (xy 369.249719 -280.541507)
			(xy 369.250214 -280.566114) (xy 369.249719 -280.590721) (xy 369.241824 -280.639298) (xy 369.22624 -280.685979)
			(xy 369.203369 -280.729556) (xy 369.173804 -280.7689) (xy 369.138311 -280.802992) (xy 369.097808 -280.830948)
			(xy 369.053346 -280.852046) (xy 369.006075 -280.865738) (xy 368.95722 -280.87167) (xy 368.908045 -280.869689)
			(xy 368.859826 -280.859845) (xy 368.81381 -280.842393) (xy 368.771189 -280.817786) (xy 368.733068 -280.786661)
			(xy 368.700433 -280.749824) (xy 368.67413 -280.708228) (xy 368.654839 -280.662952) (xy 368.643062 -280.615168)
			(xy 368.639102 -280.566114) (xy 368.31016 -280.566114) (xy 368.309665 -280.590721) (xy 368.30177 -280.639298)
			(xy 368.286186 -280.685979) (xy 368.263315 -280.729556) (xy 368.23375 -280.7689) (xy 368.198257 -280.802992)
			(xy 368.157754 -280.830948) (xy 368.113292 -280.852046) (xy 368.066021 -280.865738) (xy 368.017166 -280.87167)
			(xy 367.967991 -280.869689) (xy 367.919772 -280.859845) (xy 367.873756 -280.842393) (xy 367.831135 -280.817786)
			(xy 367.793014 -280.786661) (xy 367.760379 -280.749824) (xy 367.734076 -280.708228) (xy 367.714785 -280.662952)
			(xy 367.703008 -280.615168) (xy 367.699048 -280.566114) (xy 367.370106 -280.566114) (xy 367.369611 -280.590721)
			(xy 367.361716 -280.639298) (xy 367.346132 -280.685979) (xy 367.323261 -280.729556) (xy 367.293696 -280.7689)
			(xy 367.258203 -280.802992) (xy 367.2177 -280.830948) (xy 367.173238 -280.852046) (xy 367.125967 -280.865738)
			(xy 367.077112 -280.87167) (xy 367.027937 -280.869689) (xy 366.979718 -280.859845) (xy 366.933702 -280.842393)
			(xy 366.891081 -280.817786) (xy 366.85296 -280.786661) (xy 366.820325 -280.749824) (xy 366.794022 -280.708228)
			(xy 366.774731 -280.662952) (xy 366.762954 -280.615168) (xy 366.758994 -280.566114) (xy 366.430052 -280.566114)
			(xy 366.429557 -280.590721) (xy 366.421662 -280.639298) (xy 366.406078 -280.685979) (xy 366.383207 -280.729556)
			(xy 366.353642 -280.7689) (xy 366.318149 -280.802992) (xy 366.277646 -280.830948) (xy 366.233184 -280.852046)
			(xy 366.185913 -280.865738) (xy 366.137058 -280.87167) (xy 366.087883 -280.869689) (xy 366.039664 -280.859845)
			(xy 365.993648 -280.842393) (xy 365.951027 -280.817786) (xy 365.912906 -280.786661) (xy 365.880271 -280.749824)
			(xy 365.853968 -280.708228) (xy 365.834677 -280.662952) (xy 365.8229 -280.615168) (xy 365.81894 -280.566114)
			(xy 365.489998 -280.566114) (xy 365.489503 -280.590721) (xy 365.481608 -280.639298) (xy 365.466024 -280.685979)
			(xy 365.443153 -280.729556) (xy 365.413588 -280.7689) (xy 365.378095 -280.802992) (xy 365.337592 -280.830948)
			(xy 365.29313 -280.852046) (xy 365.245859 -280.865738) (xy 365.197004 -280.87167) (xy 365.147829 -280.869689)
			(xy 365.09961 -280.859845) (xy 365.053594 -280.842393) (xy 365.010973 -280.817786) (xy 364.972852 -280.786661)
			(xy 364.940217 -280.749824) (xy 364.913914 -280.708228) (xy 364.894623 -280.662952) (xy 364.882846 -280.615168)
			(xy 364.878886 -280.566114) (xy 364.550198 -280.566114) (xy 364.549703 -280.590721) (xy 364.541808 -280.639298)
			(xy 364.526224 -280.685979) (xy 364.503353 -280.729556) (xy 364.473788 -280.7689) (xy 364.438295 -280.802992)
			(xy 364.397792 -280.830948) (xy 364.35333 -280.852046) (xy 364.306059 -280.865738) (xy 364.257204 -280.87167)
			(xy 364.208029 -280.869689) (xy 364.15981 -280.859845) (xy 364.113794 -280.842393) (xy 364.071173 -280.817786)
			(xy 364.033052 -280.786661) (xy 364.000417 -280.749824) (xy 363.974114 -280.708228) (xy 363.954823 -280.662952)
			(xy 363.943046 -280.615168) (xy 363.939086 -280.566114) (xy 361.730036 -280.566114) (xy 361.729541 -280.590721)
			(xy 361.721646 -280.639298) (xy 361.706062 -280.685979) (xy 361.683191 -280.729556) (xy 361.653626 -280.7689)
			(xy 361.618133 -280.802992) (xy 361.57763 -280.830948) (xy 361.533168 -280.852046) (xy 361.485897 -280.865738)
			(xy 361.437042 -280.87167) (xy 361.387867 -280.869689) (xy 361.339648 -280.859845) (xy 361.293632 -280.842393)
			(xy 361.251011 -280.817786) (xy 361.21289 -280.786661) (xy 361.180255 -280.749824) (xy 361.153952 -280.708228)
			(xy 361.134661 -280.662952) (xy 361.122884 -280.615168) (xy 361.118924 -280.566114) (xy 358.916478 -280.566114)
			(xy 358.915983 -280.590721) (xy 358.908088 -280.639298) (xy 358.892504 -280.685979) (xy 358.869633 -280.729556)
			(xy 358.840068 -280.7689) (xy 358.804575 -280.802992) (xy 358.764072 -280.830948) (xy 358.71961 -280.852046)
			(xy 358.672339 -280.865738) (xy 358.623484 -280.87167) (xy 358.574309 -280.869689) (xy 358.52609 -280.859845)
			(xy 358.480074 -280.842393) (xy 358.437453 -280.817786) (xy 358.399332 -280.786661) (xy 358.366697 -280.749824)
			(xy 358.340394 -280.708228) (xy 358.321103 -280.662952) (xy 358.309326 -280.615168) (xy 358.305366 -280.566114)
			(xy 356.096316 -280.566114) (xy 356.095821 -280.590721) (xy 356.087926 -280.639298) (xy 356.072342 -280.685979)
			(xy 356.049471 -280.729556) (xy 356.019906 -280.7689) (xy 355.984413 -280.802992) (xy 355.94391 -280.830948)
			(xy 355.899448 -280.852046) (xy 355.852177 -280.865738) (xy 355.803322 -280.87167) (xy 355.754147 -280.869689)
			(xy 355.705928 -280.859845) (xy 355.659912 -280.842393) (xy 355.617291 -280.817786) (xy 355.57917 -280.786661)
			(xy 355.546535 -280.749824) (xy 355.520232 -280.708228) (xy 355.500941 -280.662952) (xy 355.489164 -280.615168)
			(xy 355.485204 -280.566114) (xy 355.156516 -280.566114) (xy 355.156021 -280.590721) (xy 355.148126 -280.639298)
			(xy 355.132542 -280.685979) (xy 355.109671 -280.729556) (xy 355.080106 -280.7689) (xy 355.044613 -280.802992)
			(xy 355.00411 -280.830948) (xy 354.959648 -280.852046) (xy 354.912377 -280.865738) (xy 354.863522 -280.87167)
			(xy 354.814347 -280.869689) (xy 354.766128 -280.859845) (xy 354.720112 -280.842393) (xy 354.677491 -280.817786)
			(xy 354.63937 -280.786661) (xy 354.606735 -280.749824) (xy 354.580432 -280.708228) (xy 354.561141 -280.662952)
			(xy 354.549364 -280.615168) (xy 354.545404 -280.566114) (xy 354.216462 -280.566114) (xy 354.215967 -280.590721)
			(xy 354.208072 -280.639298) (xy 354.192488 -280.685979) (xy 354.169617 -280.729556) (xy 354.140052 -280.7689)
			(xy 354.104559 -280.802992) (xy 354.064056 -280.830948) (xy 354.019594 -280.852046) (xy 353.972323 -280.865738)
			(xy 353.923468 -280.87167) (xy 353.874293 -280.869689) (xy 353.826074 -280.859845) (xy 353.780058 -280.842393)
			(xy 353.737437 -280.817786) (xy 353.699316 -280.786661) (xy 353.666681 -280.749824) (xy 353.640378 -280.708228)
			(xy 353.621087 -280.662952) (xy 353.60931 -280.615168) (xy 353.60535 -280.566114) (xy 353.276408 -280.566114)
			(xy 353.275913 -280.590721) (xy 353.268018 -280.639298) (xy 353.252434 -280.685979) (xy 353.229563 -280.729556)
			(xy 353.199998 -280.7689) (xy 353.164505 -280.802992) (xy 353.124002 -280.830948) (xy 353.07954 -280.852046)
			(xy 353.032269 -280.865738) (xy 352.983414 -280.87167) (xy 352.934239 -280.869689) (xy 352.88602 -280.859845)
			(xy 352.840004 -280.842393) (xy 352.797383 -280.817786) (xy 352.759262 -280.786661) (xy 352.726627 -280.749824)
			(xy 352.700324 -280.708228) (xy 352.681033 -280.662952) (xy 352.669256 -280.615168) (xy 352.665296 -280.566114)
			(xy 352.336354 -280.566114) (xy 352.335859 -280.590721) (xy 352.327964 -280.639298) (xy 352.31238 -280.685979)
			(xy 352.289509 -280.729556) (xy 352.259944 -280.7689) (xy 352.224451 -280.802992) (xy 352.183948 -280.830948)
			(xy 352.139486 -280.852046) (xy 352.092215 -280.865738) (xy 352.04336 -280.87167) (xy 351.994185 -280.869689)
			(xy 351.945966 -280.859845) (xy 351.89995 -280.842393) (xy 351.857329 -280.817786) (xy 351.819208 -280.786661)
			(xy 351.786573 -280.749824) (xy 351.76027 -280.708228) (xy 351.740979 -280.662952) (xy 351.729202 -280.615168)
			(xy 351.725242 -280.566114) (xy 351.396554 -280.566114) (xy 351.396059 -280.590721) (xy 351.388164 -280.639298)
			(xy 351.37258 -280.685979) (xy 351.349709 -280.729556) (xy 351.320144 -280.7689) (xy 351.284651 -280.802992)
			(xy 351.244148 -280.830948) (xy 351.199686 -280.852046) (xy 351.152415 -280.865738) (xy 351.10356 -280.87167)
			(xy 351.054385 -280.869689) (xy 351.006166 -280.859845) (xy 350.96015 -280.842393) (xy 350.917529 -280.817786)
			(xy 350.879408 -280.786661) (xy 350.846773 -280.749824) (xy 350.82047 -280.708228) (xy 350.801179 -280.662952)
			(xy 350.789402 -280.615168) (xy 350.785442 -280.566114) (xy 350.4565 -280.566114) (xy 350.456028 -280.590336)
			(xy 350.448365 -280.638169) (xy 350.433249 -280.684194) (xy 350.411059 -280.727256) (xy 350.382351 -280.766277)
			(xy 350.347845 -280.800278) (xy 350.308405 -280.828408) (xy 350.265021 -280.84996) (xy 350.218778 -280.864396)
			(xy 350.19488 -280.868374) (xy 350.181418 -280.870152) (xy 350.160082 -280.886916) (xy 350.116902 -280.993342)
			(xy 350.120712 -281.020012) (xy 350.12884 -281.030934) (xy 350.151942 -281.061926) (xy 350.190427 -281.128963)
			(xy 350.205548 -281.164538) (xy 350.210628 -281.177238) (xy 350.232218 -281.194002) (xy 350.346264 -281.210004)
			(xy 350.371664 -281.19959) (xy 350.380046 -281.188922) (xy 350.394589 -281.170876) (xy 350.428207 -281.138973)
			(xy 350.466263 -281.112523) (xy 350.507882 -281.092133) (xy 350.552107 -281.078273) (xy 350.597919 -281.071262)
			(xy 350.621092 -281.070812) (xy 350.646349 -281.071304) (xy 350.696173 -281.079617) (xy 350.743949 -281.096018)
			(xy 350.788374 -281.120058) (xy 350.828237 -281.151083) (xy 350.862449 -281.188247) (xy 350.890077 -281.230534)
			(xy 350.910368 -281.276792) (xy 350.922769 -281.32576) (xy 350.92694 -281.3761) (xy 350.926938 -281.37612)
			(xy 353.135196 -281.37612) (xy 353.139156 -281.327066) (xy 353.150933 -281.279282) (xy 353.170224 -281.234006)
			(xy 353.196527 -281.19241) (xy 353.229162 -281.155573) (xy 353.267283 -281.124448) (xy 353.309904 -281.099841)
			(xy 353.35592 -281.082389) (xy 353.404139 -281.072545) (xy 353.453314 -281.070564) (xy 353.502169 -281.076496)
			(xy 353.54944 -281.090188) (xy 353.593902 -281.111286) (xy 353.634405 -281.139242) (xy 353.669898 -281.173334)
			(xy 353.699463 -281.212678) (xy 353.722334 -281.256255) (xy 353.737918 -281.302936) (xy 353.745813 -281.351513)
			(xy 353.746308 -281.37612) (xy 353.745813 -281.400727) (xy 353.737918 -281.449304) (xy 353.722334 -281.495985)
			(xy 353.699463 -281.539562) (xy 353.669898 -281.578906) (xy 353.634405 -281.612998) (xy 353.593902 -281.640954)
			(xy 353.54944 -281.662052) (xy 353.502169 -281.675744) (xy 353.453314 -281.681676) (xy 353.404139 -281.679695)
			(xy 353.35592 -281.669851) (xy 353.309904 -281.652399) (xy 353.267283 -281.627792) (xy 353.229162 -281.596667)
			(xy 353.196527 -281.55983) (xy 353.170224 -281.518234) (xy 353.150933 -281.472958) (xy 353.139156 -281.425174)
			(xy 353.135196 -281.37612) (xy 350.926938 -281.37612) (xy 350.922769 -281.42644) (xy 350.910368 -281.475408)
			(xy 350.890077 -281.521666) (xy 350.862449 -281.563953) (xy 350.828237 -281.601117) (xy 350.788374 -281.632142)
			(xy 350.743949 -281.656182) (xy 350.696173 -281.672583) (xy 350.646349 -281.680896) (xy 350.621092 -281.681428)
			(xy 350.597648 -281.680999) (xy 350.551312 -281.673828) (xy 350.506618 -281.659654) (xy 350.464617 -281.638813)
			(xy 350.426298 -281.611794) (xy 350.392561 -281.579233) (xy 350.3642 -281.541895) (xy 350.341883 -281.500659)
			(xy 350.333564 -281.478736) (xy 350.330038 -281.469888) (xy 350.317617 -281.455466) (xy 350.300796 -281.44656)
			(xy 350.281886 -281.444394) (xy 350.263486 -281.449266) (xy 350.248126 -281.460507) (xy 350.237917 -281.47657)
			(xy 350.235774 -281.485848) (xy 350.231303 -281.507306) (xy 350.219479 -281.549518) (xy 350.212152 -281.570176)
			(xy 350.207072 -281.584146) (xy 350.213422 -281.612848) (xy 350.419924 -281.81935) (xy 350.427322 -281.826198)
			(xy 350.44592 -281.833931) (xy 350.455992 -281.834336) (xy 356.264464 -281.834336) (xy 356.275392 -281.833817)
			(xy 356.29527 -281.824731) (xy 356.302818 -281.81681) (xy 356.314724 -281.803222) (xy 356.340014 -281.777419)
			(xy 356.353364 -281.765248) (xy 356.361178 -281.757548) (xy 356.369946 -281.737462) (xy 356.369556 -281.715549)
			(xy 356.360079 -281.695788) (xy 356.343237 -281.681765) (xy 356.322086 -281.676026) (xy 356.3112 -281.677364)
			(xy 356.298779 -281.679272) (xy 356.273728 -281.681307) (xy 356.261162 -281.681428) (xy 356.23634 -281.680939)
			(xy 356.187351 -281.672901) (xy 356.140307 -281.657044) (xy 356.096448 -281.633785) (xy 356.05693 -281.603737)
			(xy 356.022794 -281.567692) (xy 355.994939 -281.526599) (xy 355.974099 -281.48154) (xy 355.960823 -281.433704)
			(xy 355.95546 -281.38435) (xy 355.958153 -281.334779) (xy 355.96883 -281.286296) (xy 355.98721 -281.24018)
			(xy 356.012809 -281.197644) (xy 356.044951 -281.15981) (xy 356.082791 -281.127675) (xy 356.125332 -281.102084)
			(xy 356.171452 -281.083713) (xy 356.219936 -281.073045) (xy 356.269508 -281.070362) (xy 356.318861 -281.075733)
			(xy 356.366695 -281.089019) (xy 356.411749 -281.109867) (xy 356.452837 -281.13773) (xy 356.488876 -281.171873)
			(xy 356.518917 -281.211397) (xy 356.542167 -281.25526) (xy 356.558015 -281.302307) (xy 356.566044 -281.351298)
			(xy 356.56647 -281.37612) (xy 356.565815 -281.404819) (xy 356.555068 -281.461201) (xy 356.545134 -281.488134)
			(xy 356.540308 -281.500834) (xy 356.544118 -281.52725) (xy 356.615238 -281.617674) (xy 356.64013 -281.627834)
			(xy 356.653592 -281.625802) (xy 356.672862 -281.623306) (xy 356.711632 -281.62064) (xy 356.731062 -281.620468)
			(xy 356.820216 -281.620468) (xy 356.832543 -281.619877) (xy 356.854374 -281.608427) (xy 356.861872 -281.598624)
			(xy 356.916736 -281.51963) (xy 356.919784 -281.495246) (xy 356.915466 -281.483308) (xy 356.906393 -281.457442)
			(xy 356.896546 -281.403524) (xy 356.895908 -281.37612) (xy 356.89643 -281.350865) (xy 356.904743 -281.301043)
			(xy 356.921144 -281.253269) (xy 356.945185 -281.208846) (xy 356.976209 -281.168986) (xy 357.013371 -281.134776)
			(xy 357.055657 -281.10715) (xy 357.101913 -281.08686) (xy 357.150878 -281.07446) (xy 357.201216 -281.070289)
			(xy 357.251554 -281.07446) (xy 357.300519 -281.08686) (xy 357.346775 -281.10715) (xy 357.389061 -281.134776)
			(xy 357.426223 -281.168986) (xy 357.457247 -281.208846) (xy 357.481288 -281.253269) (xy 357.497689 -281.301043)
			(xy 357.506002 -281.350865) (xy 357.506524 -281.37612) (xy 357.505923 -281.403528) (xy 357.496078 -281.457452)
			(xy 357.486966 -281.483308) (xy 357.482648 -281.495246) (xy 357.485696 -281.51963) (xy 357.54056 -281.598624)
			(xy 357.548177 -281.608284) (xy 357.569938 -281.619678) (xy 357.582216 -281.620468) (xy 357.671116 -281.620468)
			(xy 357.690547 -281.620634) (xy 357.729316 -281.623307) (xy 357.748586 -281.625802) (xy 357.762048 -281.627834)
			(xy 357.78694 -281.617674) (xy 357.85806 -281.52725) (xy 357.86187 -281.500834) (xy 357.857044 -281.488134)
			(xy 357.847127 -281.461197) (xy 357.836392 -281.404816) (xy 357.835708 -281.37612) (xy 357.836192 -281.3513)
			(xy 357.84422 -281.302314) (xy 357.860067 -281.255273) (xy 357.883315 -281.211414) (xy 357.913353 -281.171895)
			(xy 357.949389 -281.137756) (xy 357.990473 -281.109896) (xy 358.035523 -281.08905) (xy 358.083352 -281.075768)
			(xy 358.1327 -281.070398) (xy 358.182267 -281.073082) (xy 358.230746 -281.08375) (xy 358.276861 -281.102121)
			(xy 358.319396 -281.12771) (xy 358.357231 -281.159843) (xy 358.389369 -281.197675) (xy 358.414963 -281.240207)
			(xy 358.433339 -281.28632) (xy 358.444013 -281.334798) (xy 358.446703 -281.384364) (xy 358.441339 -281.433713)
			(xy 358.428062 -281.481543) (xy 358.407221 -281.526596) (xy 358.379367 -281.567683) (xy 358.345232 -281.603723)
			(xy 358.305716 -281.633765) (xy 358.26186 -281.657019) (xy 358.214821 -281.672872) (xy 358.165836 -281.680905)
			(xy 358.141016 -281.681428) (xy 358.128449 -281.681325) (xy 358.103397 -281.67929) (xy 358.090978 -281.677364)
			(xy 358.080101 -281.676141) (xy 358.059016 -281.681933) (xy 358.042231 -281.695947) (xy 358.032767 -281.715659)
			(xy 358.032328 -281.73752) (xy 358.040994 -281.757596) (xy 358.048814 -281.765248) (xy 358.062164 -281.77742)
			(xy 358.087456 -281.803221) (xy 358.09936 -281.81681) (xy 358.106916 -281.824718) (xy 358.12679 -281.833796)
			(xy 358.137714 -281.834336) (xy 358.853486 -281.834336) (xy 358.863548 -281.834776) (xy 358.882127 -281.842516)
			(xy 358.889554 -281.849322) (xy 359.766362 -282.72613) (xy 359.77376 -282.732974) (xy 359.792359 -282.740697)
			(xy 359.80243 -282.741116) (xy 360.848402 -282.741116) (xy 360.858472 -282.740693) (xy 360.877078 -282.73298)
			(xy 360.88447 -282.72613) (xy 361.189016 -282.421838) (xy 361.19181 -282.384246) (xy 361.18038 -282.369006)
			(xy 361.166056 -282.349086) (xy 361.143288 -282.305627) (xy 361.127774 -282.259084) (xy 361.119913 -282.210657)
			(xy 361.11942 -282.186126) (xy 361.119864 -282.162132) (xy 361.127368 -282.114735) (xy 361.142195 -282.069096)
			(xy 361.163979 -282.026338) (xy 361.192185 -281.987515) (xy 361.226117 -281.953583) (xy 361.26494 -281.925378)
			(xy 361.307698 -281.903594) (xy 361.353337 -281.888767) (xy 361.400734 -281.881264) (xy 361.424728 -281.880818)
			(xy 361.4479 -281.881251) (xy 361.493711 -281.888268) (xy 361.537933 -281.902134) (xy 361.579548 -281.922532)
			(xy 361.617597 -281.948991) (xy 361.651206 -281.980902) (xy 361.665774 -281.998928) (xy 361.674156 -282.009596)
			(xy 361.699556 -282.02001) (xy 361.80014 -282.00604) (xy 361.806848 -282.004873) (xy 361.819337 -281.999465)
			(xy 361.824778 -281.995372) (xy 361.829773 -281.991176) (xy 361.837618 -281.980758) (xy 361.840272 -281.974798)
			(xy 361.840272 -281.974544) (xy 361.857036 -281.937206) (xy 361.869866 -281.911801) (xy 361.899896 -281.86345)
			(xy 361.91698 -281.840686) (xy 361.925362 -281.830018) (xy 361.928918 -281.803348) (xy 361.890818 -281.709622)
			(xy 361.887145 -281.701596) (xy 361.875366 -281.688469) (xy 361.859856 -281.680073) (xy 361.851194 -281.67838)
			(xy 361.85094 -281.67838) (xy 361.827054 -281.674417) (xy 361.780852 -281.659939) (xy 361.737511 -281.638356)
			(xy 361.698115 -281.61021) (xy 361.663651 -281.576204) (xy 361.634979 -281.537189) (xy 361.612818 -281.494141)
			(xy 361.597722 -281.448137) (xy 361.590069 -281.400328) (xy 361.589574 -281.37612) (xy 361.590096 -281.350865)
			(xy 361.598409 -281.301043) (xy 361.61481 -281.253269) (xy 361.638851 -281.208846) (xy 361.669875 -281.168986)
			(xy 361.707037 -281.134776) (xy 361.749323 -281.10715) (xy 361.795579 -281.08686) (xy 361.844544 -281.07446)
			(xy 361.894882 -281.070289) (xy 361.94522 -281.07446) (xy 361.994185 -281.08686) (xy 362.040441 -281.10715)
			(xy 362.082727 -281.134776) (xy 362.119889 -281.168986) (xy 362.150913 -281.208846) (xy 362.174954 -281.253269)
			(xy 362.191355 -281.301043) (xy 362.199668 -281.350865) (xy 362.20019 -281.37612) (xy 362.199522 -281.404756)
			(xy 362.188785 -281.461013) (xy 362.178854 -281.48788) (xy 362.174028 -281.50058) (xy 362.177838 -281.52725)
			(xy 362.240576 -281.607006) (xy 362.246292 -281.613662) (xy 362.261173 -281.62293) (xy 362.278318 -281.626591)
			(xy 362.287058 -281.625802) (xy 362.287312 -281.625802) (xy 362.306582 -281.623303) (xy 362.345351 -281.620631)
			(xy 362.364782 -281.620468) (xy 362.453936 -281.620468) (xy 362.460032 -281.620214) (xy 362.469287 -281.618619)
			(xy 362.485824 -281.609754) (xy 362.49229 -281.602942) (xy 362.495592 -281.598624) (xy 362.550202 -281.51963)
			(xy 362.55325 -281.494992) (xy 362.548678 -281.483308) (xy 362.539616 -281.457446) (xy 362.529896 -281.403519)
			(xy 362.529374 -281.37612) (xy 362.529896 -281.350865) (xy 362.538209 -281.301043) (xy 362.55461 -281.253269)
			(xy 362.578651 -281.208846) (xy 362.609675 -281.168986) (xy 362.646837 -281.134776) (xy 362.689123 -281.10715)
			(xy 362.735379 -281.08686) (xy 362.784344 -281.07446) (xy 362.834682 -281.070289) (xy 362.88502 -281.07446)
			(xy 362.933985 -281.08686) (xy 362.980241 -281.10715) (xy 363.022527 -281.134776) (xy 363.059689 -281.168986)
			(xy 363.090713 -281.208846) (xy 363.114754 -281.253269) (xy 363.131155 -281.301043) (xy 363.139468 -281.350865)
			(xy 363.13999 -281.37612) (xy 363.139401 -281.403513) (xy 363.129695 -281.457432) (xy 363.120686 -281.483308)
			(xy 363.116114 -281.494992) (xy 363.119162 -281.51963) (xy 363.173772 -281.598624) (xy 363.176058 -281.601672)
			(xy 363.18256 -281.609008) (xy 363.199673 -281.618533) (xy 363.209332 -281.620214) (xy 363.215428 -281.620468)
			(xy 363.304836 -281.620468) (xy 363.324203 -281.62064) (xy 363.362845 -281.623309) (xy 363.382052 -281.625802)
			(xy 363.38256 -281.625802) (xy 363.391292 -281.62657) (xy 363.408412 -281.62286) (xy 363.423299 -281.613628)
			(xy 363.429042 -281.607006) (xy 363.49178 -281.52725) (xy 363.49559 -281.50058) (xy 363.490764 -281.48788)
			(xy 363.48086 -281.461005) (xy 363.470116 -281.404753) (xy 363.469428 -281.37612) (xy 363.46995 -281.350865)
			(xy 363.478263 -281.301043) (xy 363.494664 -281.253269) (xy 363.518705 -281.208846) (xy 363.549729 -281.168986)
			(xy 363.586891 -281.134776) (xy 363.629177 -281.10715) (xy 363.675433 -281.08686) (xy 363.724398 -281.07446)
			(xy 363.774736 -281.070289) (xy 363.825074 -281.07446) (xy 363.874039 -281.08686) (xy 363.920295 -281.10715)
			(xy 363.962581 -281.134776) (xy 363.999743 -281.168986) (xy 364.030767 -281.208846) (xy 364.054808 -281.253269)
			(xy 364.071209 -281.301043) (xy 364.079522 -281.350865) (xy 364.080044 -281.37612) (xy 366.289094 -281.37612)
			(xy 366.293054 -281.327066) (xy 366.304831 -281.279282) (xy 366.324122 -281.234006) (xy 366.350425 -281.19241)
			(xy 366.38306 -281.155573) (xy 366.421181 -281.124448) (xy 366.463802 -281.099841) (xy 366.509818 -281.082389)
			(xy 366.558037 -281.072545) (xy 366.607212 -281.070564) (xy 366.656067 -281.076496) (xy 366.703338 -281.090188)
			(xy 366.7478 -281.111286) (xy 366.788303 -281.139242) (xy 366.823796 -281.173334) (xy 366.853361 -281.212678)
			(xy 366.876232 -281.256255) (xy 366.891816 -281.302936) (xy 366.899711 -281.351513) (xy 366.900206 -281.37612)
			(xy 366.899711 -281.400727) (xy 366.891816 -281.449304) (xy 366.876232 -281.495985) (xy 366.853361 -281.539562)
			(xy 366.823796 -281.578906) (xy 366.788303 -281.612998) (xy 366.7478 -281.640954) (xy 366.703338 -281.662052)
			(xy 366.656067 -281.675744) (xy 366.607212 -281.681676) (xy 366.558037 -281.679695) (xy 366.509818 -281.669851)
			(xy 366.463802 -281.652399) (xy 366.421181 -281.627792) (xy 366.38306 -281.596667) (xy 366.350425 -281.55983)
			(xy 366.324122 -281.518234) (xy 366.304831 -281.472958) (xy 366.293054 -281.425174) (xy 366.289094 -281.37612)
			(xy 364.080044 -281.37612) (xy 364.079906 -281.388883) (xy 364.077745 -281.414317) (xy 364.075726 -281.42692)
			(xy 364.07598 -281.42692) (xy 364.071544 -281.450557) (xy 364.056224 -281.496144) (xy 364.033949 -281.538766)
			(xy 364.005269 -281.577371) (xy 363.970894 -281.611004) (xy 363.931673 -281.638834) (xy 363.888575 -281.660173)
			(xy 363.842666 -281.674495) (xy 363.818932 -281.67838) (xy 363.818424 -281.67838) (xy 363.809724 -281.679976)
			(xy 363.794153 -281.688342) (xy 363.782393 -281.701539) (xy 363.7788 -281.709622) (xy 363.747304 -281.787092)
			(xy 363.744256 -281.795619) (xy 363.743741 -281.813708) (xy 363.746288 -281.822398) (xy 363.752384 -281.840432)
			(xy 363.75721 -281.846782) (xy 363.772902 -281.868204) (xy 363.800633 -281.913492) (xy 363.812582 -281.937206)
			(xy 363.829346 -281.974544) (xy 363.829346 -281.974798) (xy 363.832008 -281.980752) (xy 363.839854 -281.991167)
			(xy 363.84484 -281.995372) (xy 363.850288 -281.999452) (xy 363.862776 -282.004851) (xy 363.869478 -282.00604)
			(xy 363.970062 -282.02001) (xy 363.995462 -282.009596) (xy 364.003844 -281.998928) (xy 364.018387 -281.980882)
			(xy 364.052004 -281.948978) (xy 364.09006 -281.922527) (xy 364.13168 -281.902136) (xy 364.175905 -281.888276)
			(xy 364.221717 -281.881264) (xy 364.24489 -281.880818) (xy 364.257653 -281.880954) (xy 364.283088 -281.883113)
			(xy 364.29569 -281.885136) (xy 364.29569 -281.884882) (xy 364.319281 -281.889373) (xy 364.364778 -281.90473)
			(xy 364.407316 -281.927011) (xy 364.445847 -281.955667) (xy 364.479425 -281.989995) (xy 364.507224 -282.02915)
			(xy 364.52856 -282.072169) (xy 364.542908 -282.117995) (xy 364.546896 -282.141676) (xy 364.54715 -282.142184)
			(xy 364.548765 -282.151186) (xy 364.557436 -282.167273) (xy 364.571199 -282.179296) (xy 364.588305 -282.185727)
			(xy 364.597442 -282.186126) (xy 364.851188 -282.186126) (xy 364.879636 -282.161488) (xy 364.88243 -282.142692)
			(xy 364.886339 -282.118764) (xy 364.900731 -282.072468) (xy 364.922257 -282.029027) (xy 364.950377 -281.989534)
			(xy 364.984384 -281.954979) (xy 365.023424 -281.926233) (xy 365.066516 -281.904016) (xy 365.112577 -281.888887)
			(xy 365.160449 -281.881227) (xy 365.208931 -281.881227) (xy 365.256803 -281.888887) (xy 365.302864 -281.904016)
			(xy 365.345956 -281.926233) (xy 365.384996 -281.954979) (xy 365.419003 -281.989534) (xy 365.447123 -282.029027)
			(xy 365.468649 -282.072468) (xy 365.483041 -282.118764) (xy 365.48695 -282.142692) (xy 365.489744 -282.161488)
			(xy 365.518192 -282.186126) (xy 365.791242 -282.186126) (xy 365.81969 -282.161488) (xy 365.822484 -282.142692)
			(xy 365.826393 -282.118764) (xy 365.840785 -282.072468) (xy 365.862311 -282.029027) (xy 365.890431 -281.989534)
			(xy 365.924438 -281.954979) (xy 365.963478 -281.926233) (xy 366.00657 -281.904016) (xy 366.052631 -281.888887)
			(xy 366.100503 -281.881227) (xy 366.148985 -281.881227) (xy 366.196857 -281.888887) (xy 366.242918 -281.904016)
			(xy 366.28601 -281.926233) (xy 366.32505 -281.954979) (xy 366.359057 -281.989534) (xy 366.387177 -282.029027)
			(xy 366.408703 -282.072468) (xy 366.423095 -282.118764) (xy 366.427004 -282.142692) (xy 366.429798 -282.161488)
			(xy 366.458246 -282.186126) (xy 366.731296 -282.186126) (xy 366.759744 -282.161488) (xy 366.762538 -282.142692)
			(xy 366.766447 -282.118764) (xy 366.780839 -282.072468) (xy 366.802365 -282.029027) (xy 366.830485 -281.989534)
			(xy 366.864492 -281.954979) (xy 366.903532 -281.926233) (xy 366.946624 -281.904016) (xy 366.992685 -281.888887)
			(xy 367.040557 -281.881227) (xy 367.089039 -281.881227) (xy 367.136911 -281.888887) (xy 367.182972 -281.904016)
			(xy 367.226064 -281.926233) (xy 367.265104 -281.954979) (xy 367.299111 -281.989534) (xy 367.327231 -282.029027)
			(xy 367.348757 -282.072468) (xy 367.363149 -282.118764) (xy 367.367058 -282.142692) (xy 367.369852 -282.161488)
			(xy 367.3983 -282.186126) (xy 367.67135 -282.186126) (xy 367.699798 -282.161488) (xy 367.702592 -282.142692)
			(xy 367.706501 -282.118764) (xy 367.720893 -282.072468) (xy 367.742419 -282.029027) (xy 367.770539 -281.989534)
			(xy 367.804546 -281.954979) (xy 367.843586 -281.926233) (xy 367.886678 -281.904016) (xy 367.932739 -281.888887)
			(xy 367.980611 -281.881227) (xy 368.029093 -281.881227) (xy 368.076965 -281.888887) (xy 368.123026 -281.904016)
			(xy 368.166118 -281.926233) (xy 368.205158 -281.954979) (xy 368.239165 -281.989534) (xy 368.267285 -282.029027)
			(xy 368.288811 -282.072468) (xy 368.303203 -282.118764) (xy 368.307112 -282.142692) (xy 368.309906 -282.161488)
			(xy 368.338354 -282.186126) (xy 368.611404 -282.186126) (xy 368.639852 -282.161488) (xy 368.642646 -282.142692)
			(xy 368.646555 -282.118764) (xy 368.660947 -282.072468) (xy 368.682473 -282.029027) (xy 368.710593 -281.989534)
			(xy 368.7446 -281.954979) (xy 368.78364 -281.926233) (xy 368.826732 -281.904016) (xy 368.872793 -281.888887)
			(xy 368.920665 -281.881227) (xy 368.969147 -281.881227) (xy 369.017019 -281.888887) (xy 369.06308 -281.904016)
			(xy 369.106172 -281.926233) (xy 369.145212 -281.954979) (xy 369.179219 -281.989534) (xy 369.207339 -282.029027)
			(xy 369.228865 -282.072468) (xy 369.243257 -282.118764) (xy 369.247166 -282.142692) (xy 369.24996 -282.161488)
			(xy 369.278408 -282.186126) (xy 369.523772 -282.186126) (xy 369.533645 -282.185657) (xy 369.551933 -282.178203)
			(xy 369.559332 -282.171648) (xy 369.559586 -282.171394) (xy 369.575334 -282.155646) (xy 369.582446 -282.14193)
			(xy 369.58397 -282.134056) (xy 369.588537 -282.110393) (xy 369.604124 -282.064792) (xy 369.626668 -282.022198)
			(xy 369.65561 -281.983666) (xy 369.690236 -281.950147) (xy 369.7097 -281.935936) (xy 369.716418 -281.930461)
			(xy 369.726019 -281.916047) (xy 369.728496 -281.907742) (xy 369.740375 -281.862726) (xy 369.770563 -281.774646)
			(xy 369.807898 -281.68935) (xy 369.829588 -281.648154) (xy 369.832636 -281.64282) (xy 369.835938 -281.629612)
			(xy 369.837257 -281.624054) (xy 369.837651 -281.612639) (xy 369.8367 -281.607006) (xy 369.834922 -281.598624)
			(xy 369.83289 -281.594052) (xy 369.83035 -281.587702) (xy 369.83035 -281.587448) (xy 369.827683 -281.581498)
			(xy 369.81983 -281.571092) (xy 369.814856 -281.566874) (xy 369.809409 -281.562792) (xy 369.796921 -281.557389)
			(xy 369.790218 -281.556206) (xy 369.689634 -281.542236) (xy 369.664234 -281.55265) (xy 369.655852 -281.563318)
			(xy 369.641307 -281.581362) (xy 369.607688 -281.61326) (xy 369.569631 -281.639707) (xy 369.528012 -281.660094)
			(xy 369.483789 -281.673952) (xy 369.437978 -281.680962) (xy 369.414806 -281.681428) (xy 369.389546 -281.680936)
			(xy 369.339716 -281.672621) (xy 369.291933 -281.656219) (xy 369.247503 -281.632175) (xy 369.207635 -281.601145)
			(xy 369.173419 -281.563977) (xy 369.145787 -281.521684) (xy 369.125494 -281.47542) (xy 369.113092 -281.426447)
			(xy 369.10892 -281.3761) (xy 369.113092 -281.325753) (xy 369.125494 -281.27678) (xy 369.145787 -281.230516)
			(xy 369.173419 -281.188223) (xy 369.207635 -281.151055) (xy 369.247503 -281.120025) (xy 369.291933 -281.095981)
			(xy 369.339716 -281.079579) (xy 369.389546 -281.071264) (xy 369.414806 -281.070812) (xy 369.437979 -281.071244)
			(xy 369.483792 -281.078257) (xy 369.528016 -281.092121) (xy 369.569634 -281.112516) (xy 369.607686 -281.138974)
			(xy 369.641298 -281.170884) (xy 369.655852 -281.188922) (xy 369.664234 -281.19959) (xy 369.689634 -281.210004)
			(xy 369.790218 -281.196034) (xy 369.796927 -281.19487) (xy 369.809419 -281.189466) (xy 369.814856 -281.185366)
			(xy 369.819845 -281.181165) (xy 369.827677 -281.170742) (xy 369.83035 -281.164792) (xy 369.83035 -281.164538)
			(xy 369.847114 -281.1272) (xy 369.859943 -281.101794) (xy 369.889974 -281.053443) (xy 369.907058 -281.03068)
			(xy 369.91544 -281.020012) (xy 369.918996 -280.993342) (xy 369.880896 -280.899616) (xy 369.877222 -280.891593)
			(xy 369.865441 -280.878472) (xy 369.84993 -280.870084) (xy 369.841272 -280.868374) (xy 369.841018 -280.868374)
			(xy 369.817104 -280.864454) (xy 369.770839 -280.850043) (xy 369.727433 -280.828502) (xy 369.687976 -280.800373)
			(xy 369.653459 -280.766363) (xy 369.62475 -280.727326) (xy 369.60257 -280.684243) (xy 369.587477 -280.638196)
			(xy 369.579849 -280.590343) (xy 369.579398 -280.566114) (xy 369.57992 -280.540859) (xy 369.588233 -280.491037)
			(xy 369.604634 -280.443263) (xy 369.628675 -280.39884) (xy 369.659699 -280.35898) (xy 369.696861 -280.32477)
			(xy 369.739147 -280.297144) (xy 369.785403 -280.276854) (xy 369.834368 -280.264454) (xy 369.884706 -280.260283)
			(xy 369.935044 -280.264454) (xy 369.984009 -280.276854) (xy 370.030265 -280.297144) (xy 370.072551 -280.32477)
			(xy 370.109713 -280.35898) (xy 370.140737 -280.39884) (xy 370.164778 -280.443263) (xy 370.181179 -280.491037)
			(xy 370.189492 -280.540859) (xy 370.190014 -280.566114) (xy 370.18936 -280.594813) (xy 370.178615 -280.651196)
			(xy 370.168678 -280.678128) (xy 370.163598 -280.690828) (xy 370.167662 -280.717498) (xy 370.238782 -280.807668)
			(xy 370.263674 -280.817828) (xy 370.277136 -280.81605) (xy 370.296469 -280.813545) (xy 370.335366 -280.810878)
			(xy 370.35486 -280.810716) (xy 370.444014 -280.810716) (xy 370.456431 -280.810096) (xy 370.478398 -280.798513)
			(xy 370.485924 -280.788618) (xy 370.54028 -280.709624) (xy 370.543328 -280.684986) (xy 370.538756 -280.673302)
			(xy 370.529695 -280.647439) (xy 370.519977 -280.593513) (xy 370.519452 -280.566114) (xy 370.519974 -280.540859)
			(xy 370.528287 -280.491037) (xy 370.544688 -280.443263) (xy 370.568729 -280.39884) (xy 370.599753 -280.35898)
			(xy 370.636915 -280.32477) (xy 370.679201 -280.297144) (xy 370.725457 -280.276854) (xy 370.774422 -280.264454)
			(xy 370.82476 -280.260283) (xy 370.875098 -280.264454) (xy 370.924063 -280.276854) (xy 370.970319 -280.297144)
			(xy 371.012605 -280.32477) (xy 371.049767 -280.35898) (xy 371.080791 -280.39884) (xy 371.104832 -280.443263)
			(xy 371.121233 -280.491037) (xy 371.129546 -280.540859) (xy 371.130068 -280.566114) (xy 371.129479 -280.593507)
			(xy 371.119774 -280.647426) (xy 371.110764 -280.673302) (xy 371.106192 -280.684986) (xy 371.10924 -280.70937)
			(xy 371.163596 -280.788618) (xy 371.171123 -280.79851) (xy 371.193091 -280.810085) (xy 371.205506 -280.810716)
			(xy 371.294914 -280.810716) (xy 371.334284 -280.811986) (xy 371.372384 -280.815796) (xy 371.372638 -280.815796)
			(xy 371.381371 -280.816568) (xy 371.398496 -280.812863) (xy 371.413388 -280.803633) (xy 371.41912 -280.797)
			(xy 371.481858 -280.717244) (xy 371.485668 -280.690574) (xy 371.480842 -280.677874) (xy 371.47094 -280.650999)
			(xy 371.460197 -280.594747) (xy 371.459506 -280.566114) (xy 371.460028 -280.540859) (xy 371.468341 -280.491037)
			(xy 371.484742 -280.443263) (xy 371.508783 -280.39884) (xy 371.539807 -280.35898) (xy 371.576969 -280.32477)
			(xy 371.619255 -280.297144) (xy 371.665511 -280.276854) (xy 371.714476 -280.264454) (xy 371.764814 -280.260283)
			(xy 371.815152 -280.264454) (xy 371.864117 -280.276854) (xy 371.910373 -280.297144) (xy 371.952659 -280.32477)
			(xy 371.989821 -280.35898) (xy 372.020845 -280.39884) (xy 372.044886 -280.443263) (xy 372.061287 -280.491037)
			(xy 372.0696 -280.540859) (xy 372.070122 -280.566114) (xy 372.069984 -280.578877) (xy 372.067824 -280.604311)
			(xy 372.065804 -280.616914) (xy 372.066058 -280.616914) (xy 372.061615 -280.640546) (xy 372.046285 -280.68612)
			(xy 372.024002 -280.728728) (xy 371.995319 -280.767319) (xy 371.960943 -280.800939) (xy 371.921723 -280.828756)
			(xy 371.87863 -280.850085) (xy 371.832726 -280.864398) (xy 371.80901 -280.868374) (xy 371.808502 -280.868374)
			(xy 371.799804 -280.869973) (xy 371.784238 -280.878342) (xy 371.772483 -280.891539) (xy 371.768878 -280.899616)
			(xy 371.737382 -280.977086) (xy 371.734335 -280.985613) (xy 371.733817 -281.003702) (xy 371.736366 -281.012392)
			(xy 371.742462 -281.030426) (xy 371.747288 -281.036776) (xy 371.757129 -281.05008) (xy 371.775427 -281.077658)
			(xy 371.783864 -281.091894) (xy 371.793884 -281.109414) (xy 371.811682 -281.145644) (xy 371.819424 -281.164284)
			(xy 371.824504 -281.176984) (xy 371.84584 -281.193748) (xy 371.937534 -281.206448) (xy 371.945012 -281.207228)
			(xy 371.959856 -281.204891) (xy 371.966744 -281.201876) (xy 371.988588 -281.191208) (xy 371.996716 -281.184858)
			(xy 372.000272 -281.18054) (xy 372.017834 -281.160354) (xy 372.058739 -281.12587) (xy 372.105026 -281.09904)
			(xy 372.15528 -281.080685) (xy 372.207963 -281.071367) (xy 372.234714 -281.070812) (xy 372.257887 -281.071244)
			(xy 372.303699 -281.078259) (xy 372.347922 -281.092123) (xy 372.389539 -281.112519) (xy 372.427591 -281.138977)
			(xy 372.461201 -281.170888) (xy 372.47576 -281.188922) (xy 372.484142 -281.19959) (xy 372.509542 -281.210004)
			(xy 372.610126 -281.196034) (xy 372.616835 -281.194869) (xy 372.629326 -281.189463) (xy 372.634764 -281.185366)
			(xy 372.639752 -281.181164) (xy 372.647583 -281.170741) (xy 372.650258 -281.164792) (xy 372.650258 -281.164538)
			(xy 372.667022 -281.1272) (xy 372.679852 -281.101794) (xy 372.709882 -281.053444) (xy 372.726966 -281.03068)
			(xy 372.735348 -281.020012) (xy 372.738904 -280.993342) (xy 372.700804 -280.899616) (xy 372.69713 -280.891592)
			(xy 372.68535 -280.87847) (xy 372.669839 -280.870079) (xy 372.66118 -280.868374) (xy 372.660926 -280.868374)
			(xy 372.637037 -280.864411) (xy 372.59083 -280.849933) (xy 372.547484 -280.828351) (xy 372.508082 -280.800206)
			(xy 372.473609 -280.766202) (xy 372.444928 -280.727188) (xy 372.422756 -280.68414) (xy 372.407648 -280.638136)
			(xy 372.399981 -280.590325) (xy 372.39956 -280.566114) (xy 372.400082 -280.540859) (xy 372.408395 -280.491037)
			(xy 372.424796 -280.443263) (xy 372.448837 -280.39884) (xy 372.479861 -280.35898) (xy 372.517023 -280.32477)
			(xy 372.559309 -280.297144) (xy 372.605565 -280.276854) (xy 372.65453 -280.264454) (xy 372.704868 -280.260283)
			(xy 372.755206 -280.264454) (xy 372.804171 -280.276854) (xy 372.850427 -280.297144) (xy 372.892713 -280.32477)
			(xy 372.929875 -280.35898) (xy 372.960899 -280.39884) (xy 372.98494 -280.443263) (xy 373.001341 -280.491037)
			(xy 373.009654 -280.540859) (xy 373.010176 -280.566114) (xy 373.009508 -280.59475) (xy 372.998772 -280.651007)
			(xy 372.98884 -280.677874) (xy 372.984014 -280.690574) (xy 372.987824 -280.717244) (xy 373.050562 -280.797)
			(xy 373.056277 -280.803658) (xy 373.071158 -280.812932) (xy 373.088305 -280.816598) (xy 373.097044 -280.815796)
			(xy 373.097298 -280.815796) (xy 373.135398 -280.811986) (xy 373.174768 -280.810716) (xy 373.264176 -280.810716)
			(xy 373.276597 -280.810104) (xy 373.298578 -280.798531) (xy 373.306086 -280.788618) (xy 373.360442 -280.709624)
			(xy 373.36349 -280.684986) (xy 373.358918 -280.673302) (xy 373.349858 -280.647439) (xy 373.340141 -280.593512)
			(xy 373.339614 -280.566114) (xy 373.340059 -280.542121) (xy 373.347564 -280.494725) (xy 373.362392 -280.449087)
			(xy 373.384177 -280.40633) (xy 373.412383 -280.367508) (xy 373.446315 -280.333577) (xy 373.485137 -280.305373)
			(xy 373.527894 -280.283589) (xy 373.573533 -280.268762) (xy 373.620929 -280.261259) (xy 373.644922 -280.260806)
			(xy 373.66945 -280.261318) (xy 373.717869 -280.269201) (xy 373.764409 -280.284713) (xy 373.807875 -280.307456)
			(xy 373.827802 -280.321766) (xy 373.843042 -280.333196) (xy 373.880634 -280.330402) (xy 374.014238 -280.196798)
			(xy 374.022421 -280.187651) (xy 374.029829 -280.164294) (xy 374.028462 -280.152094) (xy 374.014238 -280.070052)
			(xy 374.011369 -280.058069) (xy 373.996381 -280.03856) (xy 373.985536 -280.032714) (xy 373.963331 -280.021805)
			(xy 373.922481 -279.993902) (xy 373.886665 -279.959776) (xy 373.856822 -279.920322) (xy 373.833731 -279.876571)
			(xy 373.817999 -279.829669) (xy 373.810035 -279.780843) (xy 373.809514 -279.756108) (xy 373.80996 -279.732115)
			(xy 373.817465 -279.68472) (xy 373.832294 -279.639083) (xy 373.854079 -279.596327) (xy 373.882285 -279.557506)
			(xy 373.916217 -279.523576) (xy 373.955039 -279.495372) (xy 373.997796 -279.473588) (xy 374.043434 -279.458762)
			(xy 374.090829 -279.451259) (xy 374.114822 -279.4508) (xy 374.139558 -279.45128) (xy 374.188384 -279.459258)
			(xy 374.235285 -279.475001) (xy 374.279035 -279.498099) (xy 374.31849 -279.527946) (xy 374.352618 -279.563763)
			(xy 374.380526 -279.604613) (xy 374.391428 -279.626822) (xy 374.397144 -279.637771) (xy 374.416718 -279.65279)
			(xy 374.428766 -279.655524) (xy 374.510808 -279.669748) (xy 374.523 -279.671115) (xy 374.546339 -279.663674)
			(xy 374.555512 -279.655524) (xy 374.888252 -279.322784) (xy 374.88876 -279.322276) (xy 374.895346 -279.314896)
			(xy 374.902806 -279.296597) (xy 374.903238 -279.286716) (xy 374.903238 -278.441404) (xy 374.903065 -278.435252)
			(xy 374.900104 -278.423309) (xy 374.897396 -278.417782) (xy 374.884442 -278.39289) (xy 374.876822 -278.384254)
			(xy 374.87225 -278.380952) (xy 374.853548 -278.366424) (xy 374.820438 -278.332568) (xy 374.792949 -278.294008)
			(xy 374.771739 -278.251669) (xy 374.757316 -278.206564) (xy 374.750025 -278.159774) (xy 374.749568 -278.136096)
			(xy 374.749993 -278.112416) (xy 374.757267 -278.065617) (xy 374.771687 -278.020506) (xy 374.792906 -277.978165)
			(xy 374.820414 -277.939613) (xy 374.85355 -277.905775) (xy 374.87225 -277.89124) (xy 374.876822 -277.887938)
			(xy 374.884442 -277.879302) (xy 374.897396 -277.85441) (xy 374.900091 -277.848879) (xy 374.903044 -277.836938)
			(xy 374.903238 -277.830788) (xy 374.903238 -277.67026) (xy 374.90287 -277.661185) (xy 374.89652 -277.644184)
			(xy 374.884606 -277.630493) (xy 374.876822 -277.62581) (xy 374.801638 -277.584154) (xy 374.792675 -277.57966)
			(xy 374.772766 -277.577437) (xy 374.76303 -277.579836) (xy 374.74779 -277.584408) (xy 374.742202 -277.58771)
			(xy 374.718249 -277.601425) (xy 374.666613 -277.620913) (xy 374.612318 -277.630812) (xy 374.584722 -277.631398)
			(xy 374.559464 -277.630907) (xy 374.509636 -277.622596) (xy 374.461856 -277.606196) (xy 374.417428 -277.582155)
			(xy 374.377562 -277.551129) (xy 374.343347 -277.513964) (xy 374.315716 -277.471675) (xy 374.295423 -277.425414)
			(xy 374.283022 -277.376444) (xy 374.27885 -277.3261) (xy 374.283022 -277.275756) (xy 374.295423 -277.226786)
			(xy 374.315716 -277.180525) (xy 374.343347 -277.138236) (xy 374.377562 -277.101071) (xy 374.417428 -277.070045)
			(xy 374.461856 -277.046004) (xy 374.509636 -277.029604) (xy 374.559464 -277.021293) (xy 374.584722 -277.020782)
			(xy 374.597485 -277.02092) (xy 374.622919 -277.023081) (xy 374.635522 -277.0251) (xy 374.635522 -277.024846)
			(xy 374.663776 -277.030258) (xy 374.717729 -277.050204) (xy 374.74271 -277.06447) (xy 374.748552 -277.068026)
			(xy 374.76303 -277.072344) (xy 374.772774 -277.074632) (xy 374.792649 -277.072425) (xy 374.801638 -277.068026)
			(xy 374.876822 -277.02637) (xy 374.884597 -277.021681) (xy 374.896479 -277.00797) (xy 374.902874 -276.99099)
			(xy 374.903238 -276.98192) (xy 374.903238 -276.821392) (xy 374.903064 -276.81524) (xy 374.9001 -276.803299)
			(xy 374.897396 -276.79777) (xy 374.884442 -276.772878) (xy 374.876822 -276.764242) (xy 374.87225 -276.76094)
			(xy 374.853548 -276.746412) (xy 374.82044 -276.712556) (xy 374.792953 -276.673996) (xy 374.771744 -276.631656)
			(xy 374.757323 -276.586551) (xy 374.750033 -276.539761) (xy 374.749568 -276.516084) (xy 374.749994 -276.492404)
			(xy 374.75727 -276.445607) (xy 374.771691 -276.400497) (xy 374.792911 -276.358157) (xy 374.820419 -276.319607)
			(xy 374.853556 -276.28577) (xy 374.87225 -276.271228) (xy 374.876822 -276.267926) (xy 374.884442 -276.25929)
			(xy 374.897396 -276.234398) (xy 374.90009 -276.228866) (xy 374.90304 -276.216926) (xy 374.903238 -276.210776)
			(xy 374.903238 -275.20138) (xy 374.903062 -275.195229) (xy 374.900096 -275.183289) (xy 374.897396 -275.177758)
			(xy 374.884442 -275.152866) (xy 374.876822 -275.14423) (xy 374.87225 -275.140928) (xy 374.853549 -275.1264)
			(xy 374.820442 -275.092543) (xy 374.792956 -275.053983) (xy 374.771749 -275.011643) (xy 374.757329 -274.966539)
			(xy 374.750042 -274.919749) (xy 374.749568 -274.896072) (xy 374.749994 -274.872392) (xy 374.757272 -274.825596)
			(xy 374.771695 -274.780488) (xy 374.792915 -274.73815) (xy 374.820425 -274.6996) (xy 374.853561 -274.665765)
			(xy 374.87225 -274.651216) (xy 374.876822 -274.647914) (xy 374.884442 -274.639278) (xy 374.897396 -274.614386)
			(xy 374.900088 -274.608854) (xy 374.903036 -274.596913) (xy 374.903238 -274.590764) (xy 374.903238 -274.430236)
			(xy 374.902882 -274.421154) (xy 374.896549 -274.404132) (xy 374.88464 -274.39042) (xy 374.876822 -274.385786)
			(xy 374.801638 -274.34413) (xy 374.792675 -274.339637) (xy 374.772766 -274.337416) (xy 374.76303 -274.339812)
			(xy 374.74779 -274.344384) (xy 374.742202 -274.347686) (xy 374.718249 -274.361402) (xy 374.666614 -274.380892)
			(xy 374.612318 -274.390791) (xy 374.584722 -274.391374) (xy 374.559466 -274.390883) (xy 374.509642 -274.382572)
			(xy 374.461866 -274.366174) (xy 374.417441 -274.342135) (xy 374.377578 -274.311111) (xy 374.343366 -274.27395)
			(xy 374.315737 -274.231663) (xy 374.295446 -274.185406) (xy 374.283045 -274.13644) (xy 374.278874 -274.0861)
			(xy 374.283045 -274.03576) (xy 374.295446 -273.986794) (xy 374.315737 -273.940537) (xy 374.343366 -273.89825)
			(xy 374.377578 -273.861089) (xy 374.417441 -273.830065) (xy 374.461866 -273.806026) (xy 374.509642 -273.789628)
			(xy 374.559466 -273.781317) (xy 374.584722 -273.780758) (xy 374.597485 -273.780896) (xy 374.622919 -273.783057)
			(xy 374.635522 -273.785076) (xy 374.635522 -273.784822) (xy 374.663776 -273.790236) (xy 374.717725 -273.810185)
			(xy 374.74271 -273.824446) (xy 374.748552 -273.828002) (xy 374.76303 -273.83232) (xy 374.772775 -273.834607)
			(xy 374.79265 -273.832403) (xy 374.801638 -273.828002) (xy 374.876822 -273.786346) (xy 374.884594 -273.781656)
			(xy 374.89647 -273.767943) (xy 374.902857 -273.750964) (xy 374.903238 -273.741896) (xy 374.903238 -273.581114)
			(xy 374.903067 -273.575105) (xy 374.900238 -273.563426) (xy 374.89765 -273.558) (xy 374.894348 -273.55165)
			(xy 374.89003 -273.543522) (xy 374.887236 -273.538188) (xy 374.880378 -273.528282) (xy 374.877076 -273.524472)
			(xy 374.872504 -273.520916) (xy 374.87225 -273.520662) (xy 374.851897 -273.504789) (xy 374.816328 -273.467391)
			(xy 374.787555 -273.424543) (xy 374.766398 -273.377467) (xy 374.753459 -273.327504) (xy 374.749108 -273.276076)
			(xy 374.753467 -273.224649) (xy 374.766414 -273.174687) (xy 374.787578 -273.127615) (xy 374.816358 -273.084772)
			(xy 374.851932 -273.04738) (xy 374.87225 -273.031458) (xy 374.872504 -273.031204) (xy 374.877076 -273.027648)
			(xy 374.880378 -273.023838) (xy 374.887236 -273.013932) (xy 374.897396 -272.994628) (xy 374.90019 -272.98904)
			(xy 374.903238 -272.977102) (xy 374.903238 -271.961102) (xy 374.903065 -271.955094) (xy 374.900234 -271.943416)
			(xy 374.89765 -271.937988) (xy 374.894348 -271.931638) (xy 374.89003 -271.92351) (xy 374.887236 -271.918176)
			(xy 374.880378 -271.90827) (xy 374.877076 -271.90446) (xy 374.872504 -271.900904) (xy 374.87225 -271.90065)
			(xy 374.851889 -271.884776) (xy 374.816306 -271.847376) (xy 374.787519 -271.804524) (xy 374.766349 -271.757441)
			(xy 374.753399 -271.707468) (xy 374.749037 -271.656029) (xy 374.753389 -271.604589) (xy 374.76633 -271.554614)
			(xy 374.787491 -271.507527) (xy 374.81627 -271.464669) (xy 374.851846 -271.427262) (xy 374.87225 -271.411446)
			(xy 374.872504 -271.411192) (xy 374.877076 -271.407636) (xy 374.880378 -271.403826) (xy 374.887236 -271.39392)
			(xy 374.897396 -271.374616) (xy 374.90019 -271.369028) (xy 374.903238 -271.35709) (xy 374.903238 -271.18818)
			(xy 374.902919 -271.179055) (xy 374.896611 -271.161935) (xy 374.884669 -271.148142) (xy 374.876822 -271.143476)
			(xy 374.803162 -271.103344) (xy 374.7942 -271.098845) (xy 374.774287 -271.096614) (xy 374.764554 -271.099026)
			(xy 374.748552 -271.103852) (xy 374.742964 -271.107154) (xy 374.718883 -271.121034) (xy 374.666926 -271.140763)
			(xy 374.612257 -271.150762) (xy 374.584468 -271.15135) (xy 374.57761 -271.15135) (xy 374.552735 -271.150281)
			(xy 374.503809 -271.141069) (xy 374.457025 -271.124043) (xy 374.413621 -271.099655) (xy 374.374747 -271.068551)
			(xy 374.341433 -271.031553) (xy 374.31456 -270.989643) (xy 374.29484 -270.943929) (xy 374.282795 -270.895622)
			(xy 374.278744 -270.846001) (xy 374.282795 -270.79638) (xy 374.294839 -270.748073) (xy 374.314559 -270.702359)
			(xy 374.341432 -270.660448) (xy 374.374746 -270.623451) (xy 374.413619 -270.592346) (xy 374.457023 -270.567958)
			(xy 374.503807 -270.550932) (xy 374.552733 -270.541719) (xy 374.57761 -270.540734) (xy 374.584468 -270.540734)
			(xy 374.612256 -270.541322) (xy 374.666924 -270.551329) (xy 374.718881 -270.571054) (xy 374.742964 -270.58493)
			(xy 374.748552 -270.588232) (xy 374.764554 -270.593058) (xy 374.774298 -270.595341) (xy 374.794168 -270.593126)
			(xy 374.803162 -270.58874) (xy 374.876822 -270.548608) (xy 374.884623 -270.543889) (xy 374.896521 -270.530091)
			(xy 374.902869 -270.513014) (xy 374.903238 -270.503904) (xy 374.903238 -270.34109) (xy 374.903076 -270.335079)
			(xy 374.900262 -270.323392) (xy 374.89765 -270.317976) (xy 374.894348 -270.311626) (xy 374.89003 -270.303498)
			(xy 374.887236 -270.298164) (xy 374.880378 -270.288258) (xy 374.877076 -270.284448) (xy 374.872504 -270.280892)
			(xy 374.87225 -270.280638) (xy 374.85189 -270.264764) (xy 374.816309 -270.227364) (xy 374.787524 -270.184513)
			(xy 374.766355 -270.137431) (xy 374.753407 -270.087459) (xy 374.749047 -270.036022) (xy 374.7534 -269.984584)
			(xy 374.766341 -269.93461) (xy 374.787503 -269.887525) (xy 374.816282 -269.844669) (xy 374.851858 -269.807264)
			(xy 374.87225 -269.791434) (xy 374.872504 -269.79118) (xy 374.877076 -269.787624) (xy 374.880378 -269.783814)
			(xy 374.887236 -269.773908) (xy 374.897396 -269.754604) (xy 374.90019 -269.749016) (xy 374.903238 -269.737078)
			(xy 374.903238 -268.721078) (xy 374.903074 -268.715067) (xy 374.900258 -268.703381) (xy 374.89765 -268.697964)
			(xy 374.894348 -268.691614) (xy 374.89003 -268.683486) (xy 374.884442 -268.672818) (xy 374.87733 -268.66469)
			(xy 374.872504 -268.661134) (xy 374.853768 -268.646599) (xy 374.820595 -268.612718) (xy 374.793048 -268.574123)
			(xy 374.771788 -268.531739) (xy 374.757324 -268.486581) (xy 374.750002 -268.439733) (xy 374.749568 -268.416024)
			(xy 374.749973 -268.393448) (xy 374.756616 -268.348789) (xy 374.769762 -268.305593) (xy 374.789124 -268.264804)
			(xy 374.801384 -268.245844) (xy 374.805448 -268.239748) (xy 374.814592 -268.211046) (xy 374.81383 -268.1986)
			(xy 374.812814 -268.17955) (xy 374.811939 -268.170247) (xy 374.804385 -268.153173) (xy 374.798082 -268.146276)
			(xy 374.569228 -267.917422) (xy 374.553988 -267.909802) (xy 374.545606 -267.908786) (xy 374.520793 -267.905071)
			(xy 374.472757 -267.890598) (xy 374.427733 -267.868467) (xy 374.386934 -267.839272) (xy 374.351457 -267.8038)
			(xy 374.322256 -267.763005) (xy 374.300118 -267.717985) (xy 374.285639 -267.669951) (xy 374.281954 -267.645134)
			(xy 374.280938 -267.636752) (xy 374.273318 -267.621512) (xy 373.59082 -266.939014) (xy 373.582278 -266.931204)
			(xy 373.560461 -266.923539) (xy 373.54891 -266.924282) (xy 373.459756 -266.934696) (xy 373.440452 -266.946888)
			(xy 373.434356 -266.957048) (xy 373.42025 -266.97873) (xy 373.38595 -267.017443) (xy 373.34562 -267.049826)
			(xy 373.300411 -267.074953) (xy 373.251616 -267.092106) (xy 373.200629 -267.100796) (xy 373.174768 -267.10132)
			(xy 373.150778 -267.100847) (xy 373.10339 -267.093337) (xy 373.057759 -267.078507) (xy 373.01501 -267.056722)
			(xy 372.976195 -267.028518) (xy 372.942269 -266.99459) (xy 372.914068 -266.955773) (xy 372.892285 -266.913022)
			(xy 372.877458 -266.867391) (xy 372.869951 -266.820002) (xy 372.86946 -266.796012) (xy 372.8699 -266.772387)
			(xy 372.877172 -266.725699) (xy 372.891545 -266.680687) (xy 372.901718 -266.65936) (xy 372.907814 -266.647422)
			(xy 372.906544 -266.62126) (xy 372.85803 -266.543282) (xy 372.850918 -266.534138) (xy 372.845838 -266.529058)
			(xy 372.838439 -266.522215) (xy 372.81984 -266.514494) (xy 372.80977 -266.514072) (xy 372.599712 -266.514072)
			(xy 372.58964 -266.514492) (xy 372.57103 -266.5222) (xy 372.563644 -266.529058) (xy 372.558564 -266.534138)
			(xy 372.551452 -266.543282) (xy 372.502938 -266.62126) (xy 372.501668 -266.647422) (xy 372.507764 -266.65936)
			(xy 372.517936 -266.680688) (xy 372.532309 -266.725699) (xy 372.539582 -266.772387) (xy 372.540022 -266.796012)
			(xy 372.5395 -266.821267) (xy 372.531187 -266.871089) (xy 372.514786 -266.918863) (xy 372.490745 -266.963286)
			(xy 372.459721 -267.003146) (xy 372.422559 -267.037356) (xy 372.380273 -267.064982) (xy 372.334017 -267.085272)
			(xy 372.285052 -267.097672) (xy 372.234714 -267.101843) (xy 372.184376 -267.097672) (xy 372.135411 -267.085272)
			(xy 372.089155 -267.064982) (xy 372.046869 -267.037356) (xy 372.009707 -267.003146) (xy 371.978683 -266.963286)
			(xy 371.954642 -266.918863) (xy 371.938241 -266.871089) (xy 371.929928 -266.821267) (xy 371.929406 -266.796012)
			(xy 371.929846 -266.772387) (xy 371.937117 -266.725698) (xy 371.951488 -266.680686) (xy 371.961664 -266.65936)
			(xy 371.96776 -266.647422) (xy 371.96649 -266.62126) (xy 371.917976 -266.543282) (xy 371.910864 -266.534138)
			(xy 371.905784 -266.529058) (xy 371.898387 -266.522208) (xy 371.879789 -266.51447) (xy 371.869716 -266.514072)
			(xy 371.659912 -266.514072) (xy 371.64984 -266.514492) (xy 371.63123 -266.5222) (xy 371.623844 -266.529058)
			(xy 371.618764 -266.534138) (xy 371.611652 -266.543282) (xy 371.563138 -266.62126) (xy 371.561868 -266.647422)
			(xy 371.567964 -266.65936) (xy 371.578136 -266.680688) (xy 371.592509 -266.725699) (xy 371.599782 -266.772387)
			(xy 371.600222 -266.796012) (xy 371.5997 -266.821267) (xy 371.591387 -266.871089) (xy 371.574986 -266.918863)
			(xy 371.550945 -266.963286) (xy 371.519921 -267.003146) (xy 371.482759 -267.037356) (xy 371.440473 -267.064982)
			(xy 371.394217 -267.085272) (xy 371.345252 -267.097672) (xy 371.294914 -267.101843) (xy 371.244576 -267.097672)
			(xy 371.195611 -267.085272) (xy 371.149355 -267.064982) (xy 371.107069 -267.037356) (xy 371.069907 -267.003146)
			(xy 371.038883 -266.963286) (xy 371.014842 -266.918863) (xy 370.998441 -266.871089) (xy 370.990128 -266.821267)
			(xy 370.989606 -266.796012) (xy 370.990046 -266.772387) (xy 370.997317 -266.725698) (xy 371.011688 -266.680686)
			(xy 371.021864 -266.65936) (xy 371.02796 -266.647422) (xy 371.02669 -266.62126) (xy 370.978176 -266.543282)
			(xy 370.971064 -266.534138) (xy 370.965984 -266.529058) (xy 370.958587 -266.522208) (xy 370.939989 -266.51447)
			(xy 370.929916 -266.514072) (xy 369.779804 -266.514072) (xy 369.769733 -266.514494) (xy 369.751125 -266.522204)
			(xy 369.743736 -266.529058) (xy 369.738656 -266.534138) (xy 369.731544 -266.543282) (xy 369.68303 -266.62126)
			(xy 369.68176 -266.647422) (xy 369.687856 -266.65936) (xy 369.698028 -266.680688) (xy 369.712402 -266.725699)
			(xy 369.719675 -266.772387) (xy 369.720114 -266.796012) (xy 369.719592 -266.821267) (xy 369.711279 -266.871089)
			(xy 369.694878 -266.918863) (xy 369.670837 -266.963286) (xy 369.639813 -267.003146) (xy 369.602651 -267.037356)
			(xy 369.560365 -267.064982) (xy 369.514109 -267.085272) (xy 369.465144 -267.097672) (xy 369.414806 -267.101843)
			(xy 369.364468 -267.097672) (xy 369.315503 -267.085272) (xy 369.269247 -267.064982) (xy 369.226961 -267.037356)
			(xy 369.189799 -267.003146) (xy 369.158775 -266.963286) (xy 369.134734 -266.918863) (xy 369.118333 -266.871089)
			(xy 369.11002 -266.821267) (xy 369.109498 -266.796012) (xy 369.109938 -266.772386) (xy 369.117209 -266.725698)
			(xy 369.131579 -266.680686) (xy 369.141756 -266.65936) (xy 369.147852 -266.647422) (xy 369.146582 -266.62126)
			(xy 369.098068 -266.543282) (xy 369.090956 -266.534138) (xy 369.085876 -266.529058) (xy 369.078479 -266.522209)
			(xy 369.05988 -266.514474) (xy 369.049808 -266.514072) (xy 368.83975 -266.514072) (xy 368.829683 -266.514503)
			(xy 368.811089 -266.522227) (xy 368.803682 -266.529058) (xy 368.798602 -266.534138) (xy 368.79149 -266.543282)
			(xy 368.742976 -266.62126) (xy 368.741706 -266.647422) (xy 368.747802 -266.65936) (xy 368.757973 -266.680688)
			(xy 368.772344 -266.7257) (xy 368.779616 -266.772387) (xy 368.78006 -266.796012) (xy 368.779538 -266.821267)
			(xy 368.771225 -266.871089) (xy 368.754824 -266.918863) (xy 368.730783 -266.963286) (xy 368.699759 -267.003146)
			(xy 368.662597 -267.037356) (xy 368.620311 -267.064982) (xy 368.574055 -267.085272) (xy 368.52509 -267.097672)
			(xy 368.474752 -267.101843) (xy 368.424414 -267.097672) (xy 368.375449 -267.085272) (xy 368.329193 -267.064982)
			(xy 368.286907 -267.037356) (xy 368.249745 -267.003146) (xy 368.218721 -266.963286) (xy 368.19468 -266.918863)
			(xy 368.178279 -266.871089) (xy 368.169966 -266.821267) (xy 368.169444 -266.796012) (xy 368.169884 -266.772387)
			(xy 368.177156 -266.725699) (xy 368.191528 -266.680687) (xy 368.201702 -266.65936) (xy 368.207798 -266.647422)
			(xy 368.206528 -266.62126) (xy 368.158014 -266.543282) (xy 368.150902 -266.534138) (xy 368.145822 -266.529058)
			(xy 368.138422 -266.522217) (xy 368.119823 -266.514502) (xy 368.109754 -266.514072) (xy 367.899696 -266.514072)
			(xy 367.889625 -266.514495) (xy 367.871019 -266.522207) (xy 367.863628 -266.529058) (xy 367.858548 -266.534138)
			(xy 367.851436 -266.543282) (xy 367.802922 -266.62126) (xy 367.801652 -266.647422) (xy 367.807748 -266.65936)
			(xy 367.81792 -266.680688) (xy 367.832295 -266.725699) (xy 367.839568 -266.772387) (xy 367.840006 -266.796012)
			(xy 367.839484 -266.821267) (xy 367.831171 -266.871089) (xy 367.81477 -266.918863) (xy 367.790729 -266.963286)
			(xy 367.759705 -267.003146) (xy 367.722543 -267.037356) (xy 367.680257 -267.064982) (xy 367.634001 -267.085272)
			(xy 367.585036 -267.097672) (xy 367.534698 -267.101843) (xy 367.48436 -267.097672) (xy 367.435395 -267.085272)
			(xy 367.389139 -267.064982) (xy 367.346853 -267.037356) (xy 367.309691 -267.003146) (xy 367.278667 -266.963286)
			(xy 367.254626 -266.918863) (xy 367.238225 -266.871089) (xy 367.229912 -266.821267) (xy 367.22939 -266.796012)
			(xy 367.22983 -266.772386) (xy 367.2371 -266.725698) (xy 367.25147 -266.680685) (xy 367.261648 -266.65936)
			(xy 367.267744 -266.647422) (xy 367.266474 -266.62126) (xy 367.21796 -266.543282) (xy 367.210848 -266.534138)
			(xy 367.205768 -266.529058) (xy 367.19837 -266.52221) (xy 367.179772 -266.514478) (xy 367.1697 -266.514072)
			(xy 366.019842 -266.514072) (xy 366.009776 -266.514505) (xy 365.991184 -266.522231) (xy 365.983774 -266.529058)
			(xy 365.978694 -266.534138) (xy 365.971582 -266.543282) (xy 365.923068 -266.62126) (xy 365.921798 -266.647422)
			(xy 365.927894 -266.65936) (xy 365.938065 -266.680688) (xy 365.952437 -266.7257) (xy 365.959709 -266.772387)
			(xy 365.960152 -266.796012) (xy 365.95963 -266.821267) (xy 365.951317 -266.871089) (xy 365.934916 -266.918863)
			(xy 365.910875 -266.963286) (xy 365.879851 -267.003146) (xy 365.842689 -267.037356) (xy 365.800403 -267.064982)
			(xy 365.754147 -267.085272) (xy 365.705182 -267.097672) (xy 365.654844 -267.101843) (xy 365.604506 -267.097672)
			(xy 365.555541 -267.085272) (xy 365.509285 -267.064982) (xy 365.466999 -267.037356) (xy 365.429837 -267.003146)
			(xy 365.398813 -266.963286) (xy 365.374772 -266.918863) (xy 365.358371 -266.871089) (xy 365.350058 -266.821267)
			(xy 365.349536 -266.796012) (xy 365.349976 -266.772387) (xy 365.357248 -266.725699) (xy 365.37162 -266.680687)
			(xy 365.381794 -266.65936) (xy 365.38789 -266.647422) (xy 365.38662 -266.62126) (xy 365.338106 -266.543282)
			(xy 365.330994 -266.534138) (xy 365.325914 -266.529058) (xy 365.318514 -266.522219) (xy 365.299915 -266.514507)
			(xy 365.289846 -266.514072) (xy 365.079788 -266.514072) (xy 365.069718 -266.514497) (xy 365.051114 -266.522211)
			(xy 365.04372 -266.529058) (xy 365.03864 -266.534138) (xy 365.031528 -266.543282) (xy 364.983014 -266.62126)
			(xy 364.981744 -266.647422) (xy 364.98784 -266.65936) (xy 364.998012 -266.680688) (xy 365.012387 -266.725699)
			(xy 365.019661 -266.772387) (xy 365.020098 -266.796012) (xy 365.019576 -266.821267) (xy 365.011263 -266.871089)
			(xy 364.994862 -266.918863) (xy 364.970821 -266.963286) (xy 364.939797 -267.003146) (xy 364.902635 -267.037356)
			(xy 364.860349 -267.064982) (xy 364.814093 -267.085272) (xy 364.765128 -267.097672) (xy 364.71479 -267.101843)
			(xy 364.664452 -267.097672) (xy 364.615487 -267.085272) (xy 364.569231 -267.064982) (xy 364.526945 -267.037356)
			(xy 364.489783 -267.003146) (xy 364.458759 -266.963286) (xy 364.434718 -266.918863) (xy 364.418317 -266.871089)
			(xy 364.410004 -266.821267) (xy 364.409482 -266.796012) (xy 364.409922 -266.772386) (xy 364.417192 -266.725698)
			(xy 364.431562 -266.680685) (xy 364.44174 -266.65936) (xy 364.447836 -266.647422) (xy 364.446566 -266.62126)
			(xy 364.398052 -266.543282) (xy 364.39094 -266.534138) (xy 364.38586 -266.529058) (xy 364.378462 -266.522212)
			(xy 364.359863 -266.514483) (xy 364.349792 -266.514072) (xy 364.139734 -266.514072) (xy 364.129682 -266.514575)
			(xy 364.111118 -266.522293) (xy 364.103666 -266.529058) (xy 364.098586 -266.534138) (xy 364.091474 -266.543282)
			(xy 364.04296 -266.62126) (xy 364.04169 -266.647422) (xy 364.047786 -266.65936) (xy 364.057957 -266.680688)
			(xy 364.07233 -266.7257) (xy 364.079602 -266.772387) (xy 364.080044 -266.796012) (xy 364.079522 -266.821267)
			(xy 364.071209 -266.871089) (xy 364.054808 -266.918863) (xy 364.030767 -266.963286) (xy 363.999743 -267.003146)
			(xy 363.962581 -267.037356) (xy 363.920295 -267.064982) (xy 363.874039 -267.085272) (xy 363.825074 -267.097672)
			(xy 363.774736 -267.101843) (xy 363.724398 -267.097672) (xy 363.675433 -267.085272) (xy 363.629177 -267.064982)
			(xy 363.586891 -267.037356) (xy 363.549729 -267.003146) (xy 363.518705 -266.963286) (xy 363.494664 -266.918863)
			(xy 363.478263 -266.871089) (xy 363.46995 -266.821267) (xy 363.469428 -266.796012) (xy 363.469868 -266.772387)
			(xy 363.477139 -266.725699) (xy 363.491511 -266.680686) (xy 363.501686 -266.65936) (xy 363.507782 -266.647422)
			(xy 363.506512 -266.62126) (xy 363.457998 -266.543282) (xy 363.450886 -266.534138) (xy 363.445806 -266.529058)
			(xy 363.438411 -266.522204) (xy 363.419812 -266.514458) (xy 363.409738 -266.514072) (xy 362.25988 -266.514072)
			(xy 362.249811 -266.514498) (xy 362.231209 -266.522214) (xy 362.223812 -266.529058) (xy 362.218732 -266.534138)
			(xy 362.21162 -266.543282) (xy 362.163106 -266.62126) (xy 362.161836 -266.647422) (xy 362.167932 -266.65936)
			(xy 362.178102 -266.680689) (xy 362.192472 -266.7257) (xy 362.199743 -266.772387) (xy 362.20019 -266.796012)
			(xy 362.199668 -266.821267) (xy 362.191355 -266.871089) (xy 362.174954 -266.918863) (xy 362.150913 -266.963286)
			(xy 362.119889 -267.003146) (xy 362.082727 -267.037356) (xy 362.040441 -267.064982) (xy 361.994185 -267.085272)
			(xy 361.94522 -267.097672) (xy 361.894882 -267.101843) (xy 361.844544 -267.097672) (xy 361.795579 -267.085272)
			(xy 361.749323 -267.064982) (xy 361.707037 -267.037356) (xy 361.669875 -267.003146) (xy 361.638851 -266.963286)
			(xy 361.61481 -266.918863) (xy 361.598409 -266.871089) (xy 361.590096 -266.821267) (xy 361.589574 -266.796012)
			(xy 361.590014 -266.772386) (xy 361.597284 -266.725698) (xy 361.611653 -266.680685) (xy 361.621832 -266.65936)
			(xy 361.627928 -266.647422) (xy 361.626658 -266.62126) (xy 361.578144 -266.543282) (xy 361.571032 -266.534138)
			(xy 361.565952 -266.529058) (xy 361.558554 -266.522213) (xy 361.539955 -266.514487) (xy 361.529884 -266.514072)
			(xy 358.506014 -266.514072) (xy 358.495964 -266.514579) (xy 358.477405 -266.522301) (xy 358.469946 -266.529058)
			(xy 358.464866 -266.534138) (xy 358.457754 -266.543282) (xy 358.40924 -266.62126) (xy 358.40797 -266.647422)
			(xy 358.414066 -266.65936) (xy 358.424238 -266.680688) (xy 358.438611 -266.725699) (xy 358.445884 -266.772387)
			(xy 358.446324 -266.796012) (xy 358.445802 -266.821267) (xy 358.437489 -266.871089) (xy 358.421088 -266.918863)
			(xy 358.397047 -266.963286) (xy 358.366023 -267.003146) (xy 358.328861 -267.037356) (xy 358.286575 -267.064982)
			(xy 358.240319 -267.085272) (xy 358.191354 -267.097672) (xy 358.141016 -267.101843) (xy 358.090678 -267.097672)
			(xy 358.041713 -267.085272) (xy 357.995457 -267.064982) (xy 357.953171 -267.037356) (xy 357.916009 -267.003146)
			(xy 357.884985 -266.963286) (xy 357.860944 -266.918863) (xy 357.844543 -266.871089) (xy 357.83623 -266.821267)
			(xy 357.835708 -266.796012) (xy 357.836148 -266.772387) (xy 357.843419 -266.725698) (xy 357.85779 -266.680686)
			(xy 357.867966 -266.65936) (xy 357.874062 -266.647422) (xy 357.872792 -266.62126) (xy 357.824278 -266.543282)
			(xy 357.817166 -266.534138) (xy 357.812086 -266.529058) (xy 357.80469 -266.522207) (xy 357.786091 -266.514469)
			(xy 357.776018 -266.514072) (xy 357.566214 -266.514072) (xy 357.556164 -266.514579) (xy 357.537605 -266.522301)
			(xy 357.530146 -266.529058) (xy 357.525066 -266.534138) (xy 357.517954 -266.543282) (xy 357.46944 -266.62126)
			(xy 357.46817 -266.647422) (xy 357.474266 -266.65936) (xy 357.484438 -266.680688) (xy 357.498811 -266.725699)
			(xy 357.506084 -266.772387) (xy 357.506524 -266.796012) (xy 357.506002 -266.821267) (xy 357.497689 -266.871089)
			(xy 357.481288 -266.918863) (xy 357.457247 -266.963286) (xy 357.426223 -267.003146) (xy 357.389061 -267.037356)
			(xy 357.346775 -267.064982) (xy 357.300519 -267.085272) (xy 357.251554 -267.097672) (xy 357.201216 -267.101843)
			(xy 357.150878 -267.097672) (xy 357.101913 -267.085272) (xy 357.055657 -267.064982) (xy 357.013371 -267.037356)
			(xy 356.976209 -267.003146) (xy 356.945185 -266.963286) (xy 356.921144 -266.918863) (xy 356.904743 -266.871089)
			(xy 356.89643 -266.821267) (xy 356.895908 -266.796012) (xy 356.896348 -266.772387) (xy 356.903619 -266.725698)
			(xy 356.91799 -266.680686) (xy 356.928166 -266.65936) (xy 356.934262 -266.647422) (xy 356.932992 -266.62126)
			(xy 356.884478 -266.543282) (xy 356.877366 -266.534138) (xy 356.872286 -266.529058) (xy 356.86489 -266.522207)
			(xy 356.846291 -266.514469) (xy 356.836218 -266.514072) (xy 355.686106 -266.514072) (xy 355.676035 -266.514493)
			(xy 355.657426 -266.522203) (xy 355.650038 -266.529058) (xy 355.644958 -266.534138) (xy 355.637846 -266.543282)
			(xy 355.589332 -266.62126) (xy 355.588062 -266.647422) (xy 355.594158 -266.65936) (xy 355.60433 -266.680688)
			(xy 355.618704 -266.725699) (xy 355.625977 -266.772387) (xy 355.626416 -266.796012) (xy 355.625894 -266.821267)
			(xy 355.617581 -266.871089) (xy 355.60118 -266.918863) (xy 355.577139 -266.963286) (xy 355.546115 -267.003146)
			(xy 355.508953 -267.037356) (xy 355.466667 -267.064982) (xy 355.420411 -267.085272) (xy 355.371446 -267.097672)
			(xy 355.321108 -267.101843) (xy 355.27077 -267.097672) (xy 355.221805 -267.085272) (xy 355.175549 -267.064982)
			(xy 355.133263 -267.037356) (xy 355.096101 -267.003146) (xy 355.065077 -266.963286) (xy 355.041036 -266.918863)
			(xy 355.024635 -266.871089) (xy 355.016322 -266.821267) (xy 355.0158 -266.796012) (xy 355.01624 -266.772387)
			(xy 355.023511 -266.725698) (xy 355.037881 -266.680686) (xy 355.048058 -266.65936) (xy 355.054154 -266.647422)
			(xy 355.052884 -266.62126) (xy 355.00437 -266.543282) (xy 354.997258 -266.534138) (xy 354.992178 -266.529058)
			(xy 354.984781 -266.522209) (xy 354.966182 -266.514473) (xy 354.95611 -266.514072) (xy 354.746052 -266.514072)
			(xy 354.735985 -266.514503) (xy 354.717391 -266.522227) (xy 354.709984 -266.529058) (xy 354.704904 -266.534138)
			(xy 354.697792 -266.543282) (xy 354.649278 -266.62126) (xy 354.648008 -266.647422) (xy 354.654104 -266.65936)
			(xy 354.664274 -266.680688) (xy 354.678646 -266.7257) (xy 354.685918 -266.772387) (xy 354.686362 -266.796012)
			(xy 354.68584 -266.821267) (xy 354.677527 -266.871089) (xy 354.661126 -266.918863) (xy 354.637085 -266.963286)
			(xy 354.606061 -267.003146) (xy 354.568899 -267.037356) (xy 354.526613 -267.064982) (xy 354.480357 -267.085272)
			(xy 354.431392 -267.097672) (xy 354.381054 -267.101843) (xy 354.330716 -267.097672) (xy 354.281751 -267.085272)
			(xy 354.235495 -267.064982) (xy 354.193209 -267.037356) (xy 354.156047 -267.003146) (xy 354.125023 -266.963286)
			(xy 354.100982 -266.918863) (xy 354.084581 -266.871089) (xy 354.076268 -266.821267) (xy 354.075746 -266.796012)
			(xy 354.076186 -266.772387) (xy 354.083458 -266.725699) (xy 354.09783 -266.680687) (xy 354.108004 -266.65936)
			(xy 354.1141 -266.647422) (xy 354.11283 -266.62126) (xy 354.064316 -266.543282) (xy 354.057204 -266.534138)
			(xy 354.052124 -266.529058) (xy 354.044724 -266.522217) (xy 354.026125 -266.514501) (xy 354.016056 -266.514072)
			(xy 353.805998 -266.514072) (xy 353.795927 -266.514495) (xy 353.777321 -266.522206) (xy 353.76993 -266.529058)
			(xy 353.76485 -266.534138) (xy 353.757738 -266.543282) (xy 353.709224 -266.62126) (xy 353.707954 -266.647422)
			(xy 353.71405 -266.65936) (xy 353.724222 -266.680688) (xy 353.738597 -266.725699) (xy 353.745869 -266.772387)
			(xy 353.746308 -266.796012) (xy 353.745786 -266.821267) (xy 353.737473 -266.871089) (xy 353.721072 -266.918863)
			(xy 353.697031 -266.963286) (xy 353.666007 -267.003146) (xy 353.628845 -267.037356) (xy 353.586559 -267.064982)
			(xy 353.540303 -267.085272) (xy 353.491338 -267.097672) (xy 353.441 -267.101843) (xy 353.390662 -267.097672)
			(xy 353.341697 -267.085272) (xy 353.295441 -267.064982) (xy 353.253155 -267.037356) (xy 353.215993 -267.003146)
			(xy 353.184969 -266.963286) (xy 353.160928 -266.918863) (xy 353.144527 -266.871089) (xy 353.136214 -266.821267)
			(xy 353.135692 -266.796012) (xy 353.136132 -266.772386) (xy 353.143402 -266.725698) (xy 353.157773 -266.680685)
			(xy 353.16795 -266.65936) (xy 353.174046 -266.647422) (xy 353.172776 -266.62126) (xy 353.124262 -266.543282)
			(xy 353.11715 -266.534138) (xy 353.11207 -266.529058) (xy 353.104673 -266.52221) (xy 353.086074 -266.514477)
			(xy 353.076002 -266.514072) (xy 351.926144 -266.514072) (xy 351.916078 -266.514505) (xy 351.897485 -266.52223)
			(xy 351.890076 -266.529058) (xy 351.884996 -266.534138) (xy 351.877884 -266.543282) (xy 351.82937 -266.62126)
			(xy 351.8281 -266.647422) (xy 351.834196 -266.65936) (xy 351.844367 -266.680688) (xy 351.858739 -266.7257)
			(xy 351.866011 -266.772387) (xy 351.866454 -266.796012) (xy 351.865932 -266.821267) (xy 351.857619 -266.871089)
			(xy 351.841218 -266.918863) (xy 351.817177 -266.963286) (xy 351.786153 -267.003146) (xy 351.748991 -267.037356)
			(xy 351.706705 -267.064982) (xy 351.660449 -267.085272) (xy 351.611484 -267.097672) (xy 351.561146 -267.101843)
			(xy 351.510808 -267.097672) (xy 351.461843 -267.085272) (xy 351.415587 -267.064982) (xy 351.373301 -267.037356)
			(xy 351.336139 -267.003146) (xy 351.305115 -266.963286) (xy 351.281074 -266.918863) (xy 351.264673 -266.871089)
			(xy 351.25636 -266.821267) (xy 351.255838 -266.796012) (xy 351.256278 -266.772387) (xy 351.26355 -266.725699)
			(xy 351.277922 -266.680687) (xy 351.288096 -266.65936) (xy 351.294192 -266.647422) (xy 351.292922 -266.62126)
			(xy 351.244408 -266.543282) (xy 351.237296 -266.534138) (xy 351.232216 -266.529058) (xy 351.224816 -266.522219)
			(xy 351.206217 -266.514506) (xy 351.196148 -266.514072) (xy 350.98609 -266.514072) (xy 350.97602 -266.514496)
			(xy 350.957416 -266.52221) (xy 350.950022 -266.529058) (xy 350.944942 -266.534138) (xy 350.93783 -266.543282)
			(xy 350.889316 -266.62126) (xy 350.888046 -266.647422) (xy 350.894142 -266.65936) (xy 350.904314 -266.680688)
			(xy 350.918689 -266.725699) (xy 350.925962 -266.772387) (xy 350.9264 -266.796012) (xy 350.925878 -266.821267)
			(xy 350.917565 -266.871089) (xy 350.901164 -266.918863) (xy 350.877123 -266.963286) (xy 350.846099 -267.003146)
			(xy 350.808937 -267.037356) (xy 350.766651 -267.064982) (xy 350.720395 -267.085272) (xy 350.67143 -267.097672)
			(xy 350.621092 -267.101843) (xy 350.570754 -267.097672) (xy 350.521789 -267.085272) (xy 350.475533 -267.064982)
			(xy 350.433247 -267.037356) (xy 350.396085 -267.003146) (xy 350.365061 -266.963286) (xy 350.34102 -266.918863)
			(xy 350.324619 -266.871089) (xy 350.316306 -266.821267) (xy 350.315784 -266.796012) (xy 350.316224 -266.772386)
			(xy 350.323494 -266.725698) (xy 350.337864 -266.680685) (xy 350.348042 -266.65936) (xy 350.354138 -266.647422)
			(xy 350.352868 -266.62126) (xy 350.304354 -266.543282) (xy 350.297242 -266.534138) (xy 350.292162 -266.529058)
			(xy 350.284764 -266.522211) (xy 350.266165 -266.514482) (xy 350.256094 -266.514072) (xy 350.046036 -266.514072)
			(xy 350.035984 -266.514575) (xy 350.017419 -266.522292) (xy 350.009968 -266.529058) (xy 350.004888 -266.534138)
			(xy 349.997776 -266.543282) (xy 349.949262 -266.62126) (xy 349.947992 -266.647422) (xy 349.954088 -266.65936)
			(xy 349.964259 -266.680688) (xy 349.978632 -266.7257) (xy 349.985904 -266.772387) (xy 349.986346 -266.796012)
			(xy 349.985824 -266.821267) (xy 349.977511 -266.871089) (xy 349.96111 -266.918863) (xy 349.937069 -266.963286)
			(xy 349.906045 -267.003146) (xy 349.868883 -267.037356) (xy 349.826597 -267.064982) (xy 349.780341 -267.085272)
			(xy 349.731376 -267.097672) (xy 349.681038 -267.101843) (xy 349.6307 -267.097672) (xy 349.581735 -267.085272)
			(xy 349.535479 -267.064982) (xy 349.493193 -267.037356) (xy 349.456031 -267.003146) (xy 349.425007 -266.963286)
			(xy 349.400966 -266.918863) (xy 349.384565 -266.871089) (xy 349.376252 -266.821267) (xy 349.37573 -266.796012)
			(xy 349.37617 -266.772387) (xy 349.383441 -266.725699) (xy 349.397813 -266.680687) (xy 349.407988 -266.65936)
			(xy 349.414084 -266.647422) (xy 349.412814 -266.62126) (xy 349.3643 -266.543282) (xy 349.357188 -266.534138)
			(xy 349.352108 -266.529058) (xy 349.344713 -266.522204) (xy 349.326114 -266.514457) (xy 349.31604 -266.514072)
			(xy 348.126812 -266.514072) (xy 348.116975 -266.51461) (xy 348.098816 -266.522199) (xy 348.091506 -266.528804)
			(xy 348.060264 -266.560046) (xy 348.052381 -266.568812) (xy 348.04489 -266.591138) (xy 348.048071 -266.614471)
			(xy 348.054168 -266.624562) (xy 348.066565 -266.643583) (xy 348.086199 -266.684518) (xy 348.09955 -266.727911)
			(xy 348.106322 -266.772804) (xy 348.106746 -266.795504) (xy 348.106746 -266.79652) (xy 348.106238 -266.809982)
			(xy 348.106238 -266.811252) (xy 348.105984 -266.812268) (xy 348.104071 -266.837952) (xy 348.092726 -266.888185)
			(xy 348.073117 -266.935804) (xy 348.045799 -266.979459) (xy 348.011547 -267.017915) (xy 347.97133 -267.050082)
			(xy 347.926288 -267.075048) (xy 347.877697 -267.092106) (xy 347.826933 -267.100774) (xy 347.801184 -267.10132)
			(xy 347.791024 -267.10132) (xy 347.76351 -267.099816) (xy 347.709663 -267.088144) (xy 347.658779 -267.067012)
			(xy 347.635322 -267.052552) (xy 347.629226 -267.048488) (xy 347.61551 -267.043916) (xy 347.606503 -267.041477)
			(xy 347.587887 -267.042507) (xy 347.57085 -267.050082) (xy 347.563948 -267.056362) (xy 347.445838 -267.174472)
			(xy 347.437826 -267.183492) (xy 347.430399 -267.206412) (xy 347.431614 -267.218414) (xy 347.437964 -267.257784)
			(xy 347.446092 -267.3096) (xy 347.460062 -267.329158) (xy 347.470984 -267.334746) (xy 347.491992 -267.346106)
			(xy 347.530506 -267.374344) (xy 347.564156 -267.408232) (xy 347.592122 -267.446943) (xy 347.613723 -267.489535)
			(xy 347.628433 -267.53497) (xy 347.635893 -267.58214) (xy 347.636338 -267.606018) (xy 347.96528 -267.606018)
			(xy 347.96924 -267.556964) (xy 347.981017 -267.50918) (xy 348.000308 -267.463904) (xy 348.026611 -267.422308)
			(xy 348.059246 -267.385471) (xy 348.097367 -267.354346) (xy 348.139988 -267.329739) (xy 348.186004 -267.312287)
			(xy 348.234223 -267.302443) (xy 348.283398 -267.300462) (xy 348.332253 -267.306394) (xy 348.379524 -267.320086)
			(xy 348.423986 -267.341184) (xy 348.464489 -267.36914) (xy 348.499982 -267.403232) (xy 348.529547 -267.442576)
			(xy 348.552418 -267.486153) (xy 348.568002 -267.532834) (xy 348.575897 -267.581411) (xy 348.576392 -267.606018)
			(xy 349.845388 -267.606018) (xy 349.849348 -267.556964) (xy 349.861125 -267.50918) (xy 349.880416 -267.463904)
			(xy 349.906719 -267.422308) (xy 349.939354 -267.385471) (xy 349.977475 -267.354346) (xy 350.020096 -267.329739)
			(xy 350.066112 -267.312287) (xy 350.114331 -267.302443) (xy 350.163506 -267.300462) (xy 350.212361 -267.306394)
			(xy 350.259632 -267.320086) (xy 350.304094 -267.341184) (xy 350.344597 -267.36914) (xy 350.38009 -267.403232)
			(xy 350.409655 -267.442576) (xy 350.432526 -267.486153) (xy 350.44811 -267.532834) (xy 350.456005 -267.581411)
			(xy 350.4565 -267.606018) (xy 351.725242 -267.606018) (xy 351.729202 -267.556964) (xy 351.740979 -267.50918)
			(xy 351.76027 -267.463904) (xy 351.786573 -267.422308) (xy 351.819208 -267.385471) (xy 351.857329 -267.354346)
			(xy 351.89995 -267.329739) (xy 351.945966 -267.312287) (xy 351.994185 -267.302443) (xy 352.04336 -267.300462)
			(xy 352.092215 -267.306394) (xy 352.139486 -267.320086) (xy 352.183948 -267.341184) (xy 352.224451 -267.36914)
			(xy 352.259944 -267.403232) (xy 352.289509 -267.442576) (xy 352.31238 -267.486153) (xy 352.327964 -267.532834)
			(xy 352.335859 -267.581411) (xy 352.336354 -267.606018) (xy 353.60535 -267.606018) (xy 353.60931 -267.556964)
			(xy 353.621087 -267.50918) (xy 353.640378 -267.463904) (xy 353.666681 -267.422308) (xy 353.699316 -267.385471)
			(xy 353.737437 -267.354346) (xy 353.780058 -267.329739) (xy 353.826074 -267.312287) (xy 353.874293 -267.302443)
			(xy 353.923468 -267.300462) (xy 353.972323 -267.306394) (xy 354.019594 -267.320086) (xy 354.064056 -267.341184)
			(xy 354.104559 -267.36914) (xy 354.140052 -267.403232) (xy 354.169617 -267.442576) (xy 354.192488 -267.486153)
			(xy 354.208072 -267.532834) (xy 354.215967 -267.581411) (xy 354.216462 -267.606018) (xy 355.485204 -267.606018)
			(xy 355.489164 -267.556964) (xy 355.500941 -267.50918) (xy 355.520232 -267.463904) (xy 355.546535 -267.422308)
			(xy 355.57917 -267.385471) (xy 355.617291 -267.354346) (xy 355.659912 -267.329739) (xy 355.705928 -267.312287)
			(xy 355.754147 -267.302443) (xy 355.803322 -267.300462) (xy 355.852177 -267.306394) (xy 355.899448 -267.320086)
			(xy 355.94391 -267.341184) (xy 355.984413 -267.36914) (xy 356.019906 -267.403232) (xy 356.049471 -267.442576)
			(xy 356.072342 -267.486153) (xy 356.087926 -267.532834) (xy 356.095821 -267.581411) (xy 356.096316 -267.606018)
			(xy 357.365312 -267.606018) (xy 357.369272 -267.556964) (xy 357.381049 -267.50918) (xy 357.40034 -267.463904)
			(xy 357.426643 -267.422308) (xy 357.459278 -267.385471) (xy 357.497399 -267.354346) (xy 357.54002 -267.329739)
			(xy 357.586036 -267.312287) (xy 357.634255 -267.302443) (xy 357.68343 -267.300462) (xy 357.732285 -267.306394)
			(xy 357.779556 -267.320086) (xy 357.824018 -267.341184) (xy 357.864521 -267.36914) (xy 357.900014 -267.403232)
			(xy 357.929579 -267.442576) (xy 357.95245 -267.486153) (xy 357.968034 -267.532834) (xy 357.975929 -267.581411)
			(xy 357.976424 -267.606018) (xy 361.118924 -267.606018) (xy 361.122884 -267.556964) (xy 361.134661 -267.50918)
			(xy 361.153952 -267.463904) (xy 361.180255 -267.422308) (xy 361.21289 -267.385471) (xy 361.251011 -267.354346)
			(xy 361.293632 -267.329739) (xy 361.339648 -267.312287) (xy 361.387867 -267.302443) (xy 361.437042 -267.300462)
			(xy 361.485897 -267.306394) (xy 361.533168 -267.320086) (xy 361.57763 -267.341184) (xy 361.618133 -267.36914)
			(xy 361.653626 -267.403232) (xy 361.683191 -267.442576) (xy 361.706062 -267.486153) (xy 361.721646 -267.532834)
			(xy 361.729541 -267.581411) (xy 361.730036 -267.606018) (xy 362.999032 -267.606018) (xy 363.002992 -267.556964)
			(xy 363.014769 -267.50918) (xy 363.03406 -267.463904) (xy 363.060363 -267.422308) (xy 363.092998 -267.385471)
			(xy 363.131119 -267.354346) (xy 363.17374 -267.329739) (xy 363.219756 -267.312287) (xy 363.267975 -267.302443)
			(xy 363.31715 -267.300462) (xy 363.366005 -267.306394) (xy 363.413276 -267.320086) (xy 363.457738 -267.341184)
			(xy 363.498241 -267.36914) (xy 363.533734 -267.403232) (xy 363.563299 -267.442576) (xy 363.58617 -267.486153)
			(xy 363.601754 -267.532834) (xy 363.609649 -267.581411) (xy 363.610144 -267.606018) (xy 364.878886 -267.606018)
			(xy 364.882846 -267.556964) (xy 364.894623 -267.50918) (xy 364.913914 -267.463904) (xy 364.940217 -267.422308)
			(xy 364.972852 -267.385471) (xy 365.010973 -267.354346) (xy 365.053594 -267.329739) (xy 365.09961 -267.312287)
			(xy 365.147829 -267.302443) (xy 365.197004 -267.300462) (xy 365.245859 -267.306394) (xy 365.29313 -267.320086)
			(xy 365.337592 -267.341184) (xy 365.378095 -267.36914) (xy 365.413588 -267.403232) (xy 365.443153 -267.442576)
			(xy 365.466024 -267.486153) (xy 365.481608 -267.532834) (xy 365.489503 -267.581411) (xy 365.489998 -267.606018)
			(xy 366.758994 -267.606018) (xy 366.762954 -267.556964) (xy 366.774731 -267.50918) (xy 366.794022 -267.463904)
			(xy 366.820325 -267.422308) (xy 366.85296 -267.385471) (xy 366.891081 -267.354346) (xy 366.933702 -267.329739)
			(xy 366.979718 -267.312287) (xy 367.027937 -267.302443) (xy 367.077112 -267.300462) (xy 367.125967 -267.306394)
			(xy 367.173238 -267.320086) (xy 367.2177 -267.341184) (xy 367.258203 -267.36914) (xy 367.293696 -267.403232)
			(xy 367.323261 -267.442576) (xy 367.346132 -267.486153) (xy 367.361716 -267.532834) (xy 367.369611 -267.581411)
			(xy 367.370106 -267.606018) (xy 368.639102 -267.606018) (xy 368.643062 -267.556964) (xy 368.654839 -267.50918)
			(xy 368.67413 -267.463904) (xy 368.700433 -267.422308) (xy 368.733068 -267.385471) (xy 368.771189 -267.354346)
			(xy 368.81381 -267.329739) (xy 368.859826 -267.312287) (xy 368.908045 -267.302443) (xy 368.95722 -267.300462)
			(xy 369.006075 -267.306394) (xy 369.053346 -267.320086) (xy 369.097808 -267.341184) (xy 369.138311 -267.36914)
			(xy 369.173804 -267.403232) (xy 369.203369 -267.442576) (xy 369.22624 -267.486153) (xy 369.241824 -267.532834)
			(xy 369.249719 -267.581411) (xy 369.250214 -267.606018) (xy 370.518956 -267.606018) (xy 370.522916 -267.556964)
			(xy 370.534693 -267.50918) (xy 370.553984 -267.463904) (xy 370.580287 -267.422308) (xy 370.612922 -267.385471)
			(xy 370.651043 -267.354346) (xy 370.693664 -267.329739) (xy 370.73968 -267.312287) (xy 370.787899 -267.302443)
			(xy 370.837074 -267.300462) (xy 370.885929 -267.306394) (xy 370.9332 -267.320086) (xy 370.977662 -267.341184)
			(xy 371.018165 -267.36914) (xy 371.053658 -267.403232) (xy 371.083223 -267.442576) (xy 371.106094 -267.486153)
			(xy 371.121678 -267.532834) (xy 371.129573 -267.581411) (xy 371.130068 -267.606018) (xy 372.399064 -267.606018)
			(xy 372.403024 -267.556964) (xy 372.414801 -267.50918) (xy 372.434092 -267.463904) (xy 372.460395 -267.422308)
			(xy 372.49303 -267.385471) (xy 372.531151 -267.354346) (xy 372.573772 -267.329739) (xy 372.619788 -267.312287)
			(xy 372.668007 -267.302443) (xy 372.717182 -267.300462) (xy 372.766037 -267.306394) (xy 372.813308 -267.320086)
			(xy 372.85777 -267.341184) (xy 372.898273 -267.36914) (xy 372.933766 -267.403232) (xy 372.963331 -267.442576)
			(xy 372.986202 -267.486153) (xy 373.001786 -267.532834) (xy 373.009681 -267.581411) (xy 373.010176 -267.606018)
			(xy 373.009681 -267.630625) (xy 373.001786 -267.679202) (xy 372.986202 -267.725883) (xy 372.963331 -267.76946)
			(xy 372.933766 -267.808804) (xy 372.898273 -267.842896) (xy 372.85777 -267.870852) (xy 372.813308 -267.89195)
			(xy 372.766037 -267.905642) (xy 372.717182 -267.911574) (xy 372.668007 -267.909593) (xy 372.619788 -267.899749)
			(xy 372.573772 -267.882297) (xy 372.531151 -267.85769) (xy 372.49303 -267.826565) (xy 372.460395 -267.789728)
			(xy 372.434092 -267.748132) (xy 372.414801 -267.702856) (xy 372.403024 -267.655072) (xy 372.399064 -267.606018)
			(xy 371.130068 -267.606018) (xy 371.129573 -267.630625) (xy 371.121678 -267.679202) (xy 371.106094 -267.725883)
			(xy 371.083223 -267.76946) (xy 371.053658 -267.808804) (xy 371.018165 -267.842896) (xy 370.977662 -267.870852)
			(xy 370.9332 -267.89195) (xy 370.885929 -267.905642) (xy 370.837074 -267.911574) (xy 370.787899 -267.909593)
			(xy 370.73968 -267.899749) (xy 370.693664 -267.882297) (xy 370.651043 -267.85769) (xy 370.612922 -267.826565)
			(xy 370.580287 -267.789728) (xy 370.553984 -267.748132) (xy 370.534693 -267.702856) (xy 370.522916 -267.655072)
			(xy 370.518956 -267.606018) (xy 369.250214 -267.606018) (xy 369.249719 -267.630625) (xy 369.241824 -267.679202)
			(xy 369.22624 -267.725883) (xy 369.203369 -267.76946) (xy 369.173804 -267.808804) (xy 369.138311 -267.842896)
			(xy 369.097808 -267.870852) (xy 369.053346 -267.89195) (xy 369.006075 -267.905642) (xy 368.95722 -267.911574)
			(xy 368.908045 -267.909593) (xy 368.859826 -267.899749) (xy 368.81381 -267.882297) (xy 368.771189 -267.85769)
			(xy 368.733068 -267.826565) (xy 368.700433 -267.789728) (xy 368.67413 -267.748132) (xy 368.654839 -267.702856)
			(xy 368.643062 -267.655072) (xy 368.639102 -267.606018) (xy 367.370106 -267.606018) (xy 367.369611 -267.630625)
			(xy 367.361716 -267.679202) (xy 367.346132 -267.725883) (xy 367.323261 -267.76946) (xy 367.293696 -267.808804)
			(xy 367.258203 -267.842896) (xy 367.2177 -267.870852) (xy 367.173238 -267.89195) (xy 367.125967 -267.905642)
			(xy 367.077112 -267.911574) (xy 367.027937 -267.909593) (xy 366.979718 -267.899749) (xy 366.933702 -267.882297)
			(xy 366.891081 -267.85769) (xy 366.85296 -267.826565) (xy 366.820325 -267.789728) (xy 366.794022 -267.748132)
			(xy 366.774731 -267.702856) (xy 366.762954 -267.655072) (xy 366.758994 -267.606018) (xy 365.489998 -267.606018)
			(xy 365.489503 -267.630625) (xy 365.481608 -267.679202) (xy 365.466024 -267.725883) (xy 365.443153 -267.76946)
			(xy 365.413588 -267.808804) (xy 365.378095 -267.842896) (xy 365.337592 -267.870852) (xy 365.29313 -267.89195)
			(xy 365.245859 -267.905642) (xy 365.197004 -267.911574) (xy 365.147829 -267.909593) (xy 365.09961 -267.899749)
			(xy 365.053594 -267.882297) (xy 365.010973 -267.85769) (xy 364.972852 -267.826565) (xy 364.940217 -267.789728)
			(xy 364.913914 -267.748132) (xy 364.894623 -267.702856) (xy 364.882846 -267.655072) (xy 364.878886 -267.606018)
			(xy 363.610144 -267.606018) (xy 363.609649 -267.630625) (xy 363.601754 -267.679202) (xy 363.58617 -267.725883)
			(xy 363.563299 -267.76946) (xy 363.533734 -267.808804) (xy 363.498241 -267.842896) (xy 363.457738 -267.870852)
			(xy 363.413276 -267.89195) (xy 363.366005 -267.905642) (xy 363.31715 -267.911574) (xy 363.267975 -267.909593)
			(xy 363.219756 -267.899749) (xy 363.17374 -267.882297) (xy 363.131119 -267.85769) (xy 363.092998 -267.826565)
			(xy 363.060363 -267.789728) (xy 363.03406 -267.748132) (xy 363.014769 -267.702856) (xy 363.002992 -267.655072)
			(xy 362.999032 -267.606018) (xy 361.730036 -267.606018) (xy 361.729541 -267.630625) (xy 361.721646 -267.679202)
			(xy 361.706062 -267.725883) (xy 361.683191 -267.76946) (xy 361.653626 -267.808804) (xy 361.618133 -267.842896)
			(xy 361.57763 -267.870852) (xy 361.533168 -267.89195) (xy 361.485897 -267.905642) (xy 361.437042 -267.911574)
			(xy 361.387867 -267.909593) (xy 361.339648 -267.899749) (xy 361.293632 -267.882297) (xy 361.251011 -267.85769)
			(xy 361.21289 -267.826565) (xy 361.180255 -267.789728) (xy 361.153952 -267.748132) (xy 361.134661 -267.702856)
			(xy 361.122884 -267.655072) (xy 361.118924 -267.606018) (xy 357.976424 -267.606018) (xy 357.975929 -267.630625)
			(xy 357.968034 -267.679202) (xy 357.95245 -267.725883) (xy 357.929579 -267.76946) (xy 357.900014 -267.808804)
			(xy 357.864521 -267.842896) (xy 357.824018 -267.870852) (xy 357.779556 -267.89195) (xy 357.732285 -267.905642)
			(xy 357.68343 -267.911574) (xy 357.634255 -267.909593) (xy 357.586036 -267.899749) (xy 357.54002 -267.882297)
			(xy 357.497399 -267.85769) (xy 357.459278 -267.826565) (xy 357.426643 -267.789728) (xy 357.40034 -267.748132)
			(xy 357.381049 -267.702856) (xy 357.369272 -267.655072) (xy 357.365312 -267.606018) (xy 356.096316 -267.606018)
			(xy 356.095821 -267.630625) (xy 356.087926 -267.679202) (xy 356.072342 -267.725883) (xy 356.049471 -267.76946)
			(xy 356.019906 -267.808804) (xy 355.984413 -267.842896) (xy 355.94391 -267.870852) (xy 355.899448 -267.89195)
			(xy 355.852177 -267.905642) (xy 355.803322 -267.911574) (xy 355.754147 -267.909593) (xy 355.705928 -267.899749)
			(xy 355.659912 -267.882297) (xy 355.617291 -267.85769) (xy 355.57917 -267.826565) (xy 355.546535 -267.789728)
			(xy 355.520232 -267.748132) (xy 355.500941 -267.702856) (xy 355.489164 -267.655072) (xy 355.485204 -267.606018)
			(xy 354.216462 -267.606018) (xy 354.215967 -267.630625) (xy 354.208072 -267.679202) (xy 354.192488 -267.725883)
			(xy 354.169617 -267.76946) (xy 354.140052 -267.808804) (xy 354.104559 -267.842896) (xy 354.064056 -267.870852)
			(xy 354.019594 -267.89195) (xy 353.972323 -267.905642) (xy 353.923468 -267.911574) (xy 353.874293 -267.909593)
			(xy 353.826074 -267.899749) (xy 353.780058 -267.882297) (xy 353.737437 -267.85769) (xy 353.699316 -267.826565)
			(xy 353.666681 -267.789728) (xy 353.640378 -267.748132) (xy 353.621087 -267.702856) (xy 353.60931 -267.655072)
			(xy 353.60535 -267.606018) (xy 352.336354 -267.606018) (xy 352.335859 -267.630625) (xy 352.327964 -267.679202)
			(xy 352.31238 -267.725883) (xy 352.289509 -267.76946) (xy 352.259944 -267.808804) (xy 352.224451 -267.842896)
			(xy 352.183948 -267.870852) (xy 352.139486 -267.89195) (xy 352.092215 -267.905642) (xy 352.04336 -267.911574)
			(xy 351.994185 -267.909593) (xy 351.945966 -267.899749) (xy 351.89995 -267.882297) (xy 351.857329 -267.85769)
			(xy 351.819208 -267.826565) (xy 351.786573 -267.789728) (xy 351.76027 -267.748132) (xy 351.740979 -267.702856)
			(xy 351.729202 -267.655072) (xy 351.725242 -267.606018) (xy 350.4565 -267.606018) (xy 350.456005 -267.630625)
			(xy 350.44811 -267.679202) (xy 350.432526 -267.725883) (xy 350.409655 -267.76946) (xy 350.38009 -267.808804)
			(xy 350.344597 -267.842896) (xy 350.304094 -267.870852) (xy 350.259632 -267.89195) (xy 350.212361 -267.905642)
			(xy 350.163506 -267.911574) (xy 350.114331 -267.909593) (xy 350.066112 -267.899749) (xy 350.020096 -267.882297)
			(xy 349.977475 -267.85769) (xy 349.939354 -267.826565) (xy 349.906719 -267.789728) (xy 349.880416 -267.748132)
			(xy 349.861125 -267.702856) (xy 349.849348 -267.655072) (xy 349.845388 -267.606018) (xy 348.576392 -267.606018)
			(xy 348.575897 -267.630625) (xy 348.568002 -267.679202) (xy 348.552418 -267.725883) (xy 348.529547 -267.76946)
			(xy 348.499982 -267.808804) (xy 348.464489 -267.842896) (xy 348.423986 -267.870852) (xy 348.379524 -267.89195)
			(xy 348.332253 -267.905642) (xy 348.283398 -267.911574) (xy 348.234223 -267.909593) (xy 348.186004 -267.899749)
			(xy 348.139988 -267.882297) (xy 348.097367 -267.85769) (xy 348.059246 -267.826565) (xy 348.026611 -267.789728)
			(xy 348.000308 -267.748132) (xy 347.981017 -267.702856) (xy 347.96924 -267.655072) (xy 347.96528 -267.606018)
			(xy 347.636338 -267.606018) (xy 347.635866 -267.630009) (xy 347.628358 -267.6774) (xy 347.613529 -267.723034)
			(xy 347.591745 -267.765786) (xy 347.563542 -267.804605) (xy 347.529614 -267.838534) (xy 347.490797 -267.866739)
			(xy 347.448045 -267.888525) (xy 347.402412 -267.903355) (xy 347.355021 -267.910865) (xy 347.33103 -267.911326)
			(xy 347.30715 -267.910866) (xy 347.259974 -267.90343) (xy 347.214532 -267.888734) (xy 347.171935 -267.867138)
			(xy 347.133223 -267.839168) (xy 347.099341 -267.805509) (xy 347.071117 -267.766982) (xy 347.059758 -267.745972)
			(xy 347.05417 -267.73505) (xy 347.034612 -267.72108) (xy 346.982796 -267.712952) (xy 346.943426 -267.706602)
			(xy 346.93142 -267.705336) (xy 346.908492 -267.712783) (xy 346.899484 -267.720826) (xy 346.61475 -268.00556)
			(xy 359.650541 -268.00556) (xy 359.654571 -267.953062) (xy 359.666568 -267.901794) (xy 359.686251 -267.852959)
			(xy 359.713157 -267.8077) (xy 359.746657 -267.767079) (xy 359.785965 -267.732048) (xy 359.83016 -267.703428)
			(xy 359.878205 -267.681889) (xy 359.928976 -267.667937) (xy 359.981281 -267.661899) (xy 360.033895 -267.663916)
			(xy 360.085585 -267.67394) (xy 360.135138 -267.691738) (xy 360.181394 -267.716891) (xy 360.223268 -267.74881)
			(xy 360.25978 -267.786748) (xy 360.290072 -267.829814) (xy 360.313435 -267.876999) (xy 360.329321 -267.927198)
			(xy 360.337358 -267.979234) (xy 360.337862 -268.00556) (xy 360.337358 -268.031886) (xy 360.329321 -268.083922)
			(xy 360.313435 -268.134121) (xy 360.290072 -268.181306) (xy 360.25978 -268.224372) (xy 360.223268 -268.26231)
			(xy 360.181394 -268.294229) (xy 360.135138 -268.319382) (xy 360.085585 -268.33718) (xy 360.033895 -268.347204)
			(xy 359.981281 -268.349221) (xy 359.928976 -268.343183) (xy 359.878205 -268.329231) (xy 359.83016 -268.307692)
			(xy 359.785965 -268.279072) (xy 359.746657 -268.244041) (xy 359.713157 -268.20342) (xy 359.686251 -268.158161)
			(xy 359.666568 -268.109326) (xy 359.654571 -268.058058) (xy 359.650541 -268.00556) (xy 346.61475 -268.00556)
			(xy 346.454222 -268.166088) (xy 346.447371 -268.173485) (xy 346.439629 -268.192083) (xy 346.439236 -268.202156)
			(xy 346.439236 -268.222984) (xy 346.44203 -268.231366) (xy 346.451428 -268.259814) (xy 346.461922 -268.297944)
			(xy 346.473143 -268.376228) (xy 346.47378 -268.41577) (xy 346.473789 -268.416024) (xy 347.49538 -268.416024)
			(xy 347.49934 -268.36697) (xy 347.511117 -268.319186) (xy 347.530408 -268.27391) (xy 347.556711 -268.232314)
			(xy 347.589346 -268.195477) (xy 347.627467 -268.164352) (xy 347.670088 -268.139745) (xy 347.716104 -268.122293)
			(xy 347.764323 -268.112449) (xy 347.813498 -268.110468) (xy 347.862353 -268.1164) (xy 347.909624 -268.130092)
			(xy 347.954086 -268.15119) (xy 347.994589 -268.179146) (xy 348.030082 -268.213238) (xy 348.059647 -268.252582)
			(xy 348.082518 -268.296159) (xy 348.098102 -268.34284) (xy 348.105997 -268.391417) (xy 348.106492 -268.416024)
			(xy 349.375234 -268.416024) (xy 349.379194 -268.36697) (xy 349.390971 -268.319186) (xy 349.410262 -268.27391)
			(xy 349.436565 -268.232314) (xy 349.4692 -268.195477) (xy 349.507321 -268.164352) (xy 349.549942 -268.139745)
			(xy 349.595958 -268.122293) (xy 349.644177 -268.112449) (xy 349.693352 -268.110468) (xy 349.742207 -268.1164)
			(xy 349.789478 -268.130092) (xy 349.83394 -268.15119) (xy 349.874443 -268.179146) (xy 349.909936 -268.213238)
			(xy 349.939501 -268.252582) (xy 349.962372 -268.296159) (xy 349.977956 -268.34284) (xy 349.985851 -268.391417)
			(xy 349.986346 -268.416024) (xy 351.255342 -268.416024) (xy 351.259302 -268.36697) (xy 351.271079 -268.319186)
			(xy 351.29037 -268.27391) (xy 351.316673 -268.232314) (xy 351.349308 -268.195477) (xy 351.387429 -268.164352)
			(xy 351.43005 -268.139745) (xy 351.476066 -268.122293) (xy 351.524285 -268.112449) (xy 351.57346 -268.110468)
			(xy 351.622315 -268.1164) (xy 351.669586 -268.130092) (xy 351.714048 -268.15119) (xy 351.754551 -268.179146)
			(xy 351.790044 -268.213238) (xy 351.819609 -268.252582) (xy 351.84248 -268.296159) (xy 351.858064 -268.34284)
			(xy 351.865959 -268.391417) (xy 351.866454 -268.416024) (xy 353.135196 -268.416024) (xy 353.139156 -268.36697)
			(xy 353.150933 -268.319186) (xy 353.170224 -268.27391) (xy 353.196527 -268.232314) (xy 353.229162 -268.195477)
			(xy 353.267283 -268.164352) (xy 353.309904 -268.139745) (xy 353.35592 -268.122293) (xy 353.404139 -268.112449)
			(xy 353.453314 -268.110468) (xy 353.502169 -268.1164) (xy 353.54944 -268.130092) (xy 353.593902 -268.15119)
			(xy 353.634405 -268.179146) (xy 353.669898 -268.213238) (xy 353.699463 -268.252582) (xy 353.722334 -268.296159)
			(xy 353.737918 -268.34284) (xy 353.745813 -268.391417) (xy 353.746308 -268.416024) (xy 355.015304 -268.416024)
			(xy 355.019264 -268.36697) (xy 355.031041 -268.319186) (xy 355.050332 -268.27391) (xy 355.076635 -268.232314)
			(xy 355.10927 -268.195477) (xy 355.147391 -268.164352) (xy 355.190012 -268.139745) (xy 355.236028 -268.122293)
			(xy 355.284247 -268.112449) (xy 355.333422 -268.110468) (xy 355.382277 -268.1164) (xy 355.429548 -268.130092)
			(xy 355.47401 -268.15119) (xy 355.514513 -268.179146) (xy 355.550006 -268.213238) (xy 355.579571 -268.252582)
			(xy 355.602442 -268.296159) (xy 355.618026 -268.34284) (xy 355.625921 -268.391417) (xy 355.626416 -268.416024)
			(xy 356.895412 -268.416024) (xy 356.899372 -268.36697) (xy 356.911149 -268.319186) (xy 356.93044 -268.27391)
			(xy 356.956743 -268.232314) (xy 356.989378 -268.195477) (xy 357.027499 -268.164352) (xy 357.07012 -268.139745)
			(xy 357.116136 -268.122293) (xy 357.164355 -268.112449) (xy 357.21353 -268.110468) (xy 357.262385 -268.1164)
			(xy 357.309656 -268.130092) (xy 357.354118 -268.15119) (xy 357.394621 -268.179146) (xy 357.430114 -268.213238)
			(xy 357.459679 -268.252582) (xy 357.48255 -268.296159) (xy 357.498134 -268.34284) (xy 357.506029 -268.391417)
			(xy 357.506524 -268.416024) (xy 361.589078 -268.416024) (xy 361.593038 -268.36697) (xy 361.604815 -268.319186)
			(xy 361.624106 -268.27391) (xy 361.650409 -268.232314) (xy 361.683044 -268.195477) (xy 361.721165 -268.164352)
			(xy 361.763786 -268.139745) (xy 361.809802 -268.122293) (xy 361.858021 -268.112449) (xy 361.907196 -268.110468)
			(xy 361.956051 -268.1164) (xy 362.003322 -268.130092) (xy 362.047784 -268.15119) (xy 362.088287 -268.179146)
			(xy 362.12378 -268.213238) (xy 362.153345 -268.252582) (xy 362.176216 -268.296159) (xy 362.1918 -268.34284)
			(xy 362.199695 -268.391417) (xy 362.20019 -268.416024) (xy 363.468932 -268.416024) (xy 363.472892 -268.36697)
			(xy 363.484669 -268.319186) (xy 363.50396 -268.27391) (xy 363.530263 -268.232314) (xy 363.562898 -268.195477)
			(xy 363.601019 -268.164352) (xy 363.64364 -268.139745) (xy 363.689656 -268.122293) (xy 363.737875 -268.112449)
			(xy 363.78705 -268.110468) (xy 363.835905 -268.1164) (xy 363.883176 -268.130092) (xy 363.927638 -268.15119)
			(xy 363.968141 -268.179146) (xy 364.003634 -268.213238) (xy 364.033199 -268.252582) (xy 364.05607 -268.296159)
			(xy 364.071654 -268.34284) (xy 364.079549 -268.391417) (xy 364.080044 -268.416024) (xy 365.34904 -268.416024)
			(xy 365.353 -268.36697) (xy 365.364777 -268.319186) (xy 365.384068 -268.27391) (xy 365.410371 -268.232314)
			(xy 365.443006 -268.195477) (xy 365.481127 -268.164352) (xy 365.523748 -268.139745) (xy 365.569764 -268.122293)
			(xy 365.617983 -268.112449) (xy 365.667158 -268.110468) (xy 365.716013 -268.1164) (xy 365.763284 -268.130092)
			(xy 365.807746 -268.15119) (xy 365.848249 -268.179146) (xy 365.883742 -268.213238) (xy 365.913307 -268.252582)
			(xy 365.936178 -268.296159) (xy 365.951762 -268.34284) (xy 365.959657 -268.391417) (xy 365.960152 -268.416024)
			(xy 367.228894 -268.416024) (xy 367.232854 -268.36697) (xy 367.244631 -268.319186) (xy 367.263922 -268.27391)
			(xy 367.290225 -268.232314) (xy 367.32286 -268.195477) (xy 367.360981 -268.164352) (xy 367.403602 -268.139745)
			(xy 367.449618 -268.122293) (xy 367.497837 -268.112449) (xy 367.547012 -268.110468) (xy 367.595867 -268.1164)
			(xy 367.643138 -268.130092) (xy 367.6876 -268.15119) (xy 367.728103 -268.179146) (xy 367.763596 -268.213238)
			(xy 367.793161 -268.252582) (xy 367.816032 -268.296159) (xy 367.831616 -268.34284) (xy 367.839511 -268.391417)
			(xy 367.840006 -268.416024) (xy 369.109002 -268.416024) (xy 369.112962 -268.36697) (xy 369.124739 -268.319186)
			(xy 369.14403 -268.27391) (xy 369.170333 -268.232314) (xy 369.202968 -268.195477) (xy 369.241089 -268.164352)
			(xy 369.28371 -268.139745) (xy 369.329726 -268.122293) (xy 369.377945 -268.112449) (xy 369.42712 -268.110468)
			(xy 369.475975 -268.1164) (xy 369.523246 -268.130092) (xy 369.567708 -268.15119) (xy 369.608211 -268.179146)
			(xy 369.643704 -268.213238) (xy 369.673269 -268.252582) (xy 369.69614 -268.296159) (xy 369.711724 -268.34284)
			(xy 369.719619 -268.391417) (xy 369.720114 -268.416024) (xy 370.98911 -268.416024) (xy 370.99307 -268.36697)
			(xy 371.004847 -268.319186) (xy 371.024138 -268.27391) (xy 371.050441 -268.232314) (xy 371.083076 -268.195477)
			(xy 371.121197 -268.164352) (xy 371.163818 -268.139745) (xy 371.209834 -268.122293) (xy 371.258053 -268.112449)
			(xy 371.307228 -268.110468) (xy 371.356083 -268.1164) (xy 371.403354 -268.130092) (xy 371.447816 -268.15119)
			(xy 371.488319 -268.179146) (xy 371.523812 -268.213238) (xy 371.553377 -268.252582) (xy 371.576248 -268.296159)
			(xy 371.591832 -268.34284) (xy 371.599727 -268.391417) (xy 371.600222 -268.416024) (xy 372.868964 -268.416024)
			(xy 372.872924 -268.36697) (xy 372.884701 -268.319186) (xy 372.903992 -268.27391) (xy 372.930295 -268.232314)
			(xy 372.96293 -268.195477) (xy 373.001051 -268.164352) (xy 373.043672 -268.139745) (xy 373.089688 -268.122293)
			(xy 373.137907 -268.112449) (xy 373.187082 -268.110468) (xy 373.235937 -268.1164) (xy 373.283208 -268.130092)
			(xy 373.32767 -268.15119) (xy 373.368173 -268.179146) (xy 373.403666 -268.213238) (xy 373.433231 -268.252582)
			(xy 373.456102 -268.296159) (xy 373.471686 -268.34284) (xy 373.479581 -268.391417) (xy 373.480076 -268.416024)
			(xy 373.479581 -268.440631) (xy 373.471686 -268.489208) (xy 373.456102 -268.535889) (xy 373.433231 -268.579466)
			(xy 373.403666 -268.61881) (xy 373.368173 -268.652902) (xy 373.32767 -268.680858) (xy 373.283208 -268.701956)
			(xy 373.235937 -268.715648) (xy 373.187082 -268.72158) (xy 373.137907 -268.719599) (xy 373.089688 -268.709755)
			(xy 373.043672 -268.692303) (xy 373.001051 -268.667696) (xy 372.96293 -268.636571) (xy 372.930295 -268.599734)
			(xy 372.903992 -268.558138) (xy 372.884701 -268.512862) (xy 372.872924 -268.465078) (xy 372.868964 -268.416024)
			(xy 371.600222 -268.416024) (xy 371.599727 -268.440631) (xy 371.591832 -268.489208) (xy 371.576248 -268.535889)
			(xy 371.553377 -268.579466) (xy 371.523812 -268.61881) (xy 371.488319 -268.652902) (xy 371.447816 -268.680858)
			(xy 371.403354 -268.701956) (xy 371.356083 -268.715648) (xy 371.307228 -268.72158) (xy 371.258053 -268.719599)
			(xy 371.209834 -268.709755) (xy 371.163818 -268.692303) (xy 371.121197 -268.667696) (xy 371.083076 -268.636571)
			(xy 371.050441 -268.599734) (xy 371.024138 -268.558138) (xy 371.004847 -268.512862) (xy 370.99307 -268.465078)
			(xy 370.98911 -268.416024) (xy 369.720114 -268.416024) (xy 369.719619 -268.440631) (xy 369.711724 -268.489208)
			(xy 369.69614 -268.535889) (xy 369.673269 -268.579466) (xy 369.643704 -268.61881) (xy 369.608211 -268.652902)
			(xy 369.567708 -268.680858) (xy 369.523246 -268.701956) (xy 369.475975 -268.715648) (xy 369.42712 -268.72158)
			(xy 369.377945 -268.719599) (xy 369.329726 -268.709755) (xy 369.28371 -268.692303) (xy 369.241089 -268.667696)
			(xy 369.202968 -268.636571) (xy 369.170333 -268.599734) (xy 369.14403 -268.558138) (xy 369.124739 -268.512862)
			(xy 369.112962 -268.465078) (xy 369.109002 -268.416024) (xy 367.840006 -268.416024) (xy 367.839511 -268.440631)
			(xy 367.831616 -268.489208) (xy 367.816032 -268.535889) (xy 367.793161 -268.579466) (xy 367.763596 -268.61881)
			(xy 367.728103 -268.652902) (xy 367.6876 -268.680858) (xy 367.643138 -268.701956) (xy 367.595867 -268.715648)
			(xy 367.547012 -268.72158) (xy 367.497837 -268.719599) (xy 367.449618 -268.709755) (xy 367.403602 -268.692303)
			(xy 367.360981 -268.667696) (xy 367.32286 -268.636571) (xy 367.290225 -268.599734) (xy 367.263922 -268.558138)
			(xy 367.244631 -268.512862) (xy 367.232854 -268.465078) (xy 367.228894 -268.416024) (xy 365.960152 -268.416024)
			(xy 365.959657 -268.440631) (xy 365.951762 -268.489208) (xy 365.936178 -268.535889) (xy 365.913307 -268.579466)
			(xy 365.883742 -268.61881) (xy 365.848249 -268.652902) (xy 365.807746 -268.680858) (xy 365.763284 -268.701956)
			(xy 365.716013 -268.715648) (xy 365.667158 -268.72158) (xy 365.617983 -268.719599) (xy 365.569764 -268.709755)
			(xy 365.523748 -268.692303) (xy 365.481127 -268.667696) (xy 365.443006 -268.636571) (xy 365.410371 -268.599734)
			(xy 365.384068 -268.558138) (xy 365.364777 -268.512862) (xy 365.353 -268.465078) (xy 365.34904 -268.416024)
			(xy 364.080044 -268.416024) (xy 364.079549 -268.440631) (xy 364.071654 -268.489208) (xy 364.05607 -268.535889)
			(xy 364.033199 -268.579466) (xy 364.003634 -268.61881) (xy 363.968141 -268.652902) (xy 363.927638 -268.680858)
			(xy 363.883176 -268.701956) (xy 363.835905 -268.715648) (xy 363.78705 -268.72158) (xy 363.737875 -268.719599)
			(xy 363.689656 -268.709755) (xy 363.64364 -268.692303) (xy 363.601019 -268.667696) (xy 363.562898 -268.636571)
			(xy 363.530263 -268.599734) (xy 363.50396 -268.558138) (xy 363.484669 -268.512862) (xy 363.472892 -268.465078)
			(xy 363.468932 -268.416024) (xy 362.20019 -268.416024) (xy 362.199695 -268.440631) (xy 362.1918 -268.489208)
			(xy 362.176216 -268.535889) (xy 362.153345 -268.579466) (xy 362.12378 -268.61881) (xy 362.088287 -268.652902)
			(xy 362.047784 -268.680858) (xy 362.003322 -268.701956) (xy 361.956051 -268.715648) (xy 361.907196 -268.72158)
			(xy 361.858021 -268.719599) (xy 361.809802 -268.709755) (xy 361.763786 -268.692303) (xy 361.721165 -268.667696)
			(xy 361.683044 -268.636571) (xy 361.650409 -268.599734) (xy 361.624106 -268.558138) (xy 361.604815 -268.512862)
			(xy 361.593038 -268.465078) (xy 361.589078 -268.416024) (xy 357.506524 -268.416024) (xy 357.506029 -268.440631)
			(xy 357.498134 -268.489208) (xy 357.48255 -268.535889) (xy 357.459679 -268.579466) (xy 357.430114 -268.61881)
			(xy 357.394621 -268.652902) (xy 357.354118 -268.680858) (xy 357.309656 -268.701956) (xy 357.262385 -268.715648)
			(xy 357.21353 -268.72158) (xy 357.164355 -268.719599) (xy 357.116136 -268.709755) (xy 357.07012 -268.692303)
			(xy 357.027499 -268.667696) (xy 356.989378 -268.636571) (xy 356.956743 -268.599734) (xy 356.93044 -268.558138)
			(xy 356.911149 -268.512862) (xy 356.899372 -268.465078) (xy 356.895412 -268.416024) (xy 355.626416 -268.416024)
			(xy 355.625921 -268.440631) (xy 355.618026 -268.489208) (xy 355.602442 -268.535889) (xy 355.579571 -268.579466)
			(xy 355.550006 -268.61881) (xy 355.514513 -268.652902) (xy 355.47401 -268.680858) (xy 355.429548 -268.701956)
			(xy 355.382277 -268.715648) (xy 355.333422 -268.72158) (xy 355.284247 -268.719599) (xy 355.236028 -268.709755)
			(xy 355.190012 -268.692303) (xy 355.147391 -268.667696) (xy 355.10927 -268.636571) (xy 355.076635 -268.599734)
			(xy 355.050332 -268.558138) (xy 355.031041 -268.512862) (xy 355.019264 -268.465078) (xy 355.015304 -268.416024)
			(xy 353.746308 -268.416024) (xy 353.745813 -268.440631) (xy 353.737918 -268.489208) (xy 353.722334 -268.535889)
			(xy 353.699463 -268.579466) (xy 353.669898 -268.61881) (xy 353.634405 -268.652902) (xy 353.593902 -268.680858)
			(xy 353.54944 -268.701956) (xy 353.502169 -268.715648) (xy 353.453314 -268.72158) (xy 353.404139 -268.719599)
			(xy 353.35592 -268.709755) (xy 353.309904 -268.692303) (xy 353.267283 -268.667696) (xy 353.229162 -268.636571)
			(xy 353.196527 -268.599734) (xy 353.170224 -268.558138) (xy 353.150933 -268.512862) (xy 353.139156 -268.465078)
			(xy 353.135196 -268.416024) (xy 351.866454 -268.416024) (xy 351.865959 -268.440631) (xy 351.858064 -268.489208)
			(xy 351.84248 -268.535889) (xy 351.819609 -268.579466) (xy 351.790044 -268.61881) (xy 351.754551 -268.652902)
			(xy 351.714048 -268.680858) (xy 351.669586 -268.701956) (xy 351.622315 -268.715648) (xy 351.57346 -268.72158)
			(xy 351.524285 -268.719599) (xy 351.476066 -268.709755) (xy 351.43005 -268.692303) (xy 351.387429 -268.667696)
			(xy 351.349308 -268.636571) (xy 351.316673 -268.599734) (xy 351.29037 -268.558138) (xy 351.271079 -268.512862)
			(xy 351.259302 -268.465078) (xy 351.255342 -268.416024) (xy 349.986346 -268.416024) (xy 349.985851 -268.440631)
			(xy 349.977956 -268.489208) (xy 349.962372 -268.535889) (xy 349.939501 -268.579466) (xy 349.909936 -268.61881)
			(xy 349.874443 -268.652902) (xy 349.83394 -268.680858) (xy 349.789478 -268.701956) (xy 349.742207 -268.715648)
			(xy 349.693352 -268.72158) (xy 349.644177 -268.719599) (xy 349.595958 -268.709755) (xy 349.549942 -268.692303)
			(xy 349.507321 -268.667696) (xy 349.4692 -268.636571) (xy 349.436565 -268.599734) (xy 349.410262 -268.558138)
			(xy 349.390971 -268.512862) (xy 349.379194 -268.465078) (xy 349.375234 -268.416024) (xy 348.106492 -268.416024)
			(xy 348.105997 -268.440631) (xy 348.098102 -268.489208) (xy 348.082518 -268.535889) (xy 348.059647 -268.579466)
			(xy 348.030082 -268.61881) (xy 347.994589 -268.652902) (xy 347.954086 -268.680858) (xy 347.909624 -268.701956)
			(xy 347.862353 -268.715648) (xy 347.813498 -268.72158) (xy 347.764323 -268.719599) (xy 347.716104 -268.709755)
			(xy 347.670088 -268.692303) (xy 347.627467 -268.667696) (xy 347.589346 -268.636571) (xy 347.556711 -268.599734)
			(xy 347.530408 -268.558138) (xy 347.511117 -268.512862) (xy 347.49934 -268.465078) (xy 347.49538 -268.416024)
			(xy 346.473789 -268.416024) (xy 346.474034 -268.422882) (xy 346.474034 -268.423136) (xy 346.473132 -268.45616)
			(xy 346.464425 -268.521649) (xy 346.447976 -268.585634) (xy 346.424018 -268.647202) (xy 346.392894 -268.705477)
			(xy 346.355047 -268.759627) (xy 346.311017 -268.808881) (xy 346.26143 -268.852537) (xy 346.206995 -268.889973)
			(xy 346.148486 -268.920654) (xy 346.086738 -268.944145) (xy 346.02263 -268.960109) (xy 345.98991 -268.964664)
			(xy 345.97848 -268.966188) (xy 345.94546 -268.98727) (xy 345.937586 -268.995398) (xy 345.934538 -269.000224)
			(xy 345.905237 -269.046763) (xy 345.838823 -269.134428) (xy 345.80195 -269.17523) (xy 345.7956 -269.182088)
			(xy 345.781884 -269.216632) (xy 345.781884 -269.22603) (xy 347.025226 -269.22603) (xy 347.029186 -269.176976)
			(xy 347.040963 -269.129192) (xy 347.060254 -269.083916) (xy 347.086557 -269.04232) (xy 347.119192 -269.005483)
			(xy 347.157313 -268.974358) (xy 347.199934 -268.949751) (xy 347.24595 -268.932299) (xy 347.294169 -268.922455)
			(xy 347.343344 -268.920474) (xy 347.392199 -268.926406) (xy 347.43947 -268.940098) (xy 347.483932 -268.961196)
			(xy 347.524435 -268.989152) (xy 347.559928 -269.023244) (xy 347.589493 -269.062588) (xy 347.612364 -269.106165)
			(xy 347.627948 -269.152846) (xy 347.635843 -269.201423) (xy 347.636338 -269.22603) (xy 349.845388 -269.22603)
			(xy 349.849348 -269.176976) (xy 349.861125 -269.129192) (xy 349.880416 -269.083916) (xy 349.906719 -269.04232)
			(xy 349.939354 -269.005483) (xy 349.977475 -268.974358) (xy 350.020096 -268.949751) (xy 350.066112 -268.932299)
			(xy 350.114331 -268.922455) (xy 350.163506 -268.920474) (xy 350.212361 -268.926406) (xy 350.259632 -268.940098)
			(xy 350.304094 -268.961196) (xy 350.344597 -268.989152) (xy 350.38009 -269.023244) (xy 350.409655 -269.062588)
			(xy 350.432526 -269.106165) (xy 350.44811 -269.152846) (xy 350.456005 -269.201423) (xy 350.4565 -269.22603)
			(xy 352.665296 -269.22603) (xy 352.669256 -269.176976) (xy 352.681033 -269.129192) (xy 352.700324 -269.083916)
			(xy 352.726627 -269.04232) (xy 352.759262 -269.005483) (xy 352.797383 -268.974358) (xy 352.840004 -268.949751)
			(xy 352.88602 -268.932299) (xy 352.934239 -268.922455) (xy 352.983414 -268.920474) (xy 353.032269 -268.926406)
			(xy 353.07954 -268.940098) (xy 353.124002 -268.961196) (xy 353.164505 -268.989152) (xy 353.199998 -269.023244)
			(xy 353.229563 -269.062588) (xy 353.252434 -269.106165) (xy 353.268018 -269.152846) (xy 353.275913 -269.201423)
			(xy 353.276408 -269.22603) (xy 355.485204 -269.22603) (xy 355.489164 -269.176976) (xy 355.500941 -269.129192)
			(xy 355.520232 -269.083916) (xy 355.546535 -269.04232) (xy 355.57917 -269.005483) (xy 355.617291 -268.974358)
			(xy 355.659912 -268.949751) (xy 355.705928 -268.932299) (xy 355.754147 -268.922455) (xy 355.803322 -268.920474)
			(xy 355.852177 -268.926406) (xy 355.899448 -268.940098) (xy 355.94391 -268.961196) (xy 355.984413 -268.989152)
			(xy 356.019906 -269.023244) (xy 356.049471 -269.062588) (xy 356.072342 -269.106165) (xy 356.087926 -269.152846)
			(xy 356.095821 -269.201423) (xy 356.096316 -269.22603) (xy 356.425258 -269.22603) (xy 356.429218 -269.176976)
			(xy 356.440995 -269.129192) (xy 356.460286 -269.083916) (xy 356.486589 -269.04232) (xy 356.519224 -269.005483)
			(xy 356.557345 -268.974358) (xy 356.599966 -268.949751) (xy 356.645982 -268.932299) (xy 356.694201 -268.922455)
			(xy 356.743376 -268.920474) (xy 356.792231 -268.926406) (xy 356.839502 -268.940098) (xy 356.883964 -268.961196)
			(xy 356.924467 -268.989152) (xy 356.95996 -269.023244) (xy 356.989525 -269.062588) (xy 357.012396 -269.106165)
			(xy 357.02798 -269.152846) (xy 357.035875 -269.201423) (xy 357.03637 -269.22603) (xy 357.365312 -269.22603)
			(xy 357.369272 -269.176976) (xy 357.381049 -269.129192) (xy 357.40034 -269.083916) (xy 357.426643 -269.04232)
			(xy 357.459278 -269.005483) (xy 357.497399 -268.974358) (xy 357.54002 -268.949751) (xy 357.586036 -268.932299)
			(xy 357.634255 -268.922455) (xy 357.68343 -268.920474) (xy 357.732285 -268.926406) (xy 357.779556 -268.940098)
			(xy 357.824018 -268.961196) (xy 357.864521 -268.989152) (xy 357.900014 -269.023244) (xy 357.929579 -269.062588)
			(xy 357.95245 -269.106165) (xy 357.968034 -269.152846) (xy 357.975929 -269.201423) (xy 357.976424 -269.22603)
			(xy 358.305366 -269.22603) (xy 358.309326 -269.176976) (xy 358.321103 -269.129192) (xy 358.340394 -269.083916)
			(xy 358.366697 -269.04232) (xy 358.399332 -269.005483) (xy 358.437453 -268.974358) (xy 358.480074 -268.949751)
			(xy 358.52609 -268.932299) (xy 358.574309 -268.922455) (xy 358.623484 -268.920474) (xy 358.672339 -268.926406)
			(xy 358.71961 -268.940098) (xy 358.764072 -268.961196) (xy 358.804575 -268.989152) (xy 358.840068 -269.023244)
			(xy 358.869633 -269.062588) (xy 358.892504 -269.106165) (xy 358.908088 -269.152846) (xy 358.915983 -269.201423)
			(xy 358.916478 -269.22603) (xy 361.118924 -269.22603) (xy 361.122884 -269.176976) (xy 361.134661 -269.129192)
			(xy 361.153952 -269.083916) (xy 361.180255 -269.04232) (xy 361.21289 -269.005483) (xy 361.251011 -268.974358)
			(xy 361.293632 -268.949751) (xy 361.339648 -268.932299) (xy 361.387867 -268.922455) (xy 361.437042 -268.920474)
			(xy 361.485897 -268.926406) (xy 361.533168 -268.940098) (xy 361.57763 -268.961196) (xy 361.618133 -268.989152)
			(xy 361.653626 -269.023244) (xy 361.683191 -269.062588) (xy 361.706062 -269.106165) (xy 361.721646 -269.152846)
			(xy 361.729541 -269.201423) (xy 361.730036 -269.22603) (xy 362.058978 -269.22603) (xy 362.062938 -269.176976)
			(xy 362.074715 -269.129192) (xy 362.094006 -269.083916) (xy 362.120309 -269.04232) (xy 362.152944 -269.005483)
			(xy 362.191065 -268.974358) (xy 362.233686 -268.949751) (xy 362.279702 -268.932299) (xy 362.327921 -268.922455)
			(xy 362.377096 -268.920474) (xy 362.425951 -268.926406) (xy 362.473222 -268.940098) (xy 362.517684 -268.961196)
			(xy 362.558187 -268.989152) (xy 362.59368 -269.023244) (xy 362.623245 -269.062588) (xy 362.646116 -269.106165)
			(xy 362.6617 -269.152846) (xy 362.669595 -269.201423) (xy 362.67009 -269.22603) (xy 362.999032 -269.22603)
			(xy 363.002992 -269.176976) (xy 363.014769 -269.129192) (xy 363.03406 -269.083916) (xy 363.060363 -269.04232)
			(xy 363.092998 -269.005483) (xy 363.131119 -268.974358) (xy 363.17374 -268.949751) (xy 363.219756 -268.932299)
			(xy 363.267975 -268.922455) (xy 363.31715 -268.920474) (xy 363.366005 -268.926406) (xy 363.413276 -268.940098)
			(xy 363.457738 -268.961196) (xy 363.498241 -268.989152) (xy 363.533734 -269.023244) (xy 363.563299 -269.062588)
			(xy 363.58617 -269.106165) (xy 363.601754 -269.152846) (xy 363.609649 -269.201423) (xy 363.610144 -269.22603)
			(xy 363.939086 -269.22603) (xy 363.943046 -269.176976) (xy 363.954823 -269.129192) (xy 363.974114 -269.083916)
			(xy 364.000417 -269.04232) (xy 364.033052 -269.005483) (xy 364.071173 -268.974358) (xy 364.113794 -268.949751)
			(xy 364.15981 -268.932299) (xy 364.208029 -268.922455) (xy 364.257204 -268.920474) (xy 364.306059 -268.926406)
			(xy 364.35333 -268.940098) (xy 364.397792 -268.961196) (xy 364.438295 -268.989152) (xy 364.473788 -269.023244)
			(xy 364.503353 -269.062588) (xy 364.526224 -269.106165) (xy 364.541808 -269.152846) (xy 364.549703 -269.201423)
			(xy 364.550198 -269.22603) (xy 366.758994 -269.22603) (xy 366.762954 -269.176976) (xy 366.774731 -269.129192)
			(xy 366.794022 -269.083916) (xy 366.820325 -269.04232) (xy 366.85296 -269.005483) (xy 366.891081 -268.974358)
			(xy 366.933702 -268.949751) (xy 366.979718 -268.932299) (xy 367.027937 -268.922455) (xy 367.077112 -268.920474)
			(xy 367.125967 -268.926406) (xy 367.173238 -268.940098) (xy 367.2177 -268.961196) (xy 367.258203 -268.989152)
			(xy 367.293696 -269.023244) (xy 367.323261 -269.062588) (xy 367.346132 -269.106165) (xy 367.361716 -269.152846)
			(xy 367.369611 -269.201423) (xy 367.370106 -269.22603) (xy 369.578902 -269.22603) (xy 369.582862 -269.176976)
			(xy 369.594639 -269.129192) (xy 369.61393 -269.083916) (xy 369.640233 -269.04232) (xy 369.672868 -269.005483)
			(xy 369.710989 -268.974358) (xy 369.75361 -268.949751) (xy 369.799626 -268.932299) (xy 369.847845 -268.922455)
			(xy 369.89702 -268.920474) (xy 369.945875 -268.926406) (xy 369.993146 -268.940098) (xy 370.037608 -268.961196)
			(xy 370.078111 -268.989152) (xy 370.113604 -269.023244) (xy 370.143169 -269.062588) (xy 370.16604 -269.106165)
			(xy 370.181624 -269.152846) (xy 370.189519 -269.201423) (xy 370.190014 -269.22603) (xy 372.399064 -269.22603)
			(xy 372.403024 -269.176976) (xy 372.414801 -269.129192) (xy 372.434092 -269.083916) (xy 372.460395 -269.04232)
			(xy 372.49303 -269.005483) (xy 372.531151 -268.974358) (xy 372.573772 -268.949751) (xy 372.619788 -268.932299)
			(xy 372.668007 -268.922455) (xy 372.717182 -268.920474) (xy 372.766037 -268.926406) (xy 372.813308 -268.940098)
			(xy 372.85777 -268.961196) (xy 372.898273 -268.989152) (xy 372.933766 -269.023244) (xy 372.963331 -269.062588)
			(xy 372.986202 -269.106165) (xy 373.001786 -269.152846) (xy 373.009681 -269.201423) (xy 373.010176 -269.22603)
			(xy 373.009681 -269.250637) (xy 373.001786 -269.299214) (xy 372.986202 -269.345895) (xy 372.963331 -269.389472)
			(xy 372.933766 -269.428816) (xy 372.898273 -269.462908) (xy 372.85777 -269.490864) (xy 372.813308 -269.511962)
			(xy 372.766037 -269.525654) (xy 372.717182 -269.531586) (xy 372.668007 -269.529605) (xy 372.619788 -269.519761)
			(xy 372.573772 -269.502309) (xy 372.531151 -269.477702) (xy 372.49303 -269.446577) (xy 372.460395 -269.40974)
			(xy 372.434092 -269.368144) (xy 372.414801 -269.322868) (xy 372.403024 -269.275084) (xy 372.399064 -269.22603)
			(xy 370.190014 -269.22603) (xy 370.189519 -269.250637) (xy 370.181624 -269.299214) (xy 370.16604 -269.345895)
			(xy 370.143169 -269.389472) (xy 370.113604 -269.428816) (xy 370.078111 -269.462908) (xy 370.037608 -269.490864)
			(xy 369.993146 -269.511962) (xy 369.945875 -269.525654) (xy 369.89702 -269.531586) (xy 369.847845 -269.529605)
			(xy 369.799626 -269.519761) (xy 369.75361 -269.502309) (xy 369.710989 -269.477702) (xy 369.672868 -269.446577)
			(xy 369.640233 -269.40974) (xy 369.61393 -269.368144) (xy 369.594639 -269.322868) (xy 369.582862 -269.275084)
			(xy 369.578902 -269.22603) (xy 367.370106 -269.22603) (xy 367.369611 -269.250637) (xy 367.361716 -269.299214)
			(xy 367.346132 -269.345895) (xy 367.323261 -269.389472) (xy 367.293696 -269.428816) (xy 367.258203 -269.462908)
			(xy 367.2177 -269.490864) (xy 367.173238 -269.511962) (xy 367.125967 -269.525654) (xy 367.077112 -269.531586)
			(xy 367.027937 -269.529605) (xy 366.979718 -269.519761) (xy 366.933702 -269.502309) (xy 366.891081 -269.477702)
			(xy 366.85296 -269.446577) (xy 366.820325 -269.40974) (xy 366.794022 -269.368144) (xy 366.774731 -269.322868)
			(xy 366.762954 -269.275084) (xy 366.758994 -269.22603) (xy 364.550198 -269.22603) (xy 364.549703 -269.250637)
			(xy 364.541808 -269.299214) (xy 364.526224 -269.345895) (xy 364.503353 -269.389472) (xy 364.473788 -269.428816)
			(xy 364.438295 -269.462908) (xy 364.397792 -269.490864) (xy 364.35333 -269.511962) (xy 364.306059 -269.525654)
			(xy 364.257204 -269.531586) (xy 364.208029 -269.529605) (xy 364.15981 -269.519761) (xy 364.113794 -269.502309)
			(xy 364.071173 -269.477702) (xy 364.033052 -269.446577) (xy 364.000417 -269.40974) (xy 363.974114 -269.368144)
			(xy 363.954823 -269.322868) (xy 363.943046 -269.275084) (xy 363.939086 -269.22603) (xy 363.610144 -269.22603)
			(xy 363.609649 -269.250637) (xy 363.601754 -269.299214) (xy 363.58617 -269.345895) (xy 363.563299 -269.389472)
			(xy 363.533734 -269.428816) (xy 363.498241 -269.462908) (xy 363.457738 -269.490864) (xy 363.413276 -269.511962)
			(xy 363.366005 -269.525654) (xy 363.31715 -269.531586) (xy 363.267975 -269.529605) (xy 363.219756 -269.519761)
			(xy 363.17374 -269.502309) (xy 363.131119 -269.477702) (xy 363.092998 -269.446577) (xy 363.060363 -269.40974)
			(xy 363.03406 -269.368144) (xy 363.014769 -269.322868) (xy 363.002992 -269.275084) (xy 362.999032 -269.22603)
			(xy 362.67009 -269.22603) (xy 362.669595 -269.250637) (xy 362.6617 -269.299214) (xy 362.646116 -269.345895)
			(xy 362.623245 -269.389472) (xy 362.59368 -269.428816) (xy 362.558187 -269.462908) (xy 362.517684 -269.490864)
			(xy 362.473222 -269.511962) (xy 362.425951 -269.525654) (xy 362.377096 -269.531586) (xy 362.327921 -269.529605)
			(xy 362.279702 -269.519761) (xy 362.233686 -269.502309) (xy 362.191065 -269.477702) (xy 362.152944 -269.446577)
			(xy 362.120309 -269.40974) (xy 362.094006 -269.368144) (xy 362.074715 -269.322868) (xy 362.062938 -269.275084)
			(xy 362.058978 -269.22603) (xy 361.730036 -269.22603) (xy 361.729541 -269.250637) (xy 361.721646 -269.299214)
			(xy 361.706062 -269.345895) (xy 361.683191 -269.389472) (xy 361.653626 -269.428816) (xy 361.618133 -269.462908)
			(xy 361.57763 -269.490864) (xy 361.533168 -269.511962) (xy 361.485897 -269.525654) (xy 361.437042 -269.531586)
			(xy 361.387867 -269.529605) (xy 361.339648 -269.519761) (xy 361.293632 -269.502309) (xy 361.251011 -269.477702)
			(xy 361.21289 -269.446577) (xy 361.180255 -269.40974) (xy 361.153952 -269.368144) (xy 361.134661 -269.322868)
			(xy 361.122884 -269.275084) (xy 361.118924 -269.22603) (xy 358.916478 -269.22603) (xy 358.915983 -269.250637)
			(xy 358.908088 -269.299214) (xy 358.892504 -269.345895) (xy 358.869633 -269.389472) (xy 358.840068 -269.428816)
			(xy 358.804575 -269.462908) (xy 358.764072 -269.490864) (xy 358.71961 -269.511962) (xy 358.672339 -269.525654)
			(xy 358.623484 -269.531586) (xy 358.574309 -269.529605) (xy 358.52609 -269.519761) (xy 358.480074 -269.502309)
			(xy 358.437453 -269.477702) (xy 358.399332 -269.446577) (xy 358.366697 -269.40974) (xy 358.340394 -269.368144)
			(xy 358.321103 -269.322868) (xy 358.309326 -269.275084) (xy 358.305366 -269.22603) (xy 357.976424 -269.22603)
			(xy 357.975929 -269.250637) (xy 357.968034 -269.299214) (xy 357.95245 -269.345895) (xy 357.929579 -269.389472)
			(xy 357.900014 -269.428816) (xy 357.864521 -269.462908) (xy 357.824018 -269.490864) (xy 357.779556 -269.511962)
			(xy 357.732285 -269.525654) (xy 357.68343 -269.531586) (xy 357.634255 -269.529605) (xy 357.586036 -269.519761)
			(xy 357.54002 -269.502309) (xy 357.497399 -269.477702) (xy 357.459278 -269.446577) (xy 357.426643 -269.40974)
			(xy 357.40034 -269.368144) (xy 357.381049 -269.322868) (xy 357.369272 -269.275084) (xy 357.365312 -269.22603)
			(xy 357.03637 -269.22603) (xy 357.035875 -269.250637) (xy 357.02798 -269.299214) (xy 357.012396 -269.345895)
			(xy 356.989525 -269.389472) (xy 356.95996 -269.428816) (xy 356.924467 -269.462908) (xy 356.883964 -269.490864)
			(xy 356.839502 -269.511962) (xy 356.792231 -269.525654) (xy 356.743376 -269.531586) (xy 356.694201 -269.529605)
			(xy 356.645982 -269.519761) (xy 356.599966 -269.502309) (xy 356.557345 -269.477702) (xy 356.519224 -269.446577)
			(xy 356.486589 -269.40974) (xy 356.460286 -269.368144) (xy 356.440995 -269.322868) (xy 356.429218 -269.275084)
			(xy 356.425258 -269.22603) (xy 356.096316 -269.22603) (xy 356.095821 -269.250637) (xy 356.087926 -269.299214)
			(xy 356.072342 -269.345895) (xy 356.049471 -269.389472) (xy 356.019906 -269.428816) (xy 355.984413 -269.462908)
			(xy 355.94391 -269.490864) (xy 355.899448 -269.511962) (xy 355.852177 -269.525654) (xy 355.803322 -269.531586)
			(xy 355.754147 -269.529605) (xy 355.705928 -269.519761) (xy 355.659912 -269.502309) (xy 355.617291 -269.477702)
			(xy 355.57917 -269.446577) (xy 355.546535 -269.40974) (xy 355.520232 -269.368144) (xy 355.500941 -269.322868)
			(xy 355.489164 -269.275084) (xy 355.485204 -269.22603) (xy 353.276408 -269.22603) (xy 353.275913 -269.250637)
			(xy 353.268018 -269.299214) (xy 353.252434 -269.345895) (xy 353.229563 -269.389472) (xy 353.199998 -269.428816)
			(xy 353.164505 -269.462908) (xy 353.124002 -269.490864) (xy 353.07954 -269.511962) (xy 353.032269 -269.525654)
			(xy 352.983414 -269.531586) (xy 352.934239 -269.529605) (xy 352.88602 -269.519761) (xy 352.840004 -269.502309)
			(xy 352.797383 -269.477702) (xy 352.759262 -269.446577) (xy 352.726627 -269.40974) (xy 352.700324 -269.368144)
			(xy 352.681033 -269.322868) (xy 352.669256 -269.275084) (xy 352.665296 -269.22603) (xy 350.4565 -269.22603)
			(xy 350.456005 -269.250637) (xy 350.44811 -269.299214) (xy 350.432526 -269.345895) (xy 350.409655 -269.389472)
			(xy 350.38009 -269.428816) (xy 350.344597 -269.462908) (xy 350.304094 -269.490864) (xy 350.259632 -269.511962)
			(xy 350.212361 -269.525654) (xy 350.163506 -269.531586) (xy 350.114331 -269.529605) (xy 350.066112 -269.519761)
			(xy 350.020096 -269.502309) (xy 349.977475 -269.477702) (xy 349.939354 -269.446577) (xy 349.906719 -269.40974)
			(xy 349.880416 -269.368144) (xy 349.861125 -269.322868) (xy 349.849348 -269.275084) (xy 349.845388 -269.22603)
			(xy 347.636338 -269.22603) (xy 347.635843 -269.250637) (xy 347.627948 -269.299214) (xy 347.612364 -269.345895)
			(xy 347.589493 -269.389472) (xy 347.559928 -269.428816) (xy 347.524435 -269.462908) (xy 347.483932 -269.490864)
			(xy 347.43947 -269.511962) (xy 347.392199 -269.525654) (xy 347.343344 -269.531586) (xy 347.294169 -269.529605)
			(xy 347.24595 -269.519761) (xy 347.199934 -269.502309) (xy 347.157313 -269.477702) (xy 347.119192 -269.446577)
			(xy 347.086557 -269.40974) (xy 347.060254 -269.368144) (xy 347.040963 -269.322868) (xy 347.029186 -269.275084)
			(xy 347.025226 -269.22603) (xy 345.781884 -269.22603) (xy 345.781884 -269.226284) (xy 345.781421 -269.251169)
			(xy 345.773937 -269.300375) (xy 345.759165 -269.347903) (xy 345.73744 -269.392682) (xy 345.709251 -269.433701)
			(xy 345.675235 -269.470034) (xy 345.636159 -269.50086) (xy 345.614752 -269.513558) (xy 345.606624 -269.51813)
			(xy 345.58224 -269.547848) (xy 345.579192 -269.5575) (xy 345.565355 -269.600669) (xy 345.531624 -269.68482)
			(xy 345.491194 -269.765965) (xy 345.44433 -269.843573) (xy 345.39134 -269.917134) (xy 345.33257 -269.986166)
			(xy 345.300808 -270.01851) (xy 345.294463 -270.025402) (xy 345.289669 -270.036036) (xy 345.615272 -270.036036)
			(xy 345.619232 -269.986982) (xy 345.631009 -269.939198) (xy 345.6503 -269.893922) (xy 345.676603 -269.852326)
			(xy 345.709238 -269.815489) (xy 345.747359 -269.784364) (xy 345.78998 -269.759757) (xy 345.835996 -269.742305)
			(xy 345.884215 -269.732461) (xy 345.93339 -269.73048) (xy 345.982245 -269.736412) (xy 346.029516 -269.750104)
			(xy 346.073978 -269.771202) (xy 346.114481 -269.799158) (xy 346.149974 -269.83325) (xy 346.179539 -269.872594)
			(xy 346.20241 -269.916171) (xy 346.217994 -269.962852) (xy 346.225889 -270.011429) (xy 346.226384 -270.036036)
			(xy 346.555326 -270.036036) (xy 346.559286 -269.986982) (xy 346.571063 -269.939198) (xy 346.590354 -269.893922)
			(xy 346.616657 -269.852326) (xy 346.649292 -269.815489) (xy 346.687413 -269.784364) (xy 346.730034 -269.759757)
			(xy 346.77605 -269.742305) (xy 346.824269 -269.732461) (xy 346.873444 -269.73048) (xy 346.922299 -269.736412)
			(xy 346.96957 -269.750104) (xy 347.014032 -269.771202) (xy 347.054535 -269.799158) (xy 347.090028 -269.83325)
			(xy 347.119593 -269.872594) (xy 347.142464 -269.916171) (xy 347.158048 -269.962852) (xy 347.165943 -270.011429)
			(xy 347.166438 -270.036036) (xy 347.49538 -270.036036) (xy 347.49934 -269.986982) (xy 347.511117 -269.939198)
			(xy 347.530408 -269.893922) (xy 347.556711 -269.852326) (xy 347.589346 -269.815489) (xy 347.627467 -269.784364)
			(xy 347.670088 -269.759757) (xy 347.716104 -269.742305) (xy 347.764323 -269.732461) (xy 347.813498 -269.73048)
			(xy 347.862353 -269.736412) (xy 347.909624 -269.750104) (xy 347.954086 -269.771202) (xy 347.994589 -269.799158)
			(xy 348.030082 -269.83325) (xy 348.059647 -269.872594) (xy 348.082518 -269.916171) (xy 348.098102 -269.962852)
			(xy 348.105997 -270.011429) (xy 348.106492 -270.036036) (xy 348.435434 -270.036036) (xy 348.439394 -269.986982)
			(xy 348.451171 -269.939198) (xy 348.470462 -269.893922) (xy 348.496765 -269.852326) (xy 348.5294 -269.815489)
			(xy 348.567521 -269.784364) (xy 348.610142 -269.759757) (xy 348.656158 -269.742305) (xy 348.704377 -269.732461)
			(xy 348.753552 -269.73048) (xy 348.802407 -269.736412) (xy 348.849678 -269.750104) (xy 348.89414 -269.771202)
			(xy 348.934643 -269.799158) (xy 348.970136 -269.83325) (xy 348.999701 -269.872594) (xy 349.022572 -269.916171)
			(xy 349.038156 -269.962852) (xy 349.046051 -270.011429) (xy 349.046546 -270.036036) (xy 349.375234 -270.036036)
			(xy 349.379194 -269.986982) (xy 349.390971 -269.939198) (xy 349.410262 -269.893922) (xy 349.436565 -269.852326)
			(xy 349.4692 -269.815489) (xy 349.507321 -269.784364) (xy 349.549942 -269.759757) (xy 349.595958 -269.742305)
			(xy 349.644177 -269.732461) (xy 349.693352 -269.73048) (xy 349.742207 -269.736412) (xy 349.789478 -269.750104)
			(xy 349.83394 -269.771202) (xy 349.874443 -269.799158) (xy 349.909936 -269.83325) (xy 349.939501 -269.872594)
			(xy 349.962372 -269.916171) (xy 349.977956 -269.962852) (xy 349.985851 -270.011429) (xy 349.986346 -270.036036)
			(xy 350.315288 -270.036036) (xy 350.319248 -269.986982) (xy 350.331025 -269.939198) (xy 350.350316 -269.893922)
			(xy 350.376619 -269.852326) (xy 350.409254 -269.815489) (xy 350.447375 -269.784364) (xy 350.489996 -269.759757)
			(xy 350.536012 -269.742305) (xy 350.584231 -269.732461) (xy 350.633406 -269.73048) (xy 350.682261 -269.736412)
			(xy 350.729532 -269.750104) (xy 350.773994 -269.771202) (xy 350.814497 -269.799158) (xy 350.84999 -269.83325)
			(xy 350.879555 -269.872594) (xy 350.902426 -269.916171) (xy 350.91801 -269.962852) (xy 350.925905 -270.011429)
			(xy 350.9264 -270.036036) (xy 351.255342 -270.036036) (xy 351.259302 -269.986982) (xy 351.271079 -269.939198)
			(xy 351.29037 -269.893922) (xy 351.316673 -269.852326) (xy 351.349308 -269.815489) (xy 351.387429 -269.784364)
			(xy 351.43005 -269.759757) (xy 351.476066 -269.742305) (xy 351.524285 -269.732461) (xy 351.57346 -269.73048)
			(xy 351.622315 -269.736412) (xy 351.669586 -269.750104) (xy 351.714048 -269.771202) (xy 351.754551 -269.799158)
			(xy 351.790044 -269.83325) (xy 351.819609 -269.872594) (xy 351.84248 -269.916171) (xy 351.858064 -269.962852)
			(xy 351.865959 -270.011429) (xy 351.866454 -270.036036) (xy 352.195396 -270.036036) (xy 352.199356 -269.986982)
			(xy 352.211133 -269.939198) (xy 352.230424 -269.893922) (xy 352.256727 -269.852326) (xy 352.289362 -269.815489)
			(xy 352.327483 -269.784364) (xy 352.370104 -269.759757) (xy 352.41612 -269.742305) (xy 352.464339 -269.732461)
			(xy 352.513514 -269.73048) (xy 352.562369 -269.736412) (xy 352.60964 -269.750104) (xy 352.654102 -269.771202)
			(xy 352.694605 -269.799158) (xy 352.730098 -269.83325) (xy 352.759663 -269.872594) (xy 352.782534 -269.916171)
			(xy 352.798118 -269.962852) (xy 352.806013 -270.011429) (xy 352.806508 -270.036036) (xy 353.135196 -270.036036)
			(xy 353.139156 -269.986982) (xy 353.150933 -269.939198) (xy 353.170224 -269.893922) (xy 353.196527 -269.852326)
			(xy 353.229162 -269.815489) (xy 353.267283 -269.784364) (xy 353.309904 -269.759757) (xy 353.35592 -269.742305)
			(xy 353.404139 -269.732461) (xy 353.453314 -269.73048) (xy 353.502169 -269.736412) (xy 353.54944 -269.750104)
			(xy 353.593902 -269.771202) (xy 353.634405 -269.799158) (xy 353.669898 -269.83325) (xy 353.699463 -269.872594)
			(xy 353.722334 -269.916171) (xy 353.737918 -269.962852) (xy 353.745813 -270.011429) (xy 353.746308 -270.036036)
			(xy 354.07525 -270.036036) (xy 354.07921 -269.986982) (xy 354.090987 -269.939198) (xy 354.110278 -269.893922)
			(xy 354.136581 -269.852326) (xy 354.169216 -269.815489) (xy 354.207337 -269.784364) (xy 354.249958 -269.759757)
			(xy 354.295974 -269.742305) (xy 354.344193 -269.732461) (xy 354.393368 -269.73048) (xy 354.442223 -269.736412)
			(xy 354.489494 -269.750104) (xy 354.533956 -269.771202) (xy 354.574459 -269.799158) (xy 354.609952 -269.83325)
			(xy 354.639517 -269.872594) (xy 354.662388 -269.916171) (xy 354.677972 -269.962852) (xy 354.685867 -270.011429)
			(xy 354.686362 -270.036036) (xy 355.015304 -270.036036) (xy 355.019264 -269.986982) (xy 355.031041 -269.939198)
			(xy 355.050332 -269.893922) (xy 355.076635 -269.852326) (xy 355.10927 -269.815489) (xy 355.147391 -269.784364)
			(xy 355.190012 -269.759757) (xy 355.236028 -269.742305) (xy 355.284247 -269.732461) (xy 355.333422 -269.73048)
			(xy 355.382277 -269.736412) (xy 355.429548 -269.750104) (xy 355.47401 -269.771202) (xy 355.514513 -269.799158)
			(xy 355.550006 -269.83325) (xy 355.579571 -269.872594) (xy 355.602442 -269.916171) (xy 355.618026 -269.962852)
			(xy 355.625921 -270.011429) (xy 355.626416 -270.036036) (xy 355.955358 -270.036036) (xy 355.959318 -269.986982)
			(xy 355.971095 -269.939198) (xy 355.990386 -269.893922) (xy 356.016689 -269.852326) (xy 356.049324 -269.815489)
			(xy 356.087445 -269.784364) (xy 356.130066 -269.759757) (xy 356.176082 -269.742305) (xy 356.224301 -269.732461)
			(xy 356.273476 -269.73048) (xy 356.322331 -269.736412) (xy 356.369602 -269.750104) (xy 356.414064 -269.771202)
			(xy 356.454567 -269.799158) (xy 356.49006 -269.83325) (xy 356.519625 -269.872594) (xy 356.542496 -269.916171)
			(xy 356.55808 -269.962852) (xy 356.565975 -270.011429) (xy 356.56647 -270.036036) (xy 356.895412 -270.036036)
			(xy 356.899372 -269.986982) (xy 356.911149 -269.939198) (xy 356.93044 -269.893922) (xy 356.956743 -269.852326)
			(xy 356.989378 -269.815489) (xy 357.027499 -269.784364) (xy 357.07012 -269.759757) (xy 357.116136 -269.742305)
			(xy 357.164355 -269.732461) (xy 357.21353 -269.73048) (xy 357.262385 -269.736412) (xy 357.309656 -269.750104)
			(xy 357.354118 -269.771202) (xy 357.394621 -269.799158) (xy 357.430114 -269.83325) (xy 357.459679 -269.872594)
			(xy 357.48255 -269.916171) (xy 357.498134 -269.962852) (xy 357.506029 -270.011429) (xy 357.506524 -270.036036)
			(xy 357.835212 -270.036036) (xy 357.839172 -269.986982) (xy 357.850949 -269.939198) (xy 357.87024 -269.893922)
			(xy 357.896543 -269.852326) (xy 357.929178 -269.815489) (xy 357.967299 -269.784364) (xy 358.00992 -269.759757)
			(xy 358.055936 -269.742305) (xy 358.104155 -269.732461) (xy 358.15333 -269.73048) (xy 358.202185 -269.736412)
			(xy 358.249456 -269.750104) (xy 358.293918 -269.771202) (xy 358.334421 -269.799158) (xy 358.369914 -269.83325)
			(xy 358.399479 -269.872594) (xy 358.42235 -269.916171) (xy 358.437934 -269.962852) (xy 358.445829 -270.011429)
			(xy 358.446324 -270.036036) (xy 361.589078 -270.036036) (xy 361.593038 -269.986982) (xy 361.604815 -269.939198)
			(xy 361.624106 -269.893922) (xy 361.650409 -269.852326) (xy 361.683044 -269.815489) (xy 361.721165 -269.784364)
			(xy 361.763786 -269.759757) (xy 361.809802 -269.742305) (xy 361.858021 -269.732461) (xy 361.907196 -269.73048)
			(xy 361.956051 -269.736412) (xy 362.003322 -269.750104) (xy 362.047784 -269.771202) (xy 362.088287 -269.799158)
			(xy 362.12378 -269.83325) (xy 362.153345 -269.872594) (xy 362.176216 -269.916171) (xy 362.1918 -269.962852)
			(xy 362.199695 -270.011429) (xy 362.20019 -270.036036) (xy 362.528878 -270.036036) (xy 362.532838 -269.986982)
			(xy 362.544615 -269.939198) (xy 362.563906 -269.893922) (xy 362.590209 -269.852326) (xy 362.622844 -269.815489)
			(xy 362.660965 -269.784364) (xy 362.703586 -269.759757) (xy 362.749602 -269.742305) (xy 362.797821 -269.732461)
			(xy 362.846996 -269.73048) (xy 362.895851 -269.736412) (xy 362.943122 -269.750104) (xy 362.987584 -269.771202)
			(xy 363.028087 -269.799158) (xy 363.06358 -269.83325) (xy 363.093145 -269.872594) (xy 363.116016 -269.916171)
			(xy 363.1316 -269.962852) (xy 363.139495 -270.011429) (xy 363.13999 -270.036036) (xy 363.468932 -270.036036)
			(xy 363.472892 -269.986982) (xy 363.484669 -269.939198) (xy 363.50396 -269.893922) (xy 363.530263 -269.852326)
			(xy 363.562898 -269.815489) (xy 363.601019 -269.784364) (xy 363.64364 -269.759757) (xy 363.689656 -269.742305)
			(xy 363.737875 -269.732461) (xy 363.78705 -269.73048) (xy 363.835905 -269.736412) (xy 363.883176 -269.750104)
			(xy 363.927638 -269.771202) (xy 363.968141 -269.799158) (xy 364.003634 -269.83325) (xy 364.033199 -269.872594)
			(xy 364.05607 -269.916171) (xy 364.071654 -269.962852) (xy 364.079549 -270.011429) (xy 364.080044 -270.036036)
			(xy 364.408986 -270.036036) (xy 364.412946 -269.986982) (xy 364.424723 -269.939198) (xy 364.444014 -269.893922)
			(xy 364.470317 -269.852326) (xy 364.502952 -269.815489) (xy 364.541073 -269.784364) (xy 364.583694 -269.759757)
			(xy 364.62971 -269.742305) (xy 364.677929 -269.732461) (xy 364.727104 -269.73048) (xy 364.775959 -269.736412)
			(xy 364.82323 -269.750104) (xy 364.867692 -269.771202) (xy 364.908195 -269.799158) (xy 364.943688 -269.83325)
			(xy 364.973253 -269.872594) (xy 364.996124 -269.916171) (xy 365.011708 -269.962852) (xy 365.019603 -270.011429)
			(xy 365.020098 -270.036036) (xy 365.34904 -270.036036) (xy 365.353 -269.986982) (xy 365.364777 -269.939198)
			(xy 365.384068 -269.893922) (xy 365.410371 -269.852326) (xy 365.443006 -269.815489) (xy 365.481127 -269.784364)
			(xy 365.523748 -269.759757) (xy 365.569764 -269.742305) (xy 365.617983 -269.732461) (xy 365.667158 -269.73048)
			(xy 365.716013 -269.736412) (xy 365.763284 -269.750104) (xy 365.807746 -269.771202) (xy 365.848249 -269.799158)
			(xy 365.883742 -269.83325) (xy 365.913307 -269.872594) (xy 365.936178 -269.916171) (xy 365.951762 -269.962852)
			(xy 365.959657 -270.011429) (xy 365.960152 -270.036036) (xy 366.289094 -270.036036) (xy 366.293054 -269.986982)
			(xy 366.304831 -269.939198) (xy 366.324122 -269.893922) (xy 366.350425 -269.852326) (xy 366.38306 -269.815489)
			(xy 366.421181 -269.784364) (xy 366.463802 -269.759757) (xy 366.509818 -269.742305) (xy 366.558037 -269.732461)
			(xy 366.607212 -269.73048) (xy 366.656067 -269.736412) (xy 366.703338 -269.750104) (xy 366.7478 -269.771202)
			(xy 366.788303 -269.799158) (xy 366.823796 -269.83325) (xy 366.853361 -269.872594) (xy 366.876232 -269.916171)
			(xy 366.891816 -269.962852) (xy 366.899711 -270.011429) (xy 366.900206 -270.036036) (xy 367.228894 -270.036036)
			(xy 367.232854 -269.986982) (xy 367.244631 -269.939198) (xy 367.263922 -269.893922) (xy 367.290225 -269.852326)
			(xy 367.32286 -269.815489) (xy 367.360981 -269.784364) (xy 367.403602 -269.759757) (xy 367.449618 -269.742305)
			(xy 367.497837 -269.732461) (xy 367.547012 -269.73048) (xy 367.595867 -269.736412) (xy 367.643138 -269.750104)
			(xy 367.6876 -269.771202) (xy 367.728103 -269.799158) (xy 367.763596 -269.83325) (xy 367.793161 -269.872594)
			(xy 367.816032 -269.916171) (xy 367.831616 -269.962852) (xy 367.839511 -270.011429) (xy 367.840006 -270.036036)
			(xy 368.168948 -270.036036) (xy 368.172908 -269.986982) (xy 368.184685 -269.939198) (xy 368.203976 -269.893922)
			(xy 368.230279 -269.852326) (xy 368.262914 -269.815489) (xy 368.301035 -269.784364) (xy 368.343656 -269.759757)
			(xy 368.389672 -269.742305) (xy 368.437891 -269.732461) (xy 368.487066 -269.73048) (xy 368.535921 -269.736412)
			(xy 368.583192 -269.750104) (xy 368.627654 -269.771202) (xy 368.668157 -269.799158) (xy 368.70365 -269.83325)
			(xy 368.733215 -269.872594) (xy 368.756086 -269.916171) (xy 368.77167 -269.962852) (xy 368.779565 -270.011429)
			(xy 368.78006 -270.036036) (xy 369.109002 -270.036036) (xy 369.112962 -269.986982) (xy 369.124739 -269.939198)
			(xy 369.14403 -269.893922) (xy 369.170333 -269.852326) (xy 369.202968 -269.815489) (xy 369.241089 -269.784364)
			(xy 369.28371 -269.759757) (xy 369.329726 -269.742305) (xy 369.377945 -269.732461) (xy 369.42712 -269.73048)
			(xy 369.475975 -269.736412) (xy 369.523246 -269.750104) (xy 369.567708 -269.771202) (xy 369.608211 -269.799158)
			(xy 369.643704 -269.83325) (xy 369.673269 -269.872594) (xy 369.69614 -269.916171) (xy 369.711724 -269.962852)
			(xy 369.719619 -270.011429) (xy 369.720114 -270.036036) (xy 370.049056 -270.036036) (xy 370.053016 -269.986982)
			(xy 370.064793 -269.939198) (xy 370.084084 -269.893922) (xy 370.110387 -269.852326) (xy 370.143022 -269.815489)
			(xy 370.181143 -269.784364) (xy 370.223764 -269.759757) (xy 370.26978 -269.742305) (xy 370.317999 -269.732461)
			(xy 370.367174 -269.73048) (xy 370.416029 -269.736412) (xy 370.4633 -269.750104) (xy 370.507762 -269.771202)
			(xy 370.548265 -269.799158) (xy 370.583758 -269.83325) (xy 370.613323 -269.872594) (xy 370.636194 -269.916171)
			(xy 370.651778 -269.962852) (xy 370.659673 -270.011429) (xy 370.660168 -270.036036) (xy 370.98911 -270.036036)
			(xy 370.99307 -269.986982) (xy 371.004847 -269.939198) (xy 371.024138 -269.893922) (xy 371.050441 -269.852326)
			(xy 371.083076 -269.815489) (xy 371.121197 -269.784364) (xy 371.163818 -269.759757) (xy 371.209834 -269.742305)
			(xy 371.258053 -269.732461) (xy 371.307228 -269.73048) (xy 371.356083 -269.736412) (xy 371.403354 -269.750104)
			(xy 371.447816 -269.771202) (xy 371.488319 -269.799158) (xy 371.523812 -269.83325) (xy 371.553377 -269.872594)
			(xy 371.576248 -269.916171) (xy 371.591832 -269.962852) (xy 371.599727 -270.011429) (xy 371.600222 -270.036036)
			(xy 371.92891 -270.036036) (xy 371.93287 -269.986982) (xy 371.944647 -269.939198) (xy 371.963938 -269.893922)
			(xy 371.990241 -269.852326) (xy 372.022876 -269.815489) (xy 372.060997 -269.784364) (xy 372.103618 -269.759757)
			(xy 372.149634 -269.742305) (xy 372.197853 -269.732461) (xy 372.247028 -269.73048) (xy 372.295883 -269.736412)
			(xy 372.343154 -269.750104) (xy 372.387616 -269.771202) (xy 372.428119 -269.799158) (xy 372.463612 -269.83325)
			(xy 372.493177 -269.872594) (xy 372.516048 -269.916171) (xy 372.531632 -269.962852) (xy 372.539527 -270.011429)
			(xy 372.540022 -270.036036) (xy 372.868964 -270.036036) (xy 372.872924 -269.986982) (xy 372.884701 -269.939198)
			(xy 372.903992 -269.893922) (xy 372.930295 -269.852326) (xy 372.96293 -269.815489) (xy 373.001051 -269.784364)
			(xy 373.043672 -269.759757) (xy 373.089688 -269.742305) (xy 373.137907 -269.732461) (xy 373.187082 -269.73048)
			(xy 373.235937 -269.736412) (xy 373.283208 -269.750104) (xy 373.32767 -269.771202) (xy 373.368173 -269.799158)
			(xy 373.403666 -269.83325) (xy 373.433231 -269.872594) (xy 373.456102 -269.916171) (xy 373.471686 -269.962852)
			(xy 373.479581 -270.011429) (xy 373.480076 -270.036036) (xy 373.809018 -270.036036) (xy 373.812978 -269.986982)
			(xy 373.824755 -269.939198) (xy 373.844046 -269.893922) (xy 373.870349 -269.852326) (xy 373.902984 -269.815489)
			(xy 373.941105 -269.784364) (xy 373.983726 -269.759757) (xy 374.029742 -269.742305) (xy 374.077961 -269.732461)
			(xy 374.127136 -269.73048) (xy 374.175991 -269.736412) (xy 374.223262 -269.750104) (xy 374.267724 -269.771202)
			(xy 374.308227 -269.799158) (xy 374.34372 -269.83325) (xy 374.373285 -269.872594) (xy 374.396156 -269.916171)
			(xy 374.41174 -269.962852) (xy 374.419635 -270.011429) (xy 374.42013 -270.036036) (xy 374.419635 -270.060643)
			(xy 374.41174 -270.10922) (xy 374.396156 -270.155901) (xy 374.373285 -270.199478) (xy 374.34372 -270.238822)
			(xy 374.308227 -270.272914) (xy 374.267724 -270.30087) (xy 374.223262 -270.321968) (xy 374.175991 -270.33566)
			(xy 374.127136 -270.341592) (xy 374.077961 -270.339611) (xy 374.029742 -270.329767) (xy 373.983726 -270.312315)
			(xy 373.941105 -270.287708) (xy 373.902984 -270.256583) (xy 373.870349 -270.219746) (xy 373.844046 -270.17815)
			(xy 373.824755 -270.132874) (xy 373.812978 -270.08509) (xy 373.809018 -270.036036) (xy 373.480076 -270.036036)
			(xy 373.479581 -270.060643) (xy 373.471686 -270.10922) (xy 373.456102 -270.155901) (xy 373.433231 -270.199478)
			(xy 373.403666 -270.238822) (xy 373.368173 -270.272914) (xy 373.32767 -270.30087) (xy 373.283208 -270.321968)
			(xy 373.235937 -270.33566) (xy 373.187082 -270.341592) (xy 373.137907 -270.339611) (xy 373.089688 -270.329767)
			(xy 373.043672 -270.312315) (xy 373.001051 -270.287708) (xy 372.96293 -270.256583) (xy 372.930295 -270.219746)
			(xy 372.903992 -270.17815) (xy 372.884701 -270.132874) (xy 372.872924 -270.08509) (xy 372.868964 -270.036036)
			(xy 372.540022 -270.036036) (xy 372.539527 -270.060643) (xy 372.531632 -270.10922) (xy 372.516048 -270.155901)
			(xy 372.493177 -270.199478) (xy 372.463612 -270.238822) (xy 372.428119 -270.272914) (xy 372.387616 -270.30087)
			(xy 372.343154 -270.321968) (xy 372.295883 -270.33566) (xy 372.247028 -270.341592) (xy 372.197853 -270.339611)
			(xy 372.149634 -270.329767) (xy 372.103618 -270.312315) (xy 372.060997 -270.287708) (xy 372.022876 -270.256583)
			(xy 371.990241 -270.219746) (xy 371.963938 -270.17815) (xy 371.944647 -270.132874) (xy 371.93287 -270.08509)
			(xy 371.92891 -270.036036) (xy 371.600222 -270.036036) (xy 371.599727 -270.060643) (xy 371.591832 -270.10922)
			(xy 371.576248 -270.155901) (xy 371.553377 -270.199478) (xy 371.523812 -270.238822) (xy 371.488319 -270.272914)
			(xy 371.447816 -270.30087) (xy 371.403354 -270.321968) (xy 371.356083 -270.33566) (xy 371.307228 -270.341592)
			(xy 371.258053 -270.339611) (xy 371.209834 -270.329767) (xy 371.163818 -270.312315) (xy 371.121197 -270.287708)
			(xy 371.083076 -270.256583) (xy 371.050441 -270.219746) (xy 371.024138 -270.17815) (xy 371.004847 -270.132874)
			(xy 370.99307 -270.08509) (xy 370.98911 -270.036036) (xy 370.660168 -270.036036) (xy 370.659673 -270.060643)
			(xy 370.651778 -270.10922) (xy 370.636194 -270.155901) (xy 370.613323 -270.199478) (xy 370.583758 -270.238822)
			(xy 370.548265 -270.272914) (xy 370.507762 -270.30087) (xy 370.4633 -270.321968) (xy 370.416029 -270.33566)
			(xy 370.367174 -270.341592) (xy 370.317999 -270.339611) (xy 370.26978 -270.329767) (xy 370.223764 -270.312315)
			(xy 370.181143 -270.287708) (xy 370.143022 -270.256583) (xy 370.110387 -270.219746) (xy 370.084084 -270.17815)
			(xy 370.064793 -270.132874) (xy 370.053016 -270.08509) (xy 370.049056 -270.036036) (xy 369.720114 -270.036036)
			(xy 369.719619 -270.060643) (xy 369.711724 -270.10922) (xy 369.69614 -270.155901) (xy 369.673269 -270.199478)
			(xy 369.643704 -270.238822) (xy 369.608211 -270.272914) (xy 369.567708 -270.30087) (xy 369.523246 -270.321968)
			(xy 369.475975 -270.33566) (xy 369.42712 -270.341592) (xy 369.377945 -270.339611) (xy 369.329726 -270.329767)
			(xy 369.28371 -270.312315) (xy 369.241089 -270.287708) (xy 369.202968 -270.256583) (xy 369.170333 -270.219746)
			(xy 369.14403 -270.17815) (xy 369.124739 -270.132874) (xy 369.112962 -270.08509) (xy 369.109002 -270.036036)
			(xy 368.78006 -270.036036) (xy 368.779565 -270.060643) (xy 368.77167 -270.10922) (xy 368.756086 -270.155901)
			(xy 368.733215 -270.199478) (xy 368.70365 -270.238822) (xy 368.668157 -270.272914) (xy 368.627654 -270.30087)
			(xy 368.583192 -270.321968) (xy 368.535921 -270.33566) (xy 368.487066 -270.341592) (xy 368.437891 -270.339611)
			(xy 368.389672 -270.329767) (xy 368.343656 -270.312315) (xy 368.301035 -270.287708) (xy 368.262914 -270.256583)
			(xy 368.230279 -270.219746) (xy 368.203976 -270.17815) (xy 368.184685 -270.132874) (xy 368.172908 -270.08509)
			(xy 368.168948 -270.036036) (xy 367.840006 -270.036036) (xy 367.839511 -270.060643) (xy 367.831616 -270.10922)
			(xy 367.816032 -270.155901) (xy 367.793161 -270.199478) (xy 367.763596 -270.238822) (xy 367.728103 -270.272914)
			(xy 367.6876 -270.30087) (xy 367.643138 -270.321968) (xy 367.595867 -270.33566) (xy 367.547012 -270.341592)
			(xy 367.497837 -270.339611) (xy 367.449618 -270.329767) (xy 367.403602 -270.312315) (xy 367.360981 -270.287708)
			(xy 367.32286 -270.256583) (xy 367.290225 -270.219746) (xy 367.263922 -270.17815) (xy 367.244631 -270.132874)
			(xy 367.232854 -270.08509) (xy 367.228894 -270.036036) (xy 366.900206 -270.036036) (xy 366.899711 -270.060643)
			(xy 366.891816 -270.10922) (xy 366.876232 -270.155901) (xy 366.853361 -270.199478) (xy 366.823796 -270.238822)
			(xy 366.788303 -270.272914) (xy 366.7478 -270.30087) (xy 366.703338 -270.321968) (xy 366.656067 -270.33566)
			(xy 366.607212 -270.341592) (xy 366.558037 -270.339611) (xy 366.509818 -270.329767) (xy 366.463802 -270.312315)
			(xy 366.421181 -270.287708) (xy 366.38306 -270.256583) (xy 366.350425 -270.219746) (xy 366.324122 -270.17815)
			(xy 366.304831 -270.132874) (xy 366.293054 -270.08509) (xy 366.289094 -270.036036) (xy 365.960152 -270.036036)
			(xy 365.959657 -270.060643) (xy 365.951762 -270.10922) (xy 365.936178 -270.155901) (xy 365.913307 -270.199478)
			(xy 365.883742 -270.238822) (xy 365.848249 -270.272914) (xy 365.807746 -270.30087) (xy 365.763284 -270.321968)
			(xy 365.716013 -270.33566) (xy 365.667158 -270.341592) (xy 365.617983 -270.339611) (xy 365.569764 -270.329767)
			(xy 365.523748 -270.312315) (xy 365.481127 -270.287708) (xy 365.443006 -270.256583) (xy 365.410371 -270.219746)
			(xy 365.384068 -270.17815) (xy 365.364777 -270.132874) (xy 365.353 -270.08509) (xy 365.34904 -270.036036)
			(xy 365.020098 -270.036036) (xy 365.019603 -270.060643) (xy 365.011708 -270.10922) (xy 364.996124 -270.155901)
			(xy 364.973253 -270.199478) (xy 364.943688 -270.238822) (xy 364.908195 -270.272914) (xy 364.867692 -270.30087)
			(xy 364.82323 -270.321968) (xy 364.775959 -270.33566) (xy 364.727104 -270.341592) (xy 364.677929 -270.339611)
			(xy 364.62971 -270.329767) (xy 364.583694 -270.312315) (xy 364.541073 -270.287708) (xy 364.502952 -270.256583)
			(xy 364.470317 -270.219746) (xy 364.444014 -270.17815) (xy 364.424723 -270.132874) (xy 364.412946 -270.08509)
			(xy 364.408986 -270.036036) (xy 364.080044 -270.036036) (xy 364.079549 -270.060643) (xy 364.071654 -270.10922)
			(xy 364.05607 -270.155901) (xy 364.033199 -270.199478) (xy 364.003634 -270.238822) (xy 363.968141 -270.272914)
			(xy 363.927638 -270.30087) (xy 363.883176 -270.321968) (xy 363.835905 -270.33566) (xy 363.78705 -270.341592)
			(xy 363.737875 -270.339611) (xy 363.689656 -270.329767) (xy 363.64364 -270.312315) (xy 363.601019 -270.287708)
			(xy 363.562898 -270.256583) (xy 363.530263 -270.219746) (xy 363.50396 -270.17815) (xy 363.484669 -270.132874)
			(xy 363.472892 -270.08509) (xy 363.468932 -270.036036) (xy 363.13999 -270.036036) (xy 363.139495 -270.060643)
			(xy 363.1316 -270.10922) (xy 363.116016 -270.155901) (xy 363.093145 -270.199478) (xy 363.06358 -270.238822)
			(xy 363.028087 -270.272914) (xy 362.987584 -270.30087) (xy 362.943122 -270.321968) (xy 362.895851 -270.33566)
			(xy 362.846996 -270.341592) (xy 362.797821 -270.339611) (xy 362.749602 -270.329767) (xy 362.703586 -270.312315)
			(xy 362.660965 -270.287708) (xy 362.622844 -270.256583) (xy 362.590209 -270.219746) (xy 362.563906 -270.17815)
			(xy 362.544615 -270.132874) (xy 362.532838 -270.08509) (xy 362.528878 -270.036036) (xy 362.20019 -270.036036)
			(xy 362.199695 -270.060643) (xy 362.1918 -270.10922) (xy 362.176216 -270.155901) (xy 362.153345 -270.199478)
			(xy 362.12378 -270.238822) (xy 362.088287 -270.272914) (xy 362.047784 -270.30087) (xy 362.003322 -270.321968)
			(xy 361.956051 -270.33566) (xy 361.907196 -270.341592) (xy 361.858021 -270.339611) (xy 361.809802 -270.329767)
			(xy 361.763786 -270.312315) (xy 361.721165 -270.287708) (xy 361.683044 -270.256583) (xy 361.650409 -270.219746)
			(xy 361.624106 -270.17815) (xy 361.604815 -270.132874) (xy 361.593038 -270.08509) (xy 361.589078 -270.036036)
			(xy 358.446324 -270.036036) (xy 358.445829 -270.060643) (xy 358.437934 -270.10922) (xy 358.42235 -270.155901)
			(xy 358.399479 -270.199478) (xy 358.369914 -270.238822) (xy 358.334421 -270.272914) (xy 358.293918 -270.30087)
			(xy 358.249456 -270.321968) (xy 358.202185 -270.33566) (xy 358.15333 -270.341592) (xy 358.104155 -270.339611)
			(xy 358.055936 -270.329767) (xy 358.00992 -270.312315) (xy 357.967299 -270.287708) (xy 357.929178 -270.256583)
			(xy 357.896543 -270.219746) (xy 357.87024 -270.17815) (xy 357.850949 -270.132874) (xy 357.839172 -270.08509)
			(xy 357.835212 -270.036036) (xy 357.506524 -270.036036) (xy 357.506029 -270.060643) (xy 357.498134 -270.10922)
			(xy 357.48255 -270.155901) (xy 357.459679 -270.199478) (xy 357.430114 -270.238822) (xy 357.394621 -270.272914)
			(xy 357.354118 -270.30087) (xy 357.309656 -270.321968) (xy 357.262385 -270.33566) (xy 357.21353 -270.341592)
			(xy 357.164355 -270.339611) (xy 357.116136 -270.329767) (xy 357.07012 -270.312315) (xy 357.027499 -270.287708)
			(xy 356.989378 -270.256583) (xy 356.956743 -270.219746) (xy 356.93044 -270.17815) (xy 356.911149 -270.132874)
			(xy 356.899372 -270.08509) (xy 356.895412 -270.036036) (xy 356.56647 -270.036036) (xy 356.565975 -270.060643)
			(xy 356.55808 -270.10922) (xy 356.542496 -270.155901) (xy 356.519625 -270.199478) (xy 356.49006 -270.238822)
			(xy 356.454567 -270.272914) (xy 356.414064 -270.30087) (xy 356.369602 -270.321968) (xy 356.322331 -270.33566)
			(xy 356.273476 -270.341592) (xy 356.224301 -270.339611) (xy 356.176082 -270.329767) (xy 356.130066 -270.312315)
			(xy 356.087445 -270.287708) (xy 356.049324 -270.256583) (xy 356.016689 -270.219746) (xy 355.990386 -270.17815)
			(xy 355.971095 -270.132874) (xy 355.959318 -270.08509) (xy 355.955358 -270.036036) (xy 355.626416 -270.036036)
			(xy 355.625921 -270.060643) (xy 355.618026 -270.10922) (xy 355.602442 -270.155901) (xy 355.579571 -270.199478)
			(xy 355.550006 -270.238822) (xy 355.514513 -270.272914) (xy 355.47401 -270.30087) (xy 355.429548 -270.321968)
			(xy 355.382277 -270.33566) (xy 355.333422 -270.341592) (xy 355.284247 -270.339611) (xy 355.236028 -270.329767)
			(xy 355.190012 -270.312315) (xy 355.147391 -270.287708) (xy 355.10927 -270.256583) (xy 355.076635 -270.219746)
			(xy 355.050332 -270.17815) (xy 355.031041 -270.132874) (xy 355.019264 -270.08509) (xy 355.015304 -270.036036)
			(xy 354.686362 -270.036036) (xy 354.685867 -270.060643) (xy 354.677972 -270.10922) (xy 354.662388 -270.155901)
			(xy 354.639517 -270.199478) (xy 354.609952 -270.238822) (xy 354.574459 -270.272914) (xy 354.533956 -270.30087)
			(xy 354.489494 -270.321968) (xy 354.442223 -270.33566) (xy 354.393368 -270.341592) (xy 354.344193 -270.339611)
			(xy 354.295974 -270.329767) (xy 354.249958 -270.312315) (xy 354.207337 -270.287708) (xy 354.169216 -270.256583)
			(xy 354.136581 -270.219746) (xy 354.110278 -270.17815) (xy 354.090987 -270.132874) (xy 354.07921 -270.08509)
			(xy 354.07525 -270.036036) (xy 353.746308 -270.036036) (xy 353.745813 -270.060643) (xy 353.737918 -270.10922)
			(xy 353.722334 -270.155901) (xy 353.699463 -270.199478) (xy 353.669898 -270.238822) (xy 353.634405 -270.272914)
			(xy 353.593902 -270.30087) (xy 353.54944 -270.321968) (xy 353.502169 -270.33566) (xy 353.453314 -270.341592)
			(xy 353.404139 -270.339611) (xy 353.35592 -270.329767) (xy 353.309904 -270.312315) (xy 353.267283 -270.287708)
			(xy 353.229162 -270.256583) (xy 353.196527 -270.219746) (xy 353.170224 -270.17815) (xy 353.150933 -270.132874)
			(xy 353.139156 -270.08509) (xy 353.135196 -270.036036) (xy 352.806508 -270.036036) (xy 352.806013 -270.060643)
			(xy 352.798118 -270.10922) (xy 352.782534 -270.155901) (xy 352.759663 -270.199478) (xy 352.730098 -270.238822)
			(xy 352.694605 -270.272914) (xy 352.654102 -270.30087) (xy 352.60964 -270.321968) (xy 352.562369 -270.33566)
			(xy 352.513514 -270.341592) (xy 352.464339 -270.339611) (xy 352.41612 -270.329767) (xy 352.370104 -270.312315)
			(xy 352.327483 -270.287708) (xy 352.289362 -270.256583) (xy 352.256727 -270.219746) (xy 352.230424 -270.17815)
			(xy 352.211133 -270.132874) (xy 352.199356 -270.08509) (xy 352.195396 -270.036036) (xy 351.866454 -270.036036)
			(xy 351.865959 -270.060643) (xy 351.858064 -270.10922) (xy 351.84248 -270.155901) (xy 351.819609 -270.199478)
			(xy 351.790044 -270.238822) (xy 351.754551 -270.272914) (xy 351.714048 -270.30087) (xy 351.669586 -270.321968)
			(xy 351.622315 -270.33566) (xy 351.57346 -270.341592) (xy 351.524285 -270.339611) (xy 351.476066 -270.329767)
			(xy 351.43005 -270.312315) (xy 351.387429 -270.287708) (xy 351.349308 -270.256583) (xy 351.316673 -270.219746)
			(xy 351.29037 -270.17815) (xy 351.271079 -270.132874) (xy 351.259302 -270.08509) (xy 351.255342 -270.036036)
			(xy 350.9264 -270.036036) (xy 350.925905 -270.060643) (xy 350.91801 -270.10922) (xy 350.902426 -270.155901)
			(xy 350.879555 -270.199478) (xy 350.84999 -270.238822) (xy 350.814497 -270.272914) (xy 350.773994 -270.30087)
			(xy 350.729532 -270.321968) (xy 350.682261 -270.33566) (xy 350.633406 -270.341592) (xy 350.584231 -270.339611)
			(xy 350.536012 -270.329767) (xy 350.489996 -270.312315) (xy 350.447375 -270.287708) (xy 350.409254 -270.256583)
			(xy 350.376619 -270.219746) (xy 350.350316 -270.17815) (xy 350.331025 -270.132874) (xy 350.319248 -270.08509)
			(xy 350.315288 -270.036036) (xy 349.986346 -270.036036) (xy 349.985851 -270.060643) (xy 349.977956 -270.10922)
			(xy 349.962372 -270.155901) (xy 349.939501 -270.199478) (xy 349.909936 -270.238822) (xy 349.874443 -270.272914)
			(xy 349.83394 -270.30087) (xy 349.789478 -270.321968) (xy 349.742207 -270.33566) (xy 349.693352 -270.341592)
			(xy 349.644177 -270.339611) (xy 349.595958 -270.329767) (xy 349.549942 -270.312315) (xy 349.507321 -270.287708)
			(xy 349.4692 -270.256583) (xy 349.436565 -270.219746) (xy 349.410262 -270.17815) (xy 349.390971 -270.132874)
			(xy 349.379194 -270.08509) (xy 349.375234 -270.036036) (xy 349.046546 -270.036036) (xy 349.046051 -270.060643)
			(xy 349.038156 -270.10922) (xy 349.022572 -270.155901) (xy 348.999701 -270.199478) (xy 348.970136 -270.238822)
			(xy 348.934643 -270.272914) (xy 348.89414 -270.30087) (xy 348.849678 -270.321968) (xy 348.802407 -270.33566)
			(xy 348.753552 -270.341592) (xy 348.704377 -270.339611) (xy 348.656158 -270.329767) (xy 348.610142 -270.312315)
			(xy 348.567521 -270.287708) (xy 348.5294 -270.256583) (xy 348.496765 -270.219746) (xy 348.470462 -270.17815)
			(xy 348.451171 -270.132874) (xy 348.439394 -270.08509) (xy 348.435434 -270.036036) (xy 348.106492 -270.036036)
			(xy 348.105997 -270.060643) (xy 348.098102 -270.10922) (xy 348.082518 -270.155901) (xy 348.059647 -270.199478)
			(xy 348.030082 -270.238822) (xy 347.994589 -270.272914) (xy 347.954086 -270.30087) (xy 347.909624 -270.321968)
			(xy 347.862353 -270.33566) (xy 347.813498 -270.341592) (xy 347.764323 -270.339611) (xy 347.716104 -270.329767)
			(xy 347.670088 -270.312315) (xy 347.627467 -270.287708) (xy 347.589346 -270.256583) (xy 347.556711 -270.219746)
			(xy 347.530408 -270.17815) (xy 347.511117 -270.132874) (xy 347.49934 -270.08509) (xy 347.49538 -270.036036)
			(xy 347.166438 -270.036036) (xy 347.165943 -270.060643) (xy 347.158048 -270.10922) (xy 347.142464 -270.155901)
			(xy 347.119593 -270.199478) (xy 347.090028 -270.238822) (xy 347.054535 -270.272914) (xy 347.014032 -270.30087)
			(xy 346.96957 -270.321968) (xy 346.922299 -270.33566) (xy 346.873444 -270.341592) (xy 346.824269 -270.339611)
			(xy 346.77605 -270.329767) (xy 346.730034 -270.312315) (xy 346.687413 -270.287708) (xy 346.649292 -270.256583)
			(xy 346.616657 -270.219746) (xy 346.590354 -270.17815) (xy 346.571063 -270.132874) (xy 346.559286 -270.08509)
			(xy 346.555326 -270.036036) (xy 346.226384 -270.036036) (xy 346.225889 -270.060643) (xy 346.217994 -270.10922)
			(xy 346.20241 -270.155901) (xy 346.179539 -270.199478) (xy 346.149974 -270.238822) (xy 346.114481 -270.272914)
			(xy 346.073978 -270.30087) (xy 346.029516 -270.321968) (xy 345.982245 -270.33566) (xy 345.93339 -270.341592)
			(xy 345.884215 -270.339611) (xy 345.835996 -270.329767) (xy 345.78998 -270.312315) (xy 345.747359 -270.287708)
			(xy 345.709238 -270.256583) (xy 345.676603 -270.219746) (xy 345.6503 -270.17815) (xy 345.631009 -270.132874)
			(xy 345.619232 -270.08509) (xy 345.615272 -270.036036) (xy 345.289669 -270.036036) (xy 345.28677 -270.042465)
			(xy 345.285822 -270.051784) (xy 345.284087 -270.076092) (xy 345.273866 -270.123739) (xy 345.256205 -270.169157)
			(xy 345.231553 -270.211192) (xy 345.200534 -270.248776) (xy 345.163938 -270.280954) (xy 345.143582 -270.294354)
			(xy 345.1352 -270.299688) (xy 345.124024 -270.314928) (xy 345.121484 -270.32458) (xy 345.12123 -270.324834)
			(xy 345.119198 -270.332454) (xy 345.106121 -270.378159) (xy 345.073223 -270.46736) (xy 345.032873 -270.553447)
			(xy 344.985362 -270.635798) (xy 344.931031 -270.713818) (xy 344.870274 -270.786945) (xy 344.837258 -270.82115)
			(xy 344.830908 -270.827754) (xy 344.822889 -270.846042) (xy 345.145372 -270.846042) (xy 345.149332 -270.796988)
			(xy 345.161109 -270.749204) (xy 345.1804 -270.703928) (xy 345.206703 -270.662332) (xy 345.239338 -270.625495)
			(xy 345.277459 -270.59437) (xy 345.32008 -270.569763) (xy 345.366096 -270.552311) (xy 345.414315 -270.542467)
			(xy 345.46349 -270.540486) (xy 345.512345 -270.546418) (xy 345.559616 -270.56011) (xy 345.604078 -270.581208)
			(xy 345.644581 -270.609164) (xy 345.680074 -270.643256) (xy 345.709639 -270.6826) (xy 345.73251 -270.726177)
			(xy 345.748094 -270.772858) (xy 345.755989 -270.821435) (xy 345.756484 -270.846042) (xy 346.085426 -270.846042)
			(xy 346.089386 -270.796988) (xy 346.101163 -270.749204) (xy 346.120454 -270.703928) (xy 346.146757 -270.662332)
			(xy 346.179392 -270.625495) (xy 346.217513 -270.59437) (xy 346.260134 -270.569763) (xy 346.30615 -270.552311)
			(xy 346.354369 -270.542467) (xy 346.403544 -270.540486) (xy 346.452399 -270.546418) (xy 346.49967 -270.56011)
			(xy 346.544132 -270.581208) (xy 346.584635 -270.609164) (xy 346.620128 -270.643256) (xy 346.649693 -270.6826)
			(xy 346.672564 -270.726177) (xy 346.688148 -270.772858) (xy 346.696043 -270.821435) (xy 346.696538 -270.846042)
			(xy 347.025226 -270.846042) (xy 347.029186 -270.796988) (xy 347.040963 -270.749204) (xy 347.060254 -270.703928)
			(xy 347.086557 -270.662332) (xy 347.119192 -270.625495) (xy 347.157313 -270.59437) (xy 347.199934 -270.569763)
			(xy 347.24595 -270.552311) (xy 347.294169 -270.542467) (xy 347.343344 -270.540486) (xy 347.392199 -270.546418)
			(xy 347.43947 -270.56011) (xy 347.483932 -270.581208) (xy 347.524435 -270.609164) (xy 347.559928 -270.643256)
			(xy 347.589493 -270.6826) (xy 347.612364 -270.726177) (xy 347.627948 -270.772858) (xy 347.635843 -270.821435)
			(xy 347.636338 -270.846042) (xy 347.96528 -270.846042) (xy 347.96924 -270.796988) (xy 347.981017 -270.749204)
			(xy 348.000308 -270.703928) (xy 348.026611 -270.662332) (xy 348.059246 -270.625495) (xy 348.097367 -270.59437)
			(xy 348.139988 -270.569763) (xy 348.186004 -270.552311) (xy 348.234223 -270.542467) (xy 348.283398 -270.540486)
			(xy 348.332253 -270.546418) (xy 348.379524 -270.56011) (xy 348.423986 -270.581208) (xy 348.464489 -270.609164)
			(xy 348.499982 -270.643256) (xy 348.529547 -270.6826) (xy 348.552418 -270.726177) (xy 348.568002 -270.772858)
			(xy 348.575897 -270.821435) (xy 348.576392 -270.846042) (xy 348.905334 -270.846042) (xy 348.909294 -270.796988)
			(xy 348.921071 -270.749204) (xy 348.940362 -270.703928) (xy 348.966665 -270.662332) (xy 348.9993 -270.625495)
			(xy 349.037421 -270.59437) (xy 349.080042 -270.569763) (xy 349.126058 -270.552311) (xy 349.174277 -270.542467)
			(xy 349.223452 -270.540486) (xy 349.272307 -270.546418) (xy 349.319578 -270.56011) (xy 349.36404 -270.581208)
			(xy 349.404543 -270.609164) (xy 349.440036 -270.643256) (xy 349.469601 -270.6826) (xy 349.492472 -270.726177)
			(xy 349.508056 -270.772858) (xy 349.515951 -270.821435) (xy 349.516446 -270.846042) (xy 349.845388 -270.846042)
			(xy 349.849348 -270.796988) (xy 349.861125 -270.749204) (xy 349.880416 -270.703928) (xy 349.906719 -270.662332)
			(xy 349.939354 -270.625495) (xy 349.977475 -270.59437) (xy 350.020096 -270.569763) (xy 350.066112 -270.552311)
			(xy 350.114331 -270.542467) (xy 350.163506 -270.540486) (xy 350.212361 -270.546418) (xy 350.259632 -270.56011)
			(xy 350.304094 -270.581208) (xy 350.344597 -270.609164) (xy 350.38009 -270.643256) (xy 350.409655 -270.6826)
			(xy 350.432526 -270.726177) (xy 350.44811 -270.772858) (xy 350.456005 -270.821435) (xy 350.4565 -270.846042)
			(xy 350.785442 -270.846042) (xy 350.789402 -270.796988) (xy 350.801179 -270.749204) (xy 350.82047 -270.703928)
			(xy 350.846773 -270.662332) (xy 350.879408 -270.625495) (xy 350.917529 -270.59437) (xy 350.96015 -270.569763)
			(xy 351.006166 -270.552311) (xy 351.054385 -270.542467) (xy 351.10356 -270.540486) (xy 351.152415 -270.546418)
			(xy 351.199686 -270.56011) (xy 351.244148 -270.581208) (xy 351.284651 -270.609164) (xy 351.320144 -270.643256)
			(xy 351.349709 -270.6826) (xy 351.37258 -270.726177) (xy 351.388164 -270.772858) (xy 351.396059 -270.821435)
			(xy 351.396554 -270.846042) (xy 351.725242 -270.846042) (xy 351.729202 -270.796988) (xy 351.740979 -270.749204)
			(xy 351.76027 -270.703928) (xy 351.786573 -270.662332) (xy 351.819208 -270.625495) (xy 351.857329 -270.59437)
			(xy 351.89995 -270.569763) (xy 351.945966 -270.552311) (xy 351.994185 -270.542467) (xy 352.04336 -270.540486)
			(xy 352.092215 -270.546418) (xy 352.139486 -270.56011) (xy 352.183948 -270.581208) (xy 352.224451 -270.609164)
			(xy 352.259944 -270.643256) (xy 352.289509 -270.6826) (xy 352.31238 -270.726177) (xy 352.327964 -270.772858)
			(xy 352.335859 -270.821435) (xy 352.336354 -270.846042) (xy 352.665296 -270.846042) (xy 352.669256 -270.796988)
			(xy 352.681033 -270.749204) (xy 352.700324 -270.703928) (xy 352.726627 -270.662332) (xy 352.759262 -270.625495)
			(xy 352.797383 -270.59437) (xy 352.840004 -270.569763) (xy 352.88602 -270.552311) (xy 352.934239 -270.542467)
			(xy 352.983414 -270.540486) (xy 353.032269 -270.546418) (xy 353.07954 -270.56011) (xy 353.124002 -270.581208)
			(xy 353.164505 -270.609164) (xy 353.199998 -270.643256) (xy 353.229563 -270.6826) (xy 353.252434 -270.726177)
			(xy 353.268018 -270.772858) (xy 353.275913 -270.821435) (xy 353.276408 -270.846042) (xy 353.60535 -270.846042)
			(xy 353.60931 -270.796988) (xy 353.621087 -270.749204) (xy 353.640378 -270.703928) (xy 353.666681 -270.662332)
			(xy 353.699316 -270.625495) (xy 353.737437 -270.59437) (xy 353.780058 -270.569763) (xy 353.826074 -270.552311)
			(xy 353.874293 -270.542467) (xy 353.923468 -270.540486) (xy 353.972323 -270.546418) (xy 354.019594 -270.56011)
			(xy 354.064056 -270.581208) (xy 354.104559 -270.609164) (xy 354.140052 -270.643256) (xy 354.169617 -270.6826)
			(xy 354.192488 -270.726177) (xy 354.208072 -270.772858) (xy 354.215967 -270.821435) (xy 354.216462 -270.846042)
			(xy 354.545404 -270.846042) (xy 354.549364 -270.796988) (xy 354.561141 -270.749204) (xy 354.580432 -270.703928)
			(xy 354.606735 -270.662332) (xy 354.63937 -270.625495) (xy 354.677491 -270.59437) (xy 354.720112 -270.569763)
			(xy 354.766128 -270.552311) (xy 354.814347 -270.542467) (xy 354.863522 -270.540486) (xy 354.912377 -270.546418)
			(xy 354.959648 -270.56011) (xy 355.00411 -270.581208) (xy 355.044613 -270.609164) (xy 355.080106 -270.643256)
			(xy 355.109671 -270.6826) (xy 355.132542 -270.726177) (xy 355.148126 -270.772858) (xy 355.156021 -270.821435)
			(xy 355.156516 -270.846042) (xy 355.485204 -270.846042) (xy 355.489164 -270.796988) (xy 355.500941 -270.749204)
			(xy 355.520232 -270.703928) (xy 355.546535 -270.662332) (xy 355.57917 -270.625495) (xy 355.617291 -270.59437)
			(xy 355.659912 -270.569763) (xy 355.705928 -270.552311) (xy 355.754147 -270.542467) (xy 355.803322 -270.540486)
			(xy 355.852177 -270.546418) (xy 355.899448 -270.56011) (xy 355.94391 -270.581208) (xy 355.984413 -270.609164)
			(xy 356.019906 -270.643256) (xy 356.049471 -270.6826) (xy 356.072342 -270.726177) (xy 356.087926 -270.772858)
			(xy 356.095821 -270.821435) (xy 356.096316 -270.846042) (xy 356.425258 -270.846042) (xy 356.429218 -270.796988)
			(xy 356.440995 -270.749204) (xy 356.460286 -270.703928) (xy 356.486589 -270.662332) (xy 356.519224 -270.625495)
			(xy 356.557345 -270.59437) (xy 356.599966 -270.569763) (xy 356.645982 -270.552311) (xy 356.694201 -270.542467)
			(xy 356.743376 -270.540486) (xy 356.792231 -270.546418) (xy 356.839502 -270.56011) (xy 356.883964 -270.581208)
			(xy 356.924467 -270.609164) (xy 356.95996 -270.643256) (xy 356.989525 -270.6826) (xy 357.012396 -270.726177)
			(xy 357.02798 -270.772858) (xy 357.035875 -270.821435) (xy 357.03637 -270.846042) (xy 357.365312 -270.846042)
			(xy 357.369272 -270.796988) (xy 357.381049 -270.749204) (xy 357.40034 -270.703928) (xy 357.426643 -270.662332)
			(xy 357.459278 -270.625495) (xy 357.497399 -270.59437) (xy 357.54002 -270.569763) (xy 357.586036 -270.552311)
			(xy 357.634255 -270.542467) (xy 357.68343 -270.540486) (xy 357.732285 -270.546418) (xy 357.779556 -270.56011)
			(xy 357.824018 -270.581208) (xy 357.864521 -270.609164) (xy 357.900014 -270.643256) (xy 357.929579 -270.6826)
			(xy 357.95245 -270.726177) (xy 357.968034 -270.772858) (xy 357.975929 -270.821435) (xy 357.976424 -270.846042)
			(xy 358.305366 -270.846042) (xy 358.309326 -270.796988) (xy 358.321103 -270.749204) (xy 358.340394 -270.703928)
			(xy 358.366697 -270.662332) (xy 358.399332 -270.625495) (xy 358.437453 -270.59437) (xy 358.480074 -270.569763)
			(xy 358.52609 -270.552311) (xy 358.574309 -270.542467) (xy 358.623484 -270.540486) (xy 358.672339 -270.546418)
			(xy 358.71961 -270.56011) (xy 358.764072 -270.581208) (xy 358.804575 -270.609164) (xy 358.840068 -270.643256)
			(xy 358.869633 -270.6826) (xy 358.892504 -270.726177) (xy 358.908088 -270.772858) (xy 358.915983 -270.821435)
			(xy 358.916478 -270.846042) (xy 361.118924 -270.846042) (xy 361.122884 -270.796988) (xy 361.134661 -270.749204)
			(xy 361.153952 -270.703928) (xy 361.180255 -270.662332) (xy 361.21289 -270.625495) (xy 361.251011 -270.59437)
			(xy 361.293632 -270.569763) (xy 361.339648 -270.552311) (xy 361.387867 -270.542467) (xy 361.437042 -270.540486)
			(xy 361.485897 -270.546418) (xy 361.533168 -270.56011) (xy 361.57763 -270.581208) (xy 361.618133 -270.609164)
			(xy 361.653626 -270.643256) (xy 361.683191 -270.6826) (xy 361.706062 -270.726177) (xy 361.721646 -270.772858)
			(xy 361.729541 -270.821435) (xy 361.730036 -270.846042) (xy 362.058978 -270.846042) (xy 362.062938 -270.796988)
			(xy 362.074715 -270.749204) (xy 362.094006 -270.703928) (xy 362.120309 -270.662332) (xy 362.152944 -270.625495)
			(xy 362.191065 -270.59437) (xy 362.233686 -270.569763) (xy 362.279702 -270.552311) (xy 362.327921 -270.542467)
			(xy 362.377096 -270.540486) (xy 362.425951 -270.546418) (xy 362.473222 -270.56011) (xy 362.517684 -270.581208)
			(xy 362.558187 -270.609164) (xy 362.59368 -270.643256) (xy 362.623245 -270.6826) (xy 362.646116 -270.726177)
			(xy 362.6617 -270.772858) (xy 362.669595 -270.821435) (xy 362.67009 -270.846042) (xy 362.999032 -270.846042)
			(xy 363.002992 -270.796988) (xy 363.014769 -270.749204) (xy 363.03406 -270.703928) (xy 363.060363 -270.662332)
			(xy 363.092998 -270.625495) (xy 363.131119 -270.59437) (xy 363.17374 -270.569763) (xy 363.219756 -270.552311)
			(xy 363.267975 -270.542467) (xy 363.31715 -270.540486) (xy 363.366005 -270.546418) (xy 363.413276 -270.56011)
			(xy 363.457738 -270.581208) (xy 363.498241 -270.609164) (xy 363.533734 -270.643256) (xy 363.563299 -270.6826)
			(xy 363.58617 -270.726177) (xy 363.601754 -270.772858) (xy 363.609649 -270.821435) (xy 363.610144 -270.846042)
			(xy 363.939086 -270.846042) (xy 363.943046 -270.796988) (xy 363.954823 -270.749204) (xy 363.974114 -270.703928)
			(xy 364.000417 -270.662332) (xy 364.033052 -270.625495) (xy 364.071173 -270.59437) (xy 364.113794 -270.569763)
			(xy 364.15981 -270.552311) (xy 364.208029 -270.542467) (xy 364.257204 -270.540486) (xy 364.306059 -270.546418)
			(xy 364.35333 -270.56011) (xy 364.397792 -270.581208) (xy 364.438295 -270.609164) (xy 364.473788 -270.643256)
			(xy 364.503353 -270.6826) (xy 364.526224 -270.726177) (xy 364.541808 -270.772858) (xy 364.549703 -270.821435)
			(xy 364.550198 -270.846042) (xy 364.878886 -270.846042) (xy 364.882846 -270.796988) (xy 364.894623 -270.749204)
			(xy 364.913914 -270.703928) (xy 364.940217 -270.662332) (xy 364.972852 -270.625495) (xy 365.010973 -270.59437)
			(xy 365.053594 -270.569763) (xy 365.09961 -270.552311) (xy 365.147829 -270.542467) (xy 365.197004 -270.540486)
			(xy 365.245859 -270.546418) (xy 365.29313 -270.56011) (xy 365.337592 -270.581208) (xy 365.378095 -270.609164)
			(xy 365.413588 -270.643256) (xy 365.443153 -270.6826) (xy 365.466024 -270.726177) (xy 365.481608 -270.772858)
			(xy 365.489503 -270.821435) (xy 365.489998 -270.846042) (xy 365.81894 -270.846042) (xy 365.8229 -270.796988)
			(xy 365.834677 -270.749204) (xy 365.853968 -270.703928) (xy 365.880271 -270.662332) (xy 365.912906 -270.625495)
			(xy 365.951027 -270.59437) (xy 365.993648 -270.569763) (xy 366.039664 -270.552311) (xy 366.087883 -270.542467)
			(xy 366.137058 -270.540486) (xy 366.185913 -270.546418) (xy 366.233184 -270.56011) (xy 366.277646 -270.581208)
			(xy 366.318149 -270.609164) (xy 366.353642 -270.643256) (xy 366.383207 -270.6826) (xy 366.406078 -270.726177)
			(xy 366.421662 -270.772858) (xy 366.429557 -270.821435) (xy 366.430052 -270.846042) (xy 366.758994 -270.846042)
			(xy 366.762954 -270.796988) (xy 366.774731 -270.749204) (xy 366.794022 -270.703928) (xy 366.820325 -270.662332)
			(xy 366.85296 -270.625495) (xy 366.891081 -270.59437) (xy 366.933702 -270.569763) (xy 366.979718 -270.552311)
			(xy 367.027937 -270.542467) (xy 367.077112 -270.540486) (xy 367.125967 -270.546418) (xy 367.173238 -270.56011)
			(xy 367.2177 -270.581208) (xy 367.258203 -270.609164) (xy 367.293696 -270.643256) (xy 367.323261 -270.6826)
			(xy 367.346132 -270.726177) (xy 367.361716 -270.772858) (xy 367.369611 -270.821435) (xy 367.370106 -270.846042)
			(xy 367.699048 -270.846042) (xy 367.703008 -270.796988) (xy 367.714785 -270.749204) (xy 367.734076 -270.703928)
			(xy 367.760379 -270.662332) (xy 367.793014 -270.625495) (xy 367.831135 -270.59437) (xy 367.873756 -270.569763)
			(xy 367.919772 -270.552311) (xy 367.967991 -270.542467) (xy 368.017166 -270.540486) (xy 368.066021 -270.546418)
			(xy 368.113292 -270.56011) (xy 368.157754 -270.581208) (xy 368.198257 -270.609164) (xy 368.23375 -270.643256)
			(xy 368.263315 -270.6826) (xy 368.286186 -270.726177) (xy 368.30177 -270.772858) (xy 368.309665 -270.821435)
			(xy 368.31016 -270.846042) (xy 368.639102 -270.846042) (xy 368.643062 -270.796988) (xy 368.654839 -270.749204)
			(xy 368.67413 -270.703928) (xy 368.700433 -270.662332) (xy 368.733068 -270.625495) (xy 368.771189 -270.59437)
			(xy 368.81381 -270.569763) (xy 368.859826 -270.552311) (xy 368.908045 -270.542467) (xy 368.95722 -270.540486)
			(xy 369.006075 -270.546418) (xy 369.053346 -270.56011) (xy 369.097808 -270.581208) (xy 369.138311 -270.609164)
			(xy 369.173804 -270.643256) (xy 369.203369 -270.6826) (xy 369.22624 -270.726177) (xy 369.241824 -270.772858)
			(xy 369.249719 -270.821435) (xy 369.250214 -270.846042) (xy 369.578902 -270.846042) (xy 369.582862 -270.796988)
			(xy 369.594639 -270.749204) (xy 369.61393 -270.703928) (xy 369.640233 -270.662332) (xy 369.672868 -270.625495)
			(xy 369.710989 -270.59437) (xy 369.75361 -270.569763) (xy 369.799626 -270.552311) (xy 369.847845 -270.542467)
			(xy 369.89702 -270.540486) (xy 369.945875 -270.546418) (xy 369.993146 -270.56011) (xy 370.037608 -270.581208)
			(xy 370.078111 -270.609164) (xy 370.113604 -270.643256) (xy 370.143169 -270.6826) (xy 370.16604 -270.726177)
			(xy 370.181624 -270.772858) (xy 370.189519 -270.821435) (xy 370.190014 -270.846042) (xy 370.518956 -270.846042)
			(xy 370.522916 -270.796988) (xy 370.534693 -270.749204) (xy 370.553984 -270.703928) (xy 370.580287 -270.662332)
			(xy 370.612922 -270.625495) (xy 370.651043 -270.59437) (xy 370.693664 -270.569763) (xy 370.73968 -270.552311)
			(xy 370.787899 -270.542467) (xy 370.837074 -270.540486) (xy 370.885929 -270.546418) (xy 370.9332 -270.56011)
			(xy 370.977662 -270.581208) (xy 371.018165 -270.609164) (xy 371.053658 -270.643256) (xy 371.083223 -270.6826)
			(xy 371.106094 -270.726177) (xy 371.121678 -270.772858) (xy 371.129573 -270.821435) (xy 371.130068 -270.846042)
			(xy 371.45901 -270.846042) (xy 371.46297 -270.796988) (xy 371.474747 -270.749204) (xy 371.494038 -270.703928)
			(xy 371.520341 -270.662332) (xy 371.552976 -270.625495) (xy 371.591097 -270.59437) (xy 371.633718 -270.569763)
			(xy 371.679734 -270.552311) (xy 371.727953 -270.542467) (xy 371.777128 -270.540486) (xy 371.825983 -270.546418)
			(xy 371.873254 -270.56011) (xy 371.917716 -270.581208) (xy 371.958219 -270.609164) (xy 371.993712 -270.643256)
			(xy 372.023277 -270.6826) (xy 372.046148 -270.726177) (xy 372.061732 -270.772858) (xy 372.069627 -270.821435)
			(xy 372.070122 -270.846042) (xy 372.399064 -270.846042) (xy 372.403024 -270.796988) (xy 372.414801 -270.749204)
			(xy 372.434092 -270.703928) (xy 372.460395 -270.662332) (xy 372.49303 -270.625495) (xy 372.531151 -270.59437)
			(xy 372.573772 -270.569763) (xy 372.619788 -270.552311) (xy 372.668007 -270.542467) (xy 372.717182 -270.540486)
			(xy 372.766037 -270.546418) (xy 372.813308 -270.56011) (xy 372.85777 -270.581208) (xy 372.898273 -270.609164)
			(xy 372.933766 -270.643256) (xy 372.963331 -270.6826) (xy 372.986202 -270.726177) (xy 373.001786 -270.772858)
			(xy 373.009681 -270.821435) (xy 373.010176 -270.846042) (xy 373.339118 -270.846042) (xy 373.343078 -270.796988)
			(xy 373.354855 -270.749204) (xy 373.374146 -270.703928) (xy 373.400449 -270.662332) (xy 373.433084 -270.625495)
			(xy 373.471205 -270.59437) (xy 373.513826 -270.569763) (xy 373.559842 -270.552311) (xy 373.608061 -270.542467)
			(xy 373.657236 -270.540486) (xy 373.706091 -270.546418) (xy 373.753362 -270.56011) (xy 373.797824 -270.581208)
			(xy 373.838327 -270.609164) (xy 373.87382 -270.643256) (xy 373.903385 -270.6826) (xy 373.926256 -270.726177)
			(xy 373.94184 -270.772858) (xy 373.949735 -270.821435) (xy 373.95023 -270.846042) (xy 373.949735 -270.870649)
			(xy 373.94184 -270.919226) (xy 373.926256 -270.965907) (xy 373.903385 -271.009484) (xy 373.87382 -271.048828)
			(xy 373.838327 -271.08292) (xy 373.797824 -271.110876) (xy 373.753362 -271.131974) (xy 373.706091 -271.145666)
			(xy 373.657236 -271.151598) (xy 373.608061 -271.149617) (xy 373.559842 -271.139773) (xy 373.513826 -271.122321)
			(xy 373.471205 -271.097714) (xy 373.433084 -271.066589) (xy 373.400449 -271.029752) (xy 373.374146 -270.988156)
			(xy 373.354855 -270.94288) (xy 373.343078 -270.895096) (xy 373.339118 -270.846042) (xy 373.010176 -270.846042)
			(xy 373.009681 -270.870649) (xy 373.001786 -270.919226) (xy 372.986202 -270.965907) (xy 372.963331 -271.009484)
			(xy 372.933766 -271.048828) (xy 372.898273 -271.08292) (xy 372.85777 -271.110876) (xy 372.813308 -271.131974)
			(xy 372.766037 -271.145666) (xy 372.717182 -271.151598) (xy 372.668007 -271.149617) (xy 372.619788 -271.139773)
			(xy 372.573772 -271.122321) (xy 372.531151 -271.097714) (xy 372.49303 -271.066589) (xy 372.460395 -271.029752)
			(xy 372.434092 -270.988156) (xy 372.414801 -270.94288) (xy 372.403024 -270.895096) (xy 372.399064 -270.846042)
			(xy 372.070122 -270.846042) (xy 372.069627 -270.870649) (xy 372.061732 -270.919226) (xy 372.046148 -270.965907)
			(xy 372.023277 -271.009484) (xy 371.993712 -271.048828) (xy 371.958219 -271.08292) (xy 371.917716 -271.110876)
			(xy 371.873254 -271.131974) (xy 371.825983 -271.145666) (xy 371.777128 -271.151598) (xy 371.727953 -271.149617)
			(xy 371.679734 -271.139773) (xy 371.633718 -271.122321) (xy 371.591097 -271.097714) (xy 371.552976 -271.066589)
			(xy 371.520341 -271.029752) (xy 371.494038 -270.988156) (xy 371.474747 -270.94288) (xy 371.46297 -270.895096)
			(xy 371.45901 -270.846042) (xy 371.130068 -270.846042) (xy 371.129573 -270.870649) (xy 371.121678 -270.919226)
			(xy 371.106094 -270.965907) (xy 371.083223 -271.009484) (xy 371.053658 -271.048828) (xy 371.018165 -271.08292)
			(xy 370.977662 -271.110876) (xy 370.9332 -271.131974) (xy 370.885929 -271.145666) (xy 370.837074 -271.151598)
			(xy 370.787899 -271.149617) (xy 370.73968 -271.139773) (xy 370.693664 -271.122321) (xy 370.651043 -271.097714)
			(xy 370.612922 -271.066589) (xy 370.580287 -271.029752) (xy 370.553984 -270.988156) (xy 370.534693 -270.94288)
			(xy 370.522916 -270.895096) (xy 370.518956 -270.846042) (xy 370.190014 -270.846042) (xy 370.189519 -270.870649)
			(xy 370.181624 -270.919226) (xy 370.16604 -270.965907) (xy 370.143169 -271.009484) (xy 370.113604 -271.048828)
			(xy 370.078111 -271.08292) (xy 370.037608 -271.110876) (xy 369.993146 -271.131974) (xy 369.945875 -271.145666)
			(xy 369.89702 -271.151598) (xy 369.847845 -271.149617) (xy 369.799626 -271.139773) (xy 369.75361 -271.122321)
			(xy 369.710989 -271.097714) (xy 369.672868 -271.066589) (xy 369.640233 -271.029752) (xy 369.61393 -270.988156)
			(xy 369.594639 -270.94288) (xy 369.582862 -270.895096) (xy 369.578902 -270.846042) (xy 369.250214 -270.846042)
			(xy 369.249719 -270.870649) (xy 369.241824 -270.919226) (xy 369.22624 -270.965907) (xy 369.203369 -271.009484)
			(xy 369.173804 -271.048828) (xy 369.138311 -271.08292) (xy 369.097808 -271.110876) (xy 369.053346 -271.131974)
			(xy 369.006075 -271.145666) (xy 368.95722 -271.151598) (xy 368.908045 -271.149617) (xy 368.859826 -271.139773)
			(xy 368.81381 -271.122321) (xy 368.771189 -271.097714) (xy 368.733068 -271.066589) (xy 368.700433 -271.029752)
			(xy 368.67413 -270.988156) (xy 368.654839 -270.94288) (xy 368.643062 -270.895096) (xy 368.639102 -270.846042)
			(xy 368.31016 -270.846042) (xy 368.309665 -270.870649) (xy 368.30177 -270.919226) (xy 368.286186 -270.965907)
			(xy 368.263315 -271.009484) (xy 368.23375 -271.048828) (xy 368.198257 -271.08292) (xy 368.157754 -271.110876)
			(xy 368.113292 -271.131974) (xy 368.066021 -271.145666) (xy 368.017166 -271.151598) (xy 367.967991 -271.149617)
			(xy 367.919772 -271.139773) (xy 367.873756 -271.122321) (xy 367.831135 -271.097714) (xy 367.793014 -271.066589)
			(xy 367.760379 -271.029752) (xy 367.734076 -270.988156) (xy 367.714785 -270.94288) (xy 367.703008 -270.895096)
			(xy 367.699048 -270.846042) (xy 367.370106 -270.846042) (xy 367.369611 -270.870649) (xy 367.361716 -270.919226)
			(xy 367.346132 -270.965907) (xy 367.323261 -271.009484) (xy 367.293696 -271.048828) (xy 367.258203 -271.08292)
			(xy 367.2177 -271.110876) (xy 367.173238 -271.131974) (xy 367.125967 -271.145666) (xy 367.077112 -271.151598)
			(xy 367.027937 -271.149617) (xy 366.979718 -271.139773) (xy 366.933702 -271.122321) (xy 366.891081 -271.097714)
			(xy 366.85296 -271.066589) (xy 366.820325 -271.029752) (xy 366.794022 -270.988156) (xy 366.774731 -270.94288)
			(xy 366.762954 -270.895096) (xy 366.758994 -270.846042) (xy 366.430052 -270.846042) (xy 366.429557 -270.870649)
			(xy 366.421662 -270.919226) (xy 366.406078 -270.965907) (xy 366.383207 -271.009484) (xy 366.353642 -271.048828)
			(xy 366.318149 -271.08292) (xy 366.277646 -271.110876) (xy 366.233184 -271.131974) (xy 366.185913 -271.145666)
			(xy 366.137058 -271.151598) (xy 366.087883 -271.149617) (xy 366.039664 -271.139773) (xy 365.993648 -271.122321)
			(xy 365.951027 -271.097714) (xy 365.912906 -271.066589) (xy 365.880271 -271.029752) (xy 365.853968 -270.988156)
			(xy 365.834677 -270.94288) (xy 365.8229 -270.895096) (xy 365.81894 -270.846042) (xy 365.489998 -270.846042)
			(xy 365.489503 -270.870649) (xy 365.481608 -270.919226) (xy 365.466024 -270.965907) (xy 365.443153 -271.009484)
			(xy 365.413588 -271.048828) (xy 365.378095 -271.08292) (xy 365.337592 -271.110876) (xy 365.29313 -271.131974)
			(xy 365.245859 -271.145666) (xy 365.197004 -271.151598) (xy 365.147829 -271.149617) (xy 365.09961 -271.139773)
			(xy 365.053594 -271.122321) (xy 365.010973 -271.097714) (xy 364.972852 -271.066589) (xy 364.940217 -271.029752)
			(xy 364.913914 -270.988156) (xy 364.894623 -270.94288) (xy 364.882846 -270.895096) (xy 364.878886 -270.846042)
			(xy 364.550198 -270.846042) (xy 364.549703 -270.870649) (xy 364.541808 -270.919226) (xy 364.526224 -270.965907)
			(xy 364.503353 -271.009484) (xy 364.473788 -271.048828) (xy 364.438295 -271.08292) (xy 364.397792 -271.110876)
			(xy 364.35333 -271.131974) (xy 364.306059 -271.145666) (xy 364.257204 -271.151598) (xy 364.208029 -271.149617)
			(xy 364.15981 -271.139773) (xy 364.113794 -271.122321) (xy 364.071173 -271.097714) (xy 364.033052 -271.066589)
			(xy 364.000417 -271.029752) (xy 363.974114 -270.988156) (xy 363.954823 -270.94288) (xy 363.943046 -270.895096)
			(xy 363.939086 -270.846042) (xy 363.610144 -270.846042) (xy 363.609649 -270.870649) (xy 363.601754 -270.919226)
			(xy 363.58617 -270.965907) (xy 363.563299 -271.009484) (xy 363.533734 -271.048828) (xy 363.498241 -271.08292)
			(xy 363.457738 -271.110876) (xy 363.413276 -271.131974) (xy 363.366005 -271.145666) (xy 363.31715 -271.151598)
			(xy 363.267975 -271.149617) (xy 363.219756 -271.139773) (xy 363.17374 -271.122321) (xy 363.131119 -271.097714)
			(xy 363.092998 -271.066589) (xy 363.060363 -271.029752) (xy 363.03406 -270.988156) (xy 363.014769 -270.94288)
			(xy 363.002992 -270.895096) (xy 362.999032 -270.846042) (xy 362.67009 -270.846042) (xy 362.669595 -270.870649)
			(xy 362.6617 -270.919226) (xy 362.646116 -270.965907) (xy 362.623245 -271.009484) (xy 362.59368 -271.048828)
			(xy 362.558187 -271.08292) (xy 362.517684 -271.110876) (xy 362.473222 -271.131974) (xy 362.425951 -271.145666)
			(xy 362.377096 -271.151598) (xy 362.327921 -271.149617) (xy 362.279702 -271.139773) (xy 362.233686 -271.122321)
			(xy 362.191065 -271.097714) (xy 362.152944 -271.066589) (xy 362.120309 -271.029752) (xy 362.094006 -270.988156)
			(xy 362.074715 -270.94288) (xy 362.062938 -270.895096) (xy 362.058978 -270.846042) (xy 361.730036 -270.846042)
			(xy 361.729541 -270.870649) (xy 361.721646 -270.919226) (xy 361.706062 -270.965907) (xy 361.683191 -271.009484)
			(xy 361.653626 -271.048828) (xy 361.618133 -271.08292) (xy 361.57763 -271.110876) (xy 361.533168 -271.131974)
			(xy 361.485897 -271.145666) (xy 361.437042 -271.151598) (xy 361.387867 -271.149617) (xy 361.339648 -271.139773)
			(xy 361.293632 -271.122321) (xy 361.251011 -271.097714) (xy 361.21289 -271.066589) (xy 361.180255 -271.029752)
			(xy 361.153952 -270.988156) (xy 361.134661 -270.94288) (xy 361.122884 -270.895096) (xy 361.118924 -270.846042)
			(xy 358.916478 -270.846042) (xy 358.915983 -270.870649) (xy 358.908088 -270.919226) (xy 358.892504 -270.965907)
			(xy 358.869633 -271.009484) (xy 358.840068 -271.048828) (xy 358.804575 -271.08292) (xy 358.764072 -271.110876)
			(xy 358.71961 -271.131974) (xy 358.672339 -271.145666) (xy 358.623484 -271.151598) (xy 358.574309 -271.149617)
			(xy 358.52609 -271.139773) (xy 358.480074 -271.122321) (xy 358.437453 -271.097714) (xy 358.399332 -271.066589)
			(xy 358.366697 -271.029752) (xy 358.340394 -270.988156) (xy 358.321103 -270.94288) (xy 358.309326 -270.895096)
			(xy 358.305366 -270.846042) (xy 357.976424 -270.846042) (xy 357.975929 -270.870649) (xy 357.968034 -270.919226)
			(xy 357.95245 -270.965907) (xy 357.929579 -271.009484) (xy 357.900014 -271.048828) (xy 357.864521 -271.08292)
			(xy 357.824018 -271.110876) (xy 357.779556 -271.131974) (xy 357.732285 -271.145666) (xy 357.68343 -271.151598)
			(xy 357.634255 -271.149617) (xy 357.586036 -271.139773) (xy 357.54002 -271.122321) (xy 357.497399 -271.097714)
			(xy 357.459278 -271.066589) (xy 357.426643 -271.029752) (xy 357.40034 -270.988156) (xy 357.381049 -270.94288)
			(xy 357.369272 -270.895096) (xy 357.365312 -270.846042) (xy 357.03637 -270.846042) (xy 357.035875 -270.870649)
			(xy 357.02798 -270.919226) (xy 357.012396 -270.965907) (xy 356.989525 -271.009484) (xy 356.95996 -271.048828)
			(xy 356.924467 -271.08292) (xy 356.883964 -271.110876) (xy 356.839502 -271.131974) (xy 356.792231 -271.145666)
			(xy 356.743376 -271.151598) (xy 356.694201 -271.149617) (xy 356.645982 -271.139773) (xy 356.599966 -271.122321)
			(xy 356.557345 -271.097714) (xy 356.519224 -271.066589) (xy 356.486589 -271.029752) (xy 356.460286 -270.988156)
			(xy 356.440995 -270.94288) (xy 356.429218 -270.895096) (xy 356.425258 -270.846042) (xy 356.096316 -270.846042)
			(xy 356.095821 -270.870649) (xy 356.087926 -270.919226) (xy 356.072342 -270.965907) (xy 356.049471 -271.009484)
			(xy 356.019906 -271.048828) (xy 355.984413 -271.08292) (xy 355.94391 -271.110876) (xy 355.899448 -271.131974)
			(xy 355.852177 -271.145666) (xy 355.803322 -271.151598) (xy 355.754147 -271.149617) (xy 355.705928 -271.139773)
			(xy 355.659912 -271.122321) (xy 355.617291 -271.097714) (xy 355.57917 -271.066589) (xy 355.546535 -271.029752)
			(xy 355.520232 -270.988156) (xy 355.500941 -270.94288) (xy 355.489164 -270.895096) (xy 355.485204 -270.846042)
			(xy 355.156516 -270.846042) (xy 355.156021 -270.870649) (xy 355.148126 -270.919226) (xy 355.132542 -270.965907)
			(xy 355.109671 -271.009484) (xy 355.080106 -271.048828) (xy 355.044613 -271.08292) (xy 355.00411 -271.110876)
			(xy 354.959648 -271.131974) (xy 354.912377 -271.145666) (xy 354.863522 -271.151598) (xy 354.814347 -271.149617)
			(xy 354.766128 -271.139773) (xy 354.720112 -271.122321) (xy 354.677491 -271.097714) (xy 354.63937 -271.066589)
			(xy 354.606735 -271.029752) (xy 354.580432 -270.988156) (xy 354.561141 -270.94288) (xy 354.549364 -270.895096)
			(xy 354.545404 -270.846042) (xy 354.216462 -270.846042) (xy 354.215967 -270.870649) (xy 354.208072 -270.919226)
			(xy 354.192488 -270.965907) (xy 354.169617 -271.009484) (xy 354.140052 -271.048828) (xy 354.104559 -271.08292)
			(xy 354.064056 -271.110876) (xy 354.019594 -271.131974) (xy 353.972323 -271.145666) (xy 353.923468 -271.151598)
			(xy 353.874293 -271.149617) (xy 353.826074 -271.139773) (xy 353.780058 -271.122321) (xy 353.737437 -271.097714)
			(xy 353.699316 -271.066589) (xy 353.666681 -271.029752) (xy 353.640378 -270.988156) (xy 353.621087 -270.94288)
			(xy 353.60931 -270.895096) (xy 353.60535 -270.846042) (xy 353.276408 -270.846042) (xy 353.275913 -270.870649)
			(xy 353.268018 -270.919226) (xy 353.252434 -270.965907) (xy 353.229563 -271.009484) (xy 353.199998 -271.048828)
			(xy 353.164505 -271.08292) (xy 353.124002 -271.110876) (xy 353.07954 -271.131974) (xy 353.032269 -271.145666)
			(xy 352.983414 -271.151598) (xy 352.934239 -271.149617) (xy 352.88602 -271.139773) (xy 352.840004 -271.122321)
			(xy 352.797383 -271.097714) (xy 352.759262 -271.066589) (xy 352.726627 -271.029752) (xy 352.700324 -270.988156)
			(xy 352.681033 -270.94288) (xy 352.669256 -270.895096) (xy 352.665296 -270.846042) (xy 352.336354 -270.846042)
			(xy 352.335859 -270.870649) (xy 352.327964 -270.919226) (xy 352.31238 -270.965907) (xy 352.289509 -271.009484)
			(xy 352.259944 -271.048828) (xy 352.224451 -271.08292) (xy 352.183948 -271.110876) (xy 352.139486 -271.131974)
			(xy 352.092215 -271.145666) (xy 352.04336 -271.151598) (xy 351.994185 -271.149617) (xy 351.945966 -271.139773)
			(xy 351.89995 -271.122321) (xy 351.857329 -271.097714) (xy 351.819208 -271.066589) (xy 351.786573 -271.029752)
			(xy 351.76027 -270.988156) (xy 351.740979 -270.94288) (xy 351.729202 -270.895096) (xy 351.725242 -270.846042)
			(xy 351.396554 -270.846042) (xy 351.396059 -270.870649) (xy 351.388164 -270.919226) (xy 351.37258 -270.965907)
			(xy 351.349709 -271.009484) (xy 351.320144 -271.048828) (xy 351.284651 -271.08292) (xy 351.244148 -271.110876)
			(xy 351.199686 -271.131974) (xy 351.152415 -271.145666) (xy 351.10356 -271.151598) (xy 351.054385 -271.149617)
			(xy 351.006166 -271.139773) (xy 350.96015 -271.122321) (xy 350.917529 -271.097714) (xy 350.879408 -271.066589)
			(xy 350.846773 -271.029752) (xy 350.82047 -270.988156) (xy 350.801179 -270.94288) (xy 350.789402 -270.895096)
			(xy 350.785442 -270.846042) (xy 350.4565 -270.846042) (xy 350.456005 -270.870649) (xy 350.44811 -270.919226)
			(xy 350.432526 -270.965907) (xy 350.409655 -271.009484) (xy 350.38009 -271.048828) (xy 350.344597 -271.08292)
			(xy 350.304094 -271.110876) (xy 350.259632 -271.131974) (xy 350.212361 -271.145666) (xy 350.163506 -271.151598)
			(xy 350.114331 -271.149617) (xy 350.066112 -271.139773) (xy 350.020096 -271.122321) (xy 349.977475 -271.097714)
			(xy 349.939354 -271.066589) (xy 349.906719 -271.029752) (xy 349.880416 -270.988156) (xy 349.861125 -270.94288)
			(xy 349.849348 -270.895096) (xy 349.845388 -270.846042) (xy 349.516446 -270.846042) (xy 349.515951 -270.870649)
			(xy 349.508056 -270.919226) (xy 349.492472 -270.965907) (xy 349.469601 -271.009484) (xy 349.440036 -271.048828)
			(xy 349.404543 -271.08292) (xy 349.36404 -271.110876) (xy 349.319578 -271.131974) (xy 349.272307 -271.145666)
			(xy 349.223452 -271.151598) (xy 349.174277 -271.149617) (xy 349.126058 -271.139773) (xy 349.080042 -271.122321)
			(xy 349.037421 -271.097714) (xy 348.9993 -271.066589) (xy 348.966665 -271.029752) (xy 348.940362 -270.988156)
			(xy 348.921071 -270.94288) (xy 348.909294 -270.895096) (xy 348.905334 -270.846042) (xy 348.576392 -270.846042)
			(xy 348.575897 -270.870649) (xy 348.568002 -270.919226) (xy 348.552418 -270.965907) (xy 348.529547 -271.009484)
			(xy 348.499982 -271.048828) (xy 348.464489 -271.08292) (xy 348.423986 -271.110876) (xy 348.379524 -271.131974)
			(xy 348.332253 -271.145666) (xy 348.283398 -271.151598) (xy 348.234223 -271.149617) (xy 348.186004 -271.139773)
			(xy 348.139988 -271.122321) (xy 348.097367 -271.097714) (xy 348.059246 -271.066589) (xy 348.026611 -271.029752)
			(xy 348.000308 -270.988156) (xy 347.981017 -270.94288) (xy 347.96924 -270.895096) (xy 347.96528 -270.846042)
			(xy 347.636338 -270.846042) (xy 347.635843 -270.870649) (xy 347.627948 -270.919226) (xy 347.612364 -270.965907)
			(xy 347.589493 -271.009484) (xy 347.559928 -271.048828) (xy 347.524435 -271.08292) (xy 347.483932 -271.110876)
			(xy 347.43947 -271.131974) (xy 347.392199 -271.145666) (xy 347.343344 -271.151598) (xy 347.294169 -271.149617)
			(xy 347.24595 -271.139773) (xy 347.199934 -271.122321) (xy 347.157313 -271.097714) (xy 347.119192 -271.066589)
			(xy 347.086557 -271.029752) (xy 347.060254 -270.988156) (xy 347.040963 -270.94288) (xy 347.029186 -270.895096)
			(xy 347.025226 -270.846042) (xy 346.696538 -270.846042) (xy 346.696043 -270.870649) (xy 346.688148 -270.919226)
			(xy 346.672564 -270.965907) (xy 346.649693 -271.009484) (xy 346.620128 -271.048828) (xy 346.584635 -271.08292)
			(xy 346.544132 -271.110876) (xy 346.49967 -271.131974) (xy 346.452399 -271.145666) (xy 346.403544 -271.151598)
			(xy 346.354369 -271.149617) (xy 346.30615 -271.139773) (xy 346.260134 -271.122321) (xy 346.217513 -271.097714)
			(xy 346.179392 -271.066589) (xy 346.146757 -271.029752) (xy 346.120454 -270.988156) (xy 346.101163 -270.94288)
			(xy 346.089386 -270.895096) (xy 346.085426 -270.846042) (xy 345.756484 -270.846042) (xy 345.755989 -270.870649)
			(xy 345.748094 -270.919226) (xy 345.73251 -270.965907) (xy 345.709639 -271.009484) (xy 345.680074 -271.048828)
			(xy 345.644581 -271.08292) (xy 345.604078 -271.110876) (xy 345.559616 -271.131974) (xy 345.512345 -271.145666)
			(xy 345.46349 -271.151598) (xy 345.414315 -271.149617) (xy 345.366096 -271.139773) (xy 345.32008 -271.122321)
			(xy 345.277459 -271.097714) (xy 345.239338 -271.066589) (xy 345.206703 -271.029752) (xy 345.1804 -270.988156)
			(xy 345.161109 -270.94288) (xy 345.149332 -270.895096) (xy 345.145372 -270.846042) (xy 344.822889 -270.846042)
			(xy 344.81643 -270.860774) (xy 344.815668 -270.86941) (xy 344.812947 -270.896836) (xy 344.798903 -270.950125)
			(xy 344.775541 -271.000037) (xy 344.760042 -271.022826) (xy 344.755724 -271.028922) (xy 344.748612 -271.050004)
			(xy 344.747352 -271.053951) (xy 344.745955 -271.062118) (xy 344.745818 -271.06626) (xy 344.745818 -271.273524)
			(xy 344.746514 -271.285684) (xy 344.757655 -271.307302) (xy 344.767154 -271.314926) (xy 344.82913 -271.358868)
			(xy 344.843354 -271.368774) (xy 344.867484 -271.37233) (xy 344.879168 -271.368012) (xy 344.903662 -271.359959)
			(xy 344.954482 -271.351274) (xy 344.98026 -271.35074) (xy 344.981022 -271.35074) (xy 345.005013 -271.351188)
			(xy 345.052403 -271.358698) (xy 345.098034 -271.373529) (xy 345.140784 -271.395316) (xy 345.179599 -271.423523)
			(xy 345.213523 -271.457455) (xy 345.241721 -271.496276) (xy 345.263498 -271.53903) (xy 345.278319 -271.584666)
			(xy 345.285818 -271.632057) (xy 345.28633 -271.656048) (xy 345.615272 -271.656048) (xy 345.619232 -271.606994)
			(xy 345.631009 -271.55921) (xy 345.6503 -271.513934) (xy 345.676603 -271.472338) (xy 345.709238 -271.435501)
			(xy 345.747359 -271.404376) (xy 345.78998 -271.379769) (xy 345.835996 -271.362317) (xy 345.884215 -271.352473)
			(xy 345.93339 -271.350492) (xy 345.982245 -271.356424) (xy 346.029516 -271.370116) (xy 346.073978 -271.391214)
			(xy 346.114481 -271.41917) (xy 346.149974 -271.453262) (xy 346.179539 -271.492606) (xy 346.20241 -271.536183)
			(xy 346.217994 -271.582864) (xy 346.225889 -271.631441) (xy 346.226384 -271.656048) (xy 346.555326 -271.656048)
			(xy 346.559286 -271.606994) (xy 346.571063 -271.55921) (xy 346.590354 -271.513934) (xy 346.616657 -271.472338)
			(xy 346.649292 -271.435501) (xy 346.687413 -271.404376) (xy 346.730034 -271.379769) (xy 346.77605 -271.362317)
			(xy 346.824269 -271.352473) (xy 346.873444 -271.350492) (xy 346.922299 -271.356424) (xy 346.96957 -271.370116)
			(xy 347.014032 -271.391214) (xy 347.054535 -271.41917) (xy 347.090028 -271.453262) (xy 347.119593 -271.492606)
			(xy 347.142464 -271.536183) (xy 347.158048 -271.582864) (xy 347.165943 -271.631441) (xy 347.166438 -271.656048)
			(xy 347.49538 -271.656048) (xy 347.49934 -271.606994) (xy 347.511117 -271.55921) (xy 347.530408 -271.513934)
			(xy 347.556711 -271.472338) (xy 347.589346 -271.435501) (xy 347.627467 -271.404376) (xy 347.670088 -271.379769)
			(xy 347.716104 -271.362317) (xy 347.764323 -271.352473) (xy 347.813498 -271.350492) (xy 347.862353 -271.356424)
			(xy 347.909624 -271.370116) (xy 347.954086 -271.391214) (xy 347.994589 -271.41917) (xy 348.030082 -271.453262)
			(xy 348.059647 -271.492606) (xy 348.082518 -271.536183) (xy 348.098102 -271.582864) (xy 348.105997 -271.631441)
			(xy 348.106492 -271.656048) (xy 348.435434 -271.656048) (xy 348.439394 -271.606994) (xy 348.451171 -271.55921)
			(xy 348.470462 -271.513934) (xy 348.496765 -271.472338) (xy 348.5294 -271.435501) (xy 348.567521 -271.404376)
			(xy 348.610142 -271.379769) (xy 348.656158 -271.362317) (xy 348.704377 -271.352473) (xy 348.753552 -271.350492)
			(xy 348.802407 -271.356424) (xy 348.849678 -271.370116) (xy 348.89414 -271.391214) (xy 348.934643 -271.41917)
			(xy 348.970136 -271.453262) (xy 348.999701 -271.492606) (xy 349.022572 -271.536183) (xy 349.038156 -271.582864)
			(xy 349.046051 -271.631441) (xy 349.046546 -271.656048) (xy 349.375234 -271.656048) (xy 349.379194 -271.606994)
			(xy 349.390971 -271.55921) (xy 349.410262 -271.513934) (xy 349.436565 -271.472338) (xy 349.4692 -271.435501)
			(xy 349.507321 -271.404376) (xy 349.549942 -271.379769) (xy 349.595958 -271.362317) (xy 349.644177 -271.352473)
			(xy 349.693352 -271.350492) (xy 349.742207 -271.356424) (xy 349.789478 -271.370116) (xy 349.83394 -271.391214)
			(xy 349.874443 -271.41917) (xy 349.909936 -271.453262) (xy 349.939501 -271.492606) (xy 349.962372 -271.536183)
			(xy 349.977956 -271.582864) (xy 349.985851 -271.631441) (xy 349.986346 -271.656048) (xy 350.315288 -271.656048)
			(xy 350.319248 -271.606994) (xy 350.331025 -271.55921) (xy 350.350316 -271.513934) (xy 350.376619 -271.472338)
			(xy 350.409254 -271.435501) (xy 350.447375 -271.404376) (xy 350.489996 -271.379769) (xy 350.536012 -271.362317)
			(xy 350.584231 -271.352473) (xy 350.633406 -271.350492) (xy 350.682261 -271.356424) (xy 350.729532 -271.370116)
			(xy 350.773994 -271.391214) (xy 350.814497 -271.41917) (xy 350.84999 -271.453262) (xy 350.879555 -271.492606)
			(xy 350.902426 -271.536183) (xy 350.91801 -271.582864) (xy 350.925905 -271.631441) (xy 350.9264 -271.656048)
			(xy 351.255342 -271.656048) (xy 351.259302 -271.606994) (xy 351.271079 -271.55921) (xy 351.29037 -271.513934)
			(xy 351.316673 -271.472338) (xy 351.349308 -271.435501) (xy 351.387429 -271.404376) (xy 351.43005 -271.379769)
			(xy 351.476066 -271.362317) (xy 351.524285 -271.352473) (xy 351.57346 -271.350492) (xy 351.622315 -271.356424)
			(xy 351.669586 -271.370116) (xy 351.714048 -271.391214) (xy 351.754551 -271.41917) (xy 351.790044 -271.453262)
			(xy 351.819609 -271.492606) (xy 351.84248 -271.536183) (xy 351.858064 -271.582864) (xy 351.865959 -271.631441)
			(xy 351.866454 -271.656048) (xy 352.195396 -271.656048) (xy 352.199356 -271.606994) (xy 352.211133 -271.55921)
			(xy 352.230424 -271.513934) (xy 352.256727 -271.472338) (xy 352.289362 -271.435501) (xy 352.327483 -271.404376)
			(xy 352.370104 -271.379769) (xy 352.41612 -271.362317) (xy 352.464339 -271.352473) (xy 352.513514 -271.350492)
			(xy 352.562369 -271.356424) (xy 352.60964 -271.370116) (xy 352.654102 -271.391214) (xy 352.694605 -271.41917)
			(xy 352.730098 -271.453262) (xy 352.759663 -271.492606) (xy 352.782534 -271.536183) (xy 352.798118 -271.582864)
			(xy 352.806013 -271.631441) (xy 352.806508 -271.656048) (xy 353.135196 -271.656048) (xy 353.139156 -271.606994)
			(xy 353.150933 -271.55921) (xy 353.170224 -271.513934) (xy 353.196527 -271.472338) (xy 353.229162 -271.435501)
			(xy 353.267283 -271.404376) (xy 353.309904 -271.379769) (xy 353.35592 -271.362317) (xy 353.404139 -271.352473)
			(xy 353.453314 -271.350492) (xy 353.502169 -271.356424) (xy 353.54944 -271.370116) (xy 353.593902 -271.391214)
			(xy 353.634405 -271.41917) (xy 353.669898 -271.453262) (xy 353.699463 -271.492606) (xy 353.722334 -271.536183)
			(xy 353.737918 -271.582864) (xy 353.745813 -271.631441) (xy 353.746308 -271.656048) (xy 354.07525 -271.656048)
			(xy 354.07921 -271.606994) (xy 354.090987 -271.55921) (xy 354.110278 -271.513934) (xy 354.136581 -271.472338)
			(xy 354.169216 -271.435501) (xy 354.207337 -271.404376) (xy 354.249958 -271.379769) (xy 354.295974 -271.362317)
			(xy 354.344193 -271.352473) (xy 354.393368 -271.350492) (xy 354.442223 -271.356424) (xy 354.489494 -271.370116)
			(xy 354.533956 -271.391214) (xy 354.574459 -271.41917) (xy 354.609952 -271.453262) (xy 354.639517 -271.492606)
			(xy 354.662388 -271.536183) (xy 354.677972 -271.582864) (xy 354.685867 -271.631441) (xy 354.686362 -271.656048)
			(xy 355.015304 -271.656048) (xy 355.019264 -271.606994) (xy 355.031041 -271.55921) (xy 355.050332 -271.513934)
			(xy 355.076635 -271.472338) (xy 355.10927 -271.435501) (xy 355.147391 -271.404376) (xy 355.190012 -271.379769)
			(xy 355.236028 -271.362317) (xy 355.284247 -271.352473) (xy 355.333422 -271.350492) (xy 355.382277 -271.356424)
			(xy 355.429548 -271.370116) (xy 355.47401 -271.391214) (xy 355.514513 -271.41917) (xy 355.550006 -271.453262)
			(xy 355.579571 -271.492606) (xy 355.602442 -271.536183) (xy 355.618026 -271.582864) (xy 355.625921 -271.631441)
			(xy 355.626416 -271.656048) (xy 355.955358 -271.656048) (xy 355.959318 -271.606994) (xy 355.971095 -271.55921)
			(xy 355.990386 -271.513934) (xy 356.016689 -271.472338) (xy 356.049324 -271.435501) (xy 356.087445 -271.404376)
			(xy 356.130066 -271.379769) (xy 356.176082 -271.362317) (xy 356.224301 -271.352473) (xy 356.273476 -271.350492)
			(xy 356.322331 -271.356424) (xy 356.369602 -271.370116) (xy 356.414064 -271.391214) (xy 356.454567 -271.41917)
			(xy 356.49006 -271.453262) (xy 356.519625 -271.492606) (xy 356.542496 -271.536183) (xy 356.55808 -271.582864)
			(xy 356.565975 -271.631441) (xy 356.56647 -271.656048) (xy 363.468932 -271.656048) (xy 363.472892 -271.606994)
			(xy 363.484669 -271.55921) (xy 363.50396 -271.513934) (xy 363.530263 -271.472338) (xy 363.562898 -271.435501)
			(xy 363.601019 -271.404376) (xy 363.64364 -271.379769) (xy 363.689656 -271.362317) (xy 363.737875 -271.352473)
			(xy 363.78705 -271.350492) (xy 363.835905 -271.356424) (xy 363.883176 -271.370116) (xy 363.927638 -271.391214)
			(xy 363.968141 -271.41917) (xy 364.003634 -271.453262) (xy 364.033199 -271.492606) (xy 364.05607 -271.536183)
			(xy 364.071654 -271.582864) (xy 364.079549 -271.631441) (xy 364.080044 -271.656048) (xy 364.408986 -271.656048)
			(xy 364.412946 -271.606994) (xy 364.424723 -271.55921) (xy 364.444014 -271.513934) (xy 364.470317 -271.472338)
			(xy 364.502952 -271.435501) (xy 364.541073 -271.404376) (xy 364.583694 -271.379769) (xy 364.62971 -271.362317)
			(xy 364.677929 -271.352473) (xy 364.727104 -271.350492) (xy 364.775959 -271.356424) (xy 364.82323 -271.370116)
			(xy 364.867692 -271.391214) (xy 364.908195 -271.41917) (xy 364.943688 -271.453262) (xy 364.973253 -271.492606)
			(xy 364.996124 -271.536183) (xy 365.011708 -271.582864) (xy 365.019603 -271.631441) (xy 365.020098 -271.656048)
			(xy 365.34904 -271.656048) (xy 365.353 -271.606994) (xy 365.364777 -271.55921) (xy 365.384068 -271.513934)
			(xy 365.410371 -271.472338) (xy 365.443006 -271.435501) (xy 365.481127 -271.404376) (xy 365.523748 -271.379769)
			(xy 365.569764 -271.362317) (xy 365.617983 -271.352473) (xy 365.667158 -271.350492) (xy 365.716013 -271.356424)
			(xy 365.763284 -271.370116) (xy 365.807746 -271.391214) (xy 365.848249 -271.41917) (xy 365.883742 -271.453262)
			(xy 365.913307 -271.492606) (xy 365.936178 -271.536183) (xy 365.951762 -271.582864) (xy 365.959657 -271.631441)
			(xy 365.960152 -271.656048) (xy 366.289094 -271.656048) (xy 366.293054 -271.606994) (xy 366.304831 -271.55921)
			(xy 366.324122 -271.513934) (xy 366.350425 -271.472338) (xy 366.38306 -271.435501) (xy 366.421181 -271.404376)
			(xy 366.463802 -271.379769) (xy 366.509818 -271.362317) (xy 366.558037 -271.352473) (xy 366.607212 -271.350492)
			(xy 366.656067 -271.356424) (xy 366.703338 -271.370116) (xy 366.7478 -271.391214) (xy 366.788303 -271.41917)
			(xy 366.823796 -271.453262) (xy 366.853361 -271.492606) (xy 366.876232 -271.536183) (xy 366.891816 -271.582864)
			(xy 366.899711 -271.631441) (xy 366.900206 -271.656048) (xy 367.228894 -271.656048) (xy 367.232854 -271.606994)
			(xy 367.244631 -271.55921) (xy 367.263922 -271.513934) (xy 367.290225 -271.472338) (xy 367.32286 -271.435501)
			(xy 367.360981 -271.404376) (xy 367.403602 -271.379769) (xy 367.449618 -271.362317) (xy 367.497837 -271.352473)
			(xy 367.547012 -271.350492) (xy 367.595867 -271.356424) (xy 367.643138 -271.370116) (xy 367.6876 -271.391214)
			(xy 367.728103 -271.41917) (xy 367.763596 -271.453262) (xy 367.793161 -271.492606) (xy 367.816032 -271.536183)
			(xy 367.831616 -271.582864) (xy 367.839511 -271.631441) (xy 367.840006 -271.656048) (xy 368.168948 -271.656048)
			(xy 368.172908 -271.606994) (xy 368.184685 -271.55921) (xy 368.203976 -271.513934) (xy 368.230279 -271.472338)
			(xy 368.262914 -271.435501) (xy 368.301035 -271.404376) (xy 368.343656 -271.379769) (xy 368.389672 -271.362317)
			(xy 368.437891 -271.352473) (xy 368.487066 -271.350492) (xy 368.535921 -271.356424) (xy 368.583192 -271.370116)
			(xy 368.627654 -271.391214) (xy 368.668157 -271.41917) (xy 368.70365 -271.453262) (xy 368.733215 -271.492606)
			(xy 368.756086 -271.536183) (xy 368.77167 -271.582864) (xy 368.779565 -271.631441) (xy 368.78006 -271.656048)
			(xy 369.109002 -271.656048) (xy 369.112962 -271.606994) (xy 369.124739 -271.55921) (xy 369.14403 -271.513934)
			(xy 369.170333 -271.472338) (xy 369.202968 -271.435501) (xy 369.241089 -271.404376) (xy 369.28371 -271.379769)
			(xy 369.329726 -271.362317) (xy 369.377945 -271.352473) (xy 369.42712 -271.350492) (xy 369.475975 -271.356424)
			(xy 369.523246 -271.370116) (xy 369.567708 -271.391214) (xy 369.608211 -271.41917) (xy 369.643704 -271.453262)
			(xy 369.673269 -271.492606) (xy 369.69614 -271.536183) (xy 369.711724 -271.582864) (xy 369.719619 -271.631441)
			(xy 369.720114 -271.656048) (xy 370.049056 -271.656048) (xy 370.053016 -271.606994) (xy 370.064793 -271.55921)
			(xy 370.084084 -271.513934) (xy 370.110387 -271.472338) (xy 370.143022 -271.435501) (xy 370.181143 -271.404376)
			(xy 370.223764 -271.379769) (xy 370.26978 -271.362317) (xy 370.317999 -271.352473) (xy 370.367174 -271.350492)
			(xy 370.416029 -271.356424) (xy 370.4633 -271.370116) (xy 370.507762 -271.391214) (xy 370.548265 -271.41917)
			(xy 370.583758 -271.453262) (xy 370.613323 -271.492606) (xy 370.636194 -271.536183) (xy 370.651778 -271.582864)
			(xy 370.659673 -271.631441) (xy 370.660168 -271.656048) (xy 370.98911 -271.656048) (xy 370.99307 -271.606994)
			(xy 371.004847 -271.55921) (xy 371.024138 -271.513934) (xy 371.050441 -271.472338) (xy 371.083076 -271.435501)
			(xy 371.121197 -271.404376) (xy 371.163818 -271.379769) (xy 371.209834 -271.362317) (xy 371.258053 -271.352473)
			(xy 371.307228 -271.350492) (xy 371.356083 -271.356424) (xy 371.403354 -271.370116) (xy 371.447816 -271.391214)
			(xy 371.488319 -271.41917) (xy 371.523812 -271.453262) (xy 371.553377 -271.492606) (xy 371.576248 -271.536183)
			(xy 371.591832 -271.582864) (xy 371.599727 -271.631441) (xy 371.600222 -271.656048) (xy 371.92891 -271.656048)
			(xy 371.93287 -271.606994) (xy 371.944647 -271.55921) (xy 371.963938 -271.513934) (xy 371.990241 -271.472338)
			(xy 372.022876 -271.435501) (xy 372.060997 -271.404376) (xy 372.103618 -271.379769) (xy 372.149634 -271.362317)
			(xy 372.197853 -271.352473) (xy 372.247028 -271.350492) (xy 372.295883 -271.356424) (xy 372.343154 -271.370116)
			(xy 372.387616 -271.391214) (xy 372.428119 -271.41917) (xy 372.463612 -271.453262) (xy 372.493177 -271.492606)
			(xy 372.516048 -271.536183) (xy 372.531632 -271.582864) (xy 372.539527 -271.631441) (xy 372.540022 -271.656048)
			(xy 372.868964 -271.656048) (xy 372.872924 -271.606994) (xy 372.884701 -271.55921) (xy 372.903992 -271.513934)
			(xy 372.930295 -271.472338) (xy 372.96293 -271.435501) (xy 373.001051 -271.404376) (xy 373.043672 -271.379769)
			(xy 373.089688 -271.362317) (xy 373.137907 -271.352473) (xy 373.187082 -271.350492) (xy 373.235937 -271.356424)
			(xy 373.283208 -271.370116) (xy 373.32767 -271.391214) (xy 373.368173 -271.41917) (xy 373.403666 -271.453262)
			(xy 373.433231 -271.492606) (xy 373.456102 -271.536183) (xy 373.471686 -271.582864) (xy 373.479581 -271.631441)
			(xy 373.480076 -271.656048) (xy 373.809018 -271.656048) (xy 373.812978 -271.606994) (xy 373.824755 -271.55921)
			(xy 373.844046 -271.513934) (xy 373.870349 -271.472338) (xy 373.902984 -271.435501) (xy 373.941105 -271.404376)
			(xy 373.983726 -271.379769) (xy 374.029742 -271.362317) (xy 374.077961 -271.352473) (xy 374.127136 -271.350492)
			(xy 374.175991 -271.356424) (xy 374.223262 -271.370116) (xy 374.267724 -271.391214) (xy 374.308227 -271.41917)
			(xy 374.34372 -271.453262) (xy 374.373285 -271.492606) (xy 374.396156 -271.536183) (xy 374.41174 -271.582864)
			(xy 374.419635 -271.631441) (xy 374.42013 -271.656048) (xy 374.419635 -271.680655) (xy 374.41174 -271.729232)
			(xy 374.396156 -271.775913) (xy 374.373285 -271.81949) (xy 374.34372 -271.858834) (xy 374.308227 -271.892926)
			(xy 374.267724 -271.920882) (xy 374.223262 -271.94198) (xy 374.175991 -271.955672) (xy 374.127136 -271.961604)
			(xy 374.077961 -271.959623) (xy 374.029742 -271.949779) (xy 373.983726 -271.932327) (xy 373.941105 -271.90772)
			(xy 373.902984 -271.876595) (xy 373.870349 -271.839758) (xy 373.844046 -271.798162) (xy 373.824755 -271.752886)
			(xy 373.812978 -271.705102) (xy 373.809018 -271.656048) (xy 373.480076 -271.656048) (xy 373.479581 -271.680655)
			(xy 373.471686 -271.729232) (xy 373.456102 -271.775913) (xy 373.433231 -271.81949) (xy 373.403666 -271.858834)
			(xy 373.368173 -271.892926) (xy 373.32767 -271.920882) (xy 373.283208 -271.94198) (xy 373.235937 -271.955672)
			(xy 373.187082 -271.961604) (xy 373.137907 -271.959623) (xy 373.089688 -271.949779) (xy 373.043672 -271.932327)
			(xy 373.001051 -271.90772) (xy 372.96293 -271.876595) (xy 372.930295 -271.839758) (xy 372.903992 -271.798162)
			(xy 372.884701 -271.752886) (xy 372.872924 -271.705102) (xy 372.868964 -271.656048) (xy 372.540022 -271.656048)
			(xy 372.539527 -271.680655) (xy 372.531632 -271.729232) (xy 372.516048 -271.775913) (xy 372.493177 -271.81949)
			(xy 372.463612 -271.858834) (xy 372.428119 -271.892926) (xy 372.387616 -271.920882) (xy 372.343154 -271.94198)
			(xy 372.295883 -271.955672) (xy 372.247028 -271.961604) (xy 372.197853 -271.959623) (xy 372.149634 -271.949779)
			(xy 372.103618 -271.932327) (xy 372.060997 -271.90772) (xy 372.022876 -271.876595) (xy 371.990241 -271.839758)
			(xy 371.963938 -271.798162) (xy 371.944647 -271.752886) (xy 371.93287 -271.705102) (xy 371.92891 -271.656048)
			(xy 371.600222 -271.656048) (xy 371.599727 -271.680655) (xy 371.591832 -271.729232) (xy 371.576248 -271.775913)
			(xy 371.553377 -271.81949) (xy 371.523812 -271.858834) (xy 371.488319 -271.892926) (xy 371.447816 -271.920882)
			(xy 371.403354 -271.94198) (xy 371.356083 -271.955672) (xy 371.307228 -271.961604) (xy 371.258053 -271.959623)
			(xy 371.209834 -271.949779) (xy 371.163818 -271.932327) (xy 371.121197 -271.90772) (xy 371.083076 -271.876595)
			(xy 371.050441 -271.839758) (xy 371.024138 -271.798162) (xy 371.004847 -271.752886) (xy 370.99307 -271.705102)
			(xy 370.98911 -271.656048) (xy 370.660168 -271.656048) (xy 370.659673 -271.680655) (xy 370.651778 -271.729232)
			(xy 370.636194 -271.775913) (xy 370.613323 -271.81949) (xy 370.583758 -271.858834) (xy 370.548265 -271.892926)
			(xy 370.507762 -271.920882) (xy 370.4633 -271.94198) (xy 370.416029 -271.955672) (xy 370.367174 -271.961604)
			(xy 370.317999 -271.959623) (xy 370.26978 -271.949779) (xy 370.223764 -271.932327) (xy 370.181143 -271.90772)
			(xy 370.143022 -271.876595) (xy 370.110387 -271.839758) (xy 370.084084 -271.798162) (xy 370.064793 -271.752886)
			(xy 370.053016 -271.705102) (xy 370.049056 -271.656048) (xy 369.720114 -271.656048) (xy 369.719619 -271.680655)
			(xy 369.711724 -271.729232) (xy 369.69614 -271.775913) (xy 369.673269 -271.81949) (xy 369.643704 -271.858834)
			(xy 369.608211 -271.892926) (xy 369.567708 -271.920882) (xy 369.523246 -271.94198) (xy 369.475975 -271.955672)
			(xy 369.42712 -271.961604) (xy 369.377945 -271.959623) (xy 369.329726 -271.949779) (xy 369.28371 -271.932327)
			(xy 369.241089 -271.90772) (xy 369.202968 -271.876595) (xy 369.170333 -271.839758) (xy 369.14403 -271.798162)
			(xy 369.124739 -271.752886) (xy 369.112962 -271.705102) (xy 369.109002 -271.656048) (xy 368.78006 -271.656048)
			(xy 368.779565 -271.680655) (xy 368.77167 -271.729232) (xy 368.756086 -271.775913) (xy 368.733215 -271.81949)
			(xy 368.70365 -271.858834) (xy 368.668157 -271.892926) (xy 368.627654 -271.920882) (xy 368.583192 -271.94198)
			(xy 368.535921 -271.955672) (xy 368.487066 -271.961604) (xy 368.437891 -271.959623) (xy 368.389672 -271.949779)
			(xy 368.343656 -271.932327) (xy 368.301035 -271.90772) (xy 368.262914 -271.876595) (xy 368.230279 -271.839758)
			(xy 368.203976 -271.798162) (xy 368.184685 -271.752886) (xy 368.172908 -271.705102) (xy 368.168948 -271.656048)
			(xy 367.840006 -271.656048) (xy 367.839511 -271.680655) (xy 367.831616 -271.729232) (xy 367.816032 -271.775913)
			(xy 367.793161 -271.81949) (xy 367.763596 -271.858834) (xy 367.728103 -271.892926) (xy 367.6876 -271.920882)
			(xy 367.643138 -271.94198) (xy 367.595867 -271.955672) (xy 367.547012 -271.961604) (xy 367.497837 -271.959623)
			(xy 367.449618 -271.949779) (xy 367.403602 -271.932327) (xy 367.360981 -271.90772) (xy 367.32286 -271.876595)
			(xy 367.290225 -271.839758) (xy 367.263922 -271.798162) (xy 367.244631 -271.752886) (xy 367.232854 -271.705102)
			(xy 367.228894 -271.656048) (xy 366.900206 -271.656048) (xy 366.899711 -271.680655) (xy 366.891816 -271.729232)
			(xy 366.876232 -271.775913) (xy 366.853361 -271.81949) (xy 366.823796 -271.858834) (xy 366.788303 -271.892926)
			(xy 366.7478 -271.920882) (xy 366.703338 -271.94198) (xy 366.656067 -271.955672) (xy 366.607212 -271.961604)
			(xy 366.558037 -271.959623) (xy 366.509818 -271.949779) (xy 366.463802 -271.932327) (xy 366.421181 -271.90772)
			(xy 366.38306 -271.876595) (xy 366.350425 -271.839758) (xy 366.324122 -271.798162) (xy 366.304831 -271.752886)
			(xy 366.293054 -271.705102) (xy 366.289094 -271.656048) (xy 365.960152 -271.656048) (xy 365.959657 -271.680655)
			(xy 365.951762 -271.729232) (xy 365.936178 -271.775913) (xy 365.913307 -271.81949) (xy 365.883742 -271.858834)
			(xy 365.848249 -271.892926) (xy 365.807746 -271.920882) (xy 365.763284 -271.94198) (xy 365.716013 -271.955672)
			(xy 365.667158 -271.961604) (xy 365.617983 -271.959623) (xy 365.569764 -271.949779) (xy 365.523748 -271.932327)
			(xy 365.481127 -271.90772) (xy 365.443006 -271.876595) (xy 365.410371 -271.839758) (xy 365.384068 -271.798162)
			(xy 365.364777 -271.752886) (xy 365.353 -271.705102) (xy 365.34904 -271.656048) (xy 365.020098 -271.656048)
			(xy 365.019603 -271.680655) (xy 365.011708 -271.729232) (xy 364.996124 -271.775913) (xy 364.973253 -271.81949)
			(xy 364.943688 -271.858834) (xy 364.908195 -271.892926) (xy 364.867692 -271.920882) (xy 364.82323 -271.94198)
			(xy 364.775959 -271.955672) (xy 364.727104 -271.961604) (xy 364.677929 -271.959623) (xy 364.62971 -271.949779)
			(xy 364.583694 -271.932327) (xy 364.541073 -271.90772) (xy 364.502952 -271.876595) (xy 364.470317 -271.839758)
			(xy 364.444014 -271.798162) (xy 364.424723 -271.752886) (xy 364.412946 -271.705102) (xy 364.408986 -271.656048)
			(xy 364.080044 -271.656048) (xy 364.079549 -271.680655) (xy 364.071654 -271.729232) (xy 364.05607 -271.775913)
			(xy 364.033199 -271.81949) (xy 364.003634 -271.858834) (xy 363.968141 -271.892926) (xy 363.927638 -271.920882)
			(xy 363.883176 -271.94198) (xy 363.835905 -271.955672) (xy 363.78705 -271.961604) (xy 363.737875 -271.959623)
			(xy 363.689656 -271.949779) (xy 363.64364 -271.932327) (xy 363.601019 -271.90772) (xy 363.562898 -271.876595)
			(xy 363.530263 -271.839758) (xy 363.50396 -271.798162) (xy 363.484669 -271.752886) (xy 363.472892 -271.705102)
			(xy 363.468932 -271.656048) (xy 356.56647 -271.656048) (xy 356.565975 -271.680655) (xy 356.55808 -271.729232)
			(xy 356.542496 -271.775913) (xy 356.519625 -271.81949) (xy 356.49006 -271.858834) (xy 356.454567 -271.892926)
			(xy 356.414064 -271.920882) (xy 356.369602 -271.94198) (xy 356.322331 -271.955672) (xy 356.273476 -271.961604)
			(xy 356.224301 -271.959623) (xy 356.176082 -271.949779) (xy 356.130066 -271.932327) (xy 356.087445 -271.90772)
			(xy 356.049324 -271.876595) (xy 356.016689 -271.839758) (xy 355.990386 -271.798162) (xy 355.971095 -271.752886)
			(xy 355.959318 -271.705102) (xy 355.955358 -271.656048) (xy 355.626416 -271.656048) (xy 355.625921 -271.680655)
			(xy 355.618026 -271.729232) (xy 355.602442 -271.775913) (xy 355.579571 -271.81949) (xy 355.550006 -271.858834)
			(xy 355.514513 -271.892926) (xy 355.47401 -271.920882) (xy 355.429548 -271.94198) (xy 355.382277 -271.955672)
			(xy 355.333422 -271.961604) (xy 355.284247 -271.959623) (xy 355.236028 -271.949779) (xy 355.190012 -271.932327)
			(xy 355.147391 -271.90772) (xy 355.10927 -271.876595) (xy 355.076635 -271.839758) (xy 355.050332 -271.798162)
			(xy 355.031041 -271.752886) (xy 355.019264 -271.705102) (xy 355.015304 -271.656048) (xy 354.686362 -271.656048)
			(xy 354.685867 -271.680655) (xy 354.677972 -271.729232) (xy 354.662388 -271.775913) (xy 354.639517 -271.81949)
			(xy 354.609952 -271.858834) (xy 354.574459 -271.892926) (xy 354.533956 -271.920882) (xy 354.489494 -271.94198)
			(xy 354.442223 -271.955672) (xy 354.393368 -271.961604) (xy 354.344193 -271.959623) (xy 354.295974 -271.949779)
			(xy 354.249958 -271.932327) (xy 354.207337 -271.90772) (xy 354.169216 -271.876595) (xy 354.136581 -271.839758)
			(xy 354.110278 -271.798162) (xy 354.090987 -271.752886) (xy 354.07921 -271.705102) (xy 354.07525 -271.656048)
			(xy 353.746308 -271.656048) (xy 353.745813 -271.680655) (xy 353.737918 -271.729232) (xy 353.722334 -271.775913)
			(xy 353.699463 -271.81949) (xy 353.669898 -271.858834) (xy 353.634405 -271.892926) (xy 353.593902 -271.920882)
			(xy 353.54944 -271.94198) (xy 353.502169 -271.955672) (xy 353.453314 -271.961604) (xy 353.404139 -271.959623)
			(xy 353.35592 -271.949779) (xy 353.309904 -271.932327) (xy 353.267283 -271.90772) (xy 353.229162 -271.876595)
			(xy 353.196527 -271.839758) (xy 353.170224 -271.798162) (xy 353.150933 -271.752886) (xy 353.139156 -271.705102)
			(xy 353.135196 -271.656048) (xy 352.806508 -271.656048) (xy 352.806013 -271.680655) (xy 352.798118 -271.729232)
			(xy 352.782534 -271.775913) (xy 352.759663 -271.81949) (xy 352.730098 -271.858834) (xy 352.694605 -271.892926)
			(xy 352.654102 -271.920882) (xy 352.60964 -271.94198) (xy 352.562369 -271.955672) (xy 352.513514 -271.961604)
			(xy 352.464339 -271.959623) (xy 352.41612 -271.949779) (xy 352.370104 -271.932327) (xy 352.327483 -271.90772)
			(xy 352.289362 -271.876595) (xy 352.256727 -271.839758) (xy 352.230424 -271.798162) (xy 352.211133 -271.752886)
			(xy 352.199356 -271.705102) (xy 352.195396 -271.656048) (xy 351.866454 -271.656048) (xy 351.865959 -271.680655)
			(xy 351.858064 -271.729232) (xy 351.84248 -271.775913) (xy 351.819609 -271.81949) (xy 351.790044 -271.858834)
			(xy 351.754551 -271.892926) (xy 351.714048 -271.920882) (xy 351.669586 -271.94198) (xy 351.622315 -271.955672)
			(xy 351.57346 -271.961604) (xy 351.524285 -271.959623) (xy 351.476066 -271.949779) (xy 351.43005 -271.932327)
			(xy 351.387429 -271.90772) (xy 351.349308 -271.876595) (xy 351.316673 -271.839758) (xy 351.29037 -271.798162)
			(xy 351.271079 -271.752886) (xy 351.259302 -271.705102) (xy 351.255342 -271.656048) (xy 350.9264 -271.656048)
			(xy 350.925905 -271.680655) (xy 350.91801 -271.729232) (xy 350.902426 -271.775913) (xy 350.879555 -271.81949)
			(xy 350.84999 -271.858834) (xy 350.814497 -271.892926) (xy 350.773994 -271.920882) (xy 350.729532 -271.94198)
			(xy 350.682261 -271.955672) (xy 350.633406 -271.961604) (xy 350.584231 -271.959623) (xy 350.536012 -271.949779)
			(xy 350.489996 -271.932327) (xy 350.447375 -271.90772) (xy 350.409254 -271.876595) (xy 350.376619 -271.839758)
			(xy 350.350316 -271.798162) (xy 350.331025 -271.752886) (xy 350.319248 -271.705102) (xy 350.315288 -271.656048)
			(xy 349.986346 -271.656048) (xy 349.985851 -271.680655) (xy 349.977956 -271.729232) (xy 349.962372 -271.775913)
			(xy 349.939501 -271.81949) (xy 349.909936 -271.858834) (xy 349.874443 -271.892926) (xy 349.83394 -271.920882)
			(xy 349.789478 -271.94198) (xy 349.742207 -271.955672) (xy 349.693352 -271.961604) (xy 349.644177 -271.959623)
			(xy 349.595958 -271.949779) (xy 349.549942 -271.932327) (xy 349.507321 -271.90772) (xy 349.4692 -271.876595)
			(xy 349.436565 -271.839758) (xy 349.410262 -271.798162) (xy 349.390971 -271.752886) (xy 349.379194 -271.705102)
			(xy 349.375234 -271.656048) (xy 349.046546 -271.656048) (xy 349.046051 -271.680655) (xy 349.038156 -271.729232)
			(xy 349.022572 -271.775913) (xy 348.999701 -271.81949) (xy 348.970136 -271.858834) (xy 348.934643 -271.892926)
			(xy 348.89414 -271.920882) (xy 348.849678 -271.94198) (xy 348.802407 -271.955672) (xy 348.753552 -271.961604)
			(xy 348.704377 -271.959623) (xy 348.656158 -271.949779) (xy 348.610142 -271.932327) (xy 348.567521 -271.90772)
			(xy 348.5294 -271.876595) (xy 348.496765 -271.839758) (xy 348.470462 -271.798162) (xy 348.451171 -271.752886)
			(xy 348.439394 -271.705102) (xy 348.435434 -271.656048) (xy 348.106492 -271.656048) (xy 348.105997 -271.680655)
			(xy 348.098102 -271.729232) (xy 348.082518 -271.775913) (xy 348.059647 -271.81949) (xy 348.030082 -271.858834)
			(xy 347.994589 -271.892926) (xy 347.954086 -271.920882) (xy 347.909624 -271.94198) (xy 347.862353 -271.955672)
			(xy 347.813498 -271.961604) (xy 347.764323 -271.959623) (xy 347.716104 -271.949779) (xy 347.670088 -271.932327)
			(xy 347.627467 -271.90772) (xy 347.589346 -271.876595) (xy 347.556711 -271.839758) (xy 347.530408 -271.798162)
			(xy 347.511117 -271.752886) (xy 347.49934 -271.705102) (xy 347.49538 -271.656048) (xy 347.166438 -271.656048)
			(xy 347.165943 -271.680655) (xy 347.158048 -271.729232) (xy 347.142464 -271.775913) (xy 347.119593 -271.81949)
			(xy 347.090028 -271.858834) (xy 347.054535 -271.892926) (xy 347.014032 -271.920882) (xy 346.96957 -271.94198)
			(xy 346.922299 -271.955672) (xy 346.873444 -271.961604) (xy 346.824269 -271.959623) (xy 346.77605 -271.949779)
			(xy 346.730034 -271.932327) (xy 346.687413 -271.90772) (xy 346.649292 -271.876595) (xy 346.616657 -271.839758)
			(xy 346.590354 -271.798162) (xy 346.571063 -271.752886) (xy 346.559286 -271.705102) (xy 346.555326 -271.656048)
			(xy 346.226384 -271.656048) (xy 346.225889 -271.680655) (xy 346.217994 -271.729232) (xy 346.20241 -271.775913)
			(xy 346.179539 -271.81949) (xy 346.149974 -271.858834) (xy 346.114481 -271.892926) (xy 346.073978 -271.920882)
			(xy 346.029516 -271.94198) (xy 345.982245 -271.955672) (xy 345.93339 -271.961604) (xy 345.884215 -271.959623)
			(xy 345.835996 -271.949779) (xy 345.78998 -271.932327) (xy 345.747359 -271.90772) (xy 345.709238 -271.876595)
			(xy 345.676603 -271.839758) (xy 345.6503 -271.798162) (xy 345.631009 -271.752886) (xy 345.619232 -271.705102)
			(xy 345.615272 -271.656048) (xy 345.28633 -271.656048) (xy 345.285876 -271.679787) (xy 345.278522 -271.726691)
			(xy 345.263999 -271.771892) (xy 345.242656 -271.814302) (xy 345.215009 -271.852899) (xy 345.181722 -271.886752)
			(xy 345.143597 -271.915048) (xy 345.101554 -271.937103) (xy 345.056604 -271.952387) (xy 345.00983 -271.960531)
			(xy 344.986102 -271.961356) (xy 344.980768 -271.961356) (xy 344.953954 -271.960774) (xy 344.901158 -271.951365)
			(xy 344.850817 -271.932876) (xy 344.804482 -271.905876) (xy 344.783664 -271.888966) (xy 344.77706 -271.883378)
			(xy 344.753184 -271.87398) (xy 344.748898 -271.872454) (xy 344.739953 -271.870792) (xy 344.735404 -271.870678)
			(xy 344.714576 -271.870424) (xy 344.704379 -271.870777) (xy 344.685513 -271.878506) (xy 344.678 -271.88541)
			(xy 344.556842 -272.006568) (xy 344.550832 -272.013072) (xy 344.543254 -272.029064) (xy 344.541535 -272.046676)
			(xy 344.54338 -272.055336) (xy 344.564462 -272.13687) (xy 344.56766 -272.147205) (xy 344.581214 -272.164043)
			(xy 344.590624 -272.169382) (xy 344.598498 -272.173446) (xy 344.602562 -272.174716) (xy 344.625504 -272.182396)
			(xy 344.668803 -272.203973) (xy 344.708157 -272.23211) (xy 344.742581 -272.266101) (xy 344.771213 -272.305096)
			(xy 344.793336 -272.348118) (xy 344.808397 -272.394092) (xy 344.816018 -272.441865) (xy 344.81643 -272.466054)
			(xy 347.025226 -272.466054) (xy 347.029186 -272.417) (xy 347.040963 -272.369216) (xy 347.060254 -272.32394)
			(xy 347.086557 -272.282344) (xy 347.119192 -272.245507) (xy 347.157313 -272.214382) (xy 347.199934 -272.189775)
			(xy 347.24595 -272.172323) (xy 347.294169 -272.162479) (xy 347.343344 -272.160498) (xy 347.392199 -272.16643)
			(xy 347.43947 -272.180122) (xy 347.483932 -272.20122) (xy 347.524435 -272.229176) (xy 347.559928 -272.263268)
			(xy 347.589493 -272.302612) (xy 347.612364 -272.346189) (xy 347.627948 -272.39287) (xy 347.635843 -272.441447)
			(xy 347.636338 -272.466054) (xy 349.845388 -272.466054) (xy 349.849348 -272.417) (xy 349.861125 -272.369216)
			(xy 349.880416 -272.32394) (xy 349.906719 -272.282344) (xy 349.939354 -272.245507) (xy 349.977475 -272.214382)
			(xy 350.020096 -272.189775) (xy 350.066112 -272.172323) (xy 350.114331 -272.162479) (xy 350.163506 -272.160498)
			(xy 350.212361 -272.16643) (xy 350.259632 -272.180122) (xy 350.304094 -272.20122) (xy 350.344597 -272.229176)
			(xy 350.38009 -272.263268) (xy 350.409655 -272.302612) (xy 350.432526 -272.346189) (xy 350.44811 -272.39287)
			(xy 350.456005 -272.441447) (xy 350.4565 -272.466054) (xy 352.665296 -272.466054) (xy 352.669256 -272.417)
			(xy 352.681033 -272.369216) (xy 352.700324 -272.32394) (xy 352.726627 -272.282344) (xy 352.759262 -272.245507)
			(xy 352.797383 -272.214382) (xy 352.840004 -272.189775) (xy 352.88602 -272.172323) (xy 352.934239 -272.162479)
			(xy 352.983414 -272.160498) (xy 353.032269 -272.16643) (xy 353.07954 -272.180122) (xy 353.124002 -272.20122)
			(xy 353.164505 -272.229176) (xy 353.199998 -272.263268) (xy 353.229563 -272.302612) (xy 353.252434 -272.346189)
			(xy 353.268018 -272.39287) (xy 353.275913 -272.441447) (xy 353.276408 -272.466054) (xy 355.485204 -272.466054)
			(xy 355.489164 -272.417) (xy 355.500941 -272.369216) (xy 355.520232 -272.32394) (xy 355.546535 -272.282344)
			(xy 355.57917 -272.245507) (xy 355.617291 -272.214382) (xy 355.659912 -272.189775) (xy 355.705928 -272.172323)
			(xy 355.754147 -272.162479) (xy 355.803322 -272.160498) (xy 355.852177 -272.16643) (xy 355.899448 -272.180122)
			(xy 355.94391 -272.20122) (xy 355.984413 -272.229176) (xy 356.019906 -272.263268) (xy 356.049471 -272.302612)
			(xy 356.072342 -272.346189) (xy 356.087926 -272.39287) (xy 356.095821 -272.441447) (xy 356.096316 -272.466054)
			(xy 356.425258 -272.466054) (xy 356.429218 -272.417) (xy 356.440995 -272.369216) (xy 356.460286 -272.32394)
			(xy 356.486589 -272.282344) (xy 356.519224 -272.245507) (xy 356.557345 -272.214382) (xy 356.599966 -272.189775)
			(xy 356.645982 -272.172323) (xy 356.694201 -272.162479) (xy 356.743376 -272.160498) (xy 356.792231 -272.16643)
			(xy 356.839502 -272.180122) (xy 356.883964 -272.20122) (xy 356.924467 -272.229176) (xy 356.95996 -272.263268)
			(xy 356.989525 -272.302612) (xy 357.012396 -272.346189) (xy 357.02798 -272.39287) (xy 357.035875 -272.441447)
			(xy 357.03637 -272.466054) (xy 357.365312 -272.466054) (xy 357.369272 -272.417) (xy 357.381049 -272.369216)
			(xy 357.40034 -272.32394) (xy 357.426643 -272.282344) (xy 357.459278 -272.245507) (xy 357.497399 -272.214382)
			(xy 357.54002 -272.189775) (xy 357.586036 -272.172323) (xy 357.634255 -272.162479) (xy 357.68343 -272.160498)
			(xy 357.732285 -272.16643) (xy 357.779556 -272.180122) (xy 357.824018 -272.20122) (xy 357.864521 -272.229176)
			(xy 357.900014 -272.263268) (xy 357.929579 -272.302612) (xy 357.95245 -272.346189) (xy 357.968034 -272.39287)
			(xy 357.975929 -272.441447) (xy 357.976424 -272.466054) (xy 358.305366 -272.466054) (xy 358.309326 -272.417)
			(xy 358.321103 -272.369216) (xy 358.340394 -272.32394) (xy 358.366697 -272.282344) (xy 358.399332 -272.245507)
			(xy 358.437453 -272.214382) (xy 358.480074 -272.189775) (xy 358.52609 -272.172323) (xy 358.574309 -272.162479)
			(xy 358.623484 -272.160498) (xy 358.672339 -272.16643) (xy 358.71961 -272.180122) (xy 358.764072 -272.20122)
			(xy 358.804575 -272.229176) (xy 358.840068 -272.263268) (xy 358.869633 -272.302612) (xy 358.892504 -272.346189)
			(xy 358.908088 -272.39287) (xy 358.915983 -272.441447) (xy 358.916478 -272.466054) (xy 361.118924 -272.466054)
			(xy 361.122884 -272.417) (xy 361.134661 -272.369216) (xy 361.153952 -272.32394) (xy 361.180255 -272.282344)
			(xy 361.21289 -272.245507) (xy 361.251011 -272.214382) (xy 361.293632 -272.189775) (xy 361.339648 -272.172323)
			(xy 361.387867 -272.162479) (xy 361.437042 -272.160498) (xy 361.485897 -272.16643) (xy 361.533168 -272.180122)
			(xy 361.57763 -272.20122) (xy 361.618133 -272.229176) (xy 361.653626 -272.263268) (xy 361.683191 -272.302612)
			(xy 361.706062 -272.346189) (xy 361.721646 -272.39287) (xy 361.729541 -272.441447) (xy 361.730036 -272.466054)
			(xy 362.058978 -272.466054) (xy 362.062938 -272.417) (xy 362.074715 -272.369216) (xy 362.094006 -272.32394)
			(xy 362.120309 -272.282344) (xy 362.152944 -272.245507) (xy 362.191065 -272.214382) (xy 362.233686 -272.189775)
			(xy 362.279702 -272.172323) (xy 362.327921 -272.162479) (xy 362.377096 -272.160498) (xy 362.425951 -272.16643)
			(xy 362.473222 -272.180122) (xy 362.517684 -272.20122) (xy 362.558187 -272.229176) (xy 362.59368 -272.263268)
			(xy 362.623245 -272.302612) (xy 362.646116 -272.346189) (xy 362.6617 -272.39287) (xy 362.669595 -272.441447)
			(xy 362.67009 -272.466054) (xy 362.999032 -272.466054) (xy 363.002992 -272.417) (xy 363.014769 -272.369216)
			(xy 363.03406 -272.32394) (xy 363.060363 -272.282344) (xy 363.092998 -272.245507) (xy 363.131119 -272.214382)
			(xy 363.17374 -272.189775) (xy 363.219756 -272.172323) (xy 363.267975 -272.162479) (xy 363.31715 -272.160498)
			(xy 363.366005 -272.16643) (xy 363.413276 -272.180122) (xy 363.457738 -272.20122) (xy 363.498241 -272.229176)
			(xy 363.533734 -272.263268) (xy 363.563299 -272.302612) (xy 363.58617 -272.346189) (xy 363.601754 -272.39287)
			(xy 363.609649 -272.441447) (xy 363.610144 -272.466054) (xy 363.939086 -272.466054) (xy 363.943046 -272.417)
			(xy 363.954823 -272.369216) (xy 363.974114 -272.32394) (xy 364.000417 -272.282344) (xy 364.033052 -272.245507)
			(xy 364.071173 -272.214382) (xy 364.113794 -272.189775) (xy 364.15981 -272.172323) (xy 364.208029 -272.162479)
			(xy 364.257204 -272.160498) (xy 364.306059 -272.16643) (xy 364.35333 -272.180122) (xy 364.397792 -272.20122)
			(xy 364.438295 -272.229176) (xy 364.473788 -272.263268) (xy 364.503353 -272.302612) (xy 364.526224 -272.346189)
			(xy 364.541808 -272.39287) (xy 364.549703 -272.441447) (xy 364.550198 -272.466054) (xy 366.758994 -272.466054)
			(xy 366.762954 -272.417) (xy 366.774731 -272.369216) (xy 366.794022 -272.32394) (xy 366.820325 -272.282344)
			(xy 366.85296 -272.245507) (xy 366.891081 -272.214382) (xy 366.933702 -272.189775) (xy 366.979718 -272.172323)
			(xy 367.027937 -272.162479) (xy 367.077112 -272.160498) (xy 367.125967 -272.16643) (xy 367.173238 -272.180122)
			(xy 367.2177 -272.20122) (xy 367.258203 -272.229176) (xy 367.293696 -272.263268) (xy 367.323261 -272.302612)
			(xy 367.346132 -272.346189) (xy 367.361716 -272.39287) (xy 367.369611 -272.441447) (xy 367.370106 -272.466054)
			(xy 369.578902 -272.466054) (xy 369.582862 -272.417) (xy 369.594639 -272.369216) (xy 369.61393 -272.32394)
			(xy 369.640233 -272.282344) (xy 369.672868 -272.245507) (xy 369.710989 -272.214382) (xy 369.75361 -272.189775)
			(xy 369.799626 -272.172323) (xy 369.847845 -272.162479) (xy 369.89702 -272.160498) (xy 369.945875 -272.16643)
			(xy 369.993146 -272.180122) (xy 370.037608 -272.20122) (xy 370.078111 -272.229176) (xy 370.113604 -272.263268)
			(xy 370.143169 -272.302612) (xy 370.16604 -272.346189) (xy 370.181624 -272.39287) (xy 370.189519 -272.441447)
			(xy 370.190014 -272.466054) (xy 372.399064 -272.466054) (xy 372.403024 -272.417) (xy 372.414801 -272.369216)
			(xy 372.434092 -272.32394) (xy 372.460395 -272.282344) (xy 372.49303 -272.245507) (xy 372.531151 -272.214382)
			(xy 372.573772 -272.189775) (xy 372.619788 -272.172323) (xy 372.668007 -272.162479) (xy 372.717182 -272.160498)
			(xy 372.766037 -272.16643) (xy 372.813308 -272.180122) (xy 372.85777 -272.20122) (xy 372.898273 -272.229176)
			(xy 372.933766 -272.263268) (xy 372.963331 -272.302612) (xy 372.986202 -272.346189) (xy 373.001786 -272.39287)
			(xy 373.009681 -272.441447) (xy 373.010176 -272.466054) (xy 373.009681 -272.490661) (xy 373.001786 -272.539238)
			(xy 372.986202 -272.585919) (xy 372.963331 -272.629496) (xy 372.933766 -272.66884) (xy 372.898273 -272.702932)
			(xy 372.85777 -272.730888) (xy 372.813308 -272.751986) (xy 372.766037 -272.765678) (xy 372.717182 -272.77161)
			(xy 372.668007 -272.769629) (xy 372.619788 -272.759785) (xy 372.573772 -272.742333) (xy 372.531151 -272.717726)
			(xy 372.49303 -272.686601) (xy 372.460395 -272.649764) (xy 372.434092 -272.608168) (xy 372.414801 -272.562892)
			(xy 372.403024 -272.515108) (xy 372.399064 -272.466054) (xy 370.190014 -272.466054) (xy 370.189519 -272.490661)
			(xy 370.181624 -272.539238) (xy 370.16604 -272.585919) (xy 370.143169 -272.629496) (xy 370.113604 -272.66884)
			(xy 370.078111 -272.702932) (xy 370.037608 -272.730888) (xy 369.993146 -272.751986) (xy 369.945875 -272.765678)
			(xy 369.89702 -272.77161) (xy 369.847845 -272.769629) (xy 369.799626 -272.759785) (xy 369.75361 -272.742333)
			(xy 369.710989 -272.717726) (xy 369.672868 -272.686601) (xy 369.640233 -272.649764) (xy 369.61393 -272.608168)
			(xy 369.594639 -272.562892) (xy 369.582862 -272.515108) (xy 369.578902 -272.466054) (xy 367.370106 -272.466054)
			(xy 367.369611 -272.490661) (xy 367.361716 -272.539238) (xy 367.346132 -272.585919) (xy 367.323261 -272.629496)
			(xy 367.293696 -272.66884) (xy 367.258203 -272.702932) (xy 367.2177 -272.730888) (xy 367.173238 -272.751986)
			(xy 367.125967 -272.765678) (xy 367.077112 -272.77161) (xy 367.027937 -272.769629) (xy 366.979718 -272.759785)
			(xy 366.933702 -272.742333) (xy 366.891081 -272.717726) (xy 366.85296 -272.686601) (xy 366.820325 -272.649764)
			(xy 366.794022 -272.608168) (xy 366.774731 -272.562892) (xy 366.762954 -272.515108) (xy 366.758994 -272.466054)
			(xy 364.550198 -272.466054) (xy 364.549703 -272.490661) (xy 364.541808 -272.539238) (xy 364.526224 -272.585919)
			(xy 364.503353 -272.629496) (xy 364.473788 -272.66884) (xy 364.438295 -272.702932) (xy 364.397792 -272.730888)
			(xy 364.35333 -272.751986) (xy 364.306059 -272.765678) (xy 364.257204 -272.77161) (xy 364.208029 -272.769629)
			(xy 364.15981 -272.759785) (xy 364.113794 -272.742333) (xy 364.071173 -272.717726) (xy 364.033052 -272.686601)
			(xy 364.000417 -272.649764) (xy 363.974114 -272.608168) (xy 363.954823 -272.562892) (xy 363.943046 -272.515108)
			(xy 363.939086 -272.466054) (xy 363.610144 -272.466054) (xy 363.609649 -272.490661) (xy 363.601754 -272.539238)
			(xy 363.58617 -272.585919) (xy 363.563299 -272.629496) (xy 363.533734 -272.66884) (xy 363.498241 -272.702932)
			(xy 363.457738 -272.730888) (xy 363.413276 -272.751986) (xy 363.366005 -272.765678) (xy 363.31715 -272.77161)
			(xy 363.267975 -272.769629) (xy 363.219756 -272.759785) (xy 363.17374 -272.742333) (xy 363.131119 -272.717726)
			(xy 363.092998 -272.686601) (xy 363.060363 -272.649764) (xy 363.03406 -272.608168) (xy 363.014769 -272.562892)
			(xy 363.002992 -272.515108) (xy 362.999032 -272.466054) (xy 362.67009 -272.466054) (xy 362.669595 -272.490661)
			(xy 362.6617 -272.539238) (xy 362.646116 -272.585919) (xy 362.623245 -272.629496) (xy 362.59368 -272.66884)
			(xy 362.558187 -272.702932) (xy 362.517684 -272.730888) (xy 362.473222 -272.751986) (xy 362.425951 -272.765678)
			(xy 362.377096 -272.77161) (xy 362.327921 -272.769629) (xy 362.279702 -272.759785) (xy 362.233686 -272.742333)
			(xy 362.191065 -272.717726) (xy 362.152944 -272.686601) (xy 362.120309 -272.649764) (xy 362.094006 -272.608168)
			(xy 362.074715 -272.562892) (xy 362.062938 -272.515108) (xy 362.058978 -272.466054) (xy 361.730036 -272.466054)
			(xy 361.729541 -272.490661) (xy 361.721646 -272.539238) (xy 361.706062 -272.585919) (xy 361.683191 -272.629496)
			(xy 361.653626 -272.66884) (xy 361.618133 -272.702932) (xy 361.57763 -272.730888) (xy 361.533168 -272.751986)
			(xy 361.485897 -272.765678) (xy 361.437042 -272.77161) (xy 361.387867 -272.769629) (xy 361.339648 -272.759785)
			(xy 361.293632 -272.742333) (xy 361.251011 -272.717726) (xy 361.21289 -272.686601) (xy 361.180255 -272.649764)
			(xy 361.153952 -272.608168) (xy 361.134661 -272.562892) (xy 361.122884 -272.515108) (xy 361.118924 -272.466054)
			(xy 358.916478 -272.466054) (xy 358.915983 -272.490661) (xy 358.908088 -272.539238) (xy 358.892504 -272.585919)
			(xy 358.869633 -272.629496) (xy 358.840068 -272.66884) (xy 358.804575 -272.702932) (xy 358.764072 -272.730888)
			(xy 358.71961 -272.751986) (xy 358.672339 -272.765678) (xy 358.623484 -272.77161) (xy 358.574309 -272.769629)
			(xy 358.52609 -272.759785) (xy 358.480074 -272.742333) (xy 358.437453 -272.717726) (xy 358.399332 -272.686601)
			(xy 358.366697 -272.649764) (xy 358.340394 -272.608168) (xy 358.321103 -272.562892) (xy 358.309326 -272.515108)
			(xy 358.305366 -272.466054) (xy 357.976424 -272.466054) (xy 357.975929 -272.490661) (xy 357.968034 -272.539238)
			(xy 357.95245 -272.585919) (xy 357.929579 -272.629496) (xy 357.900014 -272.66884) (xy 357.864521 -272.702932)
			(xy 357.824018 -272.730888) (xy 357.779556 -272.751986) (xy 357.732285 -272.765678) (xy 357.68343 -272.77161)
			(xy 357.634255 -272.769629) (xy 357.586036 -272.759785) (xy 357.54002 -272.742333) (xy 357.497399 -272.717726)
			(xy 357.459278 -272.686601) (xy 357.426643 -272.649764) (xy 357.40034 -272.608168) (xy 357.381049 -272.562892)
			(xy 357.369272 -272.515108) (xy 357.365312 -272.466054) (xy 357.03637 -272.466054) (xy 357.035875 -272.490661)
			(xy 357.02798 -272.539238) (xy 357.012396 -272.585919) (xy 356.989525 -272.629496) (xy 356.95996 -272.66884)
			(xy 356.924467 -272.702932) (xy 356.883964 -272.730888) (xy 356.839502 -272.751986) (xy 356.792231 -272.765678)
			(xy 356.743376 -272.77161) (xy 356.694201 -272.769629) (xy 356.645982 -272.759785) (xy 356.599966 -272.742333)
			(xy 356.557345 -272.717726) (xy 356.519224 -272.686601) (xy 356.486589 -272.649764) (xy 356.460286 -272.608168)
			(xy 356.440995 -272.562892) (xy 356.429218 -272.515108) (xy 356.425258 -272.466054) (xy 356.096316 -272.466054)
			(xy 356.095821 -272.490661) (xy 356.087926 -272.539238) (xy 356.072342 -272.585919) (xy 356.049471 -272.629496)
			(xy 356.019906 -272.66884) (xy 355.984413 -272.702932) (xy 355.94391 -272.730888) (xy 355.899448 -272.751986)
			(xy 355.852177 -272.765678) (xy 355.803322 -272.77161) (xy 355.754147 -272.769629) (xy 355.705928 -272.759785)
			(xy 355.659912 -272.742333) (xy 355.617291 -272.717726) (xy 355.57917 -272.686601) (xy 355.546535 -272.649764)
			(xy 355.520232 -272.608168) (xy 355.500941 -272.562892) (xy 355.489164 -272.515108) (xy 355.485204 -272.466054)
			(xy 353.276408 -272.466054) (xy 353.275913 -272.490661) (xy 353.268018 -272.539238) (xy 353.252434 -272.585919)
			(xy 353.229563 -272.629496) (xy 353.199998 -272.66884) (xy 353.164505 -272.702932) (xy 353.124002 -272.730888)
			(xy 353.07954 -272.751986) (xy 353.032269 -272.765678) (xy 352.983414 -272.77161) (xy 352.934239 -272.769629)
			(xy 352.88602 -272.759785) (xy 352.840004 -272.742333) (xy 352.797383 -272.717726) (xy 352.759262 -272.686601)
			(xy 352.726627 -272.649764) (xy 352.700324 -272.608168) (xy 352.681033 -272.562892) (xy 352.669256 -272.515108)
			(xy 352.665296 -272.466054) (xy 350.4565 -272.466054) (xy 350.456005 -272.490661) (xy 350.44811 -272.539238)
			(xy 350.432526 -272.585919) (xy 350.409655 -272.629496) (xy 350.38009 -272.66884) (xy 350.344597 -272.702932)
			(xy 350.304094 -272.730888) (xy 350.259632 -272.751986) (xy 350.212361 -272.765678) (xy 350.163506 -272.77161)
			(xy 350.114331 -272.769629) (xy 350.066112 -272.759785) (xy 350.020096 -272.742333) (xy 349.977475 -272.717726)
			(xy 349.939354 -272.686601) (xy 349.906719 -272.649764) (xy 349.880416 -272.608168) (xy 349.861125 -272.562892)
			(xy 349.849348 -272.515108) (xy 349.845388 -272.466054) (xy 347.636338 -272.466054) (xy 347.635843 -272.490661)
			(xy 347.627948 -272.539238) (xy 347.612364 -272.585919) (xy 347.589493 -272.629496) (xy 347.559928 -272.66884)
			(xy 347.524435 -272.702932) (xy 347.483932 -272.730888) (xy 347.43947 -272.751986) (xy 347.392199 -272.765678)
			(xy 347.343344 -272.77161) (xy 347.294169 -272.769629) (xy 347.24595 -272.759785) (xy 347.199934 -272.742333)
			(xy 347.157313 -272.717726) (xy 347.119192 -272.686601) (xy 347.086557 -272.649764) (xy 347.060254 -272.608168)
			(xy 347.040963 -272.562892) (xy 347.029186 -272.515108) (xy 347.025226 -272.466054) (xy 344.81643 -272.466054)
			(xy 344.815987 -272.49005) (xy 344.808486 -272.537452) (xy 344.793662 -272.583098) (xy 344.77188 -272.625862)
			(xy 344.743675 -272.664692) (xy 344.709743 -272.698631) (xy 344.67092 -272.726844) (xy 344.628161 -272.748636)
			(xy 344.582519 -272.763471) (xy 344.535118 -272.770982) (xy 344.511122 -272.771362) (xy 344.498359 -272.771222)
			(xy 344.472926 -272.769056) (xy 344.460322 -272.767044) (xy 344.436751 -272.762581) (xy 344.391282 -272.747288)
			(xy 344.348762 -272.725079) (xy 344.310233 -272.696499) (xy 344.276643 -272.66225) (xy 344.248816 -272.623175)
			(xy 344.227436 -272.580231) (xy 344.219784 -272.557494) (xy 344.218514 -272.55343) (xy 344.21445 -272.545556)
			(xy 344.209133 -272.536124) (xy 344.192294 -272.522548) (xy 344.181938 -272.519394) (xy 344.100404 -272.498312)
			(xy 344.091006 -272.496788) (xy 344.090752 -272.496788) (xy 344.079884 -272.496625) (xy 344.059602 -272.504381)
			(xy 344.051636 -272.511774) (xy 343.660222 -272.903188) (xy 343.656412 -272.911824) (xy 343.640167 -272.948388)
			(xy 343.60315 -273.019328) (xy 343.561148 -273.087436) (xy 343.538048 -273.120104) (xy 343.511248 -273.156492)
			(xy 343.452627 -273.225282) (xy 343.420954 -273.257518) (xy 343.414648 -273.264488) (xy 343.409574 -273.27606)
			(xy 343.724987 -273.27606) (xy 343.729082 -273.225332) (xy 343.741261 -273.175918) (xy 343.761209 -273.129098)
			(xy 343.78841 -273.086084) (xy 343.822158 -273.04799) (xy 343.86158 -273.015803) (xy 343.905654 -272.990357)
			(xy 343.95324 -272.97231) (xy 344.003104 -272.96213) (xy 344.053956 -272.960081) (xy 344.104477 -272.966215)
			(xy 344.153361 -272.980375) (xy 344.19934 -273.002192) (xy 344.241224 -273.031102) (xy 344.277928 -273.066357)
			(xy 344.308501 -273.107043) (xy 344.332152 -273.152106) (xy 344.348268 -273.20038) (xy 344.356432 -273.250614)
			(xy 344.356944 -273.27606) (xy 344.675218 -273.27606) (xy 344.679178 -273.227006) (xy 344.690955 -273.179222)
			(xy 344.710246 -273.133946) (xy 344.736549 -273.09235) (xy 344.769184 -273.055513) (xy 344.807305 -273.024388)
			(xy 344.849926 -272.999781) (xy 344.895942 -272.982329) (xy 344.944161 -272.972485) (xy 344.993336 -272.970504)
			(xy 345.042191 -272.976436) (xy 345.089462 -272.990128) (xy 345.133924 -273.011226) (xy 345.174427 -273.039182)
			(xy 345.20992 -273.073274) (xy 345.239485 -273.112618) (xy 345.262356 -273.156195) (xy 345.27794 -273.202876)
			(xy 345.285835 -273.251453) (xy 345.28633 -273.27606) (xy 345.615272 -273.27606) (xy 345.619232 -273.227006)
			(xy 345.631009 -273.179222) (xy 345.6503 -273.133946) (xy 345.676603 -273.09235) (xy 345.709238 -273.055513)
			(xy 345.747359 -273.024388) (xy 345.78998 -272.999781) (xy 345.835996 -272.982329) (xy 345.884215 -272.972485)
			(xy 345.93339 -272.970504) (xy 345.982245 -272.976436) (xy 346.029516 -272.990128) (xy 346.073978 -273.011226)
			(xy 346.114481 -273.039182) (xy 346.149974 -273.073274) (xy 346.179539 -273.112618) (xy 346.20241 -273.156195)
			(xy 346.217994 -273.202876) (xy 346.225889 -273.251453) (xy 346.226384 -273.27606) (xy 346.555326 -273.27606)
			(xy 346.559286 -273.227006) (xy 346.571063 -273.179222) (xy 346.590354 -273.133946) (xy 346.616657 -273.09235)
			(xy 346.649292 -273.055513) (xy 346.687413 -273.024388) (xy 346.730034 -272.999781) (xy 346.77605 -272.982329)
			(xy 346.824269 -272.972485) (xy 346.873444 -272.970504) (xy 346.922299 -272.976436) (xy 346.96957 -272.990128)
			(xy 347.014032 -273.011226) (xy 347.054535 -273.039182) (xy 347.090028 -273.073274) (xy 347.119593 -273.112618)
			(xy 347.142464 -273.156195) (xy 347.158048 -273.202876) (xy 347.165943 -273.251453) (xy 347.166438 -273.27606)
			(xy 347.49538 -273.27606) (xy 347.49934 -273.227006) (xy 347.511117 -273.179222) (xy 347.530408 -273.133946)
			(xy 347.556711 -273.09235) (xy 347.589346 -273.055513) (xy 347.627467 -273.024388) (xy 347.670088 -272.999781)
			(xy 347.716104 -272.982329) (xy 347.764323 -272.972485) (xy 347.813498 -272.970504) (xy 347.862353 -272.976436)
			(xy 347.909624 -272.990128) (xy 347.954086 -273.011226) (xy 347.994589 -273.039182) (xy 348.030082 -273.073274)
			(xy 348.059647 -273.112618) (xy 348.082518 -273.156195) (xy 348.098102 -273.202876) (xy 348.105997 -273.251453)
			(xy 348.106492 -273.27606) (xy 348.435434 -273.27606) (xy 348.439394 -273.227006) (xy 348.451171 -273.179222)
			(xy 348.470462 -273.133946) (xy 348.496765 -273.09235) (xy 348.5294 -273.055513) (xy 348.567521 -273.024388)
			(xy 348.610142 -272.999781) (xy 348.656158 -272.982329) (xy 348.704377 -272.972485) (xy 348.753552 -272.970504)
			(xy 348.802407 -272.976436) (xy 348.849678 -272.990128) (xy 348.89414 -273.011226) (xy 348.934643 -273.039182)
			(xy 348.970136 -273.073274) (xy 348.999701 -273.112618) (xy 349.022572 -273.156195) (xy 349.038156 -273.202876)
			(xy 349.046051 -273.251453) (xy 349.046546 -273.27606) (xy 349.375234 -273.27606) (xy 349.379194 -273.227006)
			(xy 349.390971 -273.179222) (xy 349.410262 -273.133946) (xy 349.436565 -273.09235) (xy 349.4692 -273.055513)
			(xy 349.507321 -273.024388) (xy 349.549942 -272.999781) (xy 349.595958 -272.982329) (xy 349.644177 -272.972485)
			(xy 349.693352 -272.970504) (xy 349.742207 -272.976436) (xy 349.789478 -272.990128) (xy 349.83394 -273.011226)
			(xy 349.874443 -273.039182) (xy 349.909936 -273.073274) (xy 349.939501 -273.112618) (xy 349.962372 -273.156195)
			(xy 349.977956 -273.202876) (xy 349.985851 -273.251453) (xy 349.986346 -273.27606) (xy 350.315288 -273.27606)
			(xy 350.319248 -273.227006) (xy 350.331025 -273.179222) (xy 350.350316 -273.133946) (xy 350.376619 -273.09235)
			(xy 350.409254 -273.055513) (xy 350.447375 -273.024388) (xy 350.489996 -272.999781) (xy 350.536012 -272.982329)
			(xy 350.584231 -272.972485) (xy 350.633406 -272.970504) (xy 350.682261 -272.976436) (xy 350.729532 -272.990128)
			(xy 350.773994 -273.011226) (xy 350.814497 -273.039182) (xy 350.84999 -273.073274) (xy 350.879555 -273.112618)
			(xy 350.902426 -273.156195) (xy 350.91801 -273.202876) (xy 350.925905 -273.251453) (xy 350.9264 -273.27606)
			(xy 351.255342 -273.27606) (xy 351.259302 -273.227006) (xy 351.271079 -273.179222) (xy 351.29037 -273.133946)
			(xy 351.316673 -273.09235) (xy 351.349308 -273.055513) (xy 351.387429 -273.024388) (xy 351.43005 -272.999781)
			(xy 351.476066 -272.982329) (xy 351.524285 -272.972485) (xy 351.57346 -272.970504) (xy 351.622315 -272.976436)
			(xy 351.669586 -272.990128) (xy 351.714048 -273.011226) (xy 351.754551 -273.039182) (xy 351.790044 -273.073274)
			(xy 351.819609 -273.112618) (xy 351.84248 -273.156195) (xy 351.858064 -273.202876) (xy 351.865959 -273.251453)
			(xy 351.866454 -273.27606) (xy 352.195396 -273.27606) (xy 352.199356 -273.227006) (xy 352.211133 -273.179222)
			(xy 352.230424 -273.133946) (xy 352.256727 -273.09235) (xy 352.289362 -273.055513) (xy 352.327483 -273.024388)
			(xy 352.370104 -272.999781) (xy 352.41612 -272.982329) (xy 352.464339 -272.972485) (xy 352.513514 -272.970504)
			(xy 352.562369 -272.976436) (xy 352.60964 -272.990128) (xy 352.654102 -273.011226) (xy 352.694605 -273.039182)
			(xy 352.730098 -273.073274) (xy 352.759663 -273.112618) (xy 352.782534 -273.156195) (xy 352.798118 -273.202876)
			(xy 352.806013 -273.251453) (xy 352.806508 -273.27606) (xy 353.135196 -273.27606) (xy 353.139156 -273.227006)
			(xy 353.150933 -273.179222) (xy 353.170224 -273.133946) (xy 353.196527 -273.09235) (xy 353.229162 -273.055513)
			(xy 353.267283 -273.024388) (xy 353.309904 -272.999781) (xy 353.35592 -272.982329) (xy 353.404139 -272.972485)
			(xy 353.453314 -272.970504) (xy 353.502169 -272.976436) (xy 353.54944 -272.990128) (xy 353.593902 -273.011226)
			(xy 353.634405 -273.039182) (xy 353.669898 -273.073274) (xy 353.699463 -273.112618) (xy 353.722334 -273.156195)
			(xy 353.737918 -273.202876) (xy 353.745813 -273.251453) (xy 353.746308 -273.27606) (xy 354.07525 -273.27606)
			(xy 354.07921 -273.227006) (xy 354.090987 -273.179222) (xy 354.110278 -273.133946) (xy 354.136581 -273.09235)
			(xy 354.169216 -273.055513) (xy 354.207337 -273.024388) (xy 354.249958 -272.999781) (xy 354.295974 -272.982329)
			(xy 354.344193 -272.972485) (xy 354.393368 -272.970504) (xy 354.442223 -272.976436) (xy 354.489494 -272.990128)
			(xy 354.533956 -273.011226) (xy 354.574459 -273.039182) (xy 354.609952 -273.073274) (xy 354.639517 -273.112618)
			(xy 354.662388 -273.156195) (xy 354.677972 -273.202876) (xy 354.685867 -273.251453) (xy 354.686362 -273.27606)
			(xy 355.015304 -273.27606) (xy 355.019264 -273.227006) (xy 355.031041 -273.179222) (xy 355.050332 -273.133946)
			(xy 355.076635 -273.09235) (xy 355.10927 -273.055513) (xy 355.147391 -273.024388) (xy 355.190012 -272.999781)
			(xy 355.236028 -272.982329) (xy 355.284247 -272.972485) (xy 355.333422 -272.970504) (xy 355.382277 -272.976436)
			(xy 355.429548 -272.990128) (xy 355.47401 -273.011226) (xy 355.514513 -273.039182) (xy 355.550006 -273.073274)
			(xy 355.579571 -273.112618) (xy 355.602442 -273.156195) (xy 355.618026 -273.202876) (xy 355.625921 -273.251453)
			(xy 355.626416 -273.27606) (xy 355.955358 -273.27606) (xy 355.959318 -273.227006) (xy 355.971095 -273.179222)
			(xy 355.990386 -273.133946) (xy 356.016689 -273.09235) (xy 356.049324 -273.055513) (xy 356.087445 -273.024388)
			(xy 356.130066 -272.999781) (xy 356.176082 -272.982329) (xy 356.224301 -272.972485) (xy 356.273476 -272.970504)
			(xy 356.322331 -272.976436) (xy 356.369602 -272.990128) (xy 356.414064 -273.011226) (xy 356.454567 -273.039182)
			(xy 356.49006 -273.073274) (xy 356.519625 -273.112618) (xy 356.542496 -273.156195) (xy 356.55808 -273.202876)
			(xy 356.565975 -273.251453) (xy 356.56647 -273.27606) (xy 356.895412 -273.27606) (xy 356.899372 -273.227006)
			(xy 356.911149 -273.179222) (xy 356.93044 -273.133946) (xy 356.956743 -273.09235) (xy 356.989378 -273.055513)
			(xy 357.027499 -273.024388) (xy 357.07012 -272.999781) (xy 357.116136 -272.982329) (xy 357.164355 -272.972485)
			(xy 357.21353 -272.970504) (xy 357.262385 -272.976436) (xy 357.309656 -272.990128) (xy 357.354118 -273.011226)
			(xy 357.394621 -273.039182) (xy 357.430114 -273.073274) (xy 357.459679 -273.112618) (xy 357.48255 -273.156195)
			(xy 357.498134 -273.202876) (xy 357.506029 -273.251453) (xy 357.506524 -273.27606) (xy 357.835212 -273.27606)
			(xy 357.839172 -273.227006) (xy 357.850949 -273.179222) (xy 357.87024 -273.133946) (xy 357.896543 -273.09235)
			(xy 357.929178 -273.055513) (xy 357.967299 -273.024388) (xy 358.00992 -272.999781) (xy 358.055936 -272.982329)
			(xy 358.104155 -272.972485) (xy 358.15333 -272.970504) (xy 358.202185 -272.976436) (xy 358.249456 -272.990128)
			(xy 358.293918 -273.011226) (xy 358.334421 -273.039182) (xy 358.369914 -273.073274) (xy 358.399479 -273.112618)
			(xy 358.42235 -273.156195) (xy 358.437934 -273.202876) (xy 358.445829 -273.251453) (xy 358.446324 -273.27606)
			(xy 361.589078 -273.27606) (xy 361.593038 -273.227006) (xy 361.604815 -273.179222) (xy 361.624106 -273.133946)
			(xy 361.650409 -273.09235) (xy 361.683044 -273.055513) (xy 361.721165 -273.024388) (xy 361.763786 -272.999781)
			(xy 361.809802 -272.982329) (xy 361.858021 -272.972485) (xy 361.907196 -272.970504) (xy 361.956051 -272.976436)
			(xy 362.003322 -272.990128) (xy 362.047784 -273.011226) (xy 362.088287 -273.039182) (xy 362.12378 -273.073274)
			(xy 362.153345 -273.112618) (xy 362.176216 -273.156195) (xy 362.1918 -273.202876) (xy 362.199695 -273.251453)
			(xy 362.20019 -273.27606) (xy 362.528878 -273.27606) (xy 362.532838 -273.227006) (xy 362.544615 -273.179222)
			(xy 362.563906 -273.133946) (xy 362.590209 -273.09235) (xy 362.622844 -273.055513) (xy 362.660965 -273.024388)
			(xy 362.703586 -272.999781) (xy 362.749602 -272.982329) (xy 362.797821 -272.972485) (xy 362.846996 -272.970504)
			(xy 362.895851 -272.976436) (xy 362.943122 -272.990128) (xy 362.987584 -273.011226) (xy 363.028087 -273.039182)
			(xy 363.06358 -273.073274) (xy 363.093145 -273.112618) (xy 363.116016 -273.156195) (xy 363.1316 -273.202876)
			(xy 363.139495 -273.251453) (xy 363.13999 -273.27606) (xy 363.468932 -273.27606) (xy 363.472892 -273.227006)
			(xy 363.484669 -273.179222) (xy 363.50396 -273.133946) (xy 363.530263 -273.09235) (xy 363.562898 -273.055513)
			(xy 363.601019 -273.024388) (xy 363.64364 -272.999781) (xy 363.689656 -272.982329) (xy 363.737875 -272.972485)
			(xy 363.78705 -272.970504) (xy 363.835905 -272.976436) (xy 363.883176 -272.990128) (xy 363.927638 -273.011226)
			(xy 363.968141 -273.039182) (xy 364.003634 -273.073274) (xy 364.033199 -273.112618) (xy 364.05607 -273.156195)
			(xy 364.071654 -273.202876) (xy 364.079549 -273.251453) (xy 364.080044 -273.27606) (xy 364.408986 -273.27606)
			(xy 364.412946 -273.227006) (xy 364.424723 -273.179222) (xy 364.444014 -273.133946) (xy 364.470317 -273.09235)
			(xy 364.502952 -273.055513) (xy 364.541073 -273.024388) (xy 364.583694 -272.999781) (xy 364.62971 -272.982329)
			(xy 364.677929 -272.972485) (xy 364.727104 -272.970504) (xy 364.775959 -272.976436) (xy 364.82323 -272.990128)
			(xy 364.867692 -273.011226) (xy 364.908195 -273.039182) (xy 364.943688 -273.073274) (xy 364.973253 -273.112618)
			(xy 364.996124 -273.156195) (xy 365.011708 -273.202876) (xy 365.019603 -273.251453) (xy 365.020098 -273.27606)
			(xy 365.34904 -273.27606) (xy 365.353 -273.227006) (xy 365.364777 -273.179222) (xy 365.384068 -273.133946)
			(xy 365.410371 -273.09235) (xy 365.443006 -273.055513) (xy 365.481127 -273.024388) (xy 365.523748 -272.999781)
			(xy 365.569764 -272.982329) (xy 365.617983 -272.972485) (xy 365.667158 -272.970504) (xy 365.716013 -272.976436)
			(xy 365.763284 -272.990128) (xy 365.807746 -273.011226) (xy 365.848249 -273.039182) (xy 365.883742 -273.073274)
			(xy 365.913307 -273.112618) (xy 365.936178 -273.156195) (xy 365.951762 -273.202876) (xy 365.959657 -273.251453)
			(xy 365.960152 -273.27606) (xy 366.289094 -273.27606) (xy 366.293054 -273.227006) (xy 366.304831 -273.179222)
			(xy 366.324122 -273.133946) (xy 366.350425 -273.09235) (xy 366.38306 -273.055513) (xy 366.421181 -273.024388)
			(xy 366.463802 -272.999781) (xy 366.509818 -272.982329) (xy 366.558037 -272.972485) (xy 366.607212 -272.970504)
			(xy 366.656067 -272.976436) (xy 366.703338 -272.990128) (xy 366.7478 -273.011226) (xy 366.788303 -273.039182)
			(xy 366.823796 -273.073274) (xy 366.853361 -273.112618) (xy 366.876232 -273.156195) (xy 366.891816 -273.202876)
			(xy 366.899711 -273.251453) (xy 366.900206 -273.27606) (xy 367.228894 -273.27606) (xy 367.232854 -273.227006)
			(xy 367.244631 -273.179222) (xy 367.263922 -273.133946) (xy 367.290225 -273.09235) (xy 367.32286 -273.055513)
			(xy 367.360981 -273.024388) (xy 367.403602 -272.999781) (xy 367.449618 -272.982329) (xy 367.497837 -272.972485)
			(xy 367.547012 -272.970504) (xy 367.595867 -272.976436) (xy 367.643138 -272.990128) (xy 367.6876 -273.011226)
			(xy 367.728103 -273.039182) (xy 367.763596 -273.073274) (xy 367.793161 -273.112618) (xy 367.816032 -273.156195)
			(xy 367.831616 -273.202876) (xy 367.839511 -273.251453) (xy 367.840006 -273.27606) (xy 368.168948 -273.27606)
			(xy 368.172908 -273.227006) (xy 368.184685 -273.179222) (xy 368.203976 -273.133946) (xy 368.230279 -273.09235)
			(xy 368.262914 -273.055513) (xy 368.301035 -273.024388) (xy 368.343656 -272.999781) (xy 368.389672 -272.982329)
			(xy 368.437891 -272.972485) (xy 368.487066 -272.970504) (xy 368.535921 -272.976436) (xy 368.583192 -272.990128)
			(xy 368.627654 -273.011226) (xy 368.668157 -273.039182) (xy 368.70365 -273.073274) (xy 368.733215 -273.112618)
			(xy 368.756086 -273.156195) (xy 368.77167 -273.202876) (xy 368.779565 -273.251453) (xy 368.78006 -273.27606)
			(xy 369.109002 -273.27606) (xy 369.112962 -273.227006) (xy 369.124739 -273.179222) (xy 369.14403 -273.133946)
			(xy 369.170333 -273.09235) (xy 369.202968 -273.055513) (xy 369.241089 -273.024388) (xy 369.28371 -272.999781)
			(xy 369.329726 -272.982329) (xy 369.377945 -272.972485) (xy 369.42712 -272.970504) (xy 369.475975 -272.976436)
			(xy 369.523246 -272.990128) (xy 369.567708 -273.011226) (xy 369.608211 -273.039182) (xy 369.643704 -273.073274)
			(xy 369.673269 -273.112618) (xy 369.69614 -273.156195) (xy 369.711724 -273.202876) (xy 369.719619 -273.251453)
			(xy 369.720114 -273.27606) (xy 370.049056 -273.27606) (xy 370.053016 -273.227006) (xy 370.064793 -273.179222)
			(xy 370.084084 -273.133946) (xy 370.110387 -273.09235) (xy 370.143022 -273.055513) (xy 370.181143 -273.024388)
			(xy 370.223764 -272.999781) (xy 370.26978 -272.982329) (xy 370.317999 -272.972485) (xy 370.367174 -272.970504)
			(xy 370.416029 -272.976436) (xy 370.4633 -272.990128) (xy 370.507762 -273.011226) (xy 370.548265 -273.039182)
			(xy 370.583758 -273.073274) (xy 370.613323 -273.112618) (xy 370.636194 -273.156195) (xy 370.651778 -273.202876)
			(xy 370.659673 -273.251453) (xy 370.660168 -273.27606) (xy 370.98911 -273.27606) (xy 370.99307 -273.227006)
			(xy 371.004847 -273.179222) (xy 371.024138 -273.133946) (xy 371.050441 -273.09235) (xy 371.083076 -273.055513)
			(xy 371.121197 -273.024388) (xy 371.163818 -272.999781) (xy 371.209834 -272.982329) (xy 371.258053 -272.972485)
			(xy 371.307228 -272.970504) (xy 371.356083 -272.976436) (xy 371.403354 -272.990128) (xy 371.447816 -273.011226)
			(xy 371.488319 -273.039182) (xy 371.523812 -273.073274) (xy 371.553377 -273.112618) (xy 371.576248 -273.156195)
			(xy 371.591832 -273.202876) (xy 371.599727 -273.251453) (xy 371.600222 -273.27606) (xy 371.92891 -273.27606)
			(xy 371.93287 -273.227006) (xy 371.944647 -273.179222) (xy 371.963938 -273.133946) (xy 371.990241 -273.09235)
			(xy 372.022876 -273.055513) (xy 372.060997 -273.024388) (xy 372.103618 -272.999781) (xy 372.149634 -272.982329)
			(xy 372.197853 -272.972485) (xy 372.247028 -272.970504) (xy 372.295883 -272.976436) (xy 372.343154 -272.990128)
			(xy 372.387616 -273.011226) (xy 372.428119 -273.039182) (xy 372.463612 -273.073274) (xy 372.493177 -273.112618)
			(xy 372.516048 -273.156195) (xy 372.531632 -273.202876) (xy 372.539527 -273.251453) (xy 372.540022 -273.27606)
			(xy 372.868964 -273.27606) (xy 372.872924 -273.227006) (xy 372.884701 -273.179222) (xy 372.903992 -273.133946)
			(xy 372.930295 -273.09235) (xy 372.96293 -273.055513) (xy 373.001051 -273.024388) (xy 373.043672 -272.999781)
			(xy 373.089688 -272.982329) (xy 373.137907 -272.972485) (xy 373.187082 -272.970504) (xy 373.235937 -272.976436)
			(xy 373.283208 -272.990128) (xy 373.32767 -273.011226) (xy 373.368173 -273.039182) (xy 373.403666 -273.073274)
			(xy 373.433231 -273.112618) (xy 373.456102 -273.156195) (xy 373.471686 -273.202876) (xy 373.479581 -273.251453)
			(xy 373.480076 -273.27606) (xy 373.809018 -273.27606) (xy 373.812978 -273.227006) (xy 373.824755 -273.179222)
			(xy 373.844046 -273.133946) (xy 373.870349 -273.09235) (xy 373.902984 -273.055513) (xy 373.941105 -273.024388)
			(xy 373.983726 -272.999781) (xy 374.029742 -272.982329) (xy 374.077961 -272.972485) (xy 374.127136 -272.970504)
			(xy 374.175991 -272.976436) (xy 374.223262 -272.990128) (xy 374.267724 -273.011226) (xy 374.308227 -273.039182)
			(xy 374.34372 -273.073274) (xy 374.373285 -273.112618) (xy 374.396156 -273.156195) (xy 374.41174 -273.202876)
			(xy 374.419635 -273.251453) (xy 374.42013 -273.27606) (xy 374.419635 -273.300667) (xy 374.41174 -273.349244)
			(xy 374.396156 -273.395925) (xy 374.373285 -273.439502) (xy 374.34372 -273.478846) (xy 374.308227 -273.512938)
			(xy 374.267724 -273.540894) (xy 374.223262 -273.561992) (xy 374.175991 -273.575684) (xy 374.127136 -273.581616)
			(xy 374.077961 -273.579635) (xy 374.029742 -273.569791) (xy 373.983726 -273.552339) (xy 373.941105 -273.527732)
			(xy 373.902984 -273.496607) (xy 373.870349 -273.45977) (xy 373.844046 -273.418174) (xy 373.824755 -273.372898)
			(xy 373.812978 -273.325114) (xy 373.809018 -273.27606) (xy 373.480076 -273.27606) (xy 373.479581 -273.300667)
			(xy 373.471686 -273.349244) (xy 373.456102 -273.395925) (xy 373.433231 -273.439502) (xy 373.403666 -273.478846)
			(xy 373.368173 -273.512938) (xy 373.32767 -273.540894) (xy 373.283208 -273.561992) (xy 373.235937 -273.575684)
			(xy 373.187082 -273.581616) (xy 373.137907 -273.579635) (xy 373.089688 -273.569791) (xy 373.043672 -273.552339)
			(xy 373.001051 -273.527732) (xy 372.96293 -273.496607) (xy 372.930295 -273.45977) (xy 372.903992 -273.418174)
			(xy 372.884701 -273.372898) (xy 372.872924 -273.325114) (xy 372.868964 -273.27606) (xy 372.540022 -273.27606)
			(xy 372.539527 -273.300667) (xy 372.531632 -273.349244) (xy 372.516048 -273.395925) (xy 372.493177 -273.439502)
			(xy 372.463612 -273.478846) (xy 372.428119 -273.512938) (xy 372.387616 -273.540894) (xy 372.343154 -273.561992)
			(xy 372.295883 -273.575684) (xy 372.247028 -273.581616) (xy 372.197853 -273.579635) (xy 372.149634 -273.569791)
			(xy 372.103618 -273.552339) (xy 372.060997 -273.527732) (xy 372.022876 -273.496607) (xy 371.990241 -273.45977)
			(xy 371.963938 -273.418174) (xy 371.944647 -273.372898) (xy 371.93287 -273.325114) (xy 371.92891 -273.27606)
			(xy 371.600222 -273.27606) (xy 371.599727 -273.300667) (xy 371.591832 -273.349244) (xy 371.576248 -273.395925)
			(xy 371.553377 -273.439502) (xy 371.523812 -273.478846) (xy 371.488319 -273.512938) (xy 371.447816 -273.540894)
			(xy 371.403354 -273.561992) (xy 371.356083 -273.575684) (xy 371.307228 -273.581616) (xy 371.258053 -273.579635)
			(xy 371.209834 -273.569791) (xy 371.163818 -273.552339) (xy 371.121197 -273.527732) (xy 371.083076 -273.496607)
			(xy 371.050441 -273.45977) (xy 371.024138 -273.418174) (xy 371.004847 -273.372898) (xy 370.99307 -273.325114)
			(xy 370.98911 -273.27606) (xy 370.660168 -273.27606) (xy 370.659673 -273.300667) (xy 370.651778 -273.349244)
			(xy 370.636194 -273.395925) (xy 370.613323 -273.439502) (xy 370.583758 -273.478846) (xy 370.548265 -273.512938)
			(xy 370.507762 -273.540894) (xy 370.4633 -273.561992) (xy 370.416029 -273.575684) (xy 370.367174 -273.581616)
			(xy 370.317999 -273.579635) (xy 370.26978 -273.569791) (xy 370.223764 -273.552339) (xy 370.181143 -273.527732)
			(xy 370.143022 -273.496607) (xy 370.110387 -273.45977) (xy 370.084084 -273.418174) (xy 370.064793 -273.372898)
			(xy 370.053016 -273.325114) (xy 370.049056 -273.27606) (xy 369.720114 -273.27606) (xy 369.719619 -273.300667)
			(xy 369.711724 -273.349244) (xy 369.69614 -273.395925) (xy 369.673269 -273.439502) (xy 369.643704 -273.478846)
			(xy 369.608211 -273.512938) (xy 369.567708 -273.540894) (xy 369.523246 -273.561992) (xy 369.475975 -273.575684)
			(xy 369.42712 -273.581616) (xy 369.377945 -273.579635) (xy 369.329726 -273.569791) (xy 369.28371 -273.552339)
			(xy 369.241089 -273.527732) (xy 369.202968 -273.496607) (xy 369.170333 -273.45977) (xy 369.14403 -273.418174)
			(xy 369.124739 -273.372898) (xy 369.112962 -273.325114) (xy 369.109002 -273.27606) (xy 368.78006 -273.27606)
			(xy 368.779565 -273.300667) (xy 368.77167 -273.349244) (xy 368.756086 -273.395925) (xy 368.733215 -273.439502)
			(xy 368.70365 -273.478846) (xy 368.668157 -273.512938) (xy 368.627654 -273.540894) (xy 368.583192 -273.561992)
			(xy 368.535921 -273.575684) (xy 368.487066 -273.581616) (xy 368.437891 -273.579635) (xy 368.389672 -273.569791)
			(xy 368.343656 -273.552339) (xy 368.301035 -273.527732) (xy 368.262914 -273.496607) (xy 368.230279 -273.45977)
			(xy 368.203976 -273.418174) (xy 368.184685 -273.372898) (xy 368.172908 -273.325114) (xy 368.168948 -273.27606)
			(xy 367.840006 -273.27606) (xy 367.839511 -273.300667) (xy 367.831616 -273.349244) (xy 367.816032 -273.395925)
			(xy 367.793161 -273.439502) (xy 367.763596 -273.478846) (xy 367.728103 -273.512938) (xy 367.6876 -273.540894)
			(xy 367.643138 -273.561992) (xy 367.595867 -273.575684) (xy 367.547012 -273.581616) (xy 367.497837 -273.579635)
			(xy 367.449618 -273.569791) (xy 367.403602 -273.552339) (xy 367.360981 -273.527732) (xy 367.32286 -273.496607)
			(xy 367.290225 -273.45977) (xy 367.263922 -273.418174) (xy 367.244631 -273.372898) (xy 367.232854 -273.325114)
			(xy 367.228894 -273.27606) (xy 366.900206 -273.27606) (xy 366.899711 -273.300667) (xy 366.891816 -273.349244)
			(xy 366.876232 -273.395925) (xy 366.853361 -273.439502) (xy 366.823796 -273.478846) (xy 366.788303 -273.512938)
			(xy 366.7478 -273.540894) (xy 366.703338 -273.561992) (xy 366.656067 -273.575684) (xy 366.607212 -273.581616)
			(xy 366.558037 -273.579635) (xy 366.509818 -273.569791) (xy 366.463802 -273.552339) (xy 366.421181 -273.527732)
			(xy 366.38306 -273.496607) (xy 366.350425 -273.45977) (xy 366.324122 -273.418174) (xy 366.304831 -273.372898)
			(xy 366.293054 -273.325114) (xy 366.289094 -273.27606) (xy 365.960152 -273.27606) (xy 365.959657 -273.300667)
			(xy 365.951762 -273.349244) (xy 365.936178 -273.395925) (xy 365.913307 -273.439502) (xy 365.883742 -273.478846)
			(xy 365.848249 -273.512938) (xy 365.807746 -273.540894) (xy 365.763284 -273.561992) (xy 365.716013 -273.575684)
			(xy 365.667158 -273.581616) (xy 365.617983 -273.579635) (xy 365.569764 -273.569791) (xy 365.523748 -273.552339)
			(xy 365.481127 -273.527732) (xy 365.443006 -273.496607) (xy 365.410371 -273.45977) (xy 365.384068 -273.418174)
			(xy 365.364777 -273.372898) (xy 365.353 -273.325114) (xy 365.34904 -273.27606) (xy 365.020098 -273.27606)
			(xy 365.019603 -273.300667) (xy 365.011708 -273.349244) (xy 364.996124 -273.395925) (xy 364.973253 -273.439502)
			(xy 364.943688 -273.478846) (xy 364.908195 -273.512938) (xy 364.867692 -273.540894) (xy 364.82323 -273.561992)
			(xy 364.775959 -273.575684) (xy 364.727104 -273.581616) (xy 364.677929 -273.579635) (xy 364.62971 -273.569791)
			(xy 364.583694 -273.552339) (xy 364.541073 -273.527732) (xy 364.502952 -273.496607) (xy 364.470317 -273.45977)
			(xy 364.444014 -273.418174) (xy 364.424723 -273.372898) (xy 364.412946 -273.325114) (xy 364.408986 -273.27606)
			(xy 364.080044 -273.27606) (xy 364.079549 -273.300667) (xy 364.071654 -273.349244) (xy 364.05607 -273.395925)
			(xy 364.033199 -273.439502) (xy 364.003634 -273.478846) (xy 363.968141 -273.512938) (xy 363.927638 -273.540894)
			(xy 363.883176 -273.561992) (xy 363.835905 -273.575684) (xy 363.78705 -273.581616) (xy 363.737875 -273.579635)
			(xy 363.689656 -273.569791) (xy 363.64364 -273.552339) (xy 363.601019 -273.527732) (xy 363.562898 -273.496607)
			(xy 363.530263 -273.45977) (xy 363.50396 -273.418174) (xy 363.484669 -273.372898) (xy 363.472892 -273.325114)
			(xy 363.468932 -273.27606) (xy 363.13999 -273.27606) (xy 363.139495 -273.300667) (xy 363.1316 -273.349244)
			(xy 363.116016 -273.395925) (xy 363.093145 -273.439502) (xy 363.06358 -273.478846) (xy 363.028087 -273.512938)
			(xy 362.987584 -273.540894) (xy 362.943122 -273.561992) (xy 362.895851 -273.575684) (xy 362.846996 -273.581616)
			(xy 362.797821 -273.579635) (xy 362.749602 -273.569791) (xy 362.703586 -273.552339) (xy 362.660965 -273.527732)
			(xy 362.622844 -273.496607) (xy 362.590209 -273.45977) (xy 362.563906 -273.418174) (xy 362.544615 -273.372898)
			(xy 362.532838 -273.325114) (xy 362.528878 -273.27606) (xy 362.20019 -273.27606) (xy 362.199695 -273.300667)
			(xy 362.1918 -273.349244) (xy 362.176216 -273.395925) (xy 362.153345 -273.439502) (xy 362.12378 -273.478846)
			(xy 362.088287 -273.512938) (xy 362.047784 -273.540894) (xy 362.003322 -273.561992) (xy 361.956051 -273.575684)
			(xy 361.907196 -273.581616) (xy 361.858021 -273.579635) (xy 361.809802 -273.569791) (xy 361.763786 -273.552339)
			(xy 361.721165 -273.527732) (xy 361.683044 -273.496607) (xy 361.650409 -273.45977) (xy 361.624106 -273.418174)
			(xy 361.604815 -273.372898) (xy 361.593038 -273.325114) (xy 361.589078 -273.27606) (xy 358.446324 -273.27606)
			(xy 358.445829 -273.300667) (xy 358.437934 -273.349244) (xy 358.42235 -273.395925) (xy 358.399479 -273.439502)
			(xy 358.369914 -273.478846) (xy 358.334421 -273.512938) (xy 358.293918 -273.540894) (xy 358.249456 -273.561992)
			(xy 358.202185 -273.575684) (xy 358.15333 -273.581616) (xy 358.104155 -273.579635) (xy 358.055936 -273.569791)
			(xy 358.00992 -273.552339) (xy 357.967299 -273.527732) (xy 357.929178 -273.496607) (xy 357.896543 -273.45977)
			(xy 357.87024 -273.418174) (xy 357.850949 -273.372898) (xy 357.839172 -273.325114) (xy 357.835212 -273.27606)
			(xy 357.506524 -273.27606) (xy 357.506029 -273.300667) (xy 357.498134 -273.349244) (xy 357.48255 -273.395925)
			(xy 357.459679 -273.439502) (xy 357.430114 -273.478846) (xy 357.394621 -273.512938) (xy 357.354118 -273.540894)
			(xy 357.309656 -273.561992) (xy 357.262385 -273.575684) (xy 357.21353 -273.581616) (xy 357.164355 -273.579635)
			(xy 357.116136 -273.569791) (xy 357.07012 -273.552339) (xy 357.027499 -273.527732) (xy 356.989378 -273.496607)
			(xy 356.956743 -273.45977) (xy 356.93044 -273.418174) (xy 356.911149 -273.372898) (xy 356.899372 -273.325114)
			(xy 356.895412 -273.27606) (xy 356.56647 -273.27606) (xy 356.565975 -273.300667) (xy 356.55808 -273.349244)
			(xy 356.542496 -273.395925) (xy 356.519625 -273.439502) (xy 356.49006 -273.478846) (xy 356.454567 -273.512938)
			(xy 356.414064 -273.540894) (xy 356.369602 -273.561992) (xy 356.322331 -273.575684) (xy 356.273476 -273.581616)
			(xy 356.224301 -273.579635) (xy 356.176082 -273.569791) (xy 356.130066 -273.552339) (xy 356.087445 -273.527732)
			(xy 356.049324 -273.496607) (xy 356.016689 -273.45977) (xy 355.990386 -273.418174) (xy 355.971095 -273.372898)
			(xy 355.959318 -273.325114) (xy 355.955358 -273.27606) (xy 355.626416 -273.27606) (xy 355.625921 -273.300667)
			(xy 355.618026 -273.349244) (xy 355.602442 -273.395925) (xy 355.579571 -273.439502) (xy 355.550006 -273.478846)
			(xy 355.514513 -273.512938) (xy 355.47401 -273.540894) (xy 355.429548 -273.561992) (xy 355.382277 -273.575684)
			(xy 355.333422 -273.581616) (xy 355.284247 -273.579635) (xy 355.236028 -273.569791) (xy 355.190012 -273.552339)
			(xy 355.147391 -273.527732) (xy 355.10927 -273.496607) (xy 355.076635 -273.45977) (xy 355.050332 -273.418174)
			(xy 355.031041 -273.372898) (xy 355.019264 -273.325114) (xy 355.015304 -273.27606) (xy 354.686362 -273.27606)
			(xy 354.685867 -273.300667) (xy 354.677972 -273.349244) (xy 354.662388 -273.395925) (xy 354.639517 -273.439502)
			(xy 354.609952 -273.478846) (xy 354.574459 -273.512938) (xy 354.533956 -273.540894) (xy 354.489494 -273.561992)
			(xy 354.442223 -273.575684) (xy 354.393368 -273.581616) (xy 354.344193 -273.579635) (xy 354.295974 -273.569791)
			(xy 354.249958 -273.552339) (xy 354.207337 -273.527732) (xy 354.169216 -273.496607) (xy 354.136581 -273.45977)
			(xy 354.110278 -273.418174) (xy 354.090987 -273.372898) (xy 354.07921 -273.325114) (xy 354.07525 -273.27606)
			(xy 353.746308 -273.27606) (xy 353.745813 -273.300667) (xy 353.737918 -273.349244) (xy 353.722334 -273.395925)
			(xy 353.699463 -273.439502) (xy 353.669898 -273.478846) (xy 353.634405 -273.512938) (xy 353.593902 -273.540894)
			(xy 353.54944 -273.561992) (xy 353.502169 -273.575684) (xy 353.453314 -273.581616) (xy 353.404139 -273.579635)
			(xy 353.35592 -273.569791) (xy 353.309904 -273.552339) (xy 353.267283 -273.527732) (xy 353.229162 -273.496607)
			(xy 353.196527 -273.45977) (xy 353.170224 -273.418174) (xy 353.150933 -273.372898) (xy 353.139156 -273.325114)
			(xy 353.135196 -273.27606) (xy 352.806508 -273.27606) (xy 352.806013 -273.300667) (xy 352.798118 -273.349244)
			(xy 352.782534 -273.395925) (xy 352.759663 -273.439502) (xy 352.730098 -273.478846) (xy 352.694605 -273.512938)
			(xy 352.654102 -273.540894) (xy 352.60964 -273.561992) (xy 352.562369 -273.575684) (xy 352.513514 -273.581616)
			(xy 352.464339 -273.579635) (xy 352.41612 -273.569791) (xy 352.370104 -273.552339) (xy 352.327483 -273.527732)
			(xy 352.289362 -273.496607) (xy 352.256727 -273.45977) (xy 352.230424 -273.418174) (xy 352.211133 -273.372898)
			(xy 352.199356 -273.325114) (xy 352.195396 -273.27606) (xy 351.866454 -273.27606) (xy 351.865959 -273.300667)
			(xy 351.858064 -273.349244) (xy 351.84248 -273.395925) (xy 351.819609 -273.439502) (xy 351.790044 -273.478846)
			(xy 351.754551 -273.512938) (xy 351.714048 -273.540894) (xy 351.669586 -273.561992) (xy 351.622315 -273.575684)
			(xy 351.57346 -273.581616) (xy 351.524285 -273.579635) (xy 351.476066 -273.569791) (xy 351.43005 -273.552339)
			(xy 351.387429 -273.527732) (xy 351.349308 -273.496607) (xy 351.316673 -273.45977) (xy 351.29037 -273.418174)
			(xy 351.271079 -273.372898) (xy 351.259302 -273.325114) (xy 351.255342 -273.27606) (xy 350.9264 -273.27606)
			(xy 350.925905 -273.300667) (xy 350.91801 -273.349244) (xy 350.902426 -273.395925) (xy 350.879555 -273.439502)
			(xy 350.84999 -273.478846) (xy 350.814497 -273.512938) (xy 350.773994 -273.540894) (xy 350.729532 -273.561992)
			(xy 350.682261 -273.575684) (xy 350.633406 -273.581616) (xy 350.584231 -273.579635) (xy 350.536012 -273.569791)
			(xy 350.489996 -273.552339) (xy 350.447375 -273.527732) (xy 350.409254 -273.496607) (xy 350.376619 -273.45977)
			(xy 350.350316 -273.418174) (xy 350.331025 -273.372898) (xy 350.319248 -273.325114) (xy 350.315288 -273.27606)
			(xy 349.986346 -273.27606) (xy 349.985851 -273.300667) (xy 349.977956 -273.349244) (xy 349.962372 -273.395925)
			(xy 349.939501 -273.439502) (xy 349.909936 -273.478846) (xy 349.874443 -273.512938) (xy 349.83394 -273.540894)
			(xy 349.789478 -273.561992) (xy 349.742207 -273.575684) (xy 349.693352 -273.581616) (xy 349.644177 -273.579635)
			(xy 349.595958 -273.569791) (xy 349.549942 -273.552339) (xy 349.507321 -273.527732) (xy 349.4692 -273.496607)
			(xy 349.436565 -273.45977) (xy 349.410262 -273.418174) (xy 349.390971 -273.372898) (xy 349.379194 -273.325114)
			(xy 349.375234 -273.27606) (xy 349.046546 -273.27606) (xy 349.046051 -273.300667) (xy 349.038156 -273.349244)
			(xy 349.022572 -273.395925) (xy 348.999701 -273.439502) (xy 348.970136 -273.478846) (xy 348.934643 -273.512938)
			(xy 348.89414 -273.540894) (xy 348.849678 -273.561992) (xy 348.802407 -273.575684) (xy 348.753552 -273.581616)
			(xy 348.704377 -273.579635) (xy 348.656158 -273.569791) (xy 348.610142 -273.552339) (xy 348.567521 -273.527732)
			(xy 348.5294 -273.496607) (xy 348.496765 -273.45977) (xy 348.470462 -273.418174) (xy 348.451171 -273.372898)
			(xy 348.439394 -273.325114) (xy 348.435434 -273.27606) (xy 348.106492 -273.27606) (xy 348.105997 -273.300667)
			(xy 348.098102 -273.349244) (xy 348.082518 -273.395925) (xy 348.059647 -273.439502) (xy 348.030082 -273.478846)
			(xy 347.994589 -273.512938) (xy 347.954086 -273.540894) (xy 347.909624 -273.561992) (xy 347.862353 -273.575684)
			(xy 347.813498 -273.581616) (xy 347.764323 -273.579635) (xy 347.716104 -273.569791) (xy 347.670088 -273.552339)
			(xy 347.627467 -273.527732) (xy 347.589346 -273.496607) (xy 347.556711 -273.45977) (xy 347.530408 -273.418174)
			(xy 347.511117 -273.372898) (xy 347.49934 -273.325114) (xy 347.49538 -273.27606) (xy 347.166438 -273.27606)
			(xy 347.165943 -273.300667) (xy 347.158048 -273.349244) (xy 347.142464 -273.395925) (xy 347.119593 -273.439502)
			(xy 347.090028 -273.478846) (xy 347.054535 -273.512938) (xy 347.014032 -273.540894) (xy 346.96957 -273.561992)
			(xy 346.922299 -273.575684) (xy 346.873444 -273.581616) (xy 346.824269 -273.579635) (xy 346.77605 -273.569791)
			(xy 346.730034 -273.552339) (xy 346.687413 -273.527732) (xy 346.649292 -273.496607) (xy 346.616657 -273.45977)
			(xy 346.590354 -273.418174) (xy 346.571063 -273.372898) (xy 346.559286 -273.325114) (xy 346.555326 -273.27606)
			(xy 346.226384 -273.27606) (xy 346.225889 -273.300667) (xy 346.217994 -273.349244) (xy 346.20241 -273.395925)
			(xy 346.179539 -273.439502) (xy 346.149974 -273.478846) (xy 346.114481 -273.512938) (xy 346.073978 -273.540894)
			(xy 346.029516 -273.561992) (xy 345.982245 -273.575684) (xy 345.93339 -273.581616) (xy 345.884215 -273.579635)
			(xy 345.835996 -273.569791) (xy 345.78998 -273.552339) (xy 345.747359 -273.527732) (xy 345.709238 -273.496607)
			(xy 345.676603 -273.45977) (xy 345.6503 -273.418174) (xy 345.631009 -273.372898) (xy 345.619232 -273.325114)
			(xy 345.615272 -273.27606) (xy 345.28633 -273.27606) (xy 345.285835 -273.300667) (xy 345.27794 -273.349244)
			(xy 345.262356 -273.395925) (xy 345.239485 -273.439502) (xy 345.20992 -273.478846) (xy 345.174427 -273.512938)
			(xy 345.133924 -273.540894) (xy 345.089462 -273.561992) (xy 345.042191 -273.575684) (xy 344.993336 -273.581616)
			(xy 344.944161 -273.579635) (xy 344.895942 -273.569791) (xy 344.849926 -273.552339) (xy 344.807305 -273.527732)
			(xy 344.769184 -273.496607) (xy 344.736549 -273.45977) (xy 344.710246 -273.418174) (xy 344.690955 -273.372898)
			(xy 344.679178 -273.325114) (xy 344.675218 -273.27606) (xy 344.356944 -273.27606) (xy 344.356432 -273.301506)
			(xy 344.348268 -273.35174) (xy 344.332152 -273.400014) (xy 344.308501 -273.445077) (xy 344.277928 -273.485763)
			(xy 344.241224 -273.521018) (xy 344.19934 -273.549928) (xy 344.153361 -273.571745) (xy 344.104477 -273.585905)
			(xy 344.053956 -273.592039) (xy 344.003104 -273.58999) (xy 343.95324 -273.57981) (xy 343.905654 -273.561763)
			(xy 343.86158 -273.536317) (xy 343.822158 -273.50413) (xy 343.78841 -273.466036) (xy 343.761209 -273.423022)
			(xy 343.741261 -273.376202) (xy 343.729082 -273.326788) (xy 343.724987 -273.27606) (xy 343.409574 -273.27606)
			(xy 343.407107 -273.281687) (xy 343.406222 -273.291046) (xy 343.404522 -273.31543) (xy 343.394338 -273.363234)
			(xy 343.37667 -273.408807) (xy 343.35197 -273.450983) (xy 343.320867 -273.488687) (xy 343.284157 -273.520956)
			(xy 343.263728 -273.534378) (xy 343.255346 -273.539712) (xy 343.24417 -273.554952) (xy 343.24163 -273.564604)
			(xy 343.24163 -273.564858) (xy 343.23909 -273.573748) (xy 343.226096 -273.618912) (xy 343.193526 -273.707076)
			(xy 343.15367 -273.792195) (xy 343.106811 -273.873669) (xy 343.05328 -273.950923) (xy 342.993454 -274.023411)
			(xy 342.96096 -274.057364) (xy 342.95453 -274.064536) (xy 342.947108 -274.082294) (xy 342.946862 -274.086066)
			(xy 343.254833 -274.086066) (xy 343.258928 -274.035338) (xy 343.271107 -273.985924) (xy 343.291055 -273.939104)
			(xy 343.318256 -273.89609) (xy 343.352004 -273.857996) (xy 343.391426 -273.825809) (xy 343.4355 -273.800363)
			(xy 343.483086 -273.782316) (xy 343.53295 -273.772136) (xy 343.583802 -273.770087) (xy 343.634323 -273.776221)
			(xy 343.683207 -273.790381) (xy 343.729186 -273.812198) (xy 343.77107 -273.841108) (xy 343.807774 -273.876363)
			(xy 343.838347 -273.917049) (xy 343.861998 -273.962112) (xy 343.878114 -274.010386) (xy 343.886278 -274.06062)
			(xy 343.88679 -274.086066) (xy 344.205318 -274.086066) (xy 344.209278 -274.037012) (xy 344.221055 -273.989228)
			(xy 344.240346 -273.943952) (xy 344.266649 -273.902356) (xy 344.299284 -273.865519) (xy 344.337405 -273.834394)
			(xy 344.380026 -273.809787) (xy 344.426042 -273.792335) (xy 344.474261 -273.782491) (xy 344.523436 -273.78051)
			(xy 344.572291 -273.786442) (xy 344.619562 -273.800134) (xy 344.664024 -273.821232) (xy 344.704527 -273.849188)
			(xy 344.74002 -273.88328) (xy 344.769585 -273.922624) (xy 344.792456 -273.966201) (xy 344.80804 -274.012882)
			(xy 344.815935 -274.061459) (xy 344.81643 -274.086066) (xy 345.145372 -274.086066) (xy 345.149332 -274.037012)
			(xy 345.161109 -273.989228) (xy 345.1804 -273.943952) (xy 345.206703 -273.902356) (xy 345.239338 -273.865519)
			(xy 345.277459 -273.834394) (xy 345.32008 -273.809787) (xy 345.366096 -273.792335) (xy 345.414315 -273.782491)
			(xy 345.46349 -273.78051) (xy 345.512345 -273.786442) (xy 345.559616 -273.800134) (xy 345.604078 -273.821232)
			(xy 345.644581 -273.849188) (xy 345.680074 -273.88328) (xy 345.709639 -273.922624) (xy 345.73251 -273.966201)
			(xy 345.748094 -274.012882) (xy 345.755989 -274.061459) (xy 345.756484 -274.086066) (xy 346.085426 -274.086066)
			(xy 346.089386 -274.037012) (xy 346.101163 -273.989228) (xy 346.120454 -273.943952) (xy 346.146757 -273.902356)
			(xy 346.179392 -273.865519) (xy 346.217513 -273.834394) (xy 346.260134 -273.809787) (xy 346.30615 -273.792335)
			(xy 346.354369 -273.782491) (xy 346.403544 -273.78051) (xy 346.452399 -273.786442) (xy 346.49967 -273.800134)
			(xy 346.544132 -273.821232) (xy 346.584635 -273.849188) (xy 346.620128 -273.88328) (xy 346.649693 -273.922624)
			(xy 346.672564 -273.966201) (xy 346.688148 -274.012882) (xy 346.696043 -274.061459) (xy 346.696538 -274.086066)
			(xy 347.025226 -274.086066) (xy 347.029186 -274.037012) (xy 347.040963 -273.989228) (xy 347.060254 -273.943952)
			(xy 347.086557 -273.902356) (xy 347.119192 -273.865519) (xy 347.157313 -273.834394) (xy 347.199934 -273.809787)
			(xy 347.24595 -273.792335) (xy 347.294169 -273.782491) (xy 347.343344 -273.78051) (xy 347.392199 -273.786442)
			(xy 347.43947 -273.800134) (xy 347.483932 -273.821232) (xy 347.524435 -273.849188) (xy 347.559928 -273.88328)
			(xy 347.589493 -273.922624) (xy 347.612364 -273.966201) (xy 347.627948 -274.012882) (xy 347.635843 -274.061459)
			(xy 347.636338 -274.086066) (xy 347.96528 -274.086066) (xy 347.96924 -274.037012) (xy 347.981017 -273.989228)
			(xy 348.000308 -273.943952) (xy 348.026611 -273.902356) (xy 348.059246 -273.865519) (xy 348.097367 -273.834394)
			(xy 348.139988 -273.809787) (xy 348.186004 -273.792335) (xy 348.234223 -273.782491) (xy 348.283398 -273.78051)
			(xy 348.332253 -273.786442) (xy 348.379524 -273.800134) (xy 348.423986 -273.821232) (xy 348.464489 -273.849188)
			(xy 348.499982 -273.88328) (xy 348.529547 -273.922624) (xy 348.552418 -273.966201) (xy 348.568002 -274.012882)
			(xy 348.575897 -274.061459) (xy 348.576392 -274.086066) (xy 348.905334 -274.086066) (xy 348.909294 -274.037012)
			(xy 348.921071 -273.989228) (xy 348.940362 -273.943952) (xy 348.966665 -273.902356) (xy 348.9993 -273.865519)
			(xy 349.037421 -273.834394) (xy 349.080042 -273.809787) (xy 349.126058 -273.792335) (xy 349.174277 -273.782491)
			(xy 349.223452 -273.78051) (xy 349.272307 -273.786442) (xy 349.319578 -273.800134) (xy 349.36404 -273.821232)
			(xy 349.404543 -273.849188) (xy 349.440036 -273.88328) (xy 349.469601 -273.922624) (xy 349.492472 -273.966201)
			(xy 349.508056 -274.012882) (xy 349.515951 -274.061459) (xy 349.516446 -274.086066) (xy 349.845388 -274.086066)
			(xy 349.849348 -274.037012) (xy 349.861125 -273.989228) (xy 349.880416 -273.943952) (xy 349.906719 -273.902356)
			(xy 349.939354 -273.865519) (xy 349.977475 -273.834394) (xy 350.020096 -273.809787) (xy 350.066112 -273.792335)
			(xy 350.114331 -273.782491) (xy 350.163506 -273.78051) (xy 350.212361 -273.786442) (xy 350.259632 -273.800134)
			(xy 350.304094 -273.821232) (xy 350.344597 -273.849188) (xy 350.38009 -273.88328) (xy 350.409655 -273.922624)
			(xy 350.432526 -273.966201) (xy 350.44811 -274.012882) (xy 350.456005 -274.061459) (xy 350.4565 -274.086066)
			(xy 350.785442 -274.086066) (xy 350.789402 -274.037012) (xy 350.801179 -273.989228) (xy 350.82047 -273.943952)
			(xy 350.846773 -273.902356) (xy 350.879408 -273.865519) (xy 350.917529 -273.834394) (xy 350.96015 -273.809787)
			(xy 351.006166 -273.792335) (xy 351.054385 -273.782491) (xy 351.10356 -273.78051) (xy 351.152415 -273.786442)
			(xy 351.199686 -273.800134) (xy 351.244148 -273.821232) (xy 351.284651 -273.849188) (xy 351.320144 -273.88328)
			(xy 351.349709 -273.922624) (xy 351.37258 -273.966201) (xy 351.388164 -274.012882) (xy 351.396059 -274.061459)
			(xy 351.396554 -274.086066) (xy 351.725242 -274.086066) (xy 351.729202 -274.037012) (xy 351.740979 -273.989228)
			(xy 351.76027 -273.943952) (xy 351.786573 -273.902356) (xy 351.819208 -273.865519) (xy 351.857329 -273.834394)
			(xy 351.89995 -273.809787) (xy 351.945966 -273.792335) (xy 351.994185 -273.782491) (xy 352.04336 -273.78051)
			(xy 352.092215 -273.786442) (xy 352.139486 -273.800134) (xy 352.183948 -273.821232) (xy 352.224451 -273.849188)
			(xy 352.259944 -273.88328) (xy 352.289509 -273.922624) (xy 352.31238 -273.966201) (xy 352.327964 -274.012882)
			(xy 352.335859 -274.061459) (xy 352.336354 -274.086066) (xy 352.665296 -274.086066) (xy 352.669256 -274.037012)
			(xy 352.681033 -273.989228) (xy 352.700324 -273.943952) (xy 352.726627 -273.902356) (xy 352.759262 -273.865519)
			(xy 352.797383 -273.834394) (xy 352.840004 -273.809787) (xy 352.88602 -273.792335) (xy 352.934239 -273.782491)
			(xy 352.983414 -273.78051) (xy 353.032269 -273.786442) (xy 353.07954 -273.800134) (xy 353.124002 -273.821232)
			(xy 353.164505 -273.849188) (xy 353.199998 -273.88328) (xy 353.229563 -273.922624) (xy 353.252434 -273.966201)
			(xy 353.268018 -274.012882) (xy 353.275913 -274.061459) (xy 353.276408 -274.086066) (xy 353.60535 -274.086066)
			(xy 353.60931 -274.037012) (xy 353.621087 -273.989228) (xy 353.640378 -273.943952) (xy 353.666681 -273.902356)
			(xy 353.699316 -273.865519) (xy 353.737437 -273.834394) (xy 353.780058 -273.809787) (xy 353.826074 -273.792335)
			(xy 353.874293 -273.782491) (xy 353.923468 -273.78051) (xy 353.972323 -273.786442) (xy 354.019594 -273.800134)
			(xy 354.064056 -273.821232) (xy 354.104559 -273.849188) (xy 354.140052 -273.88328) (xy 354.169617 -273.922624)
			(xy 354.192488 -273.966201) (xy 354.208072 -274.012882) (xy 354.215967 -274.061459) (xy 354.216462 -274.086066)
			(xy 354.545404 -274.086066) (xy 354.549364 -274.037012) (xy 354.561141 -273.989228) (xy 354.580432 -273.943952)
			(xy 354.606735 -273.902356) (xy 354.63937 -273.865519) (xy 354.677491 -273.834394) (xy 354.720112 -273.809787)
			(xy 354.766128 -273.792335) (xy 354.814347 -273.782491) (xy 354.863522 -273.78051) (xy 354.912377 -273.786442)
			(xy 354.959648 -273.800134) (xy 355.00411 -273.821232) (xy 355.044613 -273.849188) (xy 355.080106 -273.88328)
			(xy 355.109671 -273.922624) (xy 355.132542 -273.966201) (xy 355.148126 -274.012882) (xy 355.156021 -274.061459)
			(xy 355.156516 -274.086066) (xy 355.485204 -274.086066) (xy 355.489164 -274.037012) (xy 355.500941 -273.989228)
			(xy 355.520232 -273.943952) (xy 355.546535 -273.902356) (xy 355.57917 -273.865519) (xy 355.617291 -273.834394)
			(xy 355.659912 -273.809787) (xy 355.705928 -273.792335) (xy 355.754147 -273.782491) (xy 355.803322 -273.78051)
			(xy 355.852177 -273.786442) (xy 355.899448 -273.800134) (xy 355.94391 -273.821232) (xy 355.984413 -273.849188)
			(xy 356.019906 -273.88328) (xy 356.049471 -273.922624) (xy 356.072342 -273.966201) (xy 356.087926 -274.012882)
			(xy 356.095821 -274.061459) (xy 356.096316 -274.086066) (xy 356.425258 -274.086066) (xy 356.429218 -274.037012)
			(xy 356.440995 -273.989228) (xy 356.460286 -273.943952) (xy 356.486589 -273.902356) (xy 356.519224 -273.865519)
			(xy 356.557345 -273.834394) (xy 356.599966 -273.809787) (xy 356.645982 -273.792335) (xy 356.694201 -273.782491)
			(xy 356.743376 -273.78051) (xy 356.792231 -273.786442) (xy 356.839502 -273.800134) (xy 356.883964 -273.821232)
			(xy 356.924467 -273.849188) (xy 356.95996 -273.88328) (xy 356.989525 -273.922624) (xy 357.012396 -273.966201)
			(xy 357.02798 -274.012882) (xy 357.035875 -274.061459) (xy 357.03637 -274.086066) (xy 357.365312 -274.086066)
			(xy 357.369272 -274.037012) (xy 357.381049 -273.989228) (xy 357.40034 -273.943952) (xy 357.426643 -273.902356)
			(xy 357.459278 -273.865519) (xy 357.497399 -273.834394) (xy 357.54002 -273.809787) (xy 357.586036 -273.792335)
			(xy 357.634255 -273.782491) (xy 357.68343 -273.78051) (xy 357.732285 -273.786442) (xy 357.779556 -273.800134)
			(xy 357.824018 -273.821232) (xy 357.864521 -273.849188) (xy 357.900014 -273.88328) (xy 357.929579 -273.922624)
			(xy 357.95245 -273.966201) (xy 357.968034 -274.012882) (xy 357.975929 -274.061459) (xy 357.976424 -274.086066)
			(xy 358.305366 -274.086066) (xy 358.309326 -274.037012) (xy 358.321103 -273.989228) (xy 358.340394 -273.943952)
			(xy 358.366697 -273.902356) (xy 358.399332 -273.865519) (xy 358.437453 -273.834394) (xy 358.480074 -273.809787)
			(xy 358.52609 -273.792335) (xy 358.574309 -273.782491) (xy 358.623484 -273.78051) (xy 358.672339 -273.786442)
			(xy 358.71961 -273.800134) (xy 358.764072 -273.821232) (xy 358.804575 -273.849188) (xy 358.840068 -273.88328)
			(xy 358.869633 -273.922624) (xy 358.892504 -273.966201) (xy 358.908088 -274.012882) (xy 358.915983 -274.061459)
			(xy 358.916478 -274.086066) (xy 361.118924 -274.086066) (xy 361.122884 -274.037012) (xy 361.134661 -273.989228)
			(xy 361.153952 -273.943952) (xy 361.180255 -273.902356) (xy 361.21289 -273.865519) (xy 361.251011 -273.834394)
			(xy 361.293632 -273.809787) (xy 361.339648 -273.792335) (xy 361.387867 -273.782491) (xy 361.437042 -273.78051)
			(xy 361.485897 -273.786442) (xy 361.533168 -273.800134) (xy 361.57763 -273.821232) (xy 361.618133 -273.849188)
			(xy 361.653626 -273.88328) (xy 361.683191 -273.922624) (xy 361.706062 -273.966201) (xy 361.721646 -274.012882)
			(xy 361.729541 -274.061459) (xy 361.730036 -274.086066) (xy 362.058978 -274.086066) (xy 362.062938 -274.037012)
			(xy 362.074715 -273.989228) (xy 362.094006 -273.943952) (xy 362.120309 -273.902356) (xy 362.152944 -273.865519)
			(xy 362.191065 -273.834394) (xy 362.233686 -273.809787) (xy 362.279702 -273.792335) (xy 362.327921 -273.782491)
			(xy 362.377096 -273.78051) (xy 362.425951 -273.786442) (xy 362.473222 -273.800134) (xy 362.517684 -273.821232)
			(xy 362.558187 -273.849188) (xy 362.59368 -273.88328) (xy 362.623245 -273.922624) (xy 362.646116 -273.966201)
			(xy 362.6617 -274.012882) (xy 362.669595 -274.061459) (xy 362.67009 -274.086066) (xy 362.999032 -274.086066)
			(xy 363.002992 -274.037012) (xy 363.014769 -273.989228) (xy 363.03406 -273.943952) (xy 363.060363 -273.902356)
			(xy 363.092998 -273.865519) (xy 363.131119 -273.834394) (xy 363.17374 -273.809787) (xy 363.219756 -273.792335)
			(xy 363.267975 -273.782491) (xy 363.31715 -273.78051) (xy 363.366005 -273.786442) (xy 363.413276 -273.800134)
			(xy 363.457738 -273.821232) (xy 363.498241 -273.849188) (xy 363.533734 -273.88328) (xy 363.563299 -273.922624)
			(xy 363.58617 -273.966201) (xy 363.601754 -274.012882) (xy 363.609649 -274.061459) (xy 363.610144 -274.086066)
			(xy 363.939086 -274.086066) (xy 363.943046 -274.037012) (xy 363.954823 -273.989228) (xy 363.974114 -273.943952)
			(xy 364.000417 -273.902356) (xy 364.033052 -273.865519) (xy 364.071173 -273.834394) (xy 364.113794 -273.809787)
			(xy 364.15981 -273.792335) (xy 364.208029 -273.782491) (xy 364.257204 -273.78051) (xy 364.306059 -273.786442)
			(xy 364.35333 -273.800134) (xy 364.397792 -273.821232) (xy 364.438295 -273.849188) (xy 364.473788 -273.88328)
			(xy 364.503353 -273.922624) (xy 364.526224 -273.966201) (xy 364.541808 -274.012882) (xy 364.549703 -274.061459)
			(xy 364.550198 -274.086066) (xy 364.878886 -274.086066) (xy 364.882846 -274.037012) (xy 364.894623 -273.989228)
			(xy 364.913914 -273.943952) (xy 364.940217 -273.902356) (xy 364.972852 -273.865519) (xy 365.010973 -273.834394)
			(xy 365.053594 -273.809787) (xy 365.09961 -273.792335) (xy 365.147829 -273.782491) (xy 365.197004 -273.78051)
			(xy 365.245859 -273.786442) (xy 365.29313 -273.800134) (xy 365.337592 -273.821232) (xy 365.378095 -273.849188)
			(xy 365.413588 -273.88328) (xy 365.443153 -273.922624) (xy 365.466024 -273.966201) (xy 365.481608 -274.012882)
			(xy 365.489503 -274.061459) (xy 365.489998 -274.086066) (xy 365.81894 -274.086066) (xy 365.8229 -274.037012)
			(xy 365.834677 -273.989228) (xy 365.853968 -273.943952) (xy 365.880271 -273.902356) (xy 365.912906 -273.865519)
			(xy 365.951027 -273.834394) (xy 365.993648 -273.809787) (xy 366.039664 -273.792335) (xy 366.087883 -273.782491)
			(xy 366.137058 -273.78051) (xy 366.185913 -273.786442) (xy 366.233184 -273.800134) (xy 366.277646 -273.821232)
			(xy 366.318149 -273.849188) (xy 366.353642 -273.88328) (xy 366.383207 -273.922624) (xy 366.406078 -273.966201)
			(xy 366.421662 -274.012882) (xy 366.429557 -274.061459) (xy 366.430052 -274.086066) (xy 366.758994 -274.086066)
			(xy 366.762954 -274.037012) (xy 366.774731 -273.989228) (xy 366.794022 -273.943952) (xy 366.820325 -273.902356)
			(xy 366.85296 -273.865519) (xy 366.891081 -273.834394) (xy 366.933702 -273.809787) (xy 366.979718 -273.792335)
			(xy 367.027937 -273.782491) (xy 367.077112 -273.78051) (xy 367.125967 -273.786442) (xy 367.173238 -273.800134)
			(xy 367.2177 -273.821232) (xy 367.258203 -273.849188) (xy 367.293696 -273.88328) (xy 367.323261 -273.922624)
			(xy 367.346132 -273.966201) (xy 367.361716 -274.012882) (xy 367.369611 -274.061459) (xy 367.370106 -274.086066)
			(xy 367.699048 -274.086066) (xy 367.703008 -274.037012) (xy 367.714785 -273.989228) (xy 367.734076 -273.943952)
			(xy 367.760379 -273.902356) (xy 367.793014 -273.865519) (xy 367.831135 -273.834394) (xy 367.873756 -273.809787)
			(xy 367.919772 -273.792335) (xy 367.967991 -273.782491) (xy 368.017166 -273.78051) (xy 368.066021 -273.786442)
			(xy 368.113292 -273.800134) (xy 368.157754 -273.821232) (xy 368.198257 -273.849188) (xy 368.23375 -273.88328)
			(xy 368.263315 -273.922624) (xy 368.286186 -273.966201) (xy 368.30177 -274.012882) (xy 368.309665 -274.061459)
			(xy 368.31016 -274.086066) (xy 368.639102 -274.086066) (xy 368.643062 -274.037012) (xy 368.654839 -273.989228)
			(xy 368.67413 -273.943952) (xy 368.700433 -273.902356) (xy 368.733068 -273.865519) (xy 368.771189 -273.834394)
			(xy 368.81381 -273.809787) (xy 368.859826 -273.792335) (xy 368.908045 -273.782491) (xy 368.95722 -273.78051)
			(xy 369.006075 -273.786442) (xy 369.053346 -273.800134) (xy 369.097808 -273.821232) (xy 369.138311 -273.849188)
			(xy 369.173804 -273.88328) (xy 369.203369 -273.922624) (xy 369.22624 -273.966201) (xy 369.241824 -274.012882)
			(xy 369.249719 -274.061459) (xy 369.250214 -274.086066) (xy 369.578902 -274.086066) (xy 369.582862 -274.037012)
			(xy 369.594639 -273.989228) (xy 369.61393 -273.943952) (xy 369.640233 -273.902356) (xy 369.672868 -273.865519)
			(xy 369.710989 -273.834394) (xy 369.75361 -273.809787) (xy 369.799626 -273.792335) (xy 369.847845 -273.782491)
			(xy 369.89702 -273.78051) (xy 369.945875 -273.786442) (xy 369.993146 -273.800134) (xy 370.037608 -273.821232)
			(xy 370.078111 -273.849188) (xy 370.113604 -273.88328) (xy 370.143169 -273.922624) (xy 370.16604 -273.966201)
			(xy 370.181624 -274.012882) (xy 370.189519 -274.061459) (xy 370.190014 -274.086066) (xy 370.518956 -274.086066)
			(xy 370.522916 -274.037012) (xy 370.534693 -273.989228) (xy 370.553984 -273.943952) (xy 370.580287 -273.902356)
			(xy 370.612922 -273.865519) (xy 370.651043 -273.834394) (xy 370.693664 -273.809787) (xy 370.73968 -273.792335)
			(xy 370.787899 -273.782491) (xy 370.837074 -273.78051) (xy 370.885929 -273.786442) (xy 370.9332 -273.800134)
			(xy 370.977662 -273.821232) (xy 371.018165 -273.849188) (xy 371.053658 -273.88328) (xy 371.083223 -273.922624)
			(xy 371.106094 -273.966201) (xy 371.121678 -274.012882) (xy 371.129573 -274.061459) (xy 371.130068 -274.086066)
			(xy 371.45901 -274.086066) (xy 371.46297 -274.037012) (xy 371.474747 -273.989228) (xy 371.494038 -273.943952)
			(xy 371.520341 -273.902356) (xy 371.552976 -273.865519) (xy 371.591097 -273.834394) (xy 371.633718 -273.809787)
			(xy 371.679734 -273.792335) (xy 371.727953 -273.782491) (xy 371.777128 -273.78051) (xy 371.825983 -273.786442)
			(xy 371.873254 -273.800134) (xy 371.917716 -273.821232) (xy 371.958219 -273.849188) (xy 371.993712 -273.88328)
			(xy 372.023277 -273.922624) (xy 372.046148 -273.966201) (xy 372.061732 -274.012882) (xy 372.069627 -274.061459)
			(xy 372.070122 -274.086066) (xy 372.399064 -274.086066) (xy 372.403024 -274.037012) (xy 372.414801 -273.989228)
			(xy 372.434092 -273.943952) (xy 372.460395 -273.902356) (xy 372.49303 -273.865519) (xy 372.531151 -273.834394)
			(xy 372.573772 -273.809787) (xy 372.619788 -273.792335) (xy 372.668007 -273.782491) (xy 372.717182 -273.78051)
			(xy 372.766037 -273.786442) (xy 372.813308 -273.800134) (xy 372.85777 -273.821232) (xy 372.898273 -273.849188)
			(xy 372.933766 -273.88328) (xy 372.963331 -273.922624) (xy 372.986202 -273.966201) (xy 373.001786 -274.012882)
			(xy 373.009681 -274.061459) (xy 373.010176 -274.086066) (xy 373.339118 -274.086066) (xy 373.343078 -274.037012)
			(xy 373.354855 -273.989228) (xy 373.374146 -273.943952) (xy 373.400449 -273.902356) (xy 373.433084 -273.865519)
			(xy 373.471205 -273.834394) (xy 373.513826 -273.809787) (xy 373.559842 -273.792335) (xy 373.608061 -273.782491)
			(xy 373.657236 -273.78051) (xy 373.706091 -273.786442) (xy 373.753362 -273.800134) (xy 373.797824 -273.821232)
			(xy 373.838327 -273.849188) (xy 373.87382 -273.88328) (xy 373.903385 -273.922624) (xy 373.926256 -273.966201)
			(xy 373.94184 -274.012882) (xy 373.949735 -274.061459) (xy 373.95023 -274.086066) (xy 373.949735 -274.110673)
			(xy 373.94184 -274.15925) (xy 373.926256 -274.205931) (xy 373.903385 -274.249508) (xy 373.87382 -274.288852)
			(xy 373.838327 -274.322944) (xy 373.797824 -274.3509) (xy 373.753362 -274.371998) (xy 373.706091 -274.38569)
			(xy 373.657236 -274.391622) (xy 373.608061 -274.389641) (xy 373.559842 -274.379797) (xy 373.513826 -274.362345)
			(xy 373.471205 -274.337738) (xy 373.433084 -274.306613) (xy 373.400449 -274.269776) (xy 373.374146 -274.22818)
			(xy 373.354855 -274.182904) (xy 373.343078 -274.13512) (xy 373.339118 -274.086066) (xy 373.010176 -274.086066)
			(xy 373.009681 -274.110673) (xy 373.001786 -274.15925) (xy 372.986202 -274.205931) (xy 372.963331 -274.249508)
			(xy 372.933766 -274.288852) (xy 372.898273 -274.322944) (xy 372.85777 -274.3509) (xy 372.813308 -274.371998)
			(xy 372.766037 -274.38569) (xy 372.717182 -274.391622) (xy 372.668007 -274.389641) (xy 372.619788 -274.379797)
			(xy 372.573772 -274.362345) (xy 372.531151 -274.337738) (xy 372.49303 -274.306613) (xy 372.460395 -274.269776)
			(xy 372.434092 -274.22818) (xy 372.414801 -274.182904) (xy 372.403024 -274.13512) (xy 372.399064 -274.086066)
			(xy 372.070122 -274.086066) (xy 372.069627 -274.110673) (xy 372.061732 -274.15925) (xy 372.046148 -274.205931)
			(xy 372.023277 -274.249508) (xy 371.993712 -274.288852) (xy 371.958219 -274.322944) (xy 371.917716 -274.3509)
			(xy 371.873254 -274.371998) (xy 371.825983 -274.38569) (xy 371.777128 -274.391622) (xy 371.727953 -274.389641)
			(xy 371.679734 -274.379797) (xy 371.633718 -274.362345) (xy 371.591097 -274.337738) (xy 371.552976 -274.306613)
			(xy 371.520341 -274.269776) (xy 371.494038 -274.22818) (xy 371.474747 -274.182904) (xy 371.46297 -274.13512)
			(xy 371.45901 -274.086066) (xy 371.130068 -274.086066) (xy 371.129573 -274.110673) (xy 371.121678 -274.15925)
			(xy 371.106094 -274.205931) (xy 371.083223 -274.249508) (xy 371.053658 -274.288852) (xy 371.018165 -274.322944)
			(xy 370.977662 -274.3509) (xy 370.9332 -274.371998) (xy 370.885929 -274.38569) (xy 370.837074 -274.391622)
			(xy 370.787899 -274.389641) (xy 370.73968 -274.379797) (xy 370.693664 -274.362345) (xy 370.651043 -274.337738)
			(xy 370.612922 -274.306613) (xy 370.580287 -274.269776) (xy 370.553984 -274.22818) (xy 370.534693 -274.182904)
			(xy 370.522916 -274.13512) (xy 370.518956 -274.086066) (xy 370.190014 -274.086066) (xy 370.189519 -274.110673)
			(xy 370.181624 -274.15925) (xy 370.16604 -274.205931) (xy 370.143169 -274.249508) (xy 370.113604 -274.288852)
			(xy 370.078111 -274.322944) (xy 370.037608 -274.3509) (xy 369.993146 -274.371998) (xy 369.945875 -274.38569)
			(xy 369.89702 -274.391622) (xy 369.847845 -274.389641) (xy 369.799626 -274.379797) (xy 369.75361 -274.362345)
			(xy 369.710989 -274.337738) (xy 369.672868 -274.306613) (xy 369.640233 -274.269776) (xy 369.61393 -274.22818)
			(xy 369.594639 -274.182904) (xy 369.582862 -274.13512) (xy 369.578902 -274.086066) (xy 369.250214 -274.086066)
			(xy 369.249719 -274.110673) (xy 369.241824 -274.15925) (xy 369.22624 -274.205931) (xy 369.203369 -274.249508)
			(xy 369.173804 -274.288852) (xy 369.138311 -274.322944) (xy 369.097808 -274.3509) (xy 369.053346 -274.371998)
			(xy 369.006075 -274.38569) (xy 368.95722 -274.391622) (xy 368.908045 -274.389641) (xy 368.859826 -274.379797)
			(xy 368.81381 -274.362345) (xy 368.771189 -274.337738) (xy 368.733068 -274.306613) (xy 368.700433 -274.269776)
			(xy 368.67413 -274.22818) (xy 368.654839 -274.182904) (xy 368.643062 -274.13512) (xy 368.639102 -274.086066)
			(xy 368.31016 -274.086066) (xy 368.309665 -274.110673) (xy 368.30177 -274.15925) (xy 368.286186 -274.205931)
			(xy 368.263315 -274.249508) (xy 368.23375 -274.288852) (xy 368.198257 -274.322944) (xy 368.157754 -274.3509)
			(xy 368.113292 -274.371998) (xy 368.066021 -274.38569) (xy 368.017166 -274.391622) (xy 367.967991 -274.389641)
			(xy 367.919772 -274.379797) (xy 367.873756 -274.362345) (xy 367.831135 -274.337738) (xy 367.793014 -274.306613)
			(xy 367.760379 -274.269776) (xy 367.734076 -274.22818) (xy 367.714785 -274.182904) (xy 367.703008 -274.13512)
			(xy 367.699048 -274.086066) (xy 367.370106 -274.086066) (xy 367.369611 -274.110673) (xy 367.361716 -274.15925)
			(xy 367.346132 -274.205931) (xy 367.323261 -274.249508) (xy 367.293696 -274.288852) (xy 367.258203 -274.322944)
			(xy 367.2177 -274.3509) (xy 367.173238 -274.371998) (xy 367.125967 -274.38569) (xy 367.077112 -274.391622)
			(xy 367.027937 -274.389641) (xy 366.979718 -274.379797) (xy 366.933702 -274.362345) (xy 366.891081 -274.337738)
			(xy 366.85296 -274.306613) (xy 366.820325 -274.269776) (xy 366.794022 -274.22818) (xy 366.774731 -274.182904)
			(xy 366.762954 -274.13512) (xy 366.758994 -274.086066) (xy 366.430052 -274.086066) (xy 366.429557 -274.110673)
			(xy 366.421662 -274.15925) (xy 366.406078 -274.205931) (xy 366.383207 -274.249508) (xy 366.353642 -274.288852)
			(xy 366.318149 -274.322944) (xy 366.277646 -274.3509) (xy 366.233184 -274.371998) (xy 366.185913 -274.38569)
			(xy 366.137058 -274.391622) (xy 366.087883 -274.389641) (xy 366.039664 -274.379797) (xy 365.993648 -274.362345)
			(xy 365.951027 -274.337738) (xy 365.912906 -274.306613) (xy 365.880271 -274.269776) (xy 365.853968 -274.22818)
			(xy 365.834677 -274.182904) (xy 365.8229 -274.13512) (xy 365.81894 -274.086066) (xy 365.489998 -274.086066)
			(xy 365.489503 -274.110673) (xy 365.481608 -274.15925) (xy 365.466024 -274.205931) (xy 365.443153 -274.249508)
			(xy 365.413588 -274.288852) (xy 365.378095 -274.322944) (xy 365.337592 -274.3509) (xy 365.29313 -274.371998)
			(xy 365.245859 -274.38569) (xy 365.197004 -274.391622) (xy 365.147829 -274.389641) (xy 365.09961 -274.379797)
			(xy 365.053594 -274.362345) (xy 365.010973 -274.337738) (xy 364.972852 -274.306613) (xy 364.940217 -274.269776)
			(xy 364.913914 -274.22818) (xy 364.894623 -274.182904) (xy 364.882846 -274.13512) (xy 364.878886 -274.086066)
			(xy 364.550198 -274.086066) (xy 364.549703 -274.110673) (xy 364.541808 -274.15925) (xy 364.526224 -274.205931)
			(xy 364.503353 -274.249508) (xy 364.473788 -274.288852) (xy 364.438295 -274.322944) (xy 364.397792 -274.3509)
			(xy 364.35333 -274.371998) (xy 364.306059 -274.38569) (xy 364.257204 -274.391622) (xy 364.208029 -274.389641)
			(xy 364.15981 -274.379797) (xy 364.113794 -274.362345) (xy 364.071173 -274.337738) (xy 364.033052 -274.306613)
			(xy 364.000417 -274.269776) (xy 363.974114 -274.22818) (xy 363.954823 -274.182904) (xy 363.943046 -274.13512)
			(xy 363.939086 -274.086066) (xy 363.610144 -274.086066) (xy 363.609649 -274.110673) (xy 363.601754 -274.15925)
			(xy 363.58617 -274.205931) (xy 363.563299 -274.249508) (xy 363.533734 -274.288852) (xy 363.498241 -274.322944)
			(xy 363.457738 -274.3509) (xy 363.413276 -274.371998) (xy 363.366005 -274.38569) (xy 363.31715 -274.391622)
			(xy 363.267975 -274.389641) (xy 363.219756 -274.379797) (xy 363.17374 -274.362345) (xy 363.131119 -274.337738)
			(xy 363.092998 -274.306613) (xy 363.060363 -274.269776) (xy 363.03406 -274.22818) (xy 363.014769 -274.182904)
			(xy 363.002992 -274.13512) (xy 362.999032 -274.086066) (xy 362.67009 -274.086066) (xy 362.669595 -274.110673)
			(xy 362.6617 -274.15925) (xy 362.646116 -274.205931) (xy 362.623245 -274.249508) (xy 362.59368 -274.288852)
			(xy 362.558187 -274.322944) (xy 362.517684 -274.3509) (xy 362.473222 -274.371998) (xy 362.425951 -274.38569)
			(xy 362.377096 -274.391622) (xy 362.327921 -274.389641) (xy 362.279702 -274.379797) (xy 362.233686 -274.362345)
			(xy 362.191065 -274.337738) (xy 362.152944 -274.306613) (xy 362.120309 -274.269776) (xy 362.094006 -274.22818)
			(xy 362.074715 -274.182904) (xy 362.062938 -274.13512) (xy 362.058978 -274.086066) (xy 361.730036 -274.086066)
			(xy 361.729541 -274.110673) (xy 361.721646 -274.15925) (xy 361.706062 -274.205931) (xy 361.683191 -274.249508)
			(xy 361.653626 -274.288852) (xy 361.618133 -274.322944) (xy 361.57763 -274.3509) (xy 361.533168 -274.371998)
			(xy 361.485897 -274.38569) (xy 361.437042 -274.391622) (xy 361.387867 -274.389641) (xy 361.339648 -274.379797)
			(xy 361.293632 -274.362345) (xy 361.251011 -274.337738) (xy 361.21289 -274.306613) (xy 361.180255 -274.269776)
			(xy 361.153952 -274.22818) (xy 361.134661 -274.182904) (xy 361.122884 -274.13512) (xy 361.118924 -274.086066)
			(xy 358.916478 -274.086066) (xy 358.915983 -274.110673) (xy 358.908088 -274.15925) (xy 358.892504 -274.205931)
			(xy 358.869633 -274.249508) (xy 358.840068 -274.288852) (xy 358.804575 -274.322944) (xy 358.764072 -274.3509)
			(xy 358.71961 -274.371998) (xy 358.672339 -274.38569) (xy 358.623484 -274.391622) (xy 358.574309 -274.389641)
			(xy 358.52609 -274.379797) (xy 358.480074 -274.362345) (xy 358.437453 -274.337738) (xy 358.399332 -274.306613)
			(xy 358.366697 -274.269776) (xy 358.340394 -274.22818) (xy 358.321103 -274.182904) (xy 358.309326 -274.13512)
			(xy 358.305366 -274.086066) (xy 357.976424 -274.086066) (xy 357.975929 -274.110673) (xy 357.968034 -274.15925)
			(xy 357.95245 -274.205931) (xy 357.929579 -274.249508) (xy 357.900014 -274.288852) (xy 357.864521 -274.322944)
			(xy 357.824018 -274.3509) (xy 357.779556 -274.371998) (xy 357.732285 -274.38569) (xy 357.68343 -274.391622)
			(xy 357.634255 -274.389641) (xy 357.586036 -274.379797) (xy 357.54002 -274.362345) (xy 357.497399 -274.337738)
			(xy 357.459278 -274.306613) (xy 357.426643 -274.269776) (xy 357.40034 -274.22818) (xy 357.381049 -274.182904)
			(xy 357.369272 -274.13512) (xy 357.365312 -274.086066) (xy 357.03637 -274.086066) (xy 357.035875 -274.110673)
			(xy 357.02798 -274.15925) (xy 357.012396 -274.205931) (xy 356.989525 -274.249508) (xy 356.95996 -274.288852)
			(xy 356.924467 -274.322944) (xy 356.883964 -274.3509) (xy 356.839502 -274.371998) (xy 356.792231 -274.38569)
			(xy 356.743376 -274.391622) (xy 356.694201 -274.389641) (xy 356.645982 -274.379797) (xy 356.599966 -274.362345)
			(xy 356.557345 -274.337738) (xy 356.519224 -274.306613) (xy 356.486589 -274.269776) (xy 356.460286 -274.22818)
			(xy 356.440995 -274.182904) (xy 356.429218 -274.13512) (xy 356.425258 -274.086066) (xy 356.096316 -274.086066)
			(xy 356.095821 -274.110673) (xy 356.087926 -274.15925) (xy 356.072342 -274.205931) (xy 356.049471 -274.249508)
			(xy 356.019906 -274.288852) (xy 355.984413 -274.322944) (xy 355.94391 -274.3509) (xy 355.899448 -274.371998)
			(xy 355.852177 -274.38569) (xy 355.803322 -274.391622) (xy 355.754147 -274.389641) (xy 355.705928 -274.379797)
			(xy 355.659912 -274.362345) (xy 355.617291 -274.337738) (xy 355.57917 -274.306613) (xy 355.546535 -274.269776)
			(xy 355.520232 -274.22818) (xy 355.500941 -274.182904) (xy 355.489164 -274.13512) (xy 355.485204 -274.086066)
			(xy 355.156516 -274.086066) (xy 355.156021 -274.110673) (xy 355.148126 -274.15925) (xy 355.132542 -274.205931)
			(xy 355.109671 -274.249508) (xy 355.080106 -274.288852) (xy 355.044613 -274.322944) (xy 355.00411 -274.3509)
			(xy 354.959648 -274.371998) (xy 354.912377 -274.38569) (xy 354.863522 -274.391622) (xy 354.814347 -274.389641)
			(xy 354.766128 -274.379797) (xy 354.720112 -274.362345) (xy 354.677491 -274.337738) (xy 354.63937 -274.306613)
			(xy 354.606735 -274.269776) (xy 354.580432 -274.22818) (xy 354.561141 -274.182904) (xy 354.549364 -274.13512)
			(xy 354.545404 -274.086066) (xy 354.216462 -274.086066) (xy 354.215967 -274.110673) (xy 354.208072 -274.15925)
			(xy 354.192488 -274.205931) (xy 354.169617 -274.249508) (xy 354.140052 -274.288852) (xy 354.104559 -274.322944)
			(xy 354.064056 -274.3509) (xy 354.019594 -274.371998) (xy 353.972323 -274.38569) (xy 353.923468 -274.391622)
			(xy 353.874293 -274.389641) (xy 353.826074 -274.379797) (xy 353.780058 -274.362345) (xy 353.737437 -274.337738)
			(xy 353.699316 -274.306613) (xy 353.666681 -274.269776) (xy 353.640378 -274.22818) (xy 353.621087 -274.182904)
			(xy 353.60931 -274.13512) (xy 353.60535 -274.086066) (xy 353.276408 -274.086066) (xy 353.275913 -274.110673)
			(xy 353.268018 -274.15925) (xy 353.252434 -274.205931) (xy 353.229563 -274.249508) (xy 353.199998 -274.288852)
			(xy 353.164505 -274.322944) (xy 353.124002 -274.3509) (xy 353.07954 -274.371998) (xy 353.032269 -274.38569)
			(xy 352.983414 -274.391622) (xy 352.934239 -274.389641) (xy 352.88602 -274.379797) (xy 352.840004 -274.362345)
			(xy 352.797383 -274.337738) (xy 352.759262 -274.306613) (xy 352.726627 -274.269776) (xy 352.700324 -274.22818)
			(xy 352.681033 -274.182904) (xy 352.669256 -274.13512) (xy 352.665296 -274.086066) (xy 352.336354 -274.086066)
			(xy 352.335859 -274.110673) (xy 352.327964 -274.15925) (xy 352.31238 -274.205931) (xy 352.289509 -274.249508)
			(xy 352.259944 -274.288852) (xy 352.224451 -274.322944) (xy 352.183948 -274.3509) (xy 352.139486 -274.371998)
			(xy 352.092215 -274.38569) (xy 352.04336 -274.391622) (xy 351.994185 -274.389641) (xy 351.945966 -274.379797)
			(xy 351.89995 -274.362345) (xy 351.857329 -274.337738) (xy 351.819208 -274.306613) (xy 351.786573 -274.269776)
			(xy 351.76027 -274.22818) (xy 351.740979 -274.182904) (xy 351.729202 -274.13512) (xy 351.725242 -274.086066)
			(xy 351.396554 -274.086066) (xy 351.396059 -274.110673) (xy 351.388164 -274.15925) (xy 351.37258 -274.205931)
			(xy 351.349709 -274.249508) (xy 351.320144 -274.288852) (xy 351.284651 -274.322944) (xy 351.244148 -274.3509)
			(xy 351.199686 -274.371998) (xy 351.152415 -274.38569) (xy 351.10356 -274.391622) (xy 351.054385 -274.389641)
			(xy 351.006166 -274.379797) (xy 350.96015 -274.362345) (xy 350.917529 -274.337738) (xy 350.879408 -274.306613)
			(xy 350.846773 -274.269776) (xy 350.82047 -274.22818) (xy 350.801179 -274.182904) (xy 350.789402 -274.13512)
			(xy 350.785442 -274.086066) (xy 350.4565 -274.086066) (xy 350.456005 -274.110673) (xy 350.44811 -274.15925)
			(xy 350.432526 -274.205931) (xy 350.409655 -274.249508) (xy 350.38009 -274.288852) (xy 350.344597 -274.322944)
			(xy 350.304094 -274.3509) (xy 350.259632 -274.371998) (xy 350.212361 -274.38569) (xy 350.163506 -274.391622)
			(xy 350.114331 -274.389641) (xy 350.066112 -274.379797) (xy 350.020096 -274.362345) (xy 349.977475 -274.337738)
			(xy 349.939354 -274.306613) (xy 349.906719 -274.269776) (xy 349.880416 -274.22818) (xy 349.861125 -274.182904)
			(xy 349.849348 -274.13512) (xy 349.845388 -274.086066) (xy 349.516446 -274.086066) (xy 349.515951 -274.110673)
			(xy 349.508056 -274.15925) (xy 349.492472 -274.205931) (xy 349.469601 -274.249508) (xy 349.440036 -274.288852)
			(xy 349.404543 -274.322944) (xy 349.36404 -274.3509) (xy 349.319578 -274.371998) (xy 349.272307 -274.38569)
			(xy 349.223452 -274.391622) (xy 349.174277 -274.389641) (xy 349.126058 -274.379797) (xy 349.080042 -274.362345)
			(xy 349.037421 -274.337738) (xy 348.9993 -274.306613) (xy 348.966665 -274.269776) (xy 348.940362 -274.22818)
			(xy 348.921071 -274.182904) (xy 348.909294 -274.13512) (xy 348.905334 -274.086066) (xy 348.576392 -274.086066)
			(xy 348.575897 -274.110673) (xy 348.568002 -274.15925) (xy 348.552418 -274.205931) (xy 348.529547 -274.249508)
			(xy 348.499982 -274.288852) (xy 348.464489 -274.322944) (xy 348.423986 -274.3509) (xy 348.379524 -274.371998)
			(xy 348.332253 -274.38569) (xy 348.283398 -274.391622) (xy 348.234223 -274.389641) (xy 348.186004 -274.379797)
			(xy 348.139988 -274.362345) (xy 348.097367 -274.337738) (xy 348.059246 -274.306613) (xy 348.026611 -274.269776)
			(xy 348.000308 -274.22818) (xy 347.981017 -274.182904) (xy 347.96924 -274.13512) (xy 347.96528 -274.086066)
			(xy 347.636338 -274.086066) (xy 347.635843 -274.110673) (xy 347.627948 -274.15925) (xy 347.612364 -274.205931)
			(xy 347.589493 -274.249508) (xy 347.559928 -274.288852) (xy 347.524435 -274.322944) (xy 347.483932 -274.3509)
			(xy 347.43947 -274.371998) (xy 347.392199 -274.38569) (xy 347.343344 -274.391622) (xy 347.294169 -274.389641)
			(xy 347.24595 -274.379797) (xy 347.199934 -274.362345) (xy 347.157313 -274.337738) (xy 347.119192 -274.306613)
			(xy 347.086557 -274.269776) (xy 347.060254 -274.22818) (xy 347.040963 -274.182904) (xy 347.029186 -274.13512)
			(xy 347.025226 -274.086066) (xy 346.696538 -274.086066) (xy 346.696043 -274.110673) (xy 346.688148 -274.15925)
			(xy 346.672564 -274.205931) (xy 346.649693 -274.249508) (xy 346.620128 -274.288852) (xy 346.584635 -274.322944)
			(xy 346.544132 -274.3509) (xy 346.49967 -274.371998) (xy 346.452399 -274.38569) (xy 346.403544 -274.391622)
			(xy 346.354369 -274.389641) (xy 346.30615 -274.379797) (xy 346.260134 -274.362345) (xy 346.217513 -274.337738)
			(xy 346.179392 -274.306613) (xy 346.146757 -274.269776) (xy 346.120454 -274.22818) (xy 346.101163 -274.182904)
			(xy 346.089386 -274.13512) (xy 346.085426 -274.086066) (xy 345.756484 -274.086066) (xy 345.755989 -274.110673)
			(xy 345.748094 -274.15925) (xy 345.73251 -274.205931) (xy 345.709639 -274.249508) (xy 345.680074 -274.288852)
			(xy 345.644581 -274.322944) (xy 345.604078 -274.3509) (xy 345.559616 -274.371998) (xy 345.512345 -274.38569)
			(xy 345.46349 -274.391622) (xy 345.414315 -274.389641) (xy 345.366096 -274.379797) (xy 345.32008 -274.362345)
			(xy 345.277459 -274.337738) (xy 345.239338 -274.306613) (xy 345.206703 -274.269776) (xy 345.1804 -274.22818)
			(xy 345.161109 -274.182904) (xy 345.149332 -274.13512) (xy 345.145372 -274.086066) (xy 344.81643 -274.086066)
			(xy 344.815935 -274.110673) (xy 344.80804 -274.15925) (xy 344.792456 -274.205931) (xy 344.769585 -274.249508)
			(xy 344.74002 -274.288852) (xy 344.704527 -274.322944) (xy 344.664024 -274.3509) (xy 344.619562 -274.371998)
			(xy 344.572291 -274.38569) (xy 344.523436 -274.391622) (xy 344.474261 -274.389641) (xy 344.426042 -274.379797)
			(xy 344.380026 -274.362345) (xy 344.337405 -274.337738) (xy 344.299284 -274.306613) (xy 344.266649 -274.269776)
			(xy 344.240346 -274.22818) (xy 344.221055 -274.182904) (xy 344.209278 -274.13512) (xy 344.205318 -274.086066)
			(xy 343.88679 -274.086066) (xy 343.886278 -274.111512) (xy 343.878114 -274.161746) (xy 343.861998 -274.21002)
			(xy 343.838347 -274.255083) (xy 343.807774 -274.295769) (xy 343.77107 -274.331024) (xy 343.729186 -274.359934)
			(xy 343.683207 -274.381751) (xy 343.634323 -274.395911) (xy 343.583802 -274.402045) (xy 343.53295 -274.399996)
			(xy 343.483086 -274.389816) (xy 343.4355 -274.371769) (xy 343.391426 -274.346323) (xy 343.352004 -274.314136)
			(xy 343.318256 -274.276042) (xy 343.291055 -274.233028) (xy 343.271107 -274.186208) (xy 343.258928 -274.136794)
			(xy 343.254833 -274.086066) (xy 342.946862 -274.086066) (xy 342.946482 -274.091908) (xy 342.945468 -274.118787)
			(xy 342.935421 -274.171624) (xy 342.916556 -274.221992) (xy 342.889422 -274.26843) (xy 342.854804 -274.309592)
			(xy 342.813705 -274.344286) (xy 342.79078 -274.358354) (xy 342.782609 -274.36366) (xy 342.770725 -274.379076)
			(xy 342.767666 -274.388326) (xy 342.754607 -274.433029) (xy 342.722037 -274.520287) (xy 342.682319 -274.604532)
			(xy 342.635726 -274.685179) (xy 342.582583 -274.761668) (xy 342.523259 -274.833469) (xy 342.49106 -274.867116)
			(xy 342.484622 -274.874285) (xy 342.477183 -274.892043) (xy 342.476931 -274.896072) (xy 342.795364 -274.896072)
			(xy 342.799324 -274.847018) (xy 342.811101 -274.799234) (xy 342.830392 -274.753958) (xy 342.856695 -274.712362)
			(xy 342.88933 -274.675525) (xy 342.927451 -274.6444) (xy 342.970072 -274.619793) (xy 343.016088 -274.602341)
			(xy 343.064307 -274.592497) (xy 343.113482 -274.590516) (xy 343.162337 -274.596448) (xy 343.209608 -274.61014)
			(xy 343.25407 -274.631238) (xy 343.294573 -274.659194) (xy 343.330066 -274.693286) (xy 343.359631 -274.73263)
			(xy 343.382502 -274.776207) (xy 343.398086 -274.822888) (xy 343.405981 -274.871465) (xy 343.406476 -274.896072)
			(xy 343.724987 -274.896072) (xy 343.729082 -274.845344) (xy 343.741261 -274.79593) (xy 343.761209 -274.74911)
			(xy 343.78841 -274.706096) (xy 343.822158 -274.668002) (xy 343.86158 -274.635815) (xy 343.905654 -274.610369)
			(xy 343.95324 -274.592322) (xy 344.003104 -274.582142) (xy 344.053956 -274.580093) (xy 344.104477 -274.586227)
			(xy 344.153361 -274.600387) (xy 344.19934 -274.622204) (xy 344.241224 -274.651114) (xy 344.277928 -274.686369)
			(xy 344.308501 -274.727055) (xy 344.332152 -274.772118) (xy 344.348268 -274.820392) (xy 344.356432 -274.870626)
			(xy 344.356944 -274.896072) (xy 344.675218 -274.896072) (xy 344.679178 -274.847018) (xy 344.690955 -274.799234)
			(xy 344.710246 -274.753958) (xy 344.736549 -274.712362) (xy 344.769184 -274.675525) (xy 344.807305 -274.6444)
			(xy 344.849926 -274.619793) (xy 344.895942 -274.602341) (xy 344.944161 -274.592497) (xy 344.993336 -274.590516)
			(xy 345.042191 -274.596448) (xy 345.089462 -274.61014) (xy 345.133924 -274.631238) (xy 345.174427 -274.659194)
			(xy 345.20992 -274.693286) (xy 345.239485 -274.73263) (xy 345.262356 -274.776207) (xy 345.27794 -274.822888)
			(xy 345.285835 -274.871465) (xy 345.28633 -274.896072) (xy 345.615272 -274.896072) (xy 345.619232 -274.847018)
			(xy 345.631009 -274.799234) (xy 345.6503 -274.753958) (xy 345.676603 -274.712362) (xy 345.709238 -274.675525)
			(xy 345.747359 -274.6444) (xy 345.78998 -274.619793) (xy 345.835996 -274.602341) (xy 345.884215 -274.592497)
			(xy 345.93339 -274.590516) (xy 345.982245 -274.596448) (xy 346.029516 -274.61014) (xy 346.073978 -274.631238)
			(xy 346.114481 -274.659194) (xy 346.149974 -274.693286) (xy 346.179539 -274.73263) (xy 346.20241 -274.776207)
			(xy 346.217994 -274.822888) (xy 346.225889 -274.871465) (xy 346.226384 -274.896072) (xy 346.555326 -274.896072)
			(xy 346.559286 -274.847018) (xy 346.571063 -274.799234) (xy 346.590354 -274.753958) (xy 346.616657 -274.712362)
			(xy 346.649292 -274.675525) (xy 346.687413 -274.6444) (xy 346.730034 -274.619793) (xy 346.77605 -274.602341)
			(xy 346.824269 -274.592497) (xy 346.873444 -274.590516) (xy 346.922299 -274.596448) (xy 346.96957 -274.61014)
			(xy 347.014032 -274.631238) (xy 347.054535 -274.659194) (xy 347.090028 -274.693286) (xy 347.119593 -274.73263)
			(xy 347.142464 -274.776207) (xy 347.158048 -274.822888) (xy 347.165943 -274.871465) (xy 347.166438 -274.896072)
			(xy 347.49538 -274.896072) (xy 347.49934 -274.847018) (xy 347.511117 -274.799234) (xy 347.530408 -274.753958)
			(xy 347.556711 -274.712362) (xy 347.589346 -274.675525) (xy 347.627467 -274.6444) (xy 347.670088 -274.619793)
			(xy 347.716104 -274.602341) (xy 347.764323 -274.592497) (xy 347.813498 -274.590516) (xy 347.862353 -274.596448)
			(xy 347.909624 -274.61014) (xy 347.954086 -274.631238) (xy 347.994589 -274.659194) (xy 348.030082 -274.693286)
			(xy 348.059647 -274.73263) (xy 348.082518 -274.776207) (xy 348.098102 -274.822888) (xy 348.105997 -274.871465)
			(xy 348.106492 -274.896072) (xy 348.435434 -274.896072) (xy 348.439394 -274.847018) (xy 348.451171 -274.799234)
			(xy 348.470462 -274.753958) (xy 348.496765 -274.712362) (xy 348.5294 -274.675525) (xy 348.567521 -274.6444)
			(xy 348.610142 -274.619793) (xy 348.656158 -274.602341) (xy 348.704377 -274.592497) (xy 348.753552 -274.590516)
			(xy 348.802407 -274.596448) (xy 348.849678 -274.61014) (xy 348.89414 -274.631238) (xy 348.934643 -274.659194)
			(xy 348.970136 -274.693286) (xy 348.999701 -274.73263) (xy 349.022572 -274.776207) (xy 349.038156 -274.822888)
			(xy 349.046051 -274.871465) (xy 349.046546 -274.896072) (xy 349.375234 -274.896072) (xy 349.379194 -274.847018)
			(xy 349.390971 -274.799234) (xy 349.410262 -274.753958) (xy 349.436565 -274.712362) (xy 349.4692 -274.675525)
			(xy 349.507321 -274.6444) (xy 349.549942 -274.619793) (xy 349.595958 -274.602341) (xy 349.644177 -274.592497)
			(xy 349.693352 -274.590516) (xy 349.742207 -274.596448) (xy 349.789478 -274.61014) (xy 349.83394 -274.631238)
			(xy 349.874443 -274.659194) (xy 349.909936 -274.693286) (xy 349.939501 -274.73263) (xy 349.962372 -274.776207)
			(xy 349.977956 -274.822888) (xy 349.985851 -274.871465) (xy 349.986346 -274.896072) (xy 350.315288 -274.896072)
			(xy 350.319248 -274.847018) (xy 350.331025 -274.799234) (xy 350.350316 -274.753958) (xy 350.376619 -274.712362)
			(xy 350.409254 -274.675525) (xy 350.447375 -274.6444) (xy 350.489996 -274.619793) (xy 350.536012 -274.602341)
			(xy 350.584231 -274.592497) (xy 350.633406 -274.590516) (xy 350.682261 -274.596448) (xy 350.729532 -274.61014)
			(xy 350.773994 -274.631238) (xy 350.814497 -274.659194) (xy 350.84999 -274.693286) (xy 350.879555 -274.73263)
			(xy 350.902426 -274.776207) (xy 350.91801 -274.822888) (xy 350.925905 -274.871465) (xy 350.9264 -274.896072)
			(xy 351.255342 -274.896072) (xy 351.259302 -274.847018) (xy 351.271079 -274.799234) (xy 351.29037 -274.753958)
			(xy 351.316673 -274.712362) (xy 351.349308 -274.675525) (xy 351.387429 -274.6444) (xy 351.43005 -274.619793)
			(xy 351.476066 -274.602341) (xy 351.524285 -274.592497) (xy 351.57346 -274.590516) (xy 351.622315 -274.596448)
			(xy 351.669586 -274.61014) (xy 351.714048 -274.631238) (xy 351.754551 -274.659194) (xy 351.790044 -274.693286)
			(xy 351.819609 -274.73263) (xy 351.84248 -274.776207) (xy 351.858064 -274.822888) (xy 351.865959 -274.871465)
			(xy 351.866454 -274.896072) (xy 352.195396 -274.896072) (xy 352.199356 -274.847018) (xy 352.211133 -274.799234)
			(xy 352.230424 -274.753958) (xy 352.256727 -274.712362) (xy 352.289362 -274.675525) (xy 352.327483 -274.6444)
			(xy 352.370104 -274.619793) (xy 352.41612 -274.602341) (xy 352.464339 -274.592497) (xy 352.513514 -274.590516)
			(xy 352.562369 -274.596448) (xy 352.60964 -274.61014) (xy 352.654102 -274.631238) (xy 352.694605 -274.659194)
			(xy 352.730098 -274.693286) (xy 352.759663 -274.73263) (xy 352.782534 -274.776207) (xy 352.798118 -274.822888)
			(xy 352.806013 -274.871465) (xy 352.806508 -274.896072) (xy 353.135196 -274.896072) (xy 353.139156 -274.847018)
			(xy 353.150933 -274.799234) (xy 353.170224 -274.753958) (xy 353.196527 -274.712362) (xy 353.229162 -274.675525)
			(xy 353.267283 -274.6444) (xy 353.309904 -274.619793) (xy 353.35592 -274.602341) (xy 353.404139 -274.592497)
			(xy 353.453314 -274.590516) (xy 353.502169 -274.596448) (xy 353.54944 -274.61014) (xy 353.593902 -274.631238)
			(xy 353.634405 -274.659194) (xy 353.669898 -274.693286) (xy 353.699463 -274.73263) (xy 353.722334 -274.776207)
			(xy 353.737918 -274.822888) (xy 353.745813 -274.871465) (xy 353.746308 -274.896072) (xy 354.07525 -274.896072)
			(xy 354.07921 -274.847018) (xy 354.090987 -274.799234) (xy 354.110278 -274.753958) (xy 354.136581 -274.712362)
			(xy 354.169216 -274.675525) (xy 354.207337 -274.6444) (xy 354.249958 -274.619793) (xy 354.295974 -274.602341)
			(xy 354.344193 -274.592497) (xy 354.393368 -274.590516) (xy 354.442223 -274.596448) (xy 354.489494 -274.61014)
			(xy 354.533956 -274.631238) (xy 354.574459 -274.659194) (xy 354.609952 -274.693286) (xy 354.639517 -274.73263)
			(xy 354.662388 -274.776207) (xy 354.677972 -274.822888) (xy 354.685867 -274.871465) (xy 354.686362 -274.896072)
			(xy 355.015304 -274.896072) (xy 355.019264 -274.847018) (xy 355.031041 -274.799234) (xy 355.050332 -274.753958)
			(xy 355.076635 -274.712362) (xy 355.10927 -274.675525) (xy 355.147391 -274.6444) (xy 355.190012 -274.619793)
			(xy 355.236028 -274.602341) (xy 355.284247 -274.592497) (xy 355.333422 -274.590516) (xy 355.382277 -274.596448)
			(xy 355.429548 -274.61014) (xy 355.47401 -274.631238) (xy 355.514513 -274.659194) (xy 355.550006 -274.693286)
			(xy 355.579571 -274.73263) (xy 355.602442 -274.776207) (xy 355.618026 -274.822888) (xy 355.625921 -274.871465)
			(xy 355.626416 -274.896072) (xy 355.955358 -274.896072) (xy 355.959318 -274.847018) (xy 355.971095 -274.799234)
			(xy 355.990386 -274.753958) (xy 356.016689 -274.712362) (xy 356.049324 -274.675525) (xy 356.087445 -274.6444)
			(xy 356.130066 -274.619793) (xy 356.176082 -274.602341) (xy 356.224301 -274.592497) (xy 356.273476 -274.590516)
			(xy 356.322331 -274.596448) (xy 356.369602 -274.61014) (xy 356.414064 -274.631238) (xy 356.454567 -274.659194)
			(xy 356.49006 -274.693286) (xy 356.519625 -274.73263) (xy 356.542496 -274.776207) (xy 356.55808 -274.822888)
			(xy 356.565975 -274.871465) (xy 356.56647 -274.896072) (xy 363.468932 -274.896072) (xy 363.472892 -274.847018)
			(xy 363.484669 -274.799234) (xy 363.50396 -274.753958) (xy 363.530263 -274.712362) (xy 363.562898 -274.675525)
			(xy 363.601019 -274.6444) (xy 363.64364 -274.619793) (xy 363.689656 -274.602341) (xy 363.737875 -274.592497)
			(xy 363.78705 -274.590516) (xy 363.835905 -274.596448) (xy 363.883176 -274.61014) (xy 363.927638 -274.631238)
			(xy 363.968141 -274.659194) (xy 364.003634 -274.693286) (xy 364.033199 -274.73263) (xy 364.05607 -274.776207)
			(xy 364.071654 -274.822888) (xy 364.079549 -274.871465) (xy 364.080044 -274.896072) (xy 364.408986 -274.896072)
			(xy 364.412946 -274.847018) (xy 364.424723 -274.799234) (xy 364.444014 -274.753958) (xy 364.470317 -274.712362)
			(xy 364.502952 -274.675525) (xy 364.541073 -274.6444) (xy 364.583694 -274.619793) (xy 364.62971 -274.602341)
			(xy 364.677929 -274.592497) (xy 364.727104 -274.590516) (xy 364.775959 -274.596448) (xy 364.82323 -274.61014)
			(xy 364.867692 -274.631238) (xy 364.908195 -274.659194) (xy 364.943688 -274.693286) (xy 364.973253 -274.73263)
			(xy 364.996124 -274.776207) (xy 365.011708 -274.822888) (xy 365.019603 -274.871465) (xy 365.020098 -274.896072)
			(xy 365.34904 -274.896072) (xy 365.353 -274.847018) (xy 365.364777 -274.799234) (xy 365.384068 -274.753958)
			(xy 365.410371 -274.712362) (xy 365.443006 -274.675525) (xy 365.481127 -274.6444) (xy 365.523748 -274.619793)
			(xy 365.569764 -274.602341) (xy 365.617983 -274.592497) (xy 365.667158 -274.590516) (xy 365.716013 -274.596448)
			(xy 365.763284 -274.61014) (xy 365.807746 -274.631238) (xy 365.848249 -274.659194) (xy 365.883742 -274.693286)
			(xy 365.913307 -274.73263) (xy 365.936178 -274.776207) (xy 365.951762 -274.822888) (xy 365.959657 -274.871465)
			(xy 365.960152 -274.896072) (xy 366.289094 -274.896072) (xy 366.293054 -274.847018) (xy 366.304831 -274.799234)
			(xy 366.324122 -274.753958) (xy 366.350425 -274.712362) (xy 366.38306 -274.675525) (xy 366.421181 -274.6444)
			(xy 366.463802 -274.619793) (xy 366.509818 -274.602341) (xy 366.558037 -274.592497) (xy 366.607212 -274.590516)
			(xy 366.656067 -274.596448) (xy 366.703338 -274.61014) (xy 366.7478 -274.631238) (xy 366.788303 -274.659194)
			(xy 366.823796 -274.693286) (xy 366.853361 -274.73263) (xy 366.876232 -274.776207) (xy 366.891816 -274.822888)
			(xy 366.899711 -274.871465) (xy 366.900206 -274.896072) (xy 367.228894 -274.896072) (xy 367.232854 -274.847018)
			(xy 367.244631 -274.799234) (xy 367.263922 -274.753958) (xy 367.290225 -274.712362) (xy 367.32286 -274.675525)
			(xy 367.360981 -274.6444) (xy 367.403602 -274.619793) (xy 367.449618 -274.602341) (xy 367.497837 -274.592497)
			(xy 367.547012 -274.590516) (xy 367.595867 -274.596448) (xy 367.643138 -274.61014) (xy 367.6876 -274.631238)
			(xy 367.728103 -274.659194) (xy 367.763596 -274.693286) (xy 367.793161 -274.73263) (xy 367.816032 -274.776207)
			(xy 367.831616 -274.822888) (xy 367.839511 -274.871465) (xy 367.840006 -274.896072) (xy 368.168948 -274.896072)
			(xy 368.172908 -274.847018) (xy 368.184685 -274.799234) (xy 368.203976 -274.753958) (xy 368.230279 -274.712362)
			(xy 368.262914 -274.675525) (xy 368.301035 -274.6444) (xy 368.343656 -274.619793) (xy 368.389672 -274.602341)
			(xy 368.437891 -274.592497) (xy 368.487066 -274.590516) (xy 368.535921 -274.596448) (xy 368.583192 -274.61014)
			(xy 368.627654 -274.631238) (xy 368.668157 -274.659194) (xy 368.70365 -274.693286) (xy 368.733215 -274.73263)
			(xy 368.756086 -274.776207) (xy 368.77167 -274.822888) (xy 368.779565 -274.871465) (xy 368.78006 -274.896072)
			(xy 369.109002 -274.896072) (xy 369.112962 -274.847018) (xy 369.124739 -274.799234) (xy 369.14403 -274.753958)
			(xy 369.170333 -274.712362) (xy 369.202968 -274.675525) (xy 369.241089 -274.6444) (xy 369.28371 -274.619793)
			(xy 369.329726 -274.602341) (xy 369.377945 -274.592497) (xy 369.42712 -274.590516) (xy 369.475975 -274.596448)
			(xy 369.523246 -274.61014) (xy 369.567708 -274.631238) (xy 369.608211 -274.659194) (xy 369.643704 -274.693286)
			(xy 369.673269 -274.73263) (xy 369.69614 -274.776207) (xy 369.711724 -274.822888) (xy 369.719619 -274.871465)
			(xy 369.720114 -274.896072) (xy 370.049056 -274.896072) (xy 370.053016 -274.847018) (xy 370.064793 -274.799234)
			(xy 370.084084 -274.753958) (xy 370.110387 -274.712362) (xy 370.143022 -274.675525) (xy 370.181143 -274.6444)
			(xy 370.223764 -274.619793) (xy 370.26978 -274.602341) (xy 370.317999 -274.592497) (xy 370.367174 -274.590516)
			(xy 370.416029 -274.596448) (xy 370.4633 -274.61014) (xy 370.507762 -274.631238) (xy 370.548265 -274.659194)
			(xy 370.583758 -274.693286) (xy 370.613323 -274.73263) (xy 370.636194 -274.776207) (xy 370.651778 -274.822888)
			(xy 370.659673 -274.871465) (xy 370.660168 -274.896072) (xy 370.98911 -274.896072) (xy 370.99307 -274.847018)
			(xy 371.004847 -274.799234) (xy 371.024138 -274.753958) (xy 371.050441 -274.712362) (xy 371.083076 -274.675525)
			(xy 371.121197 -274.6444) (xy 371.163818 -274.619793) (xy 371.209834 -274.602341) (xy 371.258053 -274.592497)
			(xy 371.307228 -274.590516) (xy 371.356083 -274.596448) (xy 371.403354 -274.61014) (xy 371.447816 -274.631238)
			(xy 371.488319 -274.659194) (xy 371.523812 -274.693286) (xy 371.553377 -274.73263) (xy 371.576248 -274.776207)
			(xy 371.591832 -274.822888) (xy 371.599727 -274.871465) (xy 371.600222 -274.896072) (xy 371.92891 -274.896072)
			(xy 371.93287 -274.847018) (xy 371.944647 -274.799234) (xy 371.963938 -274.753958) (xy 371.990241 -274.712362)
			(xy 372.022876 -274.675525) (xy 372.060997 -274.6444) (xy 372.103618 -274.619793) (xy 372.149634 -274.602341)
			(xy 372.197853 -274.592497) (xy 372.247028 -274.590516) (xy 372.295883 -274.596448) (xy 372.343154 -274.61014)
			(xy 372.387616 -274.631238) (xy 372.428119 -274.659194) (xy 372.463612 -274.693286) (xy 372.493177 -274.73263)
			(xy 372.516048 -274.776207) (xy 372.531632 -274.822888) (xy 372.539527 -274.871465) (xy 372.540022 -274.896072)
			(xy 372.868964 -274.896072) (xy 372.872924 -274.847018) (xy 372.884701 -274.799234) (xy 372.903992 -274.753958)
			(xy 372.930295 -274.712362) (xy 372.96293 -274.675525) (xy 373.001051 -274.6444) (xy 373.043672 -274.619793)
			(xy 373.089688 -274.602341) (xy 373.137907 -274.592497) (xy 373.187082 -274.590516) (xy 373.235937 -274.596448)
			(xy 373.283208 -274.61014) (xy 373.32767 -274.631238) (xy 373.368173 -274.659194) (xy 373.403666 -274.693286)
			(xy 373.433231 -274.73263) (xy 373.456102 -274.776207) (xy 373.471686 -274.822888) (xy 373.479581 -274.871465)
			(xy 373.480076 -274.896072) (xy 373.809018 -274.896072) (xy 373.812978 -274.847018) (xy 373.824755 -274.799234)
			(xy 373.844046 -274.753958) (xy 373.870349 -274.712362) (xy 373.902984 -274.675525) (xy 373.941105 -274.6444)
			(xy 373.983726 -274.619793) (xy 374.029742 -274.602341) (xy 374.077961 -274.592497) (xy 374.127136 -274.590516)
			(xy 374.175991 -274.596448) (xy 374.223262 -274.61014) (xy 374.267724 -274.631238) (xy 374.308227 -274.659194)
			(xy 374.34372 -274.693286) (xy 374.373285 -274.73263) (xy 374.396156 -274.776207) (xy 374.41174 -274.822888)
			(xy 374.419635 -274.871465) (xy 374.42013 -274.896072) (xy 374.419635 -274.920679) (xy 374.41174 -274.969256)
			(xy 374.396156 -275.015937) (xy 374.373285 -275.059514) (xy 374.34372 -275.098858) (xy 374.308227 -275.13295)
			(xy 374.267724 -275.160906) (xy 374.223262 -275.182004) (xy 374.175991 -275.195696) (xy 374.127136 -275.201628)
			(xy 374.077961 -275.199647) (xy 374.029742 -275.189803) (xy 373.983726 -275.172351) (xy 373.941105 -275.147744)
			(xy 373.902984 -275.116619) (xy 373.870349 -275.079782) (xy 373.844046 -275.038186) (xy 373.824755 -274.99291)
			(xy 373.812978 -274.945126) (xy 373.809018 -274.896072) (xy 373.480076 -274.896072) (xy 373.479581 -274.920679)
			(xy 373.471686 -274.969256) (xy 373.456102 -275.015937) (xy 373.433231 -275.059514) (xy 373.403666 -275.098858)
			(xy 373.368173 -275.13295) (xy 373.32767 -275.160906) (xy 373.283208 -275.182004) (xy 373.235937 -275.195696)
			(xy 373.187082 -275.201628) (xy 373.137907 -275.199647) (xy 373.089688 -275.189803) (xy 373.043672 -275.172351)
			(xy 373.001051 -275.147744) (xy 372.96293 -275.116619) (xy 372.930295 -275.079782) (xy 372.903992 -275.038186)
			(xy 372.884701 -274.99291) (xy 372.872924 -274.945126) (xy 372.868964 -274.896072) (xy 372.540022 -274.896072)
			(xy 372.539527 -274.920679) (xy 372.531632 -274.969256) (xy 372.516048 -275.015937) (xy 372.493177 -275.059514)
			(xy 372.463612 -275.098858) (xy 372.428119 -275.13295) (xy 372.387616 -275.160906) (xy 372.343154 -275.182004)
			(xy 372.295883 -275.195696) (xy 372.247028 -275.201628) (xy 372.197853 -275.199647) (xy 372.149634 -275.189803)
			(xy 372.103618 -275.172351) (xy 372.060997 -275.147744) (xy 372.022876 -275.116619) (xy 371.990241 -275.079782)
			(xy 371.963938 -275.038186) (xy 371.944647 -274.99291) (xy 371.93287 -274.945126) (xy 371.92891 -274.896072)
			(xy 371.600222 -274.896072) (xy 371.599727 -274.920679) (xy 371.591832 -274.969256) (xy 371.576248 -275.015937)
			(xy 371.553377 -275.059514) (xy 371.523812 -275.098858) (xy 371.488319 -275.13295) (xy 371.447816 -275.160906)
			(xy 371.403354 -275.182004) (xy 371.356083 -275.195696) (xy 371.307228 -275.201628) (xy 371.258053 -275.199647)
			(xy 371.209834 -275.189803) (xy 371.163818 -275.172351) (xy 371.121197 -275.147744) (xy 371.083076 -275.116619)
			(xy 371.050441 -275.079782) (xy 371.024138 -275.038186) (xy 371.004847 -274.99291) (xy 370.99307 -274.945126)
			(xy 370.98911 -274.896072) (xy 370.660168 -274.896072) (xy 370.659673 -274.920679) (xy 370.651778 -274.969256)
			(xy 370.636194 -275.015937) (xy 370.613323 -275.059514) (xy 370.583758 -275.098858) (xy 370.548265 -275.13295)
			(xy 370.507762 -275.160906) (xy 370.4633 -275.182004) (xy 370.416029 -275.195696) (xy 370.367174 -275.201628)
			(xy 370.317999 -275.199647) (xy 370.26978 -275.189803) (xy 370.223764 -275.172351) (xy 370.181143 -275.147744)
			(xy 370.143022 -275.116619) (xy 370.110387 -275.079782) (xy 370.084084 -275.038186) (xy 370.064793 -274.99291)
			(xy 370.053016 -274.945126) (xy 370.049056 -274.896072) (xy 369.720114 -274.896072) (xy 369.719619 -274.920679)
			(xy 369.711724 -274.969256) (xy 369.69614 -275.015937) (xy 369.673269 -275.059514) (xy 369.643704 -275.098858)
			(xy 369.608211 -275.13295) (xy 369.567708 -275.160906) (xy 369.523246 -275.182004) (xy 369.475975 -275.195696)
			(xy 369.42712 -275.201628) (xy 369.377945 -275.199647) (xy 369.329726 -275.189803) (xy 369.28371 -275.172351)
			(xy 369.241089 -275.147744) (xy 369.202968 -275.116619) (xy 369.170333 -275.079782) (xy 369.14403 -275.038186)
			(xy 369.124739 -274.99291) (xy 369.112962 -274.945126) (xy 369.109002 -274.896072) (xy 368.78006 -274.896072)
			(xy 368.779565 -274.920679) (xy 368.77167 -274.969256) (xy 368.756086 -275.015937) (xy 368.733215 -275.059514)
			(xy 368.70365 -275.098858) (xy 368.668157 -275.13295) (xy 368.627654 -275.160906) (xy 368.583192 -275.182004)
			(xy 368.535921 -275.195696) (xy 368.487066 -275.201628) (xy 368.437891 -275.199647) (xy 368.389672 -275.189803)
			(xy 368.343656 -275.172351) (xy 368.301035 -275.147744) (xy 368.262914 -275.116619) (xy 368.230279 -275.079782)
			(xy 368.203976 -275.038186) (xy 368.184685 -274.99291) (xy 368.172908 -274.945126) (xy 368.168948 -274.896072)
			(xy 367.840006 -274.896072) (xy 367.839511 -274.920679) (xy 367.831616 -274.969256) (xy 367.816032 -275.015937)
			(xy 367.793161 -275.059514) (xy 367.763596 -275.098858) (xy 367.728103 -275.13295) (xy 367.6876 -275.160906)
			(xy 367.643138 -275.182004) (xy 367.595867 -275.195696) (xy 367.547012 -275.201628) (xy 367.497837 -275.199647)
			(xy 367.449618 -275.189803) (xy 367.403602 -275.172351) (xy 367.360981 -275.147744) (xy 367.32286 -275.116619)
			(xy 367.290225 -275.079782) (xy 367.263922 -275.038186) (xy 367.244631 -274.99291) (xy 367.232854 -274.945126)
			(xy 367.228894 -274.896072) (xy 366.900206 -274.896072) (xy 366.899711 -274.920679) (xy 366.891816 -274.969256)
			(xy 366.876232 -275.015937) (xy 366.853361 -275.059514) (xy 366.823796 -275.098858) (xy 366.788303 -275.13295)
			(xy 366.7478 -275.160906) (xy 366.703338 -275.182004) (xy 366.656067 -275.195696) (xy 366.607212 -275.201628)
			(xy 366.558037 -275.199647) (xy 366.509818 -275.189803) (xy 366.463802 -275.172351) (xy 366.421181 -275.147744)
			(xy 366.38306 -275.116619) (xy 366.350425 -275.079782) (xy 366.324122 -275.038186) (xy 366.304831 -274.99291)
			(xy 366.293054 -274.945126) (xy 366.289094 -274.896072) (xy 365.960152 -274.896072) (xy 365.959657 -274.920679)
			(xy 365.951762 -274.969256) (xy 365.936178 -275.015937) (xy 365.913307 -275.059514) (xy 365.883742 -275.098858)
			(xy 365.848249 -275.13295) (xy 365.807746 -275.160906) (xy 365.763284 -275.182004) (xy 365.716013 -275.195696)
			(xy 365.667158 -275.201628) (xy 365.617983 -275.199647) (xy 365.569764 -275.189803) (xy 365.523748 -275.172351)
			(xy 365.481127 -275.147744) (xy 365.443006 -275.116619) (xy 365.410371 -275.079782) (xy 365.384068 -275.038186)
			(xy 365.364777 -274.99291) (xy 365.353 -274.945126) (xy 365.34904 -274.896072) (xy 365.020098 -274.896072)
			(xy 365.019603 -274.920679) (xy 365.011708 -274.969256) (xy 364.996124 -275.015937) (xy 364.973253 -275.059514)
			(xy 364.943688 -275.098858) (xy 364.908195 -275.13295) (xy 364.867692 -275.160906) (xy 364.82323 -275.182004)
			(xy 364.775959 -275.195696) (xy 364.727104 -275.201628) (xy 364.677929 -275.199647) (xy 364.62971 -275.189803)
			(xy 364.583694 -275.172351) (xy 364.541073 -275.147744) (xy 364.502952 -275.116619) (xy 364.470317 -275.079782)
			(xy 364.444014 -275.038186) (xy 364.424723 -274.99291) (xy 364.412946 -274.945126) (xy 364.408986 -274.896072)
			(xy 364.080044 -274.896072) (xy 364.079549 -274.920679) (xy 364.071654 -274.969256) (xy 364.05607 -275.015937)
			(xy 364.033199 -275.059514) (xy 364.003634 -275.098858) (xy 363.968141 -275.13295) (xy 363.927638 -275.160906)
			(xy 363.883176 -275.182004) (xy 363.835905 -275.195696) (xy 363.78705 -275.201628) (xy 363.737875 -275.199647)
			(xy 363.689656 -275.189803) (xy 363.64364 -275.172351) (xy 363.601019 -275.147744) (xy 363.562898 -275.116619)
			(xy 363.530263 -275.079782) (xy 363.50396 -275.038186) (xy 363.484669 -274.99291) (xy 363.472892 -274.945126)
			(xy 363.468932 -274.896072) (xy 356.56647 -274.896072) (xy 356.565975 -274.920679) (xy 356.55808 -274.969256)
			(xy 356.542496 -275.015937) (xy 356.519625 -275.059514) (xy 356.49006 -275.098858) (xy 356.454567 -275.13295)
			(xy 356.414064 -275.160906) (xy 356.369602 -275.182004) (xy 356.322331 -275.195696) (xy 356.273476 -275.201628)
			(xy 356.224301 -275.199647) (xy 356.176082 -275.189803) (xy 356.130066 -275.172351) (xy 356.087445 -275.147744)
			(xy 356.049324 -275.116619) (xy 356.016689 -275.079782) (xy 355.990386 -275.038186) (xy 355.971095 -274.99291)
			(xy 355.959318 -274.945126) (xy 355.955358 -274.896072) (xy 355.626416 -274.896072) (xy 355.625921 -274.920679)
			(xy 355.618026 -274.969256) (xy 355.602442 -275.015937) (xy 355.579571 -275.059514) (xy 355.550006 -275.098858)
			(xy 355.514513 -275.13295) (xy 355.47401 -275.160906) (xy 355.429548 -275.182004) (xy 355.382277 -275.195696)
			(xy 355.333422 -275.201628) (xy 355.284247 -275.199647) (xy 355.236028 -275.189803) (xy 355.190012 -275.172351)
			(xy 355.147391 -275.147744) (xy 355.10927 -275.116619) (xy 355.076635 -275.079782) (xy 355.050332 -275.038186)
			(xy 355.031041 -274.99291) (xy 355.019264 -274.945126) (xy 355.015304 -274.896072) (xy 354.686362 -274.896072)
			(xy 354.685867 -274.920679) (xy 354.677972 -274.969256) (xy 354.662388 -275.015937) (xy 354.639517 -275.059514)
			(xy 354.609952 -275.098858) (xy 354.574459 -275.13295) (xy 354.533956 -275.160906) (xy 354.489494 -275.182004)
			(xy 354.442223 -275.195696) (xy 354.393368 -275.201628) (xy 354.344193 -275.199647) (xy 354.295974 -275.189803)
			(xy 354.249958 -275.172351) (xy 354.207337 -275.147744) (xy 354.169216 -275.116619) (xy 354.136581 -275.079782)
			(xy 354.110278 -275.038186) (xy 354.090987 -274.99291) (xy 354.07921 -274.945126) (xy 354.07525 -274.896072)
			(xy 353.746308 -274.896072) (xy 353.745813 -274.920679) (xy 353.737918 -274.969256) (xy 353.722334 -275.015937)
			(xy 353.699463 -275.059514) (xy 353.669898 -275.098858) (xy 353.634405 -275.13295) (xy 353.593902 -275.160906)
			(xy 353.54944 -275.182004) (xy 353.502169 -275.195696) (xy 353.453314 -275.201628) (xy 353.404139 -275.199647)
			(xy 353.35592 -275.189803) (xy 353.309904 -275.172351) (xy 353.267283 -275.147744) (xy 353.229162 -275.116619)
			(xy 353.196527 -275.079782) (xy 353.170224 -275.038186) (xy 353.150933 -274.99291) (xy 353.139156 -274.945126)
			(xy 353.135196 -274.896072) (xy 352.806508 -274.896072) (xy 352.806013 -274.920679) (xy 352.798118 -274.969256)
			(xy 352.782534 -275.015937) (xy 352.759663 -275.059514) (xy 352.730098 -275.098858) (xy 352.694605 -275.13295)
			(xy 352.654102 -275.160906) (xy 352.60964 -275.182004) (xy 352.562369 -275.195696) (xy 352.513514 -275.201628)
			(xy 352.464339 -275.199647) (xy 352.41612 -275.189803) (xy 352.370104 -275.172351) (xy 352.327483 -275.147744)
			(xy 352.289362 -275.116619) (xy 352.256727 -275.079782) (xy 352.230424 -275.038186) (xy 352.211133 -274.99291)
			(xy 352.199356 -274.945126) (xy 352.195396 -274.896072) (xy 351.866454 -274.896072) (xy 351.865959 -274.920679)
			(xy 351.858064 -274.969256) (xy 351.84248 -275.015937) (xy 351.819609 -275.059514) (xy 351.790044 -275.098858)
			(xy 351.754551 -275.13295) (xy 351.714048 -275.160906) (xy 351.669586 -275.182004) (xy 351.622315 -275.195696)
			(xy 351.57346 -275.201628) (xy 351.524285 -275.199647) (xy 351.476066 -275.189803) (xy 351.43005 -275.172351)
			(xy 351.387429 -275.147744) (xy 351.349308 -275.116619) (xy 351.316673 -275.079782) (xy 351.29037 -275.038186)
			(xy 351.271079 -274.99291) (xy 351.259302 -274.945126) (xy 351.255342 -274.896072) (xy 350.9264 -274.896072)
			(xy 350.925905 -274.920679) (xy 350.91801 -274.969256) (xy 350.902426 -275.015937) (xy 350.879555 -275.059514)
			(xy 350.84999 -275.098858) (xy 350.814497 -275.13295) (xy 350.773994 -275.160906) (xy 350.729532 -275.182004)
			(xy 350.682261 -275.195696) (xy 350.633406 -275.201628) (xy 350.584231 -275.199647) (xy 350.536012 -275.189803)
			(xy 350.489996 -275.172351) (xy 350.447375 -275.147744) (xy 350.409254 -275.116619) (xy 350.376619 -275.079782)
			(xy 350.350316 -275.038186) (xy 350.331025 -274.99291) (xy 350.319248 -274.945126) (xy 350.315288 -274.896072)
			(xy 349.986346 -274.896072) (xy 349.985851 -274.920679) (xy 349.977956 -274.969256) (xy 349.962372 -275.015937)
			(xy 349.939501 -275.059514) (xy 349.909936 -275.098858) (xy 349.874443 -275.13295) (xy 349.83394 -275.160906)
			(xy 349.789478 -275.182004) (xy 349.742207 -275.195696) (xy 349.693352 -275.201628) (xy 349.644177 -275.199647)
			(xy 349.595958 -275.189803) (xy 349.549942 -275.172351) (xy 349.507321 -275.147744) (xy 349.4692 -275.116619)
			(xy 349.436565 -275.079782) (xy 349.410262 -275.038186) (xy 349.390971 -274.99291) (xy 349.379194 -274.945126)
			(xy 349.375234 -274.896072) (xy 349.046546 -274.896072) (xy 349.046051 -274.920679) (xy 349.038156 -274.969256)
			(xy 349.022572 -275.015937) (xy 348.999701 -275.059514) (xy 348.970136 -275.098858) (xy 348.934643 -275.13295)
			(xy 348.89414 -275.160906) (xy 348.849678 -275.182004) (xy 348.802407 -275.195696) (xy 348.753552 -275.201628)
			(xy 348.704377 -275.199647) (xy 348.656158 -275.189803) (xy 348.610142 -275.172351) (xy 348.567521 -275.147744)
			(xy 348.5294 -275.116619) (xy 348.496765 -275.079782) (xy 348.470462 -275.038186) (xy 348.451171 -274.99291)
			(xy 348.439394 -274.945126) (xy 348.435434 -274.896072) (xy 348.106492 -274.896072) (xy 348.105997 -274.920679)
			(xy 348.098102 -274.969256) (xy 348.082518 -275.015937) (xy 348.059647 -275.059514) (xy 348.030082 -275.098858)
			(xy 347.994589 -275.13295) (xy 347.954086 -275.160906) (xy 347.909624 -275.182004) (xy 347.862353 -275.195696)
			(xy 347.813498 -275.201628) (xy 347.764323 -275.199647) (xy 347.716104 -275.189803) (xy 347.670088 -275.172351)
			(xy 347.627467 -275.147744) (xy 347.589346 -275.116619) (xy 347.556711 -275.079782) (xy 347.530408 -275.038186)
			(xy 347.511117 -274.99291) (xy 347.49934 -274.945126) (xy 347.49538 -274.896072) (xy 347.166438 -274.896072)
			(xy 347.165943 -274.920679) (xy 347.158048 -274.969256) (xy 347.142464 -275.015937) (xy 347.119593 -275.059514)
			(xy 347.090028 -275.098858) (xy 347.054535 -275.13295) (xy 347.014032 -275.160906) (xy 346.96957 -275.182004)
			(xy 346.922299 -275.195696) (xy 346.873444 -275.201628) (xy 346.824269 -275.199647) (xy 346.77605 -275.189803)
			(xy 346.730034 -275.172351) (xy 346.687413 -275.147744) (xy 346.649292 -275.116619) (xy 346.616657 -275.079782)
			(xy 346.590354 -275.038186) (xy 346.571063 -274.99291) (xy 346.559286 -274.945126) (xy 346.555326 -274.896072)
			(xy 346.226384 -274.896072) (xy 346.225889 -274.920679) (xy 346.217994 -274.969256) (xy 346.20241 -275.015937)
			(xy 346.179539 -275.059514) (xy 346.149974 -275.098858) (xy 346.114481 -275.13295) (xy 346.073978 -275.160906)
			(xy 346.029516 -275.182004) (xy 345.982245 -275.195696) (xy 345.93339 -275.201628) (xy 345.884215 -275.199647)
			(xy 345.835996 -275.189803) (xy 345.78998 -275.172351) (xy 345.747359 -275.147744) (xy 345.709238 -275.116619)
			(xy 345.676603 -275.079782) (xy 345.6503 -275.038186) (xy 345.631009 -274.99291) (xy 345.619232 -274.945126)
			(xy 345.615272 -274.896072) (xy 345.28633 -274.896072) (xy 345.285835 -274.920679) (xy 345.27794 -274.969256)
			(xy 345.262356 -275.015937) (xy 345.239485 -275.059514) (xy 345.20992 -275.098858) (xy 345.174427 -275.13295)
			(xy 345.133924 -275.160906) (xy 345.089462 -275.182004) (xy 345.042191 -275.195696) (xy 344.993336 -275.201628)
			(xy 344.944161 -275.199647) (xy 344.895942 -275.189803) (xy 344.849926 -275.172351) (xy 344.807305 -275.147744)
			(xy 344.769184 -275.116619) (xy 344.736549 -275.079782) (xy 344.710246 -275.038186) (xy 344.690955 -274.99291)
			(xy 344.679178 -274.945126) (xy 344.675218 -274.896072) (xy 344.356944 -274.896072) (xy 344.356432 -274.921518)
			(xy 344.348268 -274.971752) (xy 344.332152 -275.020026) (xy 344.308501 -275.065089) (xy 344.277928 -275.105775)
			(xy 344.241224 -275.14103) (xy 344.19934 -275.16994) (xy 344.153361 -275.191757) (xy 344.104477 -275.205917)
			(xy 344.053956 -275.212051) (xy 344.003104 -275.210002) (xy 343.95324 -275.199822) (xy 343.905654 -275.181775)
			(xy 343.86158 -275.156329) (xy 343.822158 -275.124142) (xy 343.78841 -275.086048) (xy 343.761209 -275.043034)
			(xy 343.741261 -274.996214) (xy 343.729082 -274.9468) (xy 343.724987 -274.896072) (xy 343.406476 -274.896072)
			(xy 343.405981 -274.920679) (xy 343.398086 -274.969256) (xy 343.382502 -275.015937) (xy 343.359631 -275.059514)
			(xy 343.330066 -275.098858) (xy 343.294573 -275.13295) (xy 343.25407 -275.160906) (xy 343.209608 -275.182004)
			(xy 343.162337 -275.195696) (xy 343.113482 -275.201628) (xy 343.064307 -275.199647) (xy 343.016088 -275.189803)
			(xy 342.970072 -275.172351) (xy 342.927451 -275.147744) (xy 342.88933 -275.116619) (xy 342.856695 -275.079782)
			(xy 342.830392 -275.038186) (xy 342.811101 -274.99291) (xy 342.799324 -274.945126) (xy 342.795364 -274.896072)
			(xy 342.476931 -274.896072) (xy 342.476582 -274.90166) (xy 342.475588 -274.928561) (xy 342.465569 -274.981449)
			(xy 342.44672 -275.03187) (xy 342.419588 -275.07836) (xy 342.38496 -275.119571) (xy 342.34384 -275.154308)
			(xy 342.32088 -275.16836) (xy 342.31271 -275.173666) (xy 342.300827 -275.189083) (xy 342.297766 -275.198332)
			(xy 342.284366 -275.244202) (xy 342.250771 -275.333672) (xy 342.209657 -275.419945) (xy 342.161326 -275.502392)
			(xy 342.10613 -275.58041) (xy 342.044472 -275.653429) (xy 342.011 -275.687536) (xy 342.004692 -275.694505)
			(xy 341.999616 -275.706078) (xy 342.314779 -275.706078) (xy 342.318874 -275.65535) (xy 342.331053 -275.605936)
			(xy 342.351001 -275.559116) (xy 342.378202 -275.516102) (xy 342.41195 -275.478008) (xy 342.451372 -275.445821)
			(xy 342.495446 -275.420375) (xy 342.543032 -275.402328) (xy 342.592896 -275.392148) (xy 342.643748 -275.390099)
			(xy 342.694269 -275.396233) (xy 342.743153 -275.410393) (xy 342.789132 -275.43221) (xy 342.831016 -275.46112)
			(xy 342.86772 -275.496375) (xy 342.898293 -275.537061) (xy 342.921944 -275.582124) (xy 342.93806 -275.630398)
			(xy 342.946224 -275.680632) (xy 342.946736 -275.706078) (xy 343.254833 -275.706078) (xy 343.258928 -275.65535)
			(xy 343.271107 -275.605936) (xy 343.291055 -275.559116) (xy 343.318256 -275.516102) (xy 343.352004 -275.478008)
			(xy 343.391426 -275.445821) (xy 343.4355 -275.420375) (xy 343.483086 -275.402328) (xy 343.53295 -275.392148)
			(xy 343.583802 -275.390099) (xy 343.634323 -275.396233) (xy 343.683207 -275.410393) (xy 343.729186 -275.43221)
			(xy 343.77107 -275.46112) (xy 343.807774 -275.496375) (xy 343.838347 -275.537061) (xy 343.861998 -275.582124)
			(xy 343.878114 -275.630398) (xy 343.886278 -275.680632) (xy 343.88679 -275.706078) (xy 344.205318 -275.706078)
			(xy 344.209278 -275.657024) (xy 344.221055 -275.60924) (xy 344.240346 -275.563964) (xy 344.266649 -275.522368)
			(xy 344.299284 -275.485531) (xy 344.337405 -275.454406) (xy 344.380026 -275.429799) (xy 344.426042 -275.412347)
			(xy 344.474261 -275.402503) (xy 344.523436 -275.400522) (xy 344.572291 -275.406454) (xy 344.619562 -275.420146)
			(xy 344.664024 -275.441244) (xy 344.704527 -275.4692) (xy 344.74002 -275.503292) (xy 344.769585 -275.542636)
			(xy 344.792456 -275.586213) (xy 344.80804 -275.632894) (xy 344.815935 -275.681471) (xy 344.81643 -275.706078)
			(xy 347.025226 -275.706078) (xy 347.029186 -275.657024) (xy 347.040963 -275.60924) (xy 347.060254 -275.563964)
			(xy 347.086557 -275.522368) (xy 347.119192 -275.485531) (xy 347.157313 -275.454406) (xy 347.199934 -275.429799)
			(xy 347.24595 -275.412347) (xy 347.294169 -275.402503) (xy 347.343344 -275.400522) (xy 347.392199 -275.406454)
			(xy 347.43947 -275.420146) (xy 347.483932 -275.441244) (xy 347.524435 -275.4692) (xy 347.559928 -275.503292)
			(xy 347.589493 -275.542636) (xy 347.612364 -275.586213) (xy 347.627948 -275.632894) (xy 347.635843 -275.681471)
			(xy 347.636338 -275.706078) (xy 349.845388 -275.706078) (xy 349.849348 -275.657024) (xy 349.861125 -275.60924)
			(xy 349.880416 -275.563964) (xy 349.906719 -275.522368) (xy 349.939354 -275.485531) (xy 349.977475 -275.454406)
			(xy 350.020096 -275.429799) (xy 350.066112 -275.412347) (xy 350.114331 -275.402503) (xy 350.163506 -275.400522)
			(xy 350.212361 -275.406454) (xy 350.259632 -275.420146) (xy 350.304094 -275.441244) (xy 350.344597 -275.4692)
			(xy 350.38009 -275.503292) (xy 350.409655 -275.542636) (xy 350.432526 -275.586213) (xy 350.44811 -275.632894)
			(xy 350.456005 -275.681471) (xy 350.4565 -275.706078) (xy 352.665296 -275.706078) (xy 352.669256 -275.657024)
			(xy 352.681033 -275.60924) (xy 352.700324 -275.563964) (xy 352.726627 -275.522368) (xy 352.759262 -275.485531)
			(xy 352.797383 -275.454406) (xy 352.840004 -275.429799) (xy 352.88602 -275.412347) (xy 352.934239 -275.402503)
			(xy 352.983414 -275.400522) (xy 353.032269 -275.406454) (xy 353.07954 -275.420146) (xy 353.124002 -275.441244)
			(xy 353.164505 -275.4692) (xy 353.199998 -275.503292) (xy 353.229563 -275.542636) (xy 353.252434 -275.586213)
			(xy 353.268018 -275.632894) (xy 353.275913 -275.681471) (xy 353.276408 -275.706078) (xy 355.485204 -275.706078)
			(xy 355.489164 -275.657024) (xy 355.500941 -275.60924) (xy 355.520232 -275.563964) (xy 355.546535 -275.522368)
			(xy 355.57917 -275.485531) (xy 355.617291 -275.454406) (xy 355.659912 -275.429799) (xy 355.705928 -275.412347)
			(xy 355.754147 -275.402503) (xy 355.803322 -275.400522) (xy 355.852177 -275.406454) (xy 355.899448 -275.420146)
			(xy 355.94391 -275.441244) (xy 355.984413 -275.4692) (xy 356.019906 -275.503292) (xy 356.049471 -275.542636)
			(xy 356.072342 -275.586213) (xy 356.087926 -275.632894) (xy 356.095821 -275.681471) (xy 356.096316 -275.706078)
			(xy 356.425258 -275.706078) (xy 356.429218 -275.657024) (xy 356.440995 -275.60924) (xy 356.460286 -275.563964)
			(xy 356.486589 -275.522368) (xy 356.519224 -275.485531) (xy 356.557345 -275.454406) (xy 356.599966 -275.429799)
			(xy 356.645982 -275.412347) (xy 356.694201 -275.402503) (xy 356.743376 -275.400522) (xy 356.792231 -275.406454)
			(xy 356.839502 -275.420146) (xy 356.883964 -275.441244) (xy 356.924467 -275.4692) (xy 356.95996 -275.503292)
			(xy 356.989525 -275.542636) (xy 357.012396 -275.586213) (xy 357.02798 -275.632894) (xy 357.035875 -275.681471)
			(xy 357.03637 -275.706078) (xy 357.365312 -275.706078) (xy 357.369272 -275.657024) (xy 357.381049 -275.60924)
			(xy 357.40034 -275.563964) (xy 357.426643 -275.522368) (xy 357.459278 -275.485531) (xy 357.497399 -275.454406)
			(xy 357.54002 -275.429799) (xy 357.586036 -275.412347) (xy 357.634255 -275.402503) (xy 357.68343 -275.400522)
			(xy 357.732285 -275.406454) (xy 357.779556 -275.420146) (xy 357.824018 -275.441244) (xy 357.864521 -275.4692)
			(xy 357.900014 -275.503292) (xy 357.929579 -275.542636) (xy 357.95245 -275.586213) (xy 357.968034 -275.632894)
			(xy 357.975929 -275.681471) (xy 357.976424 -275.706078) (xy 358.305366 -275.706078) (xy 358.309326 -275.657024)
			(xy 358.321103 -275.60924) (xy 358.340394 -275.563964) (xy 358.366697 -275.522368) (xy 358.399332 -275.485531)
			(xy 358.437453 -275.454406) (xy 358.480074 -275.429799) (xy 358.52609 -275.412347) (xy 358.574309 -275.402503)
			(xy 358.623484 -275.400522) (xy 358.672339 -275.406454) (xy 358.71961 -275.420146) (xy 358.764072 -275.441244)
			(xy 358.804575 -275.4692) (xy 358.840068 -275.503292) (xy 358.869633 -275.542636) (xy 358.892504 -275.586213)
			(xy 358.908088 -275.632894) (xy 358.915983 -275.681471) (xy 358.916478 -275.706078) (xy 361.118924 -275.706078)
			(xy 361.122884 -275.657024) (xy 361.134661 -275.60924) (xy 361.153952 -275.563964) (xy 361.180255 -275.522368)
			(xy 361.21289 -275.485531) (xy 361.251011 -275.454406) (xy 361.293632 -275.429799) (xy 361.339648 -275.412347)
			(xy 361.387867 -275.402503) (xy 361.437042 -275.400522) (xy 361.485897 -275.406454) (xy 361.533168 -275.420146)
			(xy 361.57763 -275.441244) (xy 361.618133 -275.4692) (xy 361.653626 -275.503292) (xy 361.683191 -275.542636)
			(xy 361.706062 -275.586213) (xy 361.721646 -275.632894) (xy 361.729541 -275.681471) (xy 361.730036 -275.706078)
			(xy 362.058978 -275.706078) (xy 362.062938 -275.657024) (xy 362.074715 -275.60924) (xy 362.094006 -275.563964)
			(xy 362.120309 -275.522368) (xy 362.152944 -275.485531) (xy 362.191065 -275.454406) (xy 362.233686 -275.429799)
			(xy 362.279702 -275.412347) (xy 362.327921 -275.402503) (xy 362.377096 -275.400522) (xy 362.425951 -275.406454)
			(xy 362.473222 -275.420146) (xy 362.517684 -275.441244) (xy 362.558187 -275.4692) (xy 362.59368 -275.503292)
			(xy 362.623245 -275.542636) (xy 362.646116 -275.586213) (xy 362.6617 -275.632894) (xy 362.669595 -275.681471)
			(xy 362.67009 -275.706078) (xy 362.999032 -275.706078) (xy 363.002992 -275.657024) (xy 363.014769 -275.60924)
			(xy 363.03406 -275.563964) (xy 363.060363 -275.522368) (xy 363.092998 -275.485531) (xy 363.131119 -275.454406)
			(xy 363.17374 -275.429799) (xy 363.219756 -275.412347) (xy 363.267975 -275.402503) (xy 363.31715 -275.400522)
			(xy 363.366005 -275.406454) (xy 363.413276 -275.420146) (xy 363.457738 -275.441244) (xy 363.498241 -275.4692)
			(xy 363.533734 -275.503292) (xy 363.563299 -275.542636) (xy 363.58617 -275.586213) (xy 363.601754 -275.632894)
			(xy 363.609649 -275.681471) (xy 363.610144 -275.706078) (xy 363.939086 -275.706078) (xy 363.943046 -275.657024)
			(xy 363.954823 -275.60924) (xy 363.974114 -275.563964) (xy 364.000417 -275.522368) (xy 364.033052 -275.485531)
			(xy 364.071173 -275.454406) (xy 364.113794 -275.429799) (xy 364.15981 -275.412347) (xy 364.208029 -275.402503)
			(xy 364.257204 -275.400522) (xy 364.306059 -275.406454) (xy 364.35333 -275.420146) (xy 364.397792 -275.441244)
			(xy 364.438295 -275.4692) (xy 364.473788 -275.503292) (xy 364.503353 -275.542636) (xy 364.526224 -275.586213)
			(xy 364.541808 -275.632894) (xy 364.549703 -275.681471) (xy 364.550198 -275.706078) (xy 366.758994 -275.706078)
			(xy 366.762954 -275.657024) (xy 366.774731 -275.60924) (xy 366.794022 -275.563964) (xy 366.820325 -275.522368)
			(xy 366.85296 -275.485531) (xy 366.891081 -275.454406) (xy 366.933702 -275.429799) (xy 366.979718 -275.412347)
			(xy 367.027937 -275.402503) (xy 367.077112 -275.400522) (xy 367.125967 -275.406454) (xy 367.173238 -275.420146)
			(xy 367.2177 -275.441244) (xy 367.258203 -275.4692) (xy 367.293696 -275.503292) (xy 367.323261 -275.542636)
			(xy 367.346132 -275.586213) (xy 367.361716 -275.632894) (xy 367.369611 -275.681471) (xy 367.370106 -275.706078)
			(xy 369.578902 -275.706078) (xy 369.582862 -275.657024) (xy 369.594639 -275.60924) (xy 369.61393 -275.563964)
			(xy 369.640233 -275.522368) (xy 369.672868 -275.485531) (xy 369.710989 -275.454406) (xy 369.75361 -275.429799)
			(xy 369.799626 -275.412347) (xy 369.847845 -275.402503) (xy 369.89702 -275.400522) (xy 369.945875 -275.406454)
			(xy 369.993146 -275.420146) (xy 370.037608 -275.441244) (xy 370.078111 -275.4692) (xy 370.113604 -275.503292)
			(xy 370.143169 -275.542636) (xy 370.16604 -275.586213) (xy 370.181624 -275.632894) (xy 370.189519 -275.681471)
			(xy 370.190014 -275.706078) (xy 372.399064 -275.706078) (xy 372.403024 -275.657024) (xy 372.414801 -275.60924)
			(xy 372.434092 -275.563964) (xy 372.460395 -275.522368) (xy 372.49303 -275.485531) (xy 372.531151 -275.454406)
			(xy 372.573772 -275.429799) (xy 372.619788 -275.412347) (xy 372.668007 -275.402503) (xy 372.717182 -275.400522)
			(xy 372.766037 -275.406454) (xy 372.813308 -275.420146) (xy 372.85777 -275.441244) (xy 372.898273 -275.4692)
			(xy 372.933766 -275.503292) (xy 372.963331 -275.542636) (xy 372.986202 -275.586213) (xy 373.001786 -275.632894)
			(xy 373.009681 -275.681471) (xy 373.010176 -275.706078) (xy 373.009681 -275.730685) (xy 373.001786 -275.779262)
			(xy 372.986202 -275.825943) (xy 372.963331 -275.86952) (xy 372.933766 -275.908864) (xy 372.898273 -275.942956)
			(xy 372.85777 -275.970912) (xy 372.813308 -275.99201) (xy 372.766037 -276.005702) (xy 372.717182 -276.011634)
			(xy 372.668007 -276.009653) (xy 372.619788 -275.999809) (xy 372.573772 -275.982357) (xy 372.531151 -275.95775)
			(xy 372.49303 -275.926625) (xy 372.460395 -275.889788) (xy 372.434092 -275.848192) (xy 372.414801 -275.802916)
			(xy 372.403024 -275.755132) (xy 372.399064 -275.706078) (xy 370.190014 -275.706078) (xy 370.189519 -275.730685)
			(xy 370.181624 -275.779262) (xy 370.16604 -275.825943) (xy 370.143169 -275.86952) (xy 370.113604 -275.908864)
			(xy 370.078111 -275.942956) (xy 370.037608 -275.970912) (xy 369.993146 -275.99201) (xy 369.945875 -276.005702)
			(xy 369.89702 -276.011634) (xy 369.847845 -276.009653) (xy 369.799626 -275.999809) (xy 369.75361 -275.982357)
			(xy 369.710989 -275.95775) (xy 369.672868 -275.926625) (xy 369.640233 -275.889788) (xy 369.61393 -275.848192)
			(xy 369.594639 -275.802916) (xy 369.582862 -275.755132) (xy 369.578902 -275.706078) (xy 367.370106 -275.706078)
			(xy 367.369611 -275.730685) (xy 367.361716 -275.779262) (xy 367.346132 -275.825943) (xy 367.323261 -275.86952)
			(xy 367.293696 -275.908864) (xy 367.258203 -275.942956) (xy 367.2177 -275.970912) (xy 367.173238 -275.99201)
			(xy 367.125967 -276.005702) (xy 367.077112 -276.011634) (xy 367.027937 -276.009653) (xy 366.979718 -275.999809)
			(xy 366.933702 -275.982357) (xy 366.891081 -275.95775) (xy 366.85296 -275.926625) (xy 366.820325 -275.889788)
			(xy 366.794022 -275.848192) (xy 366.774731 -275.802916) (xy 366.762954 -275.755132) (xy 366.758994 -275.706078)
			(xy 364.550198 -275.706078) (xy 364.549703 -275.730685) (xy 364.541808 -275.779262) (xy 364.526224 -275.825943)
			(xy 364.503353 -275.86952) (xy 364.473788 -275.908864) (xy 364.438295 -275.942956) (xy 364.397792 -275.970912)
			(xy 364.35333 -275.99201) (xy 364.306059 -276.005702) (xy 364.257204 -276.011634) (xy 364.208029 -276.009653)
			(xy 364.15981 -275.999809) (xy 364.113794 -275.982357) (xy 364.071173 -275.95775) (xy 364.033052 -275.926625)
			(xy 364.000417 -275.889788) (xy 363.974114 -275.848192) (xy 363.954823 -275.802916) (xy 363.943046 -275.755132)
			(xy 363.939086 -275.706078) (xy 363.610144 -275.706078) (xy 363.609649 -275.730685) (xy 363.601754 -275.779262)
			(xy 363.58617 -275.825943) (xy 363.563299 -275.86952) (xy 363.533734 -275.908864) (xy 363.498241 -275.942956)
			(xy 363.457738 -275.970912) (xy 363.413276 -275.99201) (xy 363.366005 -276.005702) (xy 363.31715 -276.011634)
			(xy 363.267975 -276.009653) (xy 363.219756 -275.999809) (xy 363.17374 -275.982357) (xy 363.131119 -275.95775)
			(xy 363.092998 -275.926625) (xy 363.060363 -275.889788) (xy 363.03406 -275.848192) (xy 363.014769 -275.802916)
			(xy 363.002992 -275.755132) (xy 362.999032 -275.706078) (xy 362.67009 -275.706078) (xy 362.669595 -275.730685)
			(xy 362.6617 -275.779262) (xy 362.646116 -275.825943) (xy 362.623245 -275.86952) (xy 362.59368 -275.908864)
			(xy 362.558187 -275.942956) (xy 362.517684 -275.970912) (xy 362.473222 -275.99201) (xy 362.425951 -276.005702)
			(xy 362.377096 -276.011634) (xy 362.327921 -276.009653) (xy 362.279702 -275.999809) (xy 362.233686 -275.982357)
			(xy 362.191065 -275.95775) (xy 362.152944 -275.926625) (xy 362.120309 -275.889788) (xy 362.094006 -275.848192)
			(xy 362.074715 -275.802916) (xy 362.062938 -275.755132) (xy 362.058978 -275.706078) (xy 361.730036 -275.706078)
			(xy 361.729541 -275.730685) (xy 361.721646 -275.779262) (xy 361.706062 -275.825943) (xy 361.683191 -275.86952)
			(xy 361.653626 -275.908864) (xy 361.618133 -275.942956) (xy 361.57763 -275.970912) (xy 361.533168 -275.99201)
			(xy 361.485897 -276.005702) (xy 361.437042 -276.011634) (xy 361.387867 -276.009653) (xy 361.339648 -275.999809)
			(xy 361.293632 -275.982357) (xy 361.251011 -275.95775) (xy 361.21289 -275.926625) (xy 361.180255 -275.889788)
			(xy 361.153952 -275.848192) (xy 361.134661 -275.802916) (xy 361.122884 -275.755132) (xy 361.118924 -275.706078)
			(xy 358.916478 -275.706078) (xy 358.915983 -275.730685) (xy 358.908088 -275.779262) (xy 358.892504 -275.825943)
			(xy 358.869633 -275.86952) (xy 358.840068 -275.908864) (xy 358.804575 -275.942956) (xy 358.764072 -275.970912)
			(xy 358.71961 -275.99201) (xy 358.672339 -276.005702) (xy 358.623484 -276.011634) (xy 358.574309 -276.009653)
			(xy 358.52609 -275.999809) (xy 358.480074 -275.982357) (xy 358.437453 -275.95775) (xy 358.399332 -275.926625)
			(xy 358.366697 -275.889788) (xy 358.340394 -275.848192) (xy 358.321103 -275.802916) (xy 358.309326 -275.755132)
			(xy 358.305366 -275.706078) (xy 357.976424 -275.706078) (xy 357.975929 -275.730685) (xy 357.968034 -275.779262)
			(xy 357.95245 -275.825943) (xy 357.929579 -275.86952) (xy 357.900014 -275.908864) (xy 357.864521 -275.942956)
			(xy 357.824018 -275.970912) (xy 357.779556 -275.99201) (xy 357.732285 -276.005702) (xy 357.68343 -276.011634)
			(xy 357.634255 -276.009653) (xy 357.586036 -275.999809) (xy 357.54002 -275.982357) (xy 357.497399 -275.95775)
			(xy 357.459278 -275.926625) (xy 357.426643 -275.889788) (xy 357.40034 -275.848192) (xy 357.381049 -275.802916)
			(xy 357.369272 -275.755132) (xy 357.365312 -275.706078) (xy 357.03637 -275.706078) (xy 357.035875 -275.730685)
			(xy 357.02798 -275.779262) (xy 357.012396 -275.825943) (xy 356.989525 -275.86952) (xy 356.95996 -275.908864)
			(xy 356.924467 -275.942956) (xy 356.883964 -275.970912) (xy 356.839502 -275.99201) (xy 356.792231 -276.005702)
			(xy 356.743376 -276.011634) (xy 356.694201 -276.009653) (xy 356.645982 -275.999809) (xy 356.599966 -275.982357)
			(xy 356.557345 -275.95775) (xy 356.519224 -275.926625) (xy 356.486589 -275.889788) (xy 356.460286 -275.848192)
			(xy 356.440995 -275.802916) (xy 356.429218 -275.755132) (xy 356.425258 -275.706078) (xy 356.096316 -275.706078)
			(xy 356.095821 -275.730685) (xy 356.087926 -275.779262) (xy 356.072342 -275.825943) (xy 356.049471 -275.86952)
			(xy 356.019906 -275.908864) (xy 355.984413 -275.942956) (xy 355.94391 -275.970912) (xy 355.899448 -275.99201)
			(xy 355.852177 -276.005702) (xy 355.803322 -276.011634) (xy 355.754147 -276.009653) (xy 355.705928 -275.999809)
			(xy 355.659912 -275.982357) (xy 355.617291 -275.95775) (xy 355.57917 -275.926625) (xy 355.546535 -275.889788)
			(xy 355.520232 -275.848192) (xy 355.500941 -275.802916) (xy 355.489164 -275.755132) (xy 355.485204 -275.706078)
			(xy 353.276408 -275.706078) (xy 353.275913 -275.730685) (xy 353.268018 -275.779262) (xy 353.252434 -275.825943)
			(xy 353.229563 -275.86952) (xy 353.199998 -275.908864) (xy 353.164505 -275.942956) (xy 353.124002 -275.970912)
			(xy 353.07954 -275.99201) (xy 353.032269 -276.005702) (xy 352.983414 -276.011634) (xy 352.934239 -276.009653)
			(xy 352.88602 -275.999809) (xy 352.840004 -275.982357) (xy 352.797383 -275.95775) (xy 352.759262 -275.926625)
			(xy 352.726627 -275.889788) (xy 352.700324 -275.848192) (xy 352.681033 -275.802916) (xy 352.669256 -275.755132)
			(xy 352.665296 -275.706078) (xy 350.4565 -275.706078) (xy 350.456005 -275.730685) (xy 350.44811 -275.779262)
			(xy 350.432526 -275.825943) (xy 350.409655 -275.86952) (xy 350.38009 -275.908864) (xy 350.344597 -275.942956)
			(xy 350.304094 -275.970912) (xy 350.259632 -275.99201) (xy 350.212361 -276.005702) (xy 350.163506 -276.011634)
			(xy 350.114331 -276.009653) (xy 350.066112 -275.999809) (xy 350.020096 -275.982357) (xy 349.977475 -275.95775)
			(xy 349.939354 -275.926625) (xy 349.906719 -275.889788) (xy 349.880416 -275.848192) (xy 349.861125 -275.802916)
			(xy 349.849348 -275.755132) (xy 349.845388 -275.706078) (xy 347.636338 -275.706078) (xy 347.635843 -275.730685)
			(xy 347.627948 -275.779262) (xy 347.612364 -275.825943) (xy 347.589493 -275.86952) (xy 347.559928 -275.908864)
			(xy 347.524435 -275.942956) (xy 347.483932 -275.970912) (xy 347.43947 -275.99201) (xy 347.392199 -276.005702)
			(xy 347.343344 -276.011634) (xy 347.294169 -276.009653) (xy 347.24595 -275.999809) (xy 347.199934 -275.982357)
			(xy 347.157313 -275.95775) (xy 347.119192 -275.926625) (xy 347.086557 -275.889788) (xy 347.060254 -275.848192)
			(xy 347.040963 -275.802916) (xy 347.029186 -275.755132) (xy 347.025226 -275.706078) (xy 344.81643 -275.706078)
			(xy 344.815935 -275.730685) (xy 344.80804 -275.779262) (xy 344.792456 -275.825943) (xy 344.769585 -275.86952)
			(xy 344.74002 -275.908864) (xy 344.704527 -275.942956) (xy 344.664024 -275.970912) (xy 344.619562 -275.99201)
			(xy 344.572291 -276.005702) (xy 344.523436 -276.011634) (xy 344.474261 -276.009653) (xy 344.426042 -275.999809)
			(xy 344.380026 -275.982357) (xy 344.337405 -275.95775) (xy 344.299284 -275.926625) (xy 344.266649 -275.889788)
			(xy 344.240346 -275.848192) (xy 344.221055 -275.802916) (xy 344.209278 -275.755132) (xy 344.205318 -275.706078)
			(xy 343.88679 -275.706078) (xy 343.886278 -275.731524) (xy 343.878114 -275.781758) (xy 343.861998 -275.830032)
			(xy 343.838347 -275.875095) (xy 343.807774 -275.915781) (xy 343.77107 -275.951036) (xy 343.729186 -275.979946)
			(xy 343.683207 -276.001763) (xy 343.634323 -276.015923) (xy 343.583802 -276.022057) (xy 343.53295 -276.020008)
			(xy 343.483086 -276.009828) (xy 343.4355 -275.991781) (xy 343.391426 -275.966335) (xy 343.352004 -275.934148)
			(xy 343.318256 -275.896054) (xy 343.291055 -275.85304) (xy 343.271107 -275.80622) (xy 343.258928 -275.756806)
			(xy 343.254833 -275.706078) (xy 342.946736 -275.706078) (xy 342.946224 -275.731524) (xy 342.93806 -275.781758)
			(xy 342.921944 -275.830032) (xy 342.898293 -275.875095) (xy 342.86772 -275.915781) (xy 342.831016 -275.951036)
			(xy 342.789132 -275.979946) (xy 342.743153 -276.001763) (xy 342.694269 -276.015923) (xy 342.643748 -276.022057)
			(xy 342.592896 -276.020008) (xy 342.543032 -276.009828) (xy 342.495446 -275.991781) (xy 342.451372 -275.966335)
			(xy 342.41195 -275.934148) (xy 342.378202 -275.896054) (xy 342.351001 -275.85304) (xy 342.331053 -275.80622)
			(xy 342.318874 -275.756806) (xy 342.314779 -275.706078) (xy 341.999616 -275.706078) (xy 341.997149 -275.711704)
			(xy 341.996268 -275.721064) (xy 341.99466 -275.744771) (xy 341.985023 -275.791297) (xy 341.968296 -275.835769)
			(xy 341.944882 -275.877112) (xy 341.915346 -275.91433) (xy 341.880401 -275.946524) (xy 341.860886 -275.960078)
			(xy 341.85352 -275.964904) (xy 341.831676 -275.994622) (xy 341.829136 -276.003766) (xy 341.815814 -276.050102)
			(xy 341.782237 -276.140488) (xy 341.740997 -276.227645) (xy 341.692401 -276.310925) (xy 341.636811 -276.389708)
			(xy 341.57464 -276.463409) (xy 341.540846 -276.497796) (xy 341.534538 -276.504765) (xy 341.529571 -276.516084)
			(xy 341.844879 -276.516084) (xy 341.848974 -276.465356) (xy 341.861153 -276.415942) (xy 341.881101 -276.369122)
			(xy 341.908302 -276.326108) (xy 341.94205 -276.288014) (xy 341.981472 -276.255827) (xy 342.025546 -276.230381)
			(xy 342.073132 -276.212334) (xy 342.122996 -276.202154) (xy 342.173848 -276.200105) (xy 342.224369 -276.206239)
			(xy 342.273253 -276.220399) (xy 342.319232 -276.242216) (xy 342.361116 -276.271126) (xy 342.39782 -276.306381)
			(xy 342.428393 -276.347067) (xy 342.452044 -276.39213) (xy 342.46816 -276.440404) (xy 342.476324 -276.490638)
			(xy 342.476836 -276.516084) (xy 342.795364 -276.516084) (xy 342.799324 -276.46703) (xy 342.811101 -276.419246)
			(xy 342.830392 -276.37397) (xy 342.856695 -276.332374) (xy 342.88933 -276.295537) (xy 342.927451 -276.264412)
			(xy 342.970072 -276.239805) (xy 343.016088 -276.222353) (xy 343.064307 -276.212509) (xy 343.113482 -276.210528)
			(xy 343.162337 -276.21646) (xy 343.209608 -276.230152) (xy 343.25407 -276.25125) (xy 343.294573 -276.279206)
			(xy 343.330066 -276.313298) (xy 343.359631 -276.352642) (xy 343.382502 -276.396219) (xy 343.398086 -276.4429)
			(xy 343.405981 -276.491477) (xy 343.406476 -276.516084) (xy 343.724987 -276.516084) (xy 343.729082 -276.465356)
			(xy 343.741261 -276.415942) (xy 343.761209 -276.369122) (xy 343.78841 -276.326108) (xy 343.822158 -276.288014)
			(xy 343.86158 -276.255827) (xy 343.905654 -276.230381) (xy 343.95324 -276.212334) (xy 344.003104 -276.202154)
			(xy 344.053956 -276.200105) (xy 344.104477 -276.206239) (xy 344.153361 -276.220399) (xy 344.19934 -276.242216)
			(xy 344.241224 -276.271126) (xy 344.277928 -276.306381) (xy 344.308501 -276.347067) (xy 344.332152 -276.39213)
			(xy 344.348268 -276.440404) (xy 344.356432 -276.490638) (xy 344.356944 -276.516084) (xy 344.675218 -276.516084)
			(xy 344.679178 -276.46703) (xy 344.690955 -276.419246) (xy 344.710246 -276.37397) (xy 344.736549 -276.332374)
			(xy 344.769184 -276.295537) (xy 344.807305 -276.264412) (xy 344.849926 -276.239805) (xy 344.895942 -276.222353)
			(xy 344.944161 -276.212509) (xy 344.993336 -276.210528) (xy 345.042191 -276.21646) (xy 345.089462 -276.230152)
			(xy 345.133924 -276.25125) (xy 345.174427 -276.279206) (xy 345.20992 -276.313298) (xy 345.239485 -276.352642)
			(xy 345.262356 -276.396219) (xy 345.27794 -276.4429) (xy 345.285835 -276.491477) (xy 345.28633 -276.516084)
			(xy 345.615272 -276.516084) (xy 345.619232 -276.46703) (xy 345.631009 -276.419246) (xy 345.6503 -276.37397)
			(xy 345.676603 -276.332374) (xy 345.709238 -276.295537) (xy 345.747359 -276.264412) (xy 345.78998 -276.239805)
			(xy 345.835996 -276.222353) (xy 345.884215 -276.212509) (xy 345.93339 -276.210528) (xy 345.982245 -276.21646)
			(xy 346.029516 -276.230152) (xy 346.073978 -276.25125) (xy 346.114481 -276.279206) (xy 346.149974 -276.313298)
			(xy 346.179539 -276.352642) (xy 346.20241 -276.396219) (xy 346.217994 -276.4429) (xy 346.225889 -276.491477)
			(xy 346.226384 -276.516084) (xy 346.555326 -276.516084) (xy 346.559286 -276.46703) (xy 346.571063 -276.419246)
			(xy 346.590354 -276.37397) (xy 346.616657 -276.332374) (xy 346.649292 -276.295537) (xy 346.687413 -276.264412)
			(xy 346.730034 -276.239805) (xy 346.77605 -276.222353) (xy 346.824269 -276.212509) (xy 346.873444 -276.210528)
			(xy 346.922299 -276.21646) (xy 346.96957 -276.230152) (xy 347.014032 -276.25125) (xy 347.054535 -276.279206)
			(xy 347.090028 -276.313298) (xy 347.119593 -276.352642) (xy 347.142464 -276.396219) (xy 347.158048 -276.4429)
			(xy 347.165943 -276.491477) (xy 347.166438 -276.516084) (xy 347.49538 -276.516084) (xy 347.49934 -276.46703)
			(xy 347.511117 -276.419246) (xy 347.530408 -276.37397) (xy 347.556711 -276.332374) (xy 347.589346 -276.295537)
			(xy 347.627467 -276.264412) (xy 347.670088 -276.239805) (xy 347.716104 -276.222353) (xy 347.764323 -276.212509)
			(xy 347.813498 -276.210528) (xy 347.862353 -276.21646) (xy 347.909624 -276.230152) (xy 347.954086 -276.25125)
			(xy 347.994589 -276.279206) (xy 348.030082 -276.313298) (xy 348.059647 -276.352642) (xy 348.082518 -276.396219)
			(xy 348.098102 -276.4429) (xy 348.105997 -276.491477) (xy 348.106492 -276.516084) (xy 348.435434 -276.516084)
			(xy 348.439394 -276.46703) (xy 348.451171 -276.419246) (xy 348.470462 -276.37397) (xy 348.496765 -276.332374)
			(xy 348.5294 -276.295537) (xy 348.567521 -276.264412) (xy 348.610142 -276.239805) (xy 348.656158 -276.222353)
			(xy 348.704377 -276.212509) (xy 348.753552 -276.210528) (xy 348.802407 -276.21646) (xy 348.849678 -276.230152)
			(xy 348.89414 -276.25125) (xy 348.934643 -276.279206) (xy 348.970136 -276.313298) (xy 348.999701 -276.352642)
			(xy 349.022572 -276.396219) (xy 349.038156 -276.4429) (xy 349.046051 -276.491477) (xy 349.046546 -276.516084)
			(xy 349.375234 -276.516084) (xy 349.379194 -276.46703) (xy 349.390971 -276.419246) (xy 349.410262 -276.37397)
			(xy 349.436565 -276.332374) (xy 349.4692 -276.295537) (xy 349.507321 -276.264412) (xy 349.549942 -276.239805)
			(xy 349.595958 -276.222353) (xy 349.644177 -276.212509) (xy 349.693352 -276.210528) (xy 349.742207 -276.21646)
			(xy 349.789478 -276.230152) (xy 349.83394 -276.25125) (xy 349.874443 -276.279206) (xy 349.909936 -276.313298)
			(xy 349.939501 -276.352642) (xy 349.962372 -276.396219) (xy 349.977956 -276.4429) (xy 349.985851 -276.491477)
			(xy 349.986346 -276.516084) (xy 350.315288 -276.516084) (xy 350.319248 -276.46703) (xy 350.331025 -276.419246)
			(xy 350.350316 -276.37397) (xy 350.376619 -276.332374) (xy 350.409254 -276.295537) (xy 350.447375 -276.264412)
			(xy 350.489996 -276.239805) (xy 350.536012 -276.222353) (xy 350.584231 -276.212509) (xy 350.633406 -276.210528)
			(xy 350.682261 -276.21646) (xy 350.729532 -276.230152) (xy 350.773994 -276.25125) (xy 350.814497 -276.279206)
			(xy 350.84999 -276.313298) (xy 350.879555 -276.352642) (xy 350.902426 -276.396219) (xy 350.91801 -276.4429)
			(xy 350.925905 -276.491477) (xy 350.9264 -276.516084) (xy 351.255342 -276.516084) (xy 351.259302 -276.46703)
			(xy 351.271079 -276.419246) (xy 351.29037 -276.37397) (xy 351.316673 -276.332374) (xy 351.349308 -276.295537)
			(xy 351.387429 -276.264412) (xy 351.43005 -276.239805) (xy 351.476066 -276.222353) (xy 351.524285 -276.212509)
			(xy 351.57346 -276.210528) (xy 351.622315 -276.21646) (xy 351.669586 -276.230152) (xy 351.714048 -276.25125)
			(xy 351.754551 -276.279206) (xy 351.790044 -276.313298) (xy 351.819609 -276.352642) (xy 351.84248 -276.396219)
			(xy 351.858064 -276.4429) (xy 351.865959 -276.491477) (xy 351.866454 -276.516084) (xy 352.195396 -276.516084)
			(xy 352.199356 -276.46703) (xy 352.211133 -276.419246) (xy 352.230424 -276.37397) (xy 352.256727 -276.332374)
			(xy 352.289362 -276.295537) (xy 352.327483 -276.264412) (xy 352.370104 -276.239805) (xy 352.41612 -276.222353)
			(xy 352.464339 -276.212509) (xy 352.513514 -276.210528) (xy 352.562369 -276.21646) (xy 352.60964 -276.230152)
			(xy 352.654102 -276.25125) (xy 352.694605 -276.279206) (xy 352.730098 -276.313298) (xy 352.759663 -276.352642)
			(xy 352.782534 -276.396219) (xy 352.798118 -276.4429) (xy 352.806013 -276.491477) (xy 352.806508 -276.516084)
			(xy 353.135196 -276.516084) (xy 353.139156 -276.46703) (xy 353.150933 -276.419246) (xy 353.170224 -276.37397)
			(xy 353.196527 -276.332374) (xy 353.229162 -276.295537) (xy 353.267283 -276.264412) (xy 353.309904 -276.239805)
			(xy 353.35592 -276.222353) (xy 353.404139 -276.212509) (xy 353.453314 -276.210528) (xy 353.502169 -276.21646)
			(xy 353.54944 -276.230152) (xy 353.593902 -276.25125) (xy 353.634405 -276.279206) (xy 353.669898 -276.313298)
			(xy 353.699463 -276.352642) (xy 353.722334 -276.396219) (xy 353.737918 -276.4429) (xy 353.745813 -276.491477)
			(xy 353.746308 -276.516084) (xy 354.07525 -276.516084) (xy 354.07921 -276.46703) (xy 354.090987 -276.419246)
			(xy 354.110278 -276.37397) (xy 354.136581 -276.332374) (xy 354.169216 -276.295537) (xy 354.207337 -276.264412)
			(xy 354.249958 -276.239805) (xy 354.295974 -276.222353) (xy 354.344193 -276.212509) (xy 354.393368 -276.210528)
			(xy 354.442223 -276.21646) (xy 354.489494 -276.230152) (xy 354.533956 -276.25125) (xy 354.574459 -276.279206)
			(xy 354.609952 -276.313298) (xy 354.639517 -276.352642) (xy 354.662388 -276.396219) (xy 354.677972 -276.4429)
			(xy 354.685867 -276.491477) (xy 354.686362 -276.516084) (xy 355.015304 -276.516084) (xy 355.019264 -276.46703)
			(xy 355.031041 -276.419246) (xy 355.050332 -276.37397) (xy 355.076635 -276.332374) (xy 355.10927 -276.295537)
			(xy 355.147391 -276.264412) (xy 355.190012 -276.239805) (xy 355.236028 -276.222353) (xy 355.284247 -276.212509)
			(xy 355.333422 -276.210528) (xy 355.382277 -276.21646) (xy 355.429548 -276.230152) (xy 355.47401 -276.25125)
			(xy 355.514513 -276.279206) (xy 355.550006 -276.313298) (xy 355.579571 -276.352642) (xy 355.602442 -276.396219)
			(xy 355.618026 -276.4429) (xy 355.625921 -276.491477) (xy 355.626416 -276.516084) (xy 355.955358 -276.516084)
			(xy 355.959318 -276.46703) (xy 355.971095 -276.419246) (xy 355.990386 -276.37397) (xy 356.016689 -276.332374)
			(xy 356.049324 -276.295537) (xy 356.087445 -276.264412) (xy 356.130066 -276.239805) (xy 356.176082 -276.222353)
			(xy 356.224301 -276.212509) (xy 356.273476 -276.210528) (xy 356.322331 -276.21646) (xy 356.369602 -276.230152)
			(xy 356.414064 -276.25125) (xy 356.454567 -276.279206) (xy 356.49006 -276.313298) (xy 356.519625 -276.352642)
			(xy 356.542496 -276.396219) (xy 356.55808 -276.4429) (xy 356.565975 -276.491477) (xy 356.56647 -276.516084)
			(xy 356.895412 -276.516084) (xy 356.899372 -276.46703) (xy 356.911149 -276.419246) (xy 356.93044 -276.37397)
			(xy 356.956743 -276.332374) (xy 356.989378 -276.295537) (xy 357.027499 -276.264412) (xy 357.07012 -276.239805)
			(xy 357.116136 -276.222353) (xy 357.164355 -276.212509) (xy 357.21353 -276.210528) (xy 357.262385 -276.21646)
			(xy 357.309656 -276.230152) (xy 357.354118 -276.25125) (xy 357.394621 -276.279206) (xy 357.430114 -276.313298)
			(xy 357.459679 -276.352642) (xy 357.48255 -276.396219) (xy 357.498134 -276.4429) (xy 357.506029 -276.491477)
			(xy 357.506524 -276.516084) (xy 357.835212 -276.516084) (xy 357.839172 -276.46703) (xy 357.850949 -276.419246)
			(xy 357.87024 -276.37397) (xy 357.896543 -276.332374) (xy 357.929178 -276.295537) (xy 357.967299 -276.264412)
			(xy 358.00992 -276.239805) (xy 358.055936 -276.222353) (xy 358.104155 -276.212509) (xy 358.15333 -276.210528)
			(xy 358.202185 -276.21646) (xy 358.249456 -276.230152) (xy 358.293918 -276.25125) (xy 358.334421 -276.279206)
			(xy 358.369914 -276.313298) (xy 358.399479 -276.352642) (xy 358.42235 -276.396219) (xy 358.437934 -276.4429)
			(xy 358.445829 -276.491477) (xy 358.446324 -276.516084) (xy 361.589078 -276.516084) (xy 361.593038 -276.46703)
			(xy 361.604815 -276.419246) (xy 361.624106 -276.37397) (xy 361.650409 -276.332374) (xy 361.683044 -276.295537)
			(xy 361.721165 -276.264412) (xy 361.763786 -276.239805) (xy 361.809802 -276.222353) (xy 361.858021 -276.212509)
			(xy 361.907196 -276.210528) (xy 361.956051 -276.21646) (xy 362.003322 -276.230152) (xy 362.047784 -276.25125)
			(xy 362.088287 -276.279206) (xy 362.12378 -276.313298) (xy 362.153345 -276.352642) (xy 362.176216 -276.396219)
			(xy 362.1918 -276.4429) (xy 362.199695 -276.491477) (xy 362.20019 -276.516084) (xy 362.528878 -276.516084)
			(xy 362.532838 -276.46703) (xy 362.544615 -276.419246) (xy 362.563906 -276.37397) (xy 362.590209 -276.332374)
			(xy 362.622844 -276.295537) (xy 362.660965 -276.264412) (xy 362.703586 -276.239805) (xy 362.749602 -276.222353)
			(xy 362.797821 -276.212509) (xy 362.846996 -276.210528) (xy 362.895851 -276.21646) (xy 362.943122 -276.230152)
			(xy 362.987584 -276.25125) (xy 363.028087 -276.279206) (xy 363.06358 -276.313298) (xy 363.093145 -276.352642)
			(xy 363.116016 -276.396219) (xy 363.1316 -276.4429) (xy 363.139495 -276.491477) (xy 363.13999 -276.516084)
			(xy 363.468932 -276.516084) (xy 363.472892 -276.46703) (xy 363.484669 -276.419246) (xy 363.50396 -276.37397)
			(xy 363.530263 -276.332374) (xy 363.562898 -276.295537) (xy 363.601019 -276.264412) (xy 363.64364 -276.239805)
			(xy 363.689656 -276.222353) (xy 363.737875 -276.212509) (xy 363.78705 -276.210528) (xy 363.835905 -276.21646)
			(xy 363.883176 -276.230152) (xy 363.927638 -276.25125) (xy 363.968141 -276.279206) (xy 364.003634 -276.313298)
			(xy 364.033199 -276.352642) (xy 364.05607 -276.396219) (xy 364.071654 -276.4429) (xy 364.079549 -276.491477)
			(xy 364.080044 -276.516084) (xy 364.408986 -276.516084) (xy 364.412946 -276.46703) (xy 364.424723 -276.419246)
			(xy 364.444014 -276.37397) (xy 364.470317 -276.332374) (xy 364.502952 -276.295537) (xy 364.541073 -276.264412)
			(xy 364.583694 -276.239805) (xy 364.62971 -276.222353) (xy 364.677929 -276.212509) (xy 364.727104 -276.210528)
			(xy 364.775959 -276.21646) (xy 364.82323 -276.230152) (xy 364.867692 -276.25125) (xy 364.908195 -276.279206)
			(xy 364.943688 -276.313298) (xy 364.973253 -276.352642) (xy 364.996124 -276.396219) (xy 365.011708 -276.4429)
			(xy 365.019603 -276.491477) (xy 365.020098 -276.516084) (xy 365.34904 -276.516084) (xy 365.353 -276.46703)
			(xy 365.364777 -276.419246) (xy 365.384068 -276.37397) (xy 365.410371 -276.332374) (xy 365.443006 -276.295537)
			(xy 365.481127 -276.264412) (xy 365.523748 -276.239805) (xy 365.569764 -276.222353) (xy 365.617983 -276.212509)
			(xy 365.667158 -276.210528) (xy 365.716013 -276.21646) (xy 365.763284 -276.230152) (xy 365.807746 -276.25125)
			(xy 365.848249 -276.279206) (xy 365.883742 -276.313298) (xy 365.913307 -276.352642) (xy 365.936178 -276.396219)
			(xy 365.951762 -276.4429) (xy 365.959657 -276.491477) (xy 365.960152 -276.516084) (xy 366.289094 -276.516084)
			(xy 366.293054 -276.46703) (xy 366.304831 -276.419246) (xy 366.324122 -276.37397) (xy 366.350425 -276.332374)
			(xy 366.38306 -276.295537) (xy 366.421181 -276.264412) (xy 366.463802 -276.239805) (xy 366.509818 -276.222353)
			(xy 366.558037 -276.212509) (xy 366.607212 -276.210528) (xy 366.656067 -276.21646) (xy 366.703338 -276.230152)
			(xy 366.7478 -276.25125) (xy 366.788303 -276.279206) (xy 366.823796 -276.313298) (xy 366.853361 -276.352642)
			(xy 366.876232 -276.396219) (xy 366.891816 -276.4429) (xy 366.899711 -276.491477) (xy 366.900206 -276.516084)
			(xy 367.228894 -276.516084) (xy 367.232854 -276.46703) (xy 367.244631 -276.419246) (xy 367.263922 -276.37397)
			(xy 367.290225 -276.332374) (xy 367.32286 -276.295537) (xy 367.360981 -276.264412) (xy 367.403602 -276.239805)
			(xy 367.449618 -276.222353) (xy 367.497837 -276.212509) (xy 367.547012 -276.210528) (xy 367.595867 -276.21646)
			(xy 367.643138 -276.230152) (xy 367.6876 -276.25125) (xy 367.728103 -276.279206) (xy 367.763596 -276.313298)
			(xy 367.793161 -276.352642) (xy 367.816032 -276.396219) (xy 367.831616 -276.4429) (xy 367.839511 -276.491477)
			(xy 367.840006 -276.516084) (xy 368.168948 -276.516084) (xy 368.172908 -276.46703) (xy 368.184685 -276.419246)
			(xy 368.203976 -276.37397) (xy 368.230279 -276.332374) (xy 368.262914 -276.295537) (xy 368.301035 -276.264412)
			(xy 368.343656 -276.239805) (xy 368.389672 -276.222353) (xy 368.437891 -276.212509) (xy 368.487066 -276.210528)
			(xy 368.535921 -276.21646) (xy 368.583192 -276.230152) (xy 368.627654 -276.25125) (xy 368.668157 -276.279206)
			(xy 368.70365 -276.313298) (xy 368.733215 -276.352642) (xy 368.756086 -276.396219) (xy 368.77167 -276.4429)
			(xy 368.779565 -276.491477) (xy 368.78006 -276.516084) (xy 369.109002 -276.516084) (xy 369.112962 -276.46703)
			(xy 369.124739 -276.419246) (xy 369.14403 -276.37397) (xy 369.170333 -276.332374) (xy 369.202968 -276.295537)
			(xy 369.241089 -276.264412) (xy 369.28371 -276.239805) (xy 369.329726 -276.222353) (xy 369.377945 -276.212509)
			(xy 369.42712 -276.210528) (xy 369.475975 -276.21646) (xy 369.523246 -276.230152) (xy 369.567708 -276.25125)
			(xy 369.608211 -276.279206) (xy 369.643704 -276.313298) (xy 369.673269 -276.352642) (xy 369.69614 -276.396219)
			(xy 369.711724 -276.4429) (xy 369.719619 -276.491477) (xy 369.720114 -276.516084) (xy 370.049056 -276.516084)
			(xy 370.053016 -276.46703) (xy 370.064793 -276.419246) (xy 370.084084 -276.37397) (xy 370.110387 -276.332374)
			(xy 370.143022 -276.295537) (xy 370.181143 -276.264412) (xy 370.223764 -276.239805) (xy 370.26978 -276.222353)
			(xy 370.317999 -276.212509) (xy 370.367174 -276.210528) (xy 370.416029 -276.21646) (xy 370.4633 -276.230152)
			(xy 370.507762 -276.25125) (xy 370.548265 -276.279206) (xy 370.583758 -276.313298) (xy 370.613323 -276.352642)
			(xy 370.636194 -276.396219) (xy 370.651778 -276.4429) (xy 370.659673 -276.491477) (xy 370.660168 -276.516084)
			(xy 370.98911 -276.516084) (xy 370.99307 -276.46703) (xy 371.004847 -276.419246) (xy 371.024138 -276.37397)
			(xy 371.050441 -276.332374) (xy 371.083076 -276.295537) (xy 371.121197 -276.264412) (xy 371.163818 -276.239805)
			(xy 371.209834 -276.222353) (xy 371.258053 -276.212509) (xy 371.307228 -276.210528) (xy 371.356083 -276.21646)
			(xy 371.403354 -276.230152) (xy 371.447816 -276.25125) (xy 371.488319 -276.279206) (xy 371.523812 -276.313298)
			(xy 371.553377 -276.352642) (xy 371.576248 -276.396219) (xy 371.591832 -276.4429) (xy 371.599727 -276.491477)
			(xy 371.600222 -276.516084) (xy 371.92891 -276.516084) (xy 371.93287 -276.46703) (xy 371.944647 -276.419246)
			(xy 371.963938 -276.37397) (xy 371.990241 -276.332374) (xy 372.022876 -276.295537) (xy 372.060997 -276.264412)
			(xy 372.103618 -276.239805) (xy 372.149634 -276.222353) (xy 372.197853 -276.212509) (xy 372.247028 -276.210528)
			(xy 372.295883 -276.21646) (xy 372.343154 -276.230152) (xy 372.387616 -276.25125) (xy 372.428119 -276.279206)
			(xy 372.463612 -276.313298) (xy 372.493177 -276.352642) (xy 372.516048 -276.396219) (xy 372.531632 -276.4429)
			(xy 372.539527 -276.491477) (xy 372.540022 -276.516084) (xy 372.868964 -276.516084) (xy 372.872924 -276.46703)
			(xy 372.884701 -276.419246) (xy 372.903992 -276.37397) (xy 372.930295 -276.332374) (xy 372.96293 -276.295537)
			(xy 373.001051 -276.264412) (xy 373.043672 -276.239805) (xy 373.089688 -276.222353) (xy 373.137907 -276.212509)
			(xy 373.187082 -276.210528) (xy 373.235937 -276.21646) (xy 373.283208 -276.230152) (xy 373.32767 -276.25125)
			(xy 373.368173 -276.279206) (xy 373.403666 -276.313298) (xy 373.433231 -276.352642) (xy 373.456102 -276.396219)
			(xy 373.471686 -276.4429) (xy 373.479581 -276.491477) (xy 373.480076 -276.516084) (xy 373.809018 -276.516084)
			(xy 373.812978 -276.46703) (xy 373.824755 -276.419246) (xy 373.844046 -276.37397) (xy 373.870349 -276.332374)
			(xy 373.902984 -276.295537) (xy 373.941105 -276.264412) (xy 373.983726 -276.239805) (xy 374.029742 -276.222353)
			(xy 374.077961 -276.212509) (xy 374.127136 -276.210528) (xy 374.175991 -276.21646) (xy 374.223262 -276.230152)
			(xy 374.267724 -276.25125) (xy 374.308227 -276.279206) (xy 374.34372 -276.313298) (xy 374.373285 -276.352642)
			(xy 374.396156 -276.396219) (xy 374.41174 -276.4429) (xy 374.419635 -276.491477) (xy 374.42013 -276.516084)
			(xy 374.419635 -276.540691) (xy 374.41174 -276.589268) (xy 374.396156 -276.635949) (xy 374.373285 -276.679526)
			(xy 374.34372 -276.71887) (xy 374.308227 -276.752962) (xy 374.267724 -276.780918) (xy 374.223262 -276.802016)
			(xy 374.175991 -276.815708) (xy 374.127136 -276.82164) (xy 374.077961 -276.819659) (xy 374.029742 -276.809815)
			(xy 373.983726 -276.792363) (xy 373.941105 -276.767756) (xy 373.902984 -276.736631) (xy 373.870349 -276.699794)
			(xy 373.844046 -276.658198) (xy 373.824755 -276.612922) (xy 373.812978 -276.565138) (xy 373.809018 -276.516084)
			(xy 373.480076 -276.516084) (xy 373.479581 -276.540691) (xy 373.471686 -276.589268) (xy 373.456102 -276.635949)
			(xy 373.433231 -276.679526) (xy 373.403666 -276.71887) (xy 373.368173 -276.752962) (xy 373.32767 -276.780918)
			(xy 373.283208 -276.802016) (xy 373.235937 -276.815708) (xy 373.187082 -276.82164) (xy 373.137907 -276.819659)
			(xy 373.089688 -276.809815) (xy 373.043672 -276.792363) (xy 373.001051 -276.767756) (xy 372.96293 -276.736631)
			(xy 372.930295 -276.699794) (xy 372.903992 -276.658198) (xy 372.884701 -276.612922) (xy 372.872924 -276.565138)
			(xy 372.868964 -276.516084) (xy 372.540022 -276.516084) (xy 372.539527 -276.540691) (xy 372.531632 -276.589268)
			(xy 372.516048 -276.635949) (xy 372.493177 -276.679526) (xy 372.463612 -276.71887) (xy 372.428119 -276.752962)
			(xy 372.387616 -276.780918) (xy 372.343154 -276.802016) (xy 372.295883 -276.815708) (xy 372.247028 -276.82164)
			(xy 372.197853 -276.819659) (xy 372.149634 -276.809815) (xy 372.103618 -276.792363) (xy 372.060997 -276.767756)
			(xy 372.022876 -276.736631) (xy 371.990241 -276.699794) (xy 371.963938 -276.658198) (xy 371.944647 -276.612922)
			(xy 371.93287 -276.565138) (xy 371.92891 -276.516084) (xy 371.600222 -276.516084) (xy 371.599727 -276.540691)
			(xy 371.591832 -276.589268) (xy 371.576248 -276.635949) (xy 371.553377 -276.679526) (xy 371.523812 -276.71887)
			(xy 371.488319 -276.752962) (xy 371.447816 -276.780918) (xy 371.403354 -276.802016) (xy 371.356083 -276.815708)
			(xy 371.307228 -276.82164) (xy 371.258053 -276.819659) (xy 371.209834 -276.809815) (xy 371.163818 -276.792363)
			(xy 371.121197 -276.767756) (xy 371.083076 -276.736631) (xy 371.050441 -276.699794) (xy 371.024138 -276.658198)
			(xy 371.004847 -276.612922) (xy 370.99307 -276.565138) (xy 370.98911 -276.516084) (xy 370.660168 -276.516084)
			(xy 370.659673 -276.540691) (xy 370.651778 -276.589268) (xy 370.636194 -276.635949) (xy 370.613323 -276.679526)
			(xy 370.583758 -276.71887) (xy 370.548265 -276.752962) (xy 370.507762 -276.780918) (xy 370.4633 -276.802016)
			(xy 370.416029 -276.815708) (xy 370.367174 -276.82164) (xy 370.317999 -276.819659) (xy 370.26978 -276.809815)
			(xy 370.223764 -276.792363) (xy 370.181143 -276.767756) (xy 370.143022 -276.736631) (xy 370.110387 -276.699794)
			(xy 370.084084 -276.658198) (xy 370.064793 -276.612922) (xy 370.053016 -276.565138) (xy 370.049056 -276.516084)
			(xy 369.720114 -276.516084) (xy 369.719619 -276.540691) (xy 369.711724 -276.589268) (xy 369.69614 -276.635949)
			(xy 369.673269 -276.679526) (xy 369.643704 -276.71887) (xy 369.608211 -276.752962) (xy 369.567708 -276.780918)
			(xy 369.523246 -276.802016) (xy 369.475975 -276.815708) (xy 369.42712 -276.82164) (xy 369.377945 -276.819659)
			(xy 369.329726 -276.809815) (xy 369.28371 -276.792363) (xy 369.241089 -276.767756) (xy 369.202968 -276.736631)
			(xy 369.170333 -276.699794) (xy 369.14403 -276.658198) (xy 369.124739 -276.612922) (xy 369.112962 -276.565138)
			(xy 369.109002 -276.516084) (xy 368.78006 -276.516084) (xy 368.779565 -276.540691) (xy 368.77167 -276.589268)
			(xy 368.756086 -276.635949) (xy 368.733215 -276.679526) (xy 368.70365 -276.71887) (xy 368.668157 -276.752962)
			(xy 368.627654 -276.780918) (xy 368.583192 -276.802016) (xy 368.535921 -276.815708) (xy 368.487066 -276.82164)
			(xy 368.437891 -276.819659) (xy 368.389672 -276.809815) (xy 368.343656 -276.792363) (xy 368.301035 -276.767756)
			(xy 368.262914 -276.736631) (xy 368.230279 -276.699794) (xy 368.203976 -276.658198) (xy 368.184685 -276.612922)
			(xy 368.172908 -276.565138) (xy 368.168948 -276.516084) (xy 367.840006 -276.516084) (xy 367.839511 -276.540691)
			(xy 367.831616 -276.589268) (xy 367.816032 -276.635949) (xy 367.793161 -276.679526) (xy 367.763596 -276.71887)
			(xy 367.728103 -276.752962) (xy 367.6876 -276.780918) (xy 367.643138 -276.802016) (xy 367.595867 -276.815708)
			(xy 367.547012 -276.82164) (xy 367.497837 -276.819659) (xy 367.449618 -276.809815) (xy 367.403602 -276.792363)
			(xy 367.360981 -276.767756) (xy 367.32286 -276.736631) (xy 367.290225 -276.699794) (xy 367.263922 -276.658198)
			(xy 367.244631 -276.612922) (xy 367.232854 -276.565138) (xy 367.228894 -276.516084) (xy 366.900206 -276.516084)
			(xy 366.899711 -276.540691) (xy 366.891816 -276.589268) (xy 366.876232 -276.635949) (xy 366.853361 -276.679526)
			(xy 366.823796 -276.71887) (xy 366.788303 -276.752962) (xy 366.7478 -276.780918) (xy 366.703338 -276.802016)
			(xy 366.656067 -276.815708) (xy 366.607212 -276.82164) (xy 366.558037 -276.819659) (xy 366.509818 -276.809815)
			(xy 366.463802 -276.792363) (xy 366.421181 -276.767756) (xy 366.38306 -276.736631) (xy 366.350425 -276.699794)
			(xy 366.324122 -276.658198) (xy 366.304831 -276.612922) (xy 366.293054 -276.565138) (xy 366.289094 -276.516084)
			(xy 365.960152 -276.516084) (xy 365.959657 -276.540691) (xy 365.951762 -276.589268) (xy 365.936178 -276.635949)
			(xy 365.913307 -276.679526) (xy 365.883742 -276.71887) (xy 365.848249 -276.752962) (xy 365.807746 -276.780918)
			(xy 365.763284 -276.802016) (xy 365.716013 -276.815708) (xy 365.667158 -276.82164) (xy 365.617983 -276.819659)
			(xy 365.569764 -276.809815) (xy 365.523748 -276.792363) (xy 365.481127 -276.767756) (xy 365.443006 -276.736631)
			(xy 365.410371 -276.699794) (xy 365.384068 -276.658198) (xy 365.364777 -276.612922) (xy 365.353 -276.565138)
			(xy 365.34904 -276.516084) (xy 365.020098 -276.516084) (xy 365.019603 -276.540691) (xy 365.011708 -276.589268)
			(xy 364.996124 -276.635949) (xy 364.973253 -276.679526) (xy 364.943688 -276.71887) (xy 364.908195 -276.752962)
			(xy 364.867692 -276.780918) (xy 364.82323 -276.802016) (xy 364.775959 -276.815708) (xy 364.727104 -276.82164)
			(xy 364.677929 -276.819659) (xy 364.62971 -276.809815) (xy 364.583694 -276.792363) (xy 364.541073 -276.767756)
			(xy 364.502952 -276.736631) (xy 364.470317 -276.699794) (xy 364.444014 -276.658198) (xy 364.424723 -276.612922)
			(xy 364.412946 -276.565138) (xy 364.408986 -276.516084) (xy 364.080044 -276.516084) (xy 364.079549 -276.540691)
			(xy 364.071654 -276.589268) (xy 364.05607 -276.635949) (xy 364.033199 -276.679526) (xy 364.003634 -276.71887)
			(xy 363.968141 -276.752962) (xy 363.927638 -276.780918) (xy 363.883176 -276.802016) (xy 363.835905 -276.815708)
			(xy 363.78705 -276.82164) (xy 363.737875 -276.819659) (xy 363.689656 -276.809815) (xy 363.64364 -276.792363)
			(xy 363.601019 -276.767756) (xy 363.562898 -276.736631) (xy 363.530263 -276.699794) (xy 363.50396 -276.658198)
			(xy 363.484669 -276.612922) (xy 363.472892 -276.565138) (xy 363.468932 -276.516084) (xy 363.13999 -276.516084)
			(xy 363.139495 -276.540691) (xy 363.1316 -276.589268) (xy 363.116016 -276.635949) (xy 363.093145 -276.679526)
			(xy 363.06358 -276.71887) (xy 363.028087 -276.752962) (xy 362.987584 -276.780918) (xy 362.943122 -276.802016)
			(xy 362.895851 -276.815708) (xy 362.846996 -276.82164) (xy 362.797821 -276.819659) (xy 362.749602 -276.809815)
			(xy 362.703586 -276.792363) (xy 362.660965 -276.767756) (xy 362.622844 -276.736631) (xy 362.590209 -276.699794)
			(xy 362.563906 -276.658198) (xy 362.544615 -276.612922) (xy 362.532838 -276.565138) (xy 362.528878 -276.516084)
			(xy 362.20019 -276.516084) (xy 362.199695 -276.540691) (xy 362.1918 -276.589268) (xy 362.176216 -276.635949)
			(xy 362.153345 -276.679526) (xy 362.12378 -276.71887) (xy 362.088287 -276.752962) (xy 362.047784 -276.780918)
			(xy 362.003322 -276.802016) (xy 361.956051 -276.815708) (xy 361.907196 -276.82164) (xy 361.858021 -276.819659)
			(xy 361.809802 -276.809815) (xy 361.763786 -276.792363) (xy 361.721165 -276.767756) (xy 361.683044 -276.736631)
			(xy 361.650409 -276.699794) (xy 361.624106 -276.658198) (xy 361.604815 -276.612922) (xy 361.593038 -276.565138)
			(xy 361.589078 -276.516084) (xy 358.446324 -276.516084) (xy 358.445829 -276.540691) (xy 358.437934 -276.589268)
			(xy 358.42235 -276.635949) (xy 358.399479 -276.679526) (xy 358.369914 -276.71887) (xy 358.334421 -276.752962)
			(xy 358.293918 -276.780918) (xy 358.249456 -276.802016) (xy 358.202185 -276.815708) (xy 358.15333 -276.82164)
			(xy 358.104155 -276.819659) (xy 358.055936 -276.809815) (xy 358.00992 -276.792363) (xy 357.967299 -276.767756)
			(xy 357.929178 -276.736631) (xy 357.896543 -276.699794) (xy 357.87024 -276.658198) (xy 357.850949 -276.612922)
			(xy 357.839172 -276.565138) (xy 357.835212 -276.516084) (xy 357.506524 -276.516084) (xy 357.506029 -276.540691)
			(xy 357.498134 -276.589268) (xy 357.48255 -276.635949) (xy 357.459679 -276.679526) (xy 357.430114 -276.71887)
			(xy 357.394621 -276.752962) (xy 357.354118 -276.780918) (xy 357.309656 -276.802016) (xy 357.262385 -276.815708)
			(xy 357.21353 -276.82164) (xy 357.164355 -276.819659) (xy 357.116136 -276.809815) (xy 357.07012 -276.792363)
			(xy 357.027499 -276.767756) (xy 356.989378 -276.736631) (xy 356.956743 -276.699794) (xy 356.93044 -276.658198)
			(xy 356.911149 -276.612922) (xy 356.899372 -276.565138) (xy 356.895412 -276.516084) (xy 356.56647 -276.516084)
			(xy 356.565975 -276.540691) (xy 356.55808 -276.589268) (xy 356.542496 -276.635949) (xy 356.519625 -276.679526)
			(xy 356.49006 -276.71887) (xy 356.454567 -276.752962) (xy 356.414064 -276.780918) (xy 356.369602 -276.802016)
			(xy 356.322331 -276.815708) (xy 356.273476 -276.82164) (xy 356.224301 -276.819659) (xy 356.176082 -276.809815)
			(xy 356.130066 -276.792363) (xy 356.087445 -276.767756) (xy 356.049324 -276.736631) (xy 356.016689 -276.699794)
			(xy 355.990386 -276.658198) (xy 355.971095 -276.612922) (xy 355.959318 -276.565138) (xy 355.955358 -276.516084)
			(xy 355.626416 -276.516084) (xy 355.625921 -276.540691) (xy 355.618026 -276.589268) (xy 355.602442 -276.635949)
			(xy 355.579571 -276.679526) (xy 355.550006 -276.71887) (xy 355.514513 -276.752962) (xy 355.47401 -276.780918)
			(xy 355.429548 -276.802016) (xy 355.382277 -276.815708) (xy 355.333422 -276.82164) (xy 355.284247 -276.819659)
			(xy 355.236028 -276.809815) (xy 355.190012 -276.792363) (xy 355.147391 -276.767756) (xy 355.10927 -276.736631)
			(xy 355.076635 -276.699794) (xy 355.050332 -276.658198) (xy 355.031041 -276.612922) (xy 355.019264 -276.565138)
			(xy 355.015304 -276.516084) (xy 354.686362 -276.516084) (xy 354.685867 -276.540691) (xy 354.677972 -276.589268)
			(xy 354.662388 -276.635949) (xy 354.639517 -276.679526) (xy 354.609952 -276.71887) (xy 354.574459 -276.752962)
			(xy 354.533956 -276.780918) (xy 354.489494 -276.802016) (xy 354.442223 -276.815708) (xy 354.393368 -276.82164)
			(xy 354.344193 -276.819659) (xy 354.295974 -276.809815) (xy 354.249958 -276.792363) (xy 354.207337 -276.767756)
			(xy 354.169216 -276.736631) (xy 354.136581 -276.699794) (xy 354.110278 -276.658198) (xy 354.090987 -276.612922)
			(xy 354.07921 -276.565138) (xy 354.07525 -276.516084) (xy 353.746308 -276.516084) (xy 353.745813 -276.540691)
			(xy 353.737918 -276.589268) (xy 353.722334 -276.635949) (xy 353.699463 -276.679526) (xy 353.669898 -276.71887)
			(xy 353.634405 -276.752962) (xy 353.593902 -276.780918) (xy 353.54944 -276.802016) (xy 353.502169 -276.815708)
			(xy 353.453314 -276.82164) (xy 353.404139 -276.819659) (xy 353.35592 -276.809815) (xy 353.309904 -276.792363)
			(xy 353.267283 -276.767756) (xy 353.229162 -276.736631) (xy 353.196527 -276.699794) (xy 353.170224 -276.658198)
			(xy 353.150933 -276.612922) (xy 353.139156 -276.565138) (xy 353.135196 -276.516084) (xy 352.806508 -276.516084)
			(xy 352.806013 -276.540691) (xy 352.798118 -276.589268) (xy 352.782534 -276.635949) (xy 352.759663 -276.679526)
			(xy 352.730098 -276.71887) (xy 352.694605 -276.752962) (xy 352.654102 -276.780918) (xy 352.60964 -276.802016)
			(xy 352.562369 -276.815708) (xy 352.513514 -276.82164) (xy 352.464339 -276.819659) (xy 352.41612 -276.809815)
			(xy 352.370104 -276.792363) (xy 352.327483 -276.767756) (xy 352.289362 -276.736631) (xy 352.256727 -276.699794)
			(xy 352.230424 -276.658198) (xy 352.211133 -276.612922) (xy 352.199356 -276.565138) (xy 352.195396 -276.516084)
			(xy 351.866454 -276.516084) (xy 351.865959 -276.540691) (xy 351.858064 -276.589268) (xy 351.84248 -276.635949)
			(xy 351.819609 -276.679526) (xy 351.790044 -276.71887) (xy 351.754551 -276.752962) (xy 351.714048 -276.780918)
			(xy 351.669586 -276.802016) (xy 351.622315 -276.815708) (xy 351.57346 -276.82164) (xy 351.524285 -276.819659)
			(xy 351.476066 -276.809815) (xy 351.43005 -276.792363) (xy 351.387429 -276.767756) (xy 351.349308 -276.736631)
			(xy 351.316673 -276.699794) (xy 351.29037 -276.658198) (xy 351.271079 -276.612922) (xy 351.259302 -276.565138)
			(xy 351.255342 -276.516084) (xy 350.9264 -276.516084) (xy 350.925905 -276.540691) (xy 350.91801 -276.589268)
			(xy 350.902426 -276.635949) (xy 350.879555 -276.679526) (xy 350.84999 -276.71887) (xy 350.814497 -276.752962)
			(xy 350.773994 -276.780918) (xy 350.729532 -276.802016) (xy 350.682261 -276.815708) (xy 350.633406 -276.82164)
			(xy 350.584231 -276.819659) (xy 350.536012 -276.809815) (xy 350.489996 -276.792363) (xy 350.447375 -276.767756)
			(xy 350.409254 -276.736631) (xy 350.376619 -276.699794) (xy 350.350316 -276.658198) (xy 350.331025 -276.612922)
			(xy 350.319248 -276.565138) (xy 350.315288 -276.516084) (xy 349.986346 -276.516084) (xy 349.985851 -276.540691)
			(xy 349.977956 -276.589268) (xy 349.962372 -276.635949) (xy 349.939501 -276.679526) (xy 349.909936 -276.71887)
			(xy 349.874443 -276.752962) (xy 349.83394 -276.780918) (xy 349.789478 -276.802016) (xy 349.742207 -276.815708)
			(xy 349.693352 -276.82164) (xy 349.644177 -276.819659) (xy 349.595958 -276.809815) (xy 349.549942 -276.792363)
			(xy 349.507321 -276.767756) (xy 349.4692 -276.736631) (xy 349.436565 -276.699794) (xy 349.410262 -276.658198)
			(xy 349.390971 -276.612922) (xy 349.379194 -276.565138) (xy 349.375234 -276.516084) (xy 349.046546 -276.516084)
			(xy 349.046051 -276.540691) (xy 349.038156 -276.589268) (xy 349.022572 -276.635949) (xy 348.999701 -276.679526)
			(xy 348.970136 -276.71887) (xy 348.934643 -276.752962) (xy 348.89414 -276.780918) (xy 348.849678 -276.802016)
			(xy 348.802407 -276.815708) (xy 348.753552 -276.82164) (xy 348.704377 -276.819659) (xy 348.656158 -276.809815)
			(xy 348.610142 -276.792363) (xy 348.567521 -276.767756) (xy 348.5294 -276.736631) (xy 348.496765 -276.699794)
			(xy 348.470462 -276.658198) (xy 348.451171 -276.612922) (xy 348.439394 -276.565138) (xy 348.435434 -276.516084)
			(xy 348.106492 -276.516084) (xy 348.105997 -276.540691) (xy 348.098102 -276.589268) (xy 348.082518 -276.635949)
			(xy 348.059647 -276.679526) (xy 348.030082 -276.71887) (xy 347.994589 -276.752962) (xy 347.954086 -276.780918)
			(xy 347.909624 -276.802016) (xy 347.862353 -276.815708) (xy 347.813498 -276.82164) (xy 347.764323 -276.819659)
			(xy 347.716104 -276.809815) (xy 347.670088 -276.792363) (xy 347.627467 -276.767756) (xy 347.589346 -276.736631)
			(xy 347.556711 -276.699794) (xy 347.530408 -276.658198) (xy 347.511117 -276.612922) (xy 347.49934 -276.565138)
			(xy 347.49538 -276.516084) (xy 347.166438 -276.516084) (xy 347.165943 -276.540691) (xy 347.158048 -276.589268)
			(xy 347.142464 -276.635949) (xy 347.119593 -276.679526) (xy 347.090028 -276.71887) (xy 347.054535 -276.752962)
			(xy 347.014032 -276.780918) (xy 346.96957 -276.802016) (xy 346.922299 -276.815708) (xy 346.873444 -276.82164)
			(xy 346.824269 -276.819659) (xy 346.77605 -276.809815) (xy 346.730034 -276.792363) (xy 346.687413 -276.767756)
			(xy 346.649292 -276.736631) (xy 346.616657 -276.699794) (xy 346.590354 -276.658198) (xy 346.571063 -276.612922)
			(xy 346.559286 -276.565138) (xy 346.555326 -276.516084) (xy 346.226384 -276.516084) (xy 346.225889 -276.540691)
			(xy 346.217994 -276.589268) (xy 346.20241 -276.635949) (xy 346.179539 -276.679526) (xy 346.149974 -276.71887)
			(xy 346.114481 -276.752962) (xy 346.073978 -276.780918) (xy 346.029516 -276.802016) (xy 345.982245 -276.815708)
			(xy 345.93339 -276.82164) (xy 345.884215 -276.819659) (xy 345.835996 -276.809815) (xy 345.78998 -276.792363)
			(xy 345.747359 -276.767756) (xy 345.709238 -276.736631) (xy 345.676603 -276.699794) (xy 345.6503 -276.658198)
			(xy 345.631009 -276.612922) (xy 345.619232 -276.565138) (xy 345.615272 -276.516084) (xy 345.28633 -276.516084)
			(xy 345.285835 -276.540691) (xy 345.27794 -276.589268) (xy 345.262356 -276.635949) (xy 345.239485 -276.679526)
			(xy 345.20992 -276.71887) (xy 345.174427 -276.752962) (xy 345.133924 -276.780918) (xy 345.089462 -276.802016)
			(xy 345.042191 -276.815708) (xy 344.993336 -276.82164) (xy 344.944161 -276.819659) (xy 344.895942 -276.809815)
			(xy 344.849926 -276.792363) (xy 344.807305 -276.767756) (xy 344.769184 -276.736631) (xy 344.736549 -276.699794)
			(xy 344.710246 -276.658198) (xy 344.690955 -276.612922) (xy 344.679178 -276.565138) (xy 344.675218 -276.516084)
			(xy 344.356944 -276.516084) (xy 344.356432 -276.54153) (xy 344.348268 -276.591764) (xy 344.332152 -276.640038)
			(xy 344.308501 -276.685101) (xy 344.277928 -276.725787) (xy 344.241224 -276.761042) (xy 344.19934 -276.789952)
			(xy 344.153361 -276.811769) (xy 344.104477 -276.825929) (xy 344.053956 -276.832063) (xy 344.003104 -276.830014)
			(xy 343.95324 -276.819834) (xy 343.905654 -276.801787) (xy 343.86158 -276.776341) (xy 343.822158 -276.744154)
			(xy 343.78841 -276.70606) (xy 343.761209 -276.663046) (xy 343.741261 -276.616226) (xy 343.729082 -276.566812)
			(xy 343.724987 -276.516084) (xy 343.406476 -276.516084) (xy 343.405981 -276.540691) (xy 343.398086 -276.589268)
			(xy 343.382502 -276.635949) (xy 343.359631 -276.679526) (xy 343.330066 -276.71887) (xy 343.294573 -276.752962)
			(xy 343.25407 -276.780918) (xy 343.209608 -276.802016) (xy 343.162337 -276.815708) (xy 343.113482 -276.82164)
			(xy 343.064307 -276.819659) (xy 343.016088 -276.809815) (xy 342.970072 -276.792363) (xy 342.927451 -276.767756)
			(xy 342.88933 -276.736631) (xy 342.856695 -276.699794) (xy 342.830392 -276.658198) (xy 342.811101 -276.612922)
			(xy 342.799324 -276.565138) (xy 342.795364 -276.516084) (xy 342.476836 -276.516084) (xy 342.476324 -276.54153)
			(xy 342.46816 -276.591764) (xy 342.452044 -276.640038) (xy 342.428393 -276.685101) (xy 342.39782 -276.725787)
			(xy 342.361116 -276.761042) (xy 342.319232 -276.789952) (xy 342.273253 -276.811769) (xy 342.224369 -276.825929)
			(xy 342.173848 -276.832063) (xy 342.122996 -276.830014) (xy 342.073132 -276.819834) (xy 342.025546 -276.801787)
			(xy 341.981472 -276.776341) (xy 341.94205 -276.744154) (xy 341.908302 -276.70606) (xy 341.881101 -276.663046)
			(xy 341.861153 -276.616226) (xy 341.848974 -276.566812) (xy 341.844879 -276.516084) (xy 341.529571 -276.516084)
			(xy 341.52699 -276.521964) (xy 341.526114 -276.531324) (xy 341.524388 -276.555684) (xy 341.514168 -276.603436)
			(xy 341.496484 -276.648955) (xy 341.471787 -276.691083) (xy 341.440705 -276.728748) (xy 341.404029 -276.76099)
			(xy 341.38362 -276.774402) (xy 341.375238 -276.779736) (xy 341.364062 -276.794976) (xy 341.361522 -276.804628)
			(xy 341.361522 -276.804882) (xy 341.358982 -276.813518) (xy 341.346005 -276.858676) (xy 341.313471 -276.94683)
			(xy 341.273657 -277.031945) (xy 341.226844 -277.113419) (xy 341.173361 -277.19068) (xy 341.113585 -277.263182)
			(xy 341.081106 -277.297134) (xy 341.074666 -277.304302) (xy 341.067227 -277.32206) (xy 341.066976 -277.32609)
			(xy 341.38541 -277.32609) (xy 341.38937 -277.277036) (xy 341.401147 -277.229252) (xy 341.420438 -277.183976)
			(xy 341.446741 -277.14238) (xy 341.479376 -277.105543) (xy 341.517497 -277.074418) (xy 341.560118 -277.049811)
			(xy 341.606134 -277.032359) (xy 341.654353 -277.022515) (xy 341.703528 -277.020534) (xy 341.752383 -277.026466)
			(xy 341.799654 -277.040158) (xy 341.844116 -277.061256) (xy 341.884619 -277.089212) (xy 341.920112 -277.123304)
			(xy 341.949677 -277.162648) (xy 341.972548 -277.206225) (xy 341.988132 -277.252906) (xy 341.996027 -277.301483)
			(xy 341.996522 -277.32609) (xy 342.314779 -277.32609) (xy 342.318874 -277.275362) (xy 342.331053 -277.225948)
			(xy 342.351001 -277.179128) (xy 342.378202 -277.136114) (xy 342.41195 -277.09802) (xy 342.451372 -277.065833)
			(xy 342.495446 -277.040387) (xy 342.543032 -277.02234) (xy 342.592896 -277.01216) (xy 342.643748 -277.010111)
			(xy 342.694269 -277.016245) (xy 342.743153 -277.030405) (xy 342.789132 -277.052222) (xy 342.831016 -277.081132)
			(xy 342.86772 -277.116387) (xy 342.898293 -277.157073) (xy 342.921944 -277.202136) (xy 342.93806 -277.25041)
			(xy 342.946224 -277.300644) (xy 342.946736 -277.32609) (xy 343.254833 -277.32609) (xy 343.258928 -277.275362)
			(xy 343.271107 -277.225948) (xy 343.291055 -277.179128) (xy 343.318256 -277.136114) (xy 343.352004 -277.09802)
			(xy 343.391426 -277.065833) (xy 343.4355 -277.040387) (xy 343.483086 -277.02234) (xy 343.53295 -277.01216)
			(xy 343.583802 -277.010111) (xy 343.634323 -277.016245) (xy 343.683207 -277.030405) (xy 343.729186 -277.052222)
			(xy 343.77107 -277.081132) (xy 343.807774 -277.116387) (xy 343.838347 -277.157073) (xy 343.861998 -277.202136)
			(xy 343.878114 -277.25041) (xy 343.886278 -277.300644) (xy 343.88679 -277.32609) (xy 344.205318 -277.32609)
			(xy 344.209278 -277.277036) (xy 344.221055 -277.229252) (xy 344.240346 -277.183976) (xy 344.266649 -277.14238)
			(xy 344.299284 -277.105543) (xy 344.337405 -277.074418) (xy 344.380026 -277.049811) (xy 344.426042 -277.032359)
			(xy 344.474261 -277.022515) (xy 344.523436 -277.020534) (xy 344.572291 -277.026466) (xy 344.619562 -277.040158)
			(xy 344.664024 -277.061256) (xy 344.704527 -277.089212) (xy 344.74002 -277.123304) (xy 344.769585 -277.162648)
			(xy 344.792456 -277.206225) (xy 344.80804 -277.252906) (xy 344.815935 -277.301483) (xy 344.81643 -277.32609)
			(xy 345.145372 -277.32609) (xy 345.149332 -277.277036) (xy 345.161109 -277.229252) (xy 345.1804 -277.183976)
			(xy 345.206703 -277.14238) (xy 345.239338 -277.105543) (xy 345.277459 -277.074418) (xy 345.32008 -277.049811)
			(xy 345.366096 -277.032359) (xy 345.414315 -277.022515) (xy 345.46349 -277.020534) (xy 345.512345 -277.026466)
			(xy 345.559616 -277.040158) (xy 345.604078 -277.061256) (xy 345.644581 -277.089212) (xy 345.680074 -277.123304)
			(xy 345.709639 -277.162648) (xy 345.73251 -277.206225) (xy 345.748094 -277.252906) (xy 345.755989 -277.301483)
			(xy 345.756484 -277.32609) (xy 346.085426 -277.32609) (xy 346.089386 -277.277036) (xy 346.101163 -277.229252)
			(xy 346.120454 -277.183976) (xy 346.146757 -277.14238) (xy 346.179392 -277.105543) (xy 346.217513 -277.074418)
			(xy 346.260134 -277.049811) (xy 346.30615 -277.032359) (xy 346.354369 -277.022515) (xy 346.403544 -277.020534)
			(xy 346.452399 -277.026466) (xy 346.49967 -277.040158) (xy 346.544132 -277.061256) (xy 346.584635 -277.089212)
			(xy 346.620128 -277.123304) (xy 346.649693 -277.162648) (xy 346.672564 -277.206225) (xy 346.688148 -277.252906)
			(xy 346.696043 -277.301483) (xy 346.696538 -277.32609) (xy 347.025226 -277.32609) (xy 347.029186 -277.277036)
			(xy 347.040963 -277.229252) (xy 347.060254 -277.183976) (xy 347.086557 -277.14238) (xy 347.119192 -277.105543)
			(xy 347.157313 -277.074418) (xy 347.199934 -277.049811) (xy 347.24595 -277.032359) (xy 347.294169 -277.022515)
			(xy 347.343344 -277.020534) (xy 347.392199 -277.026466) (xy 347.43947 -277.040158) (xy 347.483932 -277.061256)
			(xy 347.524435 -277.089212) (xy 347.559928 -277.123304) (xy 347.589493 -277.162648) (xy 347.612364 -277.206225)
			(xy 347.627948 -277.252906) (xy 347.635843 -277.301483) (xy 347.636338 -277.32609) (xy 347.96528 -277.32609)
			(xy 347.96924 -277.277036) (xy 347.981017 -277.229252) (xy 348.000308 -277.183976) (xy 348.026611 -277.14238)
			(xy 348.059246 -277.105543) (xy 348.097367 -277.074418) (xy 348.139988 -277.049811) (xy 348.186004 -277.032359)
			(xy 348.234223 -277.022515) (xy 348.283398 -277.020534) (xy 348.332253 -277.026466) (xy 348.379524 -277.040158)
			(xy 348.423986 -277.061256) (xy 348.464489 -277.089212) (xy 348.499982 -277.123304) (xy 348.529547 -277.162648)
			(xy 348.552418 -277.206225) (xy 348.568002 -277.252906) (xy 348.575897 -277.301483) (xy 348.576392 -277.32609)
			(xy 348.905334 -277.32609) (xy 348.909294 -277.277036) (xy 348.921071 -277.229252) (xy 348.940362 -277.183976)
			(xy 348.966665 -277.14238) (xy 348.9993 -277.105543) (xy 349.037421 -277.074418) (xy 349.080042 -277.049811)
			(xy 349.126058 -277.032359) (xy 349.174277 -277.022515) (xy 349.223452 -277.020534) (xy 349.272307 -277.026466)
			(xy 349.319578 -277.040158) (xy 349.36404 -277.061256) (xy 349.404543 -277.089212) (xy 349.440036 -277.123304)
			(xy 349.469601 -277.162648) (xy 349.492472 -277.206225) (xy 349.508056 -277.252906) (xy 349.515951 -277.301483)
			(xy 349.516446 -277.32609) (xy 349.845388 -277.32609) (xy 349.849348 -277.277036) (xy 349.861125 -277.229252)
			(xy 349.880416 -277.183976) (xy 349.906719 -277.14238) (xy 349.939354 -277.105543) (xy 349.977475 -277.074418)
			(xy 350.020096 -277.049811) (xy 350.066112 -277.032359) (xy 350.114331 -277.022515) (xy 350.163506 -277.020534)
			(xy 350.212361 -277.026466) (xy 350.259632 -277.040158) (xy 350.304094 -277.061256) (xy 350.344597 -277.089212)
			(xy 350.38009 -277.123304) (xy 350.409655 -277.162648) (xy 350.432526 -277.206225) (xy 350.44811 -277.252906)
			(xy 350.456005 -277.301483) (xy 350.4565 -277.32609) (xy 350.785442 -277.32609) (xy 350.789402 -277.277036)
			(xy 350.801179 -277.229252) (xy 350.82047 -277.183976) (xy 350.846773 -277.14238) (xy 350.879408 -277.105543)
			(xy 350.917529 -277.074418) (xy 350.96015 -277.049811) (xy 351.006166 -277.032359) (xy 351.054385 -277.022515)
			(xy 351.10356 -277.020534) (xy 351.152415 -277.026466) (xy 351.199686 -277.040158) (xy 351.244148 -277.061256)
			(xy 351.284651 -277.089212) (xy 351.320144 -277.123304) (xy 351.349709 -277.162648) (xy 351.37258 -277.206225)
			(xy 351.388164 -277.252906) (xy 351.396059 -277.301483) (xy 351.396554 -277.32609) (xy 351.725242 -277.32609)
			(xy 351.729202 -277.277036) (xy 351.740979 -277.229252) (xy 351.76027 -277.183976) (xy 351.786573 -277.14238)
			(xy 351.819208 -277.105543) (xy 351.857329 -277.074418) (xy 351.89995 -277.049811) (xy 351.945966 -277.032359)
			(xy 351.994185 -277.022515) (xy 352.04336 -277.020534) (xy 352.092215 -277.026466) (xy 352.139486 -277.040158)
			(xy 352.183948 -277.061256) (xy 352.224451 -277.089212) (xy 352.259944 -277.123304) (xy 352.289509 -277.162648)
			(xy 352.31238 -277.206225) (xy 352.327964 -277.252906) (xy 352.335859 -277.301483) (xy 352.336354 -277.32609)
			(xy 352.665296 -277.32609) (xy 352.669256 -277.277036) (xy 352.681033 -277.229252) (xy 352.700324 -277.183976)
			(xy 352.726627 -277.14238) (xy 352.759262 -277.105543) (xy 352.797383 -277.074418) (xy 352.840004 -277.049811)
			(xy 352.88602 -277.032359) (xy 352.934239 -277.022515) (xy 352.983414 -277.020534) (xy 353.032269 -277.026466)
			(xy 353.07954 -277.040158) (xy 353.124002 -277.061256) (xy 353.164505 -277.089212) (xy 353.199998 -277.123304)
			(xy 353.229563 -277.162648) (xy 353.252434 -277.206225) (xy 353.268018 -277.252906) (xy 353.275913 -277.301483)
			(xy 353.276408 -277.32609) (xy 353.60535 -277.32609) (xy 353.60931 -277.277036) (xy 353.621087 -277.229252)
			(xy 353.640378 -277.183976) (xy 353.666681 -277.14238) (xy 353.699316 -277.105543) (xy 353.737437 -277.074418)
			(xy 353.780058 -277.049811) (xy 353.826074 -277.032359) (xy 353.874293 -277.022515) (xy 353.923468 -277.020534)
			(xy 353.972323 -277.026466) (xy 354.019594 -277.040158) (xy 354.064056 -277.061256) (xy 354.104559 -277.089212)
			(xy 354.140052 -277.123304) (xy 354.169617 -277.162648) (xy 354.192488 -277.206225) (xy 354.208072 -277.252906)
			(xy 354.215967 -277.301483) (xy 354.216462 -277.32609) (xy 354.545404 -277.32609) (xy 354.549364 -277.277036)
			(xy 354.561141 -277.229252) (xy 354.580432 -277.183976) (xy 354.606735 -277.14238) (xy 354.63937 -277.105543)
			(xy 354.677491 -277.074418) (xy 354.720112 -277.049811) (xy 354.766128 -277.032359) (xy 354.814347 -277.022515)
			(xy 354.863522 -277.020534) (xy 354.912377 -277.026466) (xy 354.959648 -277.040158) (xy 355.00411 -277.061256)
			(xy 355.044613 -277.089212) (xy 355.080106 -277.123304) (xy 355.109671 -277.162648) (xy 355.132542 -277.206225)
			(xy 355.148126 -277.252906) (xy 355.156021 -277.301483) (xy 355.156516 -277.32609) (xy 355.485204 -277.32609)
			(xy 355.489164 -277.277036) (xy 355.500941 -277.229252) (xy 355.520232 -277.183976) (xy 355.546535 -277.14238)
			(xy 355.57917 -277.105543) (xy 355.617291 -277.074418) (xy 355.659912 -277.049811) (xy 355.705928 -277.032359)
			(xy 355.754147 -277.022515) (xy 355.803322 -277.020534) (xy 355.852177 -277.026466) (xy 355.899448 -277.040158)
			(xy 355.94391 -277.061256) (xy 355.984413 -277.089212) (xy 356.019906 -277.123304) (xy 356.049471 -277.162648)
			(xy 356.072342 -277.206225) (xy 356.087926 -277.252906) (xy 356.095821 -277.301483) (xy 356.096316 -277.32609)
			(xy 356.425258 -277.32609) (xy 356.429218 -277.277036) (xy 356.440995 -277.229252) (xy 356.460286 -277.183976)
			(xy 356.486589 -277.14238) (xy 356.519224 -277.105543) (xy 356.557345 -277.074418) (xy 356.599966 -277.049811)
			(xy 356.645982 -277.032359) (xy 356.694201 -277.022515) (xy 356.743376 -277.020534) (xy 356.792231 -277.026466)
			(xy 356.839502 -277.040158) (xy 356.883964 -277.061256) (xy 356.924467 -277.089212) (xy 356.95996 -277.123304)
			(xy 356.989525 -277.162648) (xy 357.012396 -277.206225) (xy 357.02798 -277.252906) (xy 357.035875 -277.301483)
			(xy 357.03637 -277.32609) (xy 357.365312 -277.32609) (xy 357.369272 -277.277036) (xy 357.381049 -277.229252)
			(xy 357.40034 -277.183976) (xy 357.426643 -277.14238) (xy 357.459278 -277.105543) (xy 357.497399 -277.074418)
			(xy 357.54002 -277.049811) (xy 357.586036 -277.032359) (xy 357.634255 -277.022515) (xy 357.68343 -277.020534)
			(xy 357.732285 -277.026466) (xy 357.779556 -277.040158) (xy 357.824018 -277.061256) (xy 357.864521 -277.089212)
			(xy 357.900014 -277.123304) (xy 357.929579 -277.162648) (xy 357.95245 -277.206225) (xy 357.968034 -277.252906)
			(xy 357.975929 -277.301483) (xy 357.976424 -277.32609) (xy 358.305366 -277.32609) (xy 358.309326 -277.277036)
			(xy 358.321103 -277.229252) (xy 358.340394 -277.183976) (xy 358.366697 -277.14238) (xy 358.399332 -277.105543)
			(xy 358.437453 -277.074418) (xy 358.480074 -277.049811) (xy 358.52609 -277.032359) (xy 358.574309 -277.022515)
			(xy 358.623484 -277.020534) (xy 358.672339 -277.026466) (xy 358.71961 -277.040158) (xy 358.764072 -277.061256)
			(xy 358.804575 -277.089212) (xy 358.840068 -277.123304) (xy 358.869633 -277.162648) (xy 358.892504 -277.206225)
			(xy 358.908088 -277.252906) (xy 358.915983 -277.301483) (xy 358.916478 -277.32609) (xy 361.118924 -277.32609)
			(xy 361.122884 -277.277036) (xy 361.134661 -277.229252) (xy 361.153952 -277.183976) (xy 361.180255 -277.14238)
			(xy 361.21289 -277.105543) (xy 361.251011 -277.074418) (xy 361.293632 -277.049811) (xy 361.339648 -277.032359)
			(xy 361.387867 -277.022515) (xy 361.437042 -277.020534) (xy 361.485897 -277.026466) (xy 361.533168 -277.040158)
			(xy 361.57763 -277.061256) (xy 361.618133 -277.089212) (xy 361.653626 -277.123304) (xy 361.683191 -277.162648)
			(xy 361.706062 -277.206225) (xy 361.721646 -277.252906) (xy 361.729541 -277.301483) (xy 361.730036 -277.32609)
			(xy 362.058978 -277.32609) (xy 362.062938 -277.277036) (xy 362.074715 -277.229252) (xy 362.094006 -277.183976)
			(xy 362.120309 -277.14238) (xy 362.152944 -277.105543) (xy 362.191065 -277.074418) (xy 362.233686 -277.049811)
			(xy 362.279702 -277.032359) (xy 362.327921 -277.022515) (xy 362.377096 -277.020534) (xy 362.425951 -277.026466)
			(xy 362.473222 -277.040158) (xy 362.517684 -277.061256) (xy 362.558187 -277.089212) (xy 362.59368 -277.123304)
			(xy 362.623245 -277.162648) (xy 362.646116 -277.206225) (xy 362.6617 -277.252906) (xy 362.669595 -277.301483)
			(xy 362.67009 -277.32609) (xy 362.999032 -277.32609) (xy 363.002992 -277.277036) (xy 363.014769 -277.229252)
			(xy 363.03406 -277.183976) (xy 363.060363 -277.14238) (xy 363.092998 -277.105543) (xy 363.131119 -277.074418)
			(xy 363.17374 -277.049811) (xy 363.219756 -277.032359) (xy 363.267975 -277.022515) (xy 363.31715 -277.020534)
			(xy 363.366005 -277.026466) (xy 363.413276 -277.040158) (xy 363.457738 -277.061256) (xy 363.498241 -277.089212)
			(xy 363.533734 -277.123304) (xy 363.563299 -277.162648) (xy 363.58617 -277.206225) (xy 363.601754 -277.252906)
			(xy 363.609649 -277.301483) (xy 363.610144 -277.32609) (xy 363.939086 -277.32609) (xy 363.943046 -277.277036)
			(xy 363.954823 -277.229252) (xy 363.974114 -277.183976) (xy 364.000417 -277.14238) (xy 364.033052 -277.105543)
			(xy 364.071173 -277.074418) (xy 364.113794 -277.049811) (xy 364.15981 -277.032359) (xy 364.208029 -277.022515)
			(xy 364.257204 -277.020534) (xy 364.306059 -277.026466) (xy 364.35333 -277.040158) (xy 364.397792 -277.061256)
			(xy 364.438295 -277.089212) (xy 364.473788 -277.123304) (xy 364.503353 -277.162648) (xy 364.526224 -277.206225)
			(xy 364.541808 -277.252906) (xy 364.549703 -277.301483) (xy 364.550198 -277.32609) (xy 364.878886 -277.32609)
			(xy 364.882846 -277.277036) (xy 364.894623 -277.229252) (xy 364.913914 -277.183976) (xy 364.940217 -277.14238)
			(xy 364.972852 -277.105543) (xy 365.010973 -277.074418) (xy 365.053594 -277.049811) (xy 365.09961 -277.032359)
			(xy 365.147829 -277.022515) (xy 365.197004 -277.020534) (xy 365.245859 -277.026466) (xy 365.29313 -277.040158)
			(xy 365.337592 -277.061256) (xy 365.378095 -277.089212) (xy 365.413588 -277.123304) (xy 365.443153 -277.162648)
			(xy 365.466024 -277.206225) (xy 365.481608 -277.252906) (xy 365.489503 -277.301483) (xy 365.489998 -277.32609)
			(xy 365.81894 -277.32609) (xy 365.8229 -277.277036) (xy 365.834677 -277.229252) (xy 365.853968 -277.183976)
			(xy 365.880271 -277.14238) (xy 365.912906 -277.105543) (xy 365.951027 -277.074418) (xy 365.993648 -277.049811)
			(xy 366.039664 -277.032359) (xy 366.087883 -277.022515) (xy 366.137058 -277.020534) (xy 366.185913 -277.026466)
			(xy 366.233184 -277.040158) (xy 366.277646 -277.061256) (xy 366.318149 -277.089212) (xy 366.353642 -277.123304)
			(xy 366.383207 -277.162648) (xy 366.406078 -277.206225) (xy 366.421662 -277.252906) (xy 366.429557 -277.301483)
			(xy 366.430052 -277.32609) (xy 366.758994 -277.32609) (xy 366.762954 -277.277036) (xy 366.774731 -277.229252)
			(xy 366.794022 -277.183976) (xy 366.820325 -277.14238) (xy 366.85296 -277.105543) (xy 366.891081 -277.074418)
			(xy 366.933702 -277.049811) (xy 366.979718 -277.032359) (xy 367.027937 -277.022515) (xy 367.077112 -277.020534)
			(xy 367.125967 -277.026466) (xy 367.173238 -277.040158) (xy 367.2177 -277.061256) (xy 367.258203 -277.089212)
			(xy 367.293696 -277.123304) (xy 367.323261 -277.162648) (xy 367.346132 -277.206225) (xy 367.361716 -277.252906)
			(xy 367.369611 -277.301483) (xy 367.370106 -277.32609) (xy 367.699048 -277.32609) (xy 367.703008 -277.277036)
			(xy 367.714785 -277.229252) (xy 367.734076 -277.183976) (xy 367.760379 -277.14238) (xy 367.793014 -277.105543)
			(xy 367.831135 -277.074418) (xy 367.873756 -277.049811) (xy 367.919772 -277.032359) (xy 367.967991 -277.022515)
			(xy 368.017166 -277.020534) (xy 368.066021 -277.026466) (xy 368.113292 -277.040158) (xy 368.157754 -277.061256)
			(xy 368.198257 -277.089212) (xy 368.23375 -277.123304) (xy 368.263315 -277.162648) (xy 368.286186 -277.206225)
			(xy 368.30177 -277.252906) (xy 368.309665 -277.301483) (xy 368.31016 -277.32609) (xy 368.639102 -277.32609)
			(xy 368.643062 -277.277036) (xy 368.654839 -277.229252) (xy 368.67413 -277.183976) (xy 368.700433 -277.14238)
			(xy 368.733068 -277.105543) (xy 368.771189 -277.074418) (xy 368.81381 -277.049811) (xy 368.859826 -277.032359)
			(xy 368.908045 -277.022515) (xy 368.95722 -277.020534) (xy 369.006075 -277.026466) (xy 369.053346 -277.040158)
			(xy 369.097808 -277.061256) (xy 369.138311 -277.089212) (xy 369.173804 -277.123304) (xy 369.203369 -277.162648)
			(xy 369.22624 -277.206225) (xy 369.241824 -277.252906) (xy 369.249719 -277.301483) (xy 369.250214 -277.32609)
			(xy 369.578902 -277.32609) (xy 369.582862 -277.277036) (xy 369.594639 -277.229252) (xy 369.61393 -277.183976)
			(xy 369.640233 -277.14238) (xy 369.672868 -277.105543) (xy 369.710989 -277.074418) (xy 369.75361 -277.049811)
			(xy 369.799626 -277.032359) (xy 369.847845 -277.022515) (xy 369.89702 -277.020534) (xy 369.945875 -277.026466)
			(xy 369.993146 -277.040158) (xy 370.037608 -277.061256) (xy 370.078111 -277.089212) (xy 370.113604 -277.123304)
			(xy 370.143169 -277.162648) (xy 370.16604 -277.206225) (xy 370.181624 -277.252906) (xy 370.189519 -277.301483)
			(xy 370.190014 -277.32609) (xy 370.518956 -277.32609) (xy 370.522916 -277.277036) (xy 370.534693 -277.229252)
			(xy 370.553984 -277.183976) (xy 370.580287 -277.14238) (xy 370.612922 -277.105543) (xy 370.651043 -277.074418)
			(xy 370.693664 -277.049811) (xy 370.73968 -277.032359) (xy 370.787899 -277.022515) (xy 370.837074 -277.020534)
			(xy 370.885929 -277.026466) (xy 370.9332 -277.040158) (xy 370.977662 -277.061256) (xy 371.018165 -277.089212)
			(xy 371.053658 -277.123304) (xy 371.083223 -277.162648) (xy 371.106094 -277.206225) (xy 371.121678 -277.252906)
			(xy 371.129573 -277.301483) (xy 371.130068 -277.32609) (xy 371.45901 -277.32609) (xy 371.46297 -277.277036)
			(xy 371.474747 -277.229252) (xy 371.494038 -277.183976) (xy 371.520341 -277.14238) (xy 371.552976 -277.105543)
			(xy 371.591097 -277.074418) (xy 371.633718 -277.049811) (xy 371.679734 -277.032359) (xy 371.727953 -277.022515)
			(xy 371.777128 -277.020534) (xy 371.825983 -277.026466) (xy 371.873254 -277.040158) (xy 371.917716 -277.061256)
			(xy 371.958219 -277.089212) (xy 371.993712 -277.123304) (xy 372.023277 -277.162648) (xy 372.046148 -277.206225)
			(xy 372.061732 -277.252906) (xy 372.069627 -277.301483) (xy 372.070122 -277.32609) (xy 372.399064 -277.32609)
			(xy 372.403024 -277.277036) (xy 372.414801 -277.229252) (xy 372.434092 -277.183976) (xy 372.460395 -277.14238)
			(xy 372.49303 -277.105543) (xy 372.531151 -277.074418) (xy 372.573772 -277.049811) (xy 372.619788 -277.032359)
			(xy 372.668007 -277.022515) (xy 372.717182 -277.020534) (xy 372.766037 -277.026466) (xy 372.813308 -277.040158)
			(xy 372.85777 -277.061256) (xy 372.898273 -277.089212) (xy 372.933766 -277.123304) (xy 372.963331 -277.162648)
			(xy 372.986202 -277.206225) (xy 373.001786 -277.252906) (xy 373.009681 -277.301483) (xy 373.010176 -277.32609)
			(xy 373.339118 -277.32609) (xy 373.343078 -277.277036) (xy 373.354855 -277.229252) (xy 373.374146 -277.183976)
			(xy 373.400449 -277.14238) (xy 373.433084 -277.105543) (xy 373.471205 -277.074418) (xy 373.513826 -277.049811)
			(xy 373.559842 -277.032359) (xy 373.608061 -277.022515) (xy 373.657236 -277.020534) (xy 373.706091 -277.026466)
			(xy 373.753362 -277.040158) (xy 373.797824 -277.061256) (xy 373.838327 -277.089212) (xy 373.87382 -277.123304)
			(xy 373.903385 -277.162648) (xy 373.926256 -277.206225) (xy 373.94184 -277.252906) (xy 373.949735 -277.301483)
			(xy 373.95023 -277.32609) (xy 373.949735 -277.350697) (xy 373.94184 -277.399274) (xy 373.926256 -277.445955)
			(xy 373.903385 -277.489532) (xy 373.87382 -277.528876) (xy 373.838327 -277.562968) (xy 373.797824 -277.590924)
			(xy 373.753362 -277.612022) (xy 373.706091 -277.625714) (xy 373.657236 -277.631646) (xy 373.608061 -277.629665)
			(xy 373.559842 -277.619821) (xy 373.513826 -277.602369) (xy 373.471205 -277.577762) (xy 373.433084 -277.546637)
			(xy 373.400449 -277.5098) (xy 373.374146 -277.468204) (xy 373.354855 -277.422928) (xy 373.343078 -277.375144)
			(xy 373.339118 -277.32609) (xy 373.010176 -277.32609) (xy 373.009681 -277.350697) (xy 373.001786 -277.399274)
			(xy 372.986202 -277.445955) (xy 372.963331 -277.489532) (xy 372.933766 -277.528876) (xy 372.898273 -277.562968)
			(xy 372.85777 -277.590924) (xy 372.813308 -277.612022) (xy 372.766037 -277.625714) (xy 372.717182 -277.631646)
			(xy 372.668007 -277.629665) (xy 372.619788 -277.619821) (xy 372.573772 -277.602369) (xy 372.531151 -277.577762)
			(xy 372.49303 -277.546637) (xy 372.460395 -277.5098) (xy 372.434092 -277.468204) (xy 372.414801 -277.422928)
			(xy 372.403024 -277.375144) (xy 372.399064 -277.32609) (xy 372.070122 -277.32609) (xy 372.069627 -277.350697)
			(xy 372.061732 -277.399274) (xy 372.046148 -277.445955) (xy 372.023277 -277.489532) (xy 371.993712 -277.528876)
			(xy 371.958219 -277.562968) (xy 371.917716 -277.590924) (xy 371.873254 -277.612022) (xy 371.825983 -277.625714)
			(xy 371.777128 -277.631646) (xy 371.727953 -277.629665) (xy 371.679734 -277.619821) (xy 371.633718 -277.602369)
			(xy 371.591097 -277.577762) (xy 371.552976 -277.546637) (xy 371.520341 -277.5098) (xy 371.494038 -277.468204)
			(xy 371.474747 -277.422928) (xy 371.46297 -277.375144) (xy 371.45901 -277.32609) (xy 371.130068 -277.32609)
			(xy 371.129573 -277.350697) (xy 371.121678 -277.399274) (xy 371.106094 -277.445955) (xy 371.083223 -277.489532)
			(xy 371.053658 -277.528876) (xy 371.018165 -277.562968) (xy 370.977662 -277.590924) (xy 370.9332 -277.612022)
			(xy 370.885929 -277.625714) (xy 370.837074 -277.631646) (xy 370.787899 -277.629665) (xy 370.73968 -277.619821)
			(xy 370.693664 -277.602369) (xy 370.651043 -277.577762) (xy 370.612922 -277.546637) (xy 370.580287 -277.5098)
			(xy 370.553984 -277.468204) (xy 370.534693 -277.422928) (xy 370.522916 -277.375144) (xy 370.518956 -277.32609)
			(xy 370.190014 -277.32609) (xy 370.189519 -277.350697) (xy 370.181624 -277.399274) (xy 370.16604 -277.445955)
			(xy 370.143169 -277.489532) (xy 370.113604 -277.528876) (xy 370.078111 -277.562968) (xy 370.037608 -277.590924)
			(xy 369.993146 -277.612022) (xy 369.945875 -277.625714) (xy 369.89702 -277.631646) (xy 369.847845 -277.629665)
			(xy 369.799626 -277.619821) (xy 369.75361 -277.602369) (xy 369.710989 -277.577762) (xy 369.672868 -277.546637)
			(xy 369.640233 -277.5098) (xy 369.61393 -277.468204) (xy 369.594639 -277.422928) (xy 369.582862 -277.375144)
			(xy 369.578902 -277.32609) (xy 369.250214 -277.32609) (xy 369.249719 -277.350697) (xy 369.241824 -277.399274)
			(xy 369.22624 -277.445955) (xy 369.203369 -277.489532) (xy 369.173804 -277.528876) (xy 369.138311 -277.562968)
			(xy 369.097808 -277.590924) (xy 369.053346 -277.612022) (xy 369.006075 -277.625714) (xy 368.95722 -277.631646)
			(xy 368.908045 -277.629665) (xy 368.859826 -277.619821) (xy 368.81381 -277.602369) (xy 368.771189 -277.577762)
			(xy 368.733068 -277.546637) (xy 368.700433 -277.5098) (xy 368.67413 -277.468204) (xy 368.654839 -277.422928)
			(xy 368.643062 -277.375144) (xy 368.639102 -277.32609) (xy 368.31016 -277.32609) (xy 368.309665 -277.350697)
			(xy 368.30177 -277.399274) (xy 368.286186 -277.445955) (xy 368.263315 -277.489532) (xy 368.23375 -277.528876)
			(xy 368.198257 -277.562968) (xy 368.157754 -277.590924) (xy 368.113292 -277.612022) (xy 368.066021 -277.625714)
			(xy 368.017166 -277.631646) (xy 367.967991 -277.629665) (xy 367.919772 -277.619821) (xy 367.873756 -277.602369)
			(xy 367.831135 -277.577762) (xy 367.793014 -277.546637) (xy 367.760379 -277.5098) (xy 367.734076 -277.468204)
			(xy 367.714785 -277.422928) (xy 367.703008 -277.375144) (xy 367.699048 -277.32609) (xy 367.370106 -277.32609)
			(xy 367.369611 -277.350697) (xy 367.361716 -277.399274) (xy 367.346132 -277.445955) (xy 367.323261 -277.489532)
			(xy 367.293696 -277.528876) (xy 367.258203 -277.562968) (xy 367.2177 -277.590924) (xy 367.173238 -277.612022)
			(xy 367.125967 -277.625714) (xy 367.077112 -277.631646) (xy 367.027937 -277.629665) (xy 366.979718 -277.619821)
			(xy 366.933702 -277.602369) (xy 366.891081 -277.577762) (xy 366.85296 -277.546637) (xy 366.820325 -277.5098)
			(xy 366.794022 -277.468204) (xy 366.774731 -277.422928) (xy 366.762954 -277.375144) (xy 366.758994 -277.32609)
			(xy 366.430052 -277.32609) (xy 366.429557 -277.350697) (xy 366.421662 -277.399274) (xy 366.406078 -277.445955)
			(xy 366.383207 -277.489532) (xy 366.353642 -277.528876) (xy 366.318149 -277.562968) (xy 366.277646 -277.590924)
			(xy 366.233184 -277.612022) (xy 366.185913 -277.625714) (xy 366.137058 -277.631646) (xy 366.087883 -277.629665)
			(xy 366.039664 -277.619821) (xy 365.993648 -277.602369) (xy 365.951027 -277.577762) (xy 365.912906 -277.546637)
			(xy 365.880271 -277.5098) (xy 365.853968 -277.468204) (xy 365.834677 -277.422928) (xy 365.8229 -277.375144)
			(xy 365.81894 -277.32609) (xy 365.489998 -277.32609) (xy 365.489503 -277.350697) (xy 365.481608 -277.399274)
			(xy 365.466024 -277.445955) (xy 365.443153 -277.489532) (xy 365.413588 -277.528876) (xy 365.378095 -277.562968)
			(xy 365.337592 -277.590924) (xy 365.29313 -277.612022) (xy 365.245859 -277.625714) (xy 365.197004 -277.631646)
			(xy 365.147829 -277.629665) (xy 365.09961 -277.619821) (xy 365.053594 -277.602369) (xy 365.010973 -277.577762)
			(xy 364.972852 -277.546637) (xy 364.940217 -277.5098) (xy 364.913914 -277.468204) (xy 364.894623 -277.422928)
			(xy 364.882846 -277.375144) (xy 364.878886 -277.32609) (xy 364.550198 -277.32609) (xy 364.549703 -277.350697)
			(xy 364.541808 -277.399274) (xy 364.526224 -277.445955) (xy 364.503353 -277.489532) (xy 364.473788 -277.528876)
			(xy 364.438295 -277.562968) (xy 364.397792 -277.590924) (xy 364.35333 -277.612022) (xy 364.306059 -277.625714)
			(xy 364.257204 -277.631646) (xy 364.208029 -277.629665) (xy 364.15981 -277.619821) (xy 364.113794 -277.602369)
			(xy 364.071173 -277.577762) (xy 364.033052 -277.546637) (xy 364.000417 -277.5098) (xy 363.974114 -277.468204)
			(xy 363.954823 -277.422928) (xy 363.943046 -277.375144) (xy 363.939086 -277.32609) (xy 363.610144 -277.32609)
			(xy 363.609649 -277.350697) (xy 363.601754 -277.399274) (xy 363.58617 -277.445955) (xy 363.563299 -277.489532)
			(xy 363.533734 -277.528876) (xy 363.498241 -277.562968) (xy 363.457738 -277.590924) (xy 363.413276 -277.612022)
			(xy 363.366005 -277.625714) (xy 363.31715 -277.631646) (xy 363.267975 -277.629665) (xy 363.219756 -277.619821)
			(xy 363.17374 -277.602369) (xy 363.131119 -277.577762) (xy 363.092998 -277.546637) (xy 363.060363 -277.5098)
			(xy 363.03406 -277.468204) (xy 363.014769 -277.422928) (xy 363.002992 -277.375144) (xy 362.999032 -277.32609)
			(xy 362.67009 -277.32609) (xy 362.669595 -277.350697) (xy 362.6617 -277.399274) (xy 362.646116 -277.445955)
			(xy 362.623245 -277.489532) (xy 362.59368 -277.528876) (xy 362.558187 -277.562968) (xy 362.517684 -277.590924)
			(xy 362.473222 -277.612022) (xy 362.425951 -277.625714) (xy 362.377096 -277.631646) (xy 362.327921 -277.629665)
			(xy 362.279702 -277.619821) (xy 362.233686 -277.602369) (xy 362.191065 -277.577762) (xy 362.152944 -277.546637)
			(xy 362.120309 -277.5098) (xy 362.094006 -277.468204) (xy 362.074715 -277.422928) (xy 362.062938 -277.375144)
			(xy 362.058978 -277.32609) (xy 361.730036 -277.32609) (xy 361.729541 -277.350697) (xy 361.721646 -277.399274)
			(xy 361.706062 -277.445955) (xy 361.683191 -277.489532) (xy 361.653626 -277.528876) (xy 361.618133 -277.562968)
			(xy 361.57763 -277.590924) (xy 361.533168 -277.612022) (xy 361.485897 -277.625714) (xy 361.437042 -277.631646)
			(xy 361.387867 -277.629665) (xy 361.339648 -277.619821) (xy 361.293632 -277.602369) (xy 361.251011 -277.577762)
			(xy 361.21289 -277.546637) (xy 361.180255 -277.5098) (xy 361.153952 -277.468204) (xy 361.134661 -277.422928)
			(xy 361.122884 -277.375144) (xy 361.118924 -277.32609) (xy 358.916478 -277.32609) (xy 358.915983 -277.350697)
			(xy 358.908088 -277.399274) (xy 358.892504 -277.445955) (xy 358.869633 -277.489532) (xy 358.840068 -277.528876)
			(xy 358.804575 -277.562968) (xy 358.764072 -277.590924) (xy 358.71961 -277.612022) (xy 358.672339 -277.625714)
			(xy 358.623484 -277.631646) (xy 358.574309 -277.629665) (xy 358.52609 -277.619821) (xy 358.480074 -277.602369)
			(xy 358.437453 -277.577762) (xy 358.399332 -277.546637) (xy 358.366697 -277.5098) (xy 358.340394 -277.468204)
			(xy 358.321103 -277.422928) (xy 358.309326 -277.375144) (xy 358.305366 -277.32609) (xy 357.976424 -277.32609)
			(xy 357.975929 -277.350697) (xy 357.968034 -277.399274) (xy 357.95245 -277.445955) (xy 357.929579 -277.489532)
			(xy 357.900014 -277.528876) (xy 357.864521 -277.562968) (xy 357.824018 -277.590924) (xy 357.779556 -277.612022)
			(xy 357.732285 -277.625714) (xy 357.68343 -277.631646) (xy 357.634255 -277.629665) (xy 357.586036 -277.619821)
			(xy 357.54002 -277.602369) (xy 357.497399 -277.577762) (xy 357.459278 -277.546637) (xy 357.426643 -277.5098)
			(xy 357.40034 -277.468204) (xy 357.381049 -277.422928) (xy 357.369272 -277.375144) (xy 357.365312 -277.32609)
			(xy 357.03637 -277.32609) (xy 357.035875 -277.350697) (xy 357.02798 -277.399274) (xy 357.012396 -277.445955)
			(xy 356.989525 -277.489532) (xy 356.95996 -277.528876) (xy 356.924467 -277.562968) (xy 356.883964 -277.590924)
			(xy 356.839502 -277.612022) (xy 356.792231 -277.625714) (xy 356.743376 -277.631646) (xy 356.694201 -277.629665)
			(xy 356.645982 -277.619821) (xy 356.599966 -277.602369) (xy 356.557345 -277.577762) (xy 356.519224 -277.546637)
			(xy 356.486589 -277.5098) (xy 356.460286 -277.468204) (xy 356.440995 -277.422928) (xy 356.429218 -277.375144)
			(xy 356.425258 -277.32609) (xy 356.096316 -277.32609) (xy 356.095821 -277.350697) (xy 356.087926 -277.399274)
			(xy 356.072342 -277.445955) (xy 356.049471 -277.489532) (xy 356.019906 -277.528876) (xy 355.984413 -277.562968)
			(xy 355.94391 -277.590924) (xy 355.899448 -277.612022) (xy 355.852177 -277.625714) (xy 355.803322 -277.631646)
			(xy 355.754147 -277.629665) (xy 355.705928 -277.619821) (xy 355.659912 -277.602369) (xy 355.617291 -277.577762)
			(xy 355.57917 -277.546637) (xy 355.546535 -277.5098) (xy 355.520232 -277.468204) (xy 355.500941 -277.422928)
			(xy 355.489164 -277.375144) (xy 355.485204 -277.32609) (xy 355.156516 -277.32609) (xy 355.156021 -277.350697)
			(xy 355.148126 -277.399274) (xy 355.132542 -277.445955) (xy 355.109671 -277.489532) (xy 355.080106 -277.528876)
			(xy 355.044613 -277.562968) (xy 355.00411 -277.590924) (xy 354.959648 -277.612022) (xy 354.912377 -277.625714)
			(xy 354.863522 -277.631646) (xy 354.814347 -277.629665) (xy 354.766128 -277.619821) (xy 354.720112 -277.602369)
			(xy 354.677491 -277.577762) (xy 354.63937 -277.546637) (xy 354.606735 -277.5098) (xy 354.580432 -277.468204)
			(xy 354.561141 -277.422928) (xy 354.549364 -277.375144) (xy 354.545404 -277.32609) (xy 354.216462 -277.32609)
			(xy 354.215967 -277.350697) (xy 354.208072 -277.399274) (xy 354.192488 -277.445955) (xy 354.169617 -277.489532)
			(xy 354.140052 -277.528876) (xy 354.104559 -277.562968) (xy 354.064056 -277.590924) (xy 354.019594 -277.612022)
			(xy 353.972323 -277.625714) (xy 353.923468 -277.631646) (xy 353.874293 -277.629665) (xy 353.826074 -277.619821)
			(xy 353.780058 -277.602369) (xy 353.737437 -277.577762) (xy 353.699316 -277.546637) (xy 353.666681 -277.5098)
			(xy 353.640378 -277.468204) (xy 353.621087 -277.422928) (xy 353.60931 -277.375144) (xy 353.60535 -277.32609)
			(xy 353.276408 -277.32609) (xy 353.275913 -277.350697) (xy 353.268018 -277.399274) (xy 353.252434 -277.445955)
			(xy 353.229563 -277.489532) (xy 353.199998 -277.528876) (xy 353.164505 -277.562968) (xy 353.124002 -277.590924)
			(xy 353.07954 -277.612022) (xy 353.032269 -277.625714) (xy 352.983414 -277.631646) (xy 352.934239 -277.629665)
			(xy 352.88602 -277.619821) (xy 352.840004 -277.602369) (xy 352.797383 -277.577762) (xy 352.759262 -277.546637)
			(xy 352.726627 -277.5098) (xy 352.700324 -277.468204) (xy 352.681033 -277.422928) (xy 352.669256 -277.375144)
			(xy 352.665296 -277.32609) (xy 352.336354 -277.32609) (xy 352.335859 -277.350697) (xy 352.327964 -277.399274)
			(xy 352.31238 -277.445955) (xy 352.289509 -277.489532) (xy 352.259944 -277.528876) (xy 352.224451 -277.562968)
			(xy 352.183948 -277.590924) (xy 352.139486 -277.612022) (xy 352.092215 -277.625714) (xy 352.04336 -277.631646)
			(xy 351.994185 -277.629665) (xy 351.945966 -277.619821) (xy 351.89995 -277.602369) (xy 351.857329 -277.577762)
			(xy 351.819208 -277.546637) (xy 351.786573 -277.5098) (xy 351.76027 -277.468204) (xy 351.740979 -277.422928)
			(xy 351.729202 -277.375144) (xy 351.725242 -277.32609) (xy 351.396554 -277.32609) (xy 351.396059 -277.350697)
			(xy 351.388164 -277.399274) (xy 351.37258 -277.445955) (xy 351.349709 -277.489532) (xy 351.320144 -277.528876)
			(xy 351.284651 -277.562968) (xy 351.244148 -277.590924) (xy 351.199686 -277.612022) (xy 351.152415 -277.625714)
			(xy 351.10356 -277.631646) (xy 351.054385 -277.629665) (xy 351.006166 -277.619821) (xy 350.96015 -277.602369)
			(xy 350.917529 -277.577762) (xy 350.879408 -277.546637) (xy 350.846773 -277.5098) (xy 350.82047 -277.468204)
			(xy 350.801179 -277.422928) (xy 350.789402 -277.375144) (xy 350.785442 -277.32609) (xy 350.4565 -277.32609)
			(xy 350.456005 -277.350697) (xy 350.44811 -277.399274) (xy 350.432526 -277.445955) (xy 350.409655 -277.489532)
			(xy 350.38009 -277.528876) (xy 350.344597 -277.562968) (xy 350.304094 -277.590924) (xy 350.259632 -277.612022)
			(xy 350.212361 -277.625714) (xy 350.163506 -277.631646) (xy 350.114331 -277.629665) (xy 350.066112 -277.619821)
			(xy 350.020096 -277.602369) (xy 349.977475 -277.577762) (xy 349.939354 -277.546637) (xy 349.906719 -277.5098)
			(xy 349.880416 -277.468204) (xy 349.861125 -277.422928) (xy 349.849348 -277.375144) (xy 349.845388 -277.32609)
			(xy 349.516446 -277.32609) (xy 349.515951 -277.350697) (xy 349.508056 -277.399274) (xy 349.492472 -277.445955)
			(xy 349.469601 -277.489532) (xy 349.440036 -277.528876) (xy 349.404543 -277.562968) (xy 349.36404 -277.590924)
			(xy 349.319578 -277.612022) (xy 349.272307 -277.625714) (xy 349.223452 -277.631646) (xy 349.174277 -277.629665)
			(xy 349.126058 -277.619821) (xy 349.080042 -277.602369) (xy 349.037421 -277.577762) (xy 348.9993 -277.546637)
			(xy 348.966665 -277.5098) (xy 348.940362 -277.468204) (xy 348.921071 -277.422928) (xy 348.909294 -277.375144)
			(xy 348.905334 -277.32609) (xy 348.576392 -277.32609) (xy 348.575897 -277.350697) (xy 348.568002 -277.399274)
			(xy 348.552418 -277.445955) (xy 348.529547 -277.489532) (xy 348.499982 -277.528876) (xy 348.464489 -277.562968)
			(xy 348.423986 -277.590924) (xy 348.379524 -277.612022) (xy 348.332253 -277.625714) (xy 348.283398 -277.631646)
			(xy 348.234223 -277.629665) (xy 348.186004 -277.619821) (xy 348.139988 -277.602369) (xy 348.097367 -277.577762)
			(xy 348.059246 -277.546637) (xy 348.026611 -277.5098) (xy 348.000308 -277.468204) (xy 347.981017 -277.422928)
			(xy 347.96924 -277.375144) (xy 347.96528 -277.32609) (xy 347.636338 -277.32609) (xy 347.635843 -277.350697)
			(xy 347.627948 -277.399274) (xy 347.612364 -277.445955) (xy 347.589493 -277.489532) (xy 347.559928 -277.528876)
			(xy 347.524435 -277.562968) (xy 347.483932 -277.590924) (xy 347.43947 -277.612022) (xy 347.392199 -277.625714)
			(xy 347.343344 -277.631646) (xy 347.294169 -277.629665) (xy 347.24595 -277.619821) (xy 347.199934 -277.602369)
			(xy 347.157313 -277.577762) (xy 347.119192 -277.546637) (xy 347.086557 -277.5098) (xy 347.060254 -277.468204)
			(xy 347.040963 -277.422928) (xy 347.029186 -277.375144) (xy 347.025226 -277.32609) (xy 346.696538 -277.32609)
			(xy 346.696043 -277.350697) (xy 346.688148 -277.399274) (xy 346.672564 -277.445955) (xy 346.649693 -277.489532)
			(xy 346.620128 -277.528876) (xy 346.584635 -277.562968) (xy 346.544132 -277.590924) (xy 346.49967 -277.612022)
			(xy 346.452399 -277.625714) (xy 346.403544 -277.631646) (xy 346.354369 -277.629665) (xy 346.30615 -277.619821)
			(xy 346.260134 -277.602369) (xy 346.217513 -277.577762) (xy 346.179392 -277.546637) (xy 346.146757 -277.5098)
			(xy 346.120454 -277.468204) (xy 346.101163 -277.422928) (xy 346.089386 -277.375144) (xy 346.085426 -277.32609)
			(xy 345.756484 -277.32609) (xy 345.755989 -277.350697) (xy 345.748094 -277.399274) (xy 345.73251 -277.445955)
			(xy 345.709639 -277.489532) (xy 345.680074 -277.528876) (xy 345.644581 -277.562968) (xy 345.604078 -277.590924)
			(xy 345.559616 -277.612022) (xy 345.512345 -277.625714) (xy 345.46349 -277.631646) (xy 345.414315 -277.629665)
			(xy 345.366096 -277.619821) (xy 345.32008 -277.602369) (xy 345.277459 -277.577762) (xy 345.239338 -277.546637)
			(xy 345.206703 -277.5098) (xy 345.1804 -277.468204) (xy 345.161109 -277.422928) (xy 345.149332 -277.375144)
			(xy 345.145372 -277.32609) (xy 344.81643 -277.32609) (xy 344.815935 -277.350697) (xy 344.80804 -277.399274)
			(xy 344.792456 -277.445955) (xy 344.769585 -277.489532) (xy 344.74002 -277.528876) (xy 344.704527 -277.562968)
			(xy 344.664024 -277.590924) (xy 344.619562 -277.612022) (xy 344.572291 -277.625714) (xy 344.523436 -277.631646)
			(xy 344.474261 -277.629665) (xy 344.426042 -277.619821) (xy 344.380026 -277.602369) (xy 344.337405 -277.577762)
			(xy 344.299284 -277.546637) (xy 344.266649 -277.5098) (xy 344.240346 -277.468204) (xy 344.221055 -277.422928)
			(xy 344.209278 -277.375144) (xy 344.205318 -277.32609) (xy 343.88679 -277.32609) (xy 343.886278 -277.351536)
			(xy 343.878114 -277.40177) (xy 343.861998 -277.450044) (xy 343.838347 -277.495107) (xy 343.807774 -277.535793)
			(xy 343.77107 -277.571048) (xy 343.729186 -277.599958) (xy 343.683207 -277.621775) (xy 343.634323 -277.635935)
			(xy 343.583802 -277.642069) (xy 343.53295 -277.64002) (xy 343.483086 -277.62984) (xy 343.4355 -277.611793)
			(xy 343.391426 -277.586347) (xy 343.352004 -277.55416) (xy 343.318256 -277.516066) (xy 343.291055 -277.473052)
			(xy 343.271107 -277.426232) (xy 343.258928 -277.376818) (xy 343.254833 -277.32609) (xy 342.946736 -277.32609)
			(xy 342.946224 -277.351536) (xy 342.93806 -277.40177) (xy 342.921944 -277.450044) (xy 342.898293 -277.495107)
			(xy 342.86772 -277.535793) (xy 342.831016 -277.571048) (xy 342.789132 -277.599958) (xy 342.743153 -277.621775)
			(xy 342.694269 -277.635935) (xy 342.643748 -277.642069) (xy 342.592896 -277.64002) (xy 342.543032 -277.62984)
			(xy 342.495446 -277.611793) (xy 342.451372 -277.586347) (xy 342.41195 -277.55416) (xy 342.378202 -277.516066)
			(xy 342.351001 -277.473052) (xy 342.331053 -277.426232) (xy 342.318874 -277.376818) (xy 342.314779 -277.32609)
			(xy 341.996522 -277.32609) (xy 341.996027 -277.350697) (xy 341.988132 -277.399274) (xy 341.972548 -277.445955)
			(xy 341.949677 -277.489532) (xy 341.920112 -277.528876) (xy 341.884619 -277.562968) (xy 341.844116 -277.590924)
			(xy 341.799654 -277.612022) (xy 341.752383 -277.625714) (xy 341.703528 -277.631646) (xy 341.654353 -277.629665)
			(xy 341.606134 -277.619821) (xy 341.560118 -277.602369) (xy 341.517497 -277.577762) (xy 341.479376 -277.546637)
			(xy 341.446741 -277.5098) (xy 341.420438 -277.468204) (xy 341.401147 -277.422928) (xy 341.38937 -277.375144)
			(xy 341.38541 -277.32609) (xy 341.066976 -277.32609) (xy 341.066628 -277.331678) (xy 341.065747 -277.355941)
			(xy 341.057454 -277.403777) (xy 341.041939 -277.44978) (xy 341.019564 -277.492866) (xy 340.990859 -277.53202)
			(xy 340.9565 -277.56632) (xy 340.917296 -277.594956) (xy 340.89594 -277.606506) (xy 340.89402 -277.609721)
			(xy 340.891083 -277.616609) (xy 340.890098 -277.620222) (xy 340.889844 -277.62073) (xy 340.876918 -277.666242)
			(xy 340.844406 -277.755101) (xy 340.804514 -277.840901) (xy 340.757525 -277.923028) (xy 340.703774 -278.000899)
			(xy 340.643646 -278.073957) (xy 340.610952 -278.108156) (xy 340.604511 -278.115323) (xy 340.597072 -278.133082)
			(xy 340.596885 -278.136096) (xy 340.915256 -278.136096) (xy 340.919216 -278.087042) (xy 340.930993 -278.039258)
			(xy 340.950284 -277.993982) (xy 340.976587 -277.952386) (xy 341.009222 -277.915549) (xy 341.047343 -277.884424)
			(xy 341.089964 -277.859817) (xy 341.13598 -277.842365) (xy 341.184199 -277.832521) (xy 341.233374 -277.83054)
			(xy 341.282229 -277.836472) (xy 341.3295 -277.850164) (xy 341.373962 -277.871262) (xy 341.414465 -277.899218)
			(xy 341.449958 -277.93331) (xy 341.479523 -277.972654) (xy 341.502394 -278.016231) (xy 341.517978 -278.062912)
			(xy 341.525873 -278.111489) (xy 341.526368 -278.136096) (xy 341.844879 -278.136096) (xy 341.848974 -278.085368)
			(xy 341.861153 -278.035954) (xy 341.881101 -277.989134) (xy 341.908302 -277.94612) (xy 341.94205 -277.908026)
			(xy 341.981472 -277.875839) (xy 342.025546 -277.850393) (xy 342.073132 -277.832346) (xy 342.122996 -277.822166)
			(xy 342.173848 -277.820117) (xy 342.224369 -277.826251) (xy 342.273253 -277.840411) (xy 342.319232 -277.862228)
			(xy 342.361116 -277.891138) (xy 342.39782 -277.926393) (xy 342.428393 -277.967079) (xy 342.452044 -278.012142)
			(xy 342.46816 -278.060416) (xy 342.476324 -278.11065) (xy 342.476836 -278.136096) (xy 342.795364 -278.136096)
			(xy 342.799324 -278.087042) (xy 342.811101 -278.039258) (xy 342.830392 -277.993982) (xy 342.856695 -277.952386)
			(xy 342.88933 -277.915549) (xy 342.927451 -277.884424) (xy 342.970072 -277.859817) (xy 343.016088 -277.842365)
			(xy 343.064307 -277.832521) (xy 343.113482 -277.83054) (xy 343.162337 -277.836472) (xy 343.209608 -277.850164)
			(xy 343.25407 -277.871262) (xy 343.294573 -277.899218) (xy 343.330066 -277.93331) (xy 343.359631 -277.972654)
			(xy 343.382502 -278.016231) (xy 343.398086 -278.062912) (xy 343.405981 -278.111489) (xy 343.406476 -278.136096)
			(xy 343.724987 -278.136096) (xy 343.729082 -278.085368) (xy 343.741261 -278.035954) (xy 343.761209 -277.989134)
			(xy 343.78841 -277.94612) (xy 343.822158 -277.908026) (xy 343.86158 -277.875839) (xy 343.905654 -277.850393)
			(xy 343.95324 -277.832346) (xy 344.003104 -277.822166) (xy 344.053956 -277.820117) (xy 344.104477 -277.826251)
			(xy 344.153361 -277.840411) (xy 344.19934 -277.862228) (xy 344.241224 -277.891138) (xy 344.277928 -277.926393)
			(xy 344.308501 -277.967079) (xy 344.332152 -278.012142) (xy 344.348268 -278.060416) (xy 344.356432 -278.11065)
			(xy 344.356944 -278.136096) (xy 344.675218 -278.136096) (xy 344.679178 -278.087042) (xy 344.690955 -278.039258)
			(xy 344.710246 -277.993982) (xy 344.736549 -277.952386) (xy 344.769184 -277.915549) (xy 344.807305 -277.884424)
			(xy 344.849926 -277.859817) (xy 344.895942 -277.842365) (xy 344.944161 -277.832521) (xy 344.993336 -277.83054)
			(xy 345.042191 -277.836472) (xy 345.089462 -277.850164) (xy 345.133924 -277.871262) (xy 345.174427 -277.899218)
			(xy 345.20992 -277.93331) (xy 345.239485 -277.972654) (xy 345.262356 -278.016231) (xy 345.27794 -278.062912)
			(xy 345.285835 -278.111489) (xy 345.28633 -278.136096) (xy 345.615272 -278.136096) (xy 345.619232 -278.087042)
			(xy 345.631009 -278.039258) (xy 345.6503 -277.993982) (xy 345.676603 -277.952386) (xy 345.709238 -277.915549)
			(xy 345.747359 -277.884424) (xy 345.78998 -277.859817) (xy 345.835996 -277.842365) (xy 345.884215 -277.832521)
			(xy 345.93339 -277.83054) (xy 345.982245 -277.836472) (xy 346.029516 -277.850164) (xy 346.073978 -277.871262)
			(xy 346.114481 -277.899218) (xy 346.149974 -277.93331) (xy 346.179539 -277.972654) (xy 346.20241 -278.016231)
			(xy 346.217994 -278.062912) (xy 346.225889 -278.111489) (xy 346.226384 -278.136096) (xy 346.555326 -278.136096)
			(xy 346.559286 -278.087042) (xy 346.571063 -278.039258) (xy 346.590354 -277.993982) (xy 346.616657 -277.952386)
			(xy 346.649292 -277.915549) (xy 346.687413 -277.884424) (xy 346.730034 -277.859817) (xy 346.77605 -277.842365)
			(xy 346.824269 -277.832521) (xy 346.873444 -277.83054) (xy 346.922299 -277.836472) (xy 346.96957 -277.850164)
			(xy 347.014032 -277.871262) (xy 347.054535 -277.899218) (xy 347.090028 -277.93331) (xy 347.119593 -277.972654)
			(xy 347.142464 -278.016231) (xy 347.158048 -278.062912) (xy 347.165943 -278.111489) (xy 347.166438 -278.136096)
			(xy 347.49538 -278.136096) (xy 347.49934 -278.087042) (xy 347.511117 -278.039258) (xy 347.530408 -277.993982)
			(xy 347.556711 -277.952386) (xy 347.589346 -277.915549) (xy 347.627467 -277.884424) (xy 347.670088 -277.859817)
			(xy 347.716104 -277.842365) (xy 347.764323 -277.832521) (xy 347.813498 -277.83054) (xy 347.862353 -277.836472)
			(xy 347.909624 -277.850164) (xy 347.954086 -277.871262) (xy 347.994589 -277.899218) (xy 348.030082 -277.93331)
			(xy 348.059647 -277.972654) (xy 348.082518 -278.016231) (xy 348.098102 -278.062912) (xy 348.105997 -278.111489)
			(xy 348.106492 -278.136096) (xy 348.435434 -278.136096) (xy 348.439394 -278.087042) (xy 348.451171 -278.039258)
			(xy 348.470462 -277.993982) (xy 348.496765 -277.952386) (xy 348.5294 -277.915549) (xy 348.567521 -277.884424)
			(xy 348.610142 -277.859817) (xy 348.656158 -277.842365) (xy 348.704377 -277.832521) (xy 348.753552 -277.83054)
			(xy 348.802407 -277.836472) (xy 348.849678 -277.850164) (xy 348.89414 -277.871262) (xy 348.934643 -277.899218)
			(xy 348.970136 -277.93331) (xy 348.999701 -277.972654) (xy 349.022572 -278.016231) (xy 349.038156 -278.062912)
			(xy 349.046051 -278.111489) (xy 349.046546 -278.136096) (xy 349.375234 -278.136096) (xy 349.379194 -278.087042)
			(xy 349.390971 -278.039258) (xy 349.410262 -277.993982) (xy 349.436565 -277.952386) (xy 349.4692 -277.915549)
			(xy 349.507321 -277.884424) (xy 349.549942 -277.859817) (xy 349.595958 -277.842365) (xy 349.644177 -277.832521)
			(xy 349.693352 -277.83054) (xy 349.742207 -277.836472) (xy 349.789478 -277.850164) (xy 349.83394 -277.871262)
			(xy 349.874443 -277.899218) (xy 349.909936 -277.93331) (xy 349.939501 -277.972654) (xy 349.962372 -278.016231)
			(xy 349.977956 -278.062912) (xy 349.985851 -278.111489) (xy 349.986346 -278.136096) (xy 350.315288 -278.136096)
			(xy 350.319248 -278.087042) (xy 350.331025 -278.039258) (xy 350.350316 -277.993982) (xy 350.376619 -277.952386)
			(xy 350.409254 -277.915549) (xy 350.447375 -277.884424) (xy 350.489996 -277.859817) (xy 350.536012 -277.842365)
			(xy 350.584231 -277.832521) (xy 350.633406 -277.83054) (xy 350.682261 -277.836472) (xy 350.729532 -277.850164)
			(xy 350.773994 -277.871262) (xy 350.814497 -277.899218) (xy 350.84999 -277.93331) (xy 350.879555 -277.972654)
			(xy 350.902426 -278.016231) (xy 350.91801 -278.062912) (xy 350.925905 -278.111489) (xy 350.9264 -278.136096)
			(xy 351.255342 -278.136096) (xy 351.259302 -278.087042) (xy 351.271079 -278.039258) (xy 351.29037 -277.993982)
			(xy 351.316673 -277.952386) (xy 351.349308 -277.915549) (xy 351.387429 -277.884424) (xy 351.43005 -277.859817)
			(xy 351.476066 -277.842365) (xy 351.524285 -277.832521) (xy 351.57346 -277.83054) (xy 351.622315 -277.836472)
			(xy 351.669586 -277.850164) (xy 351.714048 -277.871262) (xy 351.754551 -277.899218) (xy 351.790044 -277.93331)
			(xy 351.819609 -277.972654) (xy 351.84248 -278.016231) (xy 351.858064 -278.062912) (xy 351.865959 -278.111489)
			(xy 351.866454 -278.136096) (xy 352.195396 -278.136096) (xy 352.199356 -278.087042) (xy 352.211133 -278.039258)
			(xy 352.230424 -277.993982) (xy 352.256727 -277.952386) (xy 352.289362 -277.915549) (xy 352.327483 -277.884424)
			(xy 352.370104 -277.859817) (xy 352.41612 -277.842365) (xy 352.464339 -277.832521) (xy 352.513514 -277.83054)
			(xy 352.562369 -277.836472) (xy 352.60964 -277.850164) (xy 352.654102 -277.871262) (xy 352.694605 -277.899218)
			(xy 352.730098 -277.93331) (xy 352.759663 -277.972654) (xy 352.782534 -278.016231) (xy 352.798118 -278.062912)
			(xy 352.806013 -278.111489) (xy 352.806508 -278.136096) (xy 353.135196 -278.136096) (xy 353.139156 -278.087042)
			(xy 353.150933 -278.039258) (xy 353.170224 -277.993982) (xy 353.196527 -277.952386) (xy 353.229162 -277.915549)
			(xy 353.267283 -277.884424) (xy 353.309904 -277.859817) (xy 353.35592 -277.842365) (xy 353.404139 -277.832521)
			(xy 353.453314 -277.83054) (xy 353.502169 -277.836472) (xy 353.54944 -277.850164) (xy 353.593902 -277.871262)
			(xy 353.634405 -277.899218) (xy 353.669898 -277.93331) (xy 353.699463 -277.972654) (xy 353.722334 -278.016231)
			(xy 353.737918 -278.062912) (xy 353.745813 -278.111489) (xy 353.746308 -278.136096) (xy 354.07525 -278.136096)
			(xy 354.07921 -278.087042) (xy 354.090987 -278.039258) (xy 354.110278 -277.993982) (xy 354.136581 -277.952386)
			(xy 354.169216 -277.915549) (xy 354.207337 -277.884424) (xy 354.249958 -277.859817) (xy 354.295974 -277.842365)
			(xy 354.344193 -277.832521) (xy 354.393368 -277.83054) (xy 354.442223 -277.836472) (xy 354.489494 -277.850164)
			(xy 354.533956 -277.871262) (xy 354.574459 -277.899218) (xy 354.609952 -277.93331) (xy 354.639517 -277.972654)
			(xy 354.662388 -278.016231) (xy 354.677972 -278.062912) (xy 354.685867 -278.111489) (xy 354.686362 -278.136096)
			(xy 355.015304 -278.136096) (xy 355.019264 -278.087042) (xy 355.031041 -278.039258) (xy 355.050332 -277.993982)
			(xy 355.076635 -277.952386) (xy 355.10927 -277.915549) (xy 355.147391 -277.884424) (xy 355.190012 -277.859817)
			(xy 355.236028 -277.842365) (xy 355.284247 -277.832521) (xy 355.333422 -277.83054) (xy 355.382277 -277.836472)
			(xy 355.429548 -277.850164) (xy 355.47401 -277.871262) (xy 355.514513 -277.899218) (xy 355.550006 -277.93331)
			(xy 355.579571 -277.972654) (xy 355.602442 -278.016231) (xy 355.618026 -278.062912) (xy 355.625921 -278.111489)
			(xy 355.626416 -278.136096) (xy 355.955358 -278.136096) (xy 355.959318 -278.087042) (xy 355.971095 -278.039258)
			(xy 355.990386 -277.993982) (xy 356.016689 -277.952386) (xy 356.049324 -277.915549) (xy 356.087445 -277.884424)
			(xy 356.130066 -277.859817) (xy 356.176082 -277.842365) (xy 356.224301 -277.832521) (xy 356.273476 -277.83054)
			(xy 356.322331 -277.836472) (xy 356.369602 -277.850164) (xy 356.414064 -277.871262) (xy 356.454567 -277.899218)
			(xy 356.49006 -277.93331) (xy 356.519625 -277.972654) (xy 356.542496 -278.016231) (xy 356.55808 -278.062912)
			(xy 356.565975 -278.111489) (xy 356.56647 -278.136096) (xy 363.468932 -278.136096) (xy 363.472892 -278.087042)
			(xy 363.484669 -278.039258) (xy 363.50396 -277.993982) (xy 363.530263 -277.952386) (xy 363.562898 -277.915549)
			(xy 363.601019 -277.884424) (xy 363.64364 -277.859817) (xy 363.689656 -277.842365) (xy 363.737875 -277.832521)
			(xy 363.78705 -277.83054) (xy 363.835905 -277.836472) (xy 363.883176 -277.850164) (xy 363.927638 -277.871262)
			(xy 363.968141 -277.899218) (xy 364.003634 -277.93331) (xy 364.033199 -277.972654) (xy 364.05607 -278.016231)
			(xy 364.071654 -278.062912) (xy 364.079549 -278.111489) (xy 364.080044 -278.136096) (xy 364.408986 -278.136096)
			(xy 364.412946 -278.087042) (xy 364.424723 -278.039258) (xy 364.444014 -277.993982) (xy 364.470317 -277.952386)
			(xy 364.502952 -277.915549) (xy 364.541073 -277.884424) (xy 364.583694 -277.859817) (xy 364.62971 -277.842365)
			(xy 364.677929 -277.832521) (xy 364.727104 -277.83054) (xy 364.775959 -277.836472) (xy 364.82323 -277.850164)
			(xy 364.867692 -277.871262) (xy 364.908195 -277.899218) (xy 364.943688 -277.93331) (xy 364.973253 -277.972654)
			(xy 364.996124 -278.016231) (xy 365.011708 -278.062912) (xy 365.019603 -278.111489) (xy 365.020098 -278.136096)
			(xy 365.34904 -278.136096) (xy 365.353 -278.087042) (xy 365.364777 -278.039258) (xy 365.384068 -277.993982)
			(xy 365.410371 -277.952386) (xy 365.443006 -277.915549) (xy 365.481127 -277.884424) (xy 365.523748 -277.859817)
			(xy 365.569764 -277.842365) (xy 365.617983 -277.832521) (xy 365.667158 -277.83054) (xy 365.716013 -277.836472)
			(xy 365.763284 -277.850164) (xy 365.807746 -277.871262) (xy 365.848249 -277.899218) (xy 365.883742 -277.93331)
			(xy 365.913307 -277.972654) (xy 365.936178 -278.016231) (xy 365.951762 -278.062912) (xy 365.959657 -278.111489)
			(xy 365.960152 -278.136096) (xy 366.289094 -278.136096) (xy 366.293054 -278.087042) (xy 366.304831 -278.039258)
			(xy 366.324122 -277.993982) (xy 366.350425 -277.952386) (xy 366.38306 -277.915549) (xy 366.421181 -277.884424)
			(xy 366.463802 -277.859817) (xy 366.509818 -277.842365) (xy 366.558037 -277.832521) (xy 366.607212 -277.83054)
			(xy 366.656067 -277.836472) (xy 366.703338 -277.850164) (xy 366.7478 -277.871262) (xy 366.788303 -277.899218)
			(xy 366.823796 -277.93331) (xy 366.853361 -277.972654) (xy 366.876232 -278.016231) (xy 366.891816 -278.062912)
			(xy 366.899711 -278.111489) (xy 366.900206 -278.136096) (xy 367.228894 -278.136096) (xy 367.232854 -278.087042)
			(xy 367.244631 -278.039258) (xy 367.263922 -277.993982) (xy 367.290225 -277.952386) (xy 367.32286 -277.915549)
			(xy 367.360981 -277.884424) (xy 367.403602 -277.859817) (xy 367.449618 -277.842365) (xy 367.497837 -277.832521)
			(xy 367.547012 -277.83054) (xy 367.595867 -277.836472) (xy 367.643138 -277.850164) (xy 367.6876 -277.871262)
			(xy 367.728103 -277.899218) (xy 367.763596 -277.93331) (xy 367.793161 -277.972654) (xy 367.816032 -278.016231)
			(xy 367.831616 -278.062912) (xy 367.839511 -278.111489) (xy 367.840006 -278.136096) (xy 368.168948 -278.136096)
			(xy 368.172908 -278.087042) (xy 368.184685 -278.039258) (xy 368.203976 -277.993982) (xy 368.230279 -277.952386)
			(xy 368.262914 -277.915549) (xy 368.301035 -277.884424) (xy 368.343656 -277.859817) (xy 368.389672 -277.842365)
			(xy 368.437891 -277.832521) (xy 368.487066 -277.83054) (xy 368.535921 -277.836472) (xy 368.583192 -277.850164)
			(xy 368.627654 -277.871262) (xy 368.668157 -277.899218) (xy 368.70365 -277.93331) (xy 368.733215 -277.972654)
			(xy 368.756086 -278.016231) (xy 368.77167 -278.062912) (xy 368.779565 -278.111489) (xy 368.78006 -278.136096)
			(xy 369.109002 -278.136096) (xy 369.112962 -278.087042) (xy 369.124739 -278.039258) (xy 369.14403 -277.993982)
			(xy 369.170333 -277.952386) (xy 369.202968 -277.915549) (xy 369.241089 -277.884424) (xy 369.28371 -277.859817)
			(xy 369.329726 -277.842365) (xy 369.377945 -277.832521) (xy 369.42712 -277.83054) (xy 369.475975 -277.836472)
			(xy 369.523246 -277.850164) (xy 369.567708 -277.871262) (xy 369.608211 -277.899218) (xy 369.643704 -277.93331)
			(xy 369.673269 -277.972654) (xy 369.69614 -278.016231) (xy 369.711724 -278.062912) (xy 369.719619 -278.111489)
			(xy 369.720114 -278.136096) (xy 370.049056 -278.136096) (xy 370.053016 -278.087042) (xy 370.064793 -278.039258)
			(xy 370.084084 -277.993982) (xy 370.110387 -277.952386) (xy 370.143022 -277.915549) (xy 370.181143 -277.884424)
			(xy 370.223764 -277.859817) (xy 370.26978 -277.842365) (xy 370.317999 -277.832521) (xy 370.367174 -277.83054)
			(xy 370.416029 -277.836472) (xy 370.4633 -277.850164) (xy 370.507762 -277.871262) (xy 370.548265 -277.899218)
			(xy 370.583758 -277.93331) (xy 370.613323 -277.972654) (xy 370.636194 -278.016231) (xy 370.651778 -278.062912)
			(xy 370.659673 -278.111489) (xy 370.660168 -278.136096) (xy 370.98911 -278.136096) (xy 370.99307 -278.087042)
			(xy 371.004847 -278.039258) (xy 371.024138 -277.993982) (xy 371.050441 -277.952386) (xy 371.083076 -277.915549)
			(xy 371.121197 -277.884424) (xy 371.163818 -277.859817) (xy 371.209834 -277.842365) (xy 371.258053 -277.832521)
			(xy 371.307228 -277.83054) (xy 371.356083 -277.836472) (xy 371.403354 -277.850164) (xy 371.447816 -277.871262)
			(xy 371.488319 -277.899218) (xy 371.523812 -277.93331) (xy 371.553377 -277.972654) (xy 371.576248 -278.016231)
			(xy 371.591832 -278.062912) (xy 371.599727 -278.111489) (xy 371.600222 -278.136096) (xy 371.92891 -278.136096)
			(xy 371.93287 -278.087042) (xy 371.944647 -278.039258) (xy 371.963938 -277.993982) (xy 371.990241 -277.952386)
			(xy 372.022876 -277.915549) (xy 372.060997 -277.884424) (xy 372.103618 -277.859817) (xy 372.149634 -277.842365)
			(xy 372.197853 -277.832521) (xy 372.247028 -277.83054) (xy 372.295883 -277.836472) (xy 372.343154 -277.850164)
			(xy 372.387616 -277.871262) (xy 372.428119 -277.899218) (xy 372.463612 -277.93331) (xy 372.493177 -277.972654)
			(xy 372.516048 -278.016231) (xy 372.531632 -278.062912) (xy 372.539527 -278.111489) (xy 372.540022 -278.136096)
			(xy 372.868964 -278.136096) (xy 372.872924 -278.087042) (xy 372.884701 -278.039258) (xy 372.903992 -277.993982)
			(xy 372.930295 -277.952386) (xy 372.96293 -277.915549) (xy 373.001051 -277.884424) (xy 373.043672 -277.859817)
			(xy 373.089688 -277.842365) (xy 373.137907 -277.832521) (xy 373.187082 -277.83054) (xy 373.235937 -277.836472)
			(xy 373.283208 -277.850164) (xy 373.32767 -277.871262) (xy 373.368173 -277.899218) (xy 373.403666 -277.93331)
			(xy 373.433231 -277.972654) (xy 373.456102 -278.016231) (xy 373.471686 -278.062912) (xy 373.479581 -278.111489)
			(xy 373.480076 -278.136096) (xy 373.809018 -278.136096) (xy 373.812978 -278.087042) (xy 373.824755 -278.039258)
			(xy 373.844046 -277.993982) (xy 373.870349 -277.952386) (xy 373.902984 -277.915549) (xy 373.941105 -277.884424)
			(xy 373.983726 -277.859817) (xy 374.029742 -277.842365) (xy 374.077961 -277.832521) (xy 374.127136 -277.83054)
			(xy 374.175991 -277.836472) (xy 374.223262 -277.850164) (xy 374.267724 -277.871262) (xy 374.308227 -277.899218)
			(xy 374.34372 -277.93331) (xy 374.373285 -277.972654) (xy 374.396156 -278.016231) (xy 374.41174 -278.062912)
			(xy 374.419635 -278.111489) (xy 374.42013 -278.136096) (xy 374.419635 -278.160703) (xy 374.41174 -278.20928)
			(xy 374.396156 -278.255961) (xy 374.373285 -278.299538) (xy 374.34372 -278.338882) (xy 374.308227 -278.372974)
			(xy 374.267724 -278.40093) (xy 374.223262 -278.422028) (xy 374.175991 -278.43572) (xy 374.127136 -278.441652)
			(xy 374.077961 -278.439671) (xy 374.029742 -278.429827) (xy 373.983726 -278.412375) (xy 373.941105 -278.387768)
			(xy 373.902984 -278.356643) (xy 373.870349 -278.319806) (xy 373.844046 -278.27821) (xy 373.824755 -278.232934)
			(xy 373.812978 -278.18515) (xy 373.809018 -278.136096) (xy 373.480076 -278.136096) (xy 373.479581 -278.160703)
			(xy 373.471686 -278.20928) (xy 373.456102 -278.255961) (xy 373.433231 -278.299538) (xy 373.403666 -278.338882)
			(xy 373.368173 -278.372974) (xy 373.32767 -278.40093) (xy 373.283208 -278.422028) (xy 373.235937 -278.43572)
			(xy 373.187082 -278.441652) (xy 373.137907 -278.439671) (xy 373.089688 -278.429827) (xy 373.043672 -278.412375)
			(xy 373.001051 -278.387768) (xy 372.96293 -278.356643) (xy 372.930295 -278.319806) (xy 372.903992 -278.27821)
			(xy 372.884701 -278.232934) (xy 372.872924 -278.18515) (xy 372.868964 -278.136096) (xy 372.540022 -278.136096)
			(xy 372.539527 -278.160703) (xy 372.531632 -278.20928) (xy 372.516048 -278.255961) (xy 372.493177 -278.299538)
			(xy 372.463612 -278.338882) (xy 372.428119 -278.372974) (xy 372.387616 -278.40093) (xy 372.343154 -278.422028)
			(xy 372.295883 -278.43572) (xy 372.247028 -278.441652) (xy 372.197853 -278.439671) (xy 372.149634 -278.429827)
			(xy 372.103618 -278.412375) (xy 372.060997 -278.387768) (xy 372.022876 -278.356643) (xy 371.990241 -278.319806)
			(xy 371.963938 -278.27821) (xy 371.944647 -278.232934) (xy 371.93287 -278.18515) (xy 371.92891 -278.136096)
			(xy 371.600222 -278.136096) (xy 371.599727 -278.160703) (xy 371.591832 -278.20928) (xy 371.576248 -278.255961)
			(xy 371.553377 -278.299538) (xy 371.523812 -278.338882) (xy 371.488319 -278.372974) (xy 371.447816 -278.40093)
			(xy 371.403354 -278.422028) (xy 371.356083 -278.43572) (xy 371.307228 -278.441652) (xy 371.258053 -278.439671)
			(xy 371.209834 -278.429827) (xy 371.163818 -278.412375) (xy 371.121197 -278.387768) (xy 371.083076 -278.356643)
			(xy 371.050441 -278.319806) (xy 371.024138 -278.27821) (xy 371.004847 -278.232934) (xy 370.99307 -278.18515)
			(xy 370.98911 -278.136096) (xy 370.660168 -278.136096) (xy 370.659673 -278.160703) (xy 370.651778 -278.20928)
			(xy 370.636194 -278.255961) (xy 370.613323 -278.299538) (xy 370.583758 -278.338882) (xy 370.548265 -278.372974)
			(xy 370.507762 -278.40093) (xy 370.4633 -278.422028) (xy 370.416029 -278.43572) (xy 370.367174 -278.441652)
			(xy 370.317999 -278.439671) (xy 370.26978 -278.429827) (xy 370.223764 -278.412375) (xy 370.181143 -278.387768)
			(xy 370.143022 -278.356643) (xy 370.110387 -278.319806) (xy 370.084084 -278.27821) (xy 370.064793 -278.232934)
			(xy 370.053016 -278.18515) (xy 370.049056 -278.136096) (xy 369.720114 -278.136096) (xy 369.719619 -278.160703)
			(xy 369.711724 -278.20928) (xy 369.69614 -278.255961) (xy 369.673269 -278.299538) (xy 369.643704 -278.338882)
			(xy 369.608211 -278.372974) (xy 369.567708 -278.40093) (xy 369.523246 -278.422028) (xy 369.475975 -278.43572)
			(xy 369.42712 -278.441652) (xy 369.377945 -278.439671) (xy 369.329726 -278.429827) (xy 369.28371 -278.412375)
			(xy 369.241089 -278.387768) (xy 369.202968 -278.356643) (xy 369.170333 -278.319806) (xy 369.14403 -278.27821)
			(xy 369.124739 -278.232934) (xy 369.112962 -278.18515) (xy 369.109002 -278.136096) (xy 368.78006 -278.136096)
			(xy 368.779565 -278.160703) (xy 368.77167 -278.20928) (xy 368.756086 -278.255961) (xy 368.733215 -278.299538)
			(xy 368.70365 -278.338882) (xy 368.668157 -278.372974) (xy 368.627654 -278.40093) (xy 368.583192 -278.422028)
			(xy 368.535921 -278.43572) (xy 368.487066 -278.441652) (xy 368.437891 -278.439671) (xy 368.389672 -278.429827)
			(xy 368.343656 -278.412375) (xy 368.301035 -278.387768) (xy 368.262914 -278.356643) (xy 368.230279 -278.319806)
			(xy 368.203976 -278.27821) (xy 368.184685 -278.232934) (xy 368.172908 -278.18515) (xy 368.168948 -278.136096)
			(xy 367.840006 -278.136096) (xy 367.839511 -278.160703) (xy 367.831616 -278.20928) (xy 367.816032 -278.255961)
			(xy 367.793161 -278.299538) (xy 367.763596 -278.338882) (xy 367.728103 -278.372974) (xy 367.6876 -278.40093)
			(xy 367.643138 -278.422028) (xy 367.595867 -278.43572) (xy 367.547012 -278.441652) (xy 367.497837 -278.439671)
			(xy 367.449618 -278.429827) (xy 367.403602 -278.412375) (xy 367.360981 -278.387768) (xy 367.32286 -278.356643)
			(xy 367.290225 -278.319806) (xy 367.263922 -278.27821) (xy 367.244631 -278.232934) (xy 367.232854 -278.18515)
			(xy 367.228894 -278.136096) (xy 366.900206 -278.136096) (xy 366.899711 -278.160703) (xy 366.891816 -278.20928)
			(xy 366.876232 -278.255961) (xy 366.853361 -278.299538) (xy 366.823796 -278.338882) (xy 366.788303 -278.372974)
			(xy 366.7478 -278.40093) (xy 366.703338 -278.422028) (xy 366.656067 -278.43572) (xy 366.607212 -278.441652)
			(xy 366.558037 -278.439671) (xy 366.509818 -278.429827) (xy 366.463802 -278.412375) (xy 366.421181 -278.387768)
			(xy 366.38306 -278.356643) (xy 366.350425 -278.319806) (xy 366.324122 -278.27821) (xy 366.304831 -278.232934)
			(xy 366.293054 -278.18515) (xy 366.289094 -278.136096) (xy 365.960152 -278.136096) (xy 365.959657 -278.160703)
			(xy 365.951762 -278.20928) (xy 365.936178 -278.255961) (xy 365.913307 -278.299538) (xy 365.883742 -278.338882)
			(xy 365.848249 -278.372974) (xy 365.807746 -278.40093) (xy 365.763284 -278.422028) (xy 365.716013 -278.43572)
			(xy 365.667158 -278.441652) (xy 365.617983 -278.439671) (xy 365.569764 -278.429827) (xy 365.523748 -278.412375)
			(xy 365.481127 -278.387768) (xy 365.443006 -278.356643) (xy 365.410371 -278.319806) (xy 365.384068 -278.27821)
			(xy 365.364777 -278.232934) (xy 365.353 -278.18515) (xy 365.34904 -278.136096) (xy 365.020098 -278.136096)
			(xy 365.019603 -278.160703) (xy 365.011708 -278.20928) (xy 364.996124 -278.255961) (xy 364.973253 -278.299538)
			(xy 364.943688 -278.338882) (xy 364.908195 -278.372974) (xy 364.867692 -278.40093) (xy 364.82323 -278.422028)
			(xy 364.775959 -278.43572) (xy 364.727104 -278.441652) (xy 364.677929 -278.439671) (xy 364.62971 -278.429827)
			(xy 364.583694 -278.412375) (xy 364.541073 -278.387768) (xy 364.502952 -278.356643) (xy 364.470317 -278.319806)
			(xy 364.444014 -278.27821) (xy 364.424723 -278.232934) (xy 364.412946 -278.18515) (xy 364.408986 -278.136096)
			(xy 364.080044 -278.136096) (xy 364.079549 -278.160703) (xy 364.071654 -278.20928) (xy 364.05607 -278.255961)
			(xy 364.033199 -278.299538) (xy 364.003634 -278.338882) (xy 363.968141 -278.372974) (xy 363.927638 -278.40093)
			(xy 363.883176 -278.422028) (xy 363.835905 -278.43572) (xy 363.78705 -278.441652) (xy 363.737875 -278.439671)
			(xy 363.689656 -278.429827) (xy 363.64364 -278.412375) (xy 363.601019 -278.387768) (xy 363.562898 -278.356643)
			(xy 363.530263 -278.319806) (xy 363.50396 -278.27821) (xy 363.484669 -278.232934) (xy 363.472892 -278.18515)
			(xy 363.468932 -278.136096) (xy 356.56647 -278.136096) (xy 356.565975 -278.160703) (xy 356.55808 -278.20928)
			(xy 356.542496 -278.255961) (xy 356.519625 -278.299538) (xy 356.49006 -278.338882) (xy 356.454567 -278.372974)
			(xy 356.414064 -278.40093) (xy 356.369602 -278.422028) (xy 356.322331 -278.43572) (xy 356.273476 -278.441652)
			(xy 356.224301 -278.439671) (xy 356.176082 -278.429827) (xy 356.130066 -278.412375) (xy 356.087445 -278.387768)
			(xy 356.049324 -278.356643) (xy 356.016689 -278.319806) (xy 355.990386 -278.27821) (xy 355.971095 -278.232934)
			(xy 355.959318 -278.18515) (xy 355.955358 -278.136096) (xy 355.626416 -278.136096) (xy 355.625921 -278.160703)
			(xy 355.618026 -278.20928) (xy 355.602442 -278.255961) (xy 355.579571 -278.299538) (xy 355.550006 -278.338882)
			(xy 355.514513 -278.372974) (xy 355.47401 -278.40093) (xy 355.429548 -278.422028) (xy 355.382277 -278.43572)
			(xy 355.333422 -278.441652) (xy 355.284247 -278.439671) (xy 355.236028 -278.429827) (xy 355.190012 -278.412375)
			(xy 355.147391 -278.387768) (xy 355.10927 -278.356643) (xy 355.076635 -278.319806) (xy 355.050332 -278.27821)
			(xy 355.031041 -278.232934) (xy 355.019264 -278.18515) (xy 355.015304 -278.136096) (xy 354.686362 -278.136096)
			(xy 354.685867 -278.160703) (xy 354.677972 -278.20928) (xy 354.662388 -278.255961) (xy 354.639517 -278.299538)
			(xy 354.609952 -278.338882) (xy 354.574459 -278.372974) (xy 354.533956 -278.40093) (xy 354.489494 -278.422028)
			(xy 354.442223 -278.43572) (xy 354.393368 -278.441652) (xy 354.344193 -278.439671) (xy 354.295974 -278.429827)
			(xy 354.249958 -278.412375) (xy 354.207337 -278.387768) (xy 354.169216 -278.356643) (xy 354.136581 -278.319806)
			(xy 354.110278 -278.27821) (xy 354.090987 -278.232934) (xy 354.07921 -278.18515) (xy 354.07525 -278.136096)
			(xy 353.746308 -278.136096) (xy 353.745813 -278.160703) (xy 353.737918 -278.20928) (xy 353.722334 -278.255961)
			(xy 353.699463 -278.299538) (xy 353.669898 -278.338882) (xy 353.634405 -278.372974) (xy 353.593902 -278.40093)
			(xy 353.54944 -278.422028) (xy 353.502169 -278.43572) (xy 353.453314 -278.441652) (xy 353.404139 -278.439671)
			(xy 353.35592 -278.429827) (xy 353.309904 -278.412375) (xy 353.267283 -278.387768) (xy 353.229162 -278.356643)
			(xy 353.196527 -278.319806) (xy 353.170224 -278.27821) (xy 353.150933 -278.232934) (xy 353.139156 -278.18515)
			(xy 353.135196 -278.136096) (xy 352.806508 -278.136096) (xy 352.806013 -278.160703) (xy 352.798118 -278.20928)
			(xy 352.782534 -278.255961) (xy 352.759663 -278.299538) (xy 352.730098 -278.338882) (xy 352.694605 -278.372974)
			(xy 352.654102 -278.40093) (xy 352.60964 -278.422028) (xy 352.562369 -278.43572) (xy 352.513514 -278.441652)
			(xy 352.464339 -278.439671) (xy 352.41612 -278.429827) (xy 352.370104 -278.412375) (xy 352.327483 -278.387768)
			(xy 352.289362 -278.356643) (xy 352.256727 -278.319806) (xy 352.230424 -278.27821) (xy 352.211133 -278.232934)
			(xy 352.199356 -278.18515) (xy 352.195396 -278.136096) (xy 351.866454 -278.136096) (xy 351.865959 -278.160703)
			(xy 351.858064 -278.20928) (xy 351.84248 -278.255961) (xy 351.819609 -278.299538) (xy 351.790044 -278.338882)
			(xy 351.754551 -278.372974) (xy 351.714048 -278.40093) (xy 351.669586 -278.422028) (xy 351.622315 -278.43572)
			(xy 351.57346 -278.441652) (xy 351.524285 -278.439671) (xy 351.476066 -278.429827) (xy 351.43005 -278.412375)
			(xy 351.387429 -278.387768) (xy 351.349308 -278.356643) (xy 351.316673 -278.319806) (xy 351.29037 -278.27821)
			(xy 351.271079 -278.232934) (xy 351.259302 -278.18515) (xy 351.255342 -278.136096) (xy 350.9264 -278.136096)
			(xy 350.925905 -278.160703) (xy 350.91801 -278.20928) (xy 350.902426 -278.255961) (xy 350.879555 -278.299538)
			(xy 350.84999 -278.338882) (xy 350.814497 -278.372974) (xy 350.773994 -278.40093) (xy 350.729532 -278.422028)
			(xy 350.682261 -278.43572) (xy 350.633406 -278.441652) (xy 350.584231 -278.439671) (xy 350.536012 -278.429827)
			(xy 350.489996 -278.412375) (xy 350.447375 -278.387768) (xy 350.409254 -278.356643) (xy 350.376619 -278.319806)
			(xy 350.350316 -278.27821) (xy 350.331025 -278.232934) (xy 350.319248 -278.18515) (xy 350.315288 -278.136096)
			(xy 349.986346 -278.136096) (xy 349.985851 -278.160703) (xy 349.977956 -278.20928) (xy 349.962372 -278.255961)
			(xy 349.939501 -278.299538) (xy 349.909936 -278.338882) (xy 349.874443 -278.372974) (xy 349.83394 -278.40093)
			(xy 349.789478 -278.422028) (xy 349.742207 -278.43572) (xy 349.693352 -278.441652) (xy 349.644177 -278.439671)
			(xy 349.595958 -278.429827) (xy 349.549942 -278.412375) (xy 349.507321 -278.387768) (xy 349.4692 -278.356643)
			(xy 349.436565 -278.319806) (xy 349.410262 -278.27821) (xy 349.390971 -278.232934) (xy 349.379194 -278.18515)
			(xy 349.375234 -278.136096) (xy 349.046546 -278.136096) (xy 349.046051 -278.160703) (xy 349.038156 -278.20928)
			(xy 349.022572 -278.255961) (xy 348.999701 -278.299538) (xy 348.970136 -278.338882) (xy 348.934643 -278.372974)
			(xy 348.89414 -278.40093) (xy 348.849678 -278.422028) (xy 348.802407 -278.43572) (xy 348.753552 -278.441652)
			(xy 348.704377 -278.439671) (xy 348.656158 -278.429827) (xy 348.610142 -278.412375) (xy 348.567521 -278.387768)
			(xy 348.5294 -278.356643) (xy 348.496765 -278.319806) (xy 348.470462 -278.27821) (xy 348.451171 -278.232934)
			(xy 348.439394 -278.18515) (xy 348.435434 -278.136096) (xy 348.106492 -278.136096) (xy 348.105997 -278.160703)
			(xy 348.098102 -278.20928) (xy 348.082518 -278.255961) (xy 348.059647 -278.299538) (xy 348.030082 -278.338882)
			(xy 347.994589 -278.372974) (xy 347.954086 -278.40093) (xy 347.909624 -278.422028) (xy 347.862353 -278.43572)
			(xy 347.813498 -278.441652) (xy 347.764323 -278.439671) (xy 347.716104 -278.429827) (xy 347.670088 -278.412375)
			(xy 347.627467 -278.387768) (xy 347.589346 -278.356643) (xy 347.556711 -278.319806) (xy 347.530408 -278.27821)
			(xy 347.511117 -278.232934) (xy 347.49934 -278.18515) (xy 347.49538 -278.136096) (xy 347.166438 -278.136096)
			(xy 347.165943 -278.160703) (xy 347.158048 -278.20928) (xy 347.142464 -278.255961) (xy 347.119593 -278.299538)
			(xy 347.090028 -278.338882) (xy 347.054535 -278.372974) (xy 347.014032 -278.40093) (xy 346.96957 -278.422028)
			(xy 346.922299 -278.43572) (xy 346.873444 -278.441652) (xy 346.824269 -278.439671) (xy 346.77605 -278.429827)
			(xy 346.730034 -278.412375) (xy 346.687413 -278.387768) (xy 346.649292 -278.356643) (xy 346.616657 -278.319806)
			(xy 346.590354 -278.27821) (xy 346.571063 -278.232934) (xy 346.559286 -278.18515) (xy 346.555326 -278.136096)
			(xy 346.226384 -278.136096) (xy 346.225889 -278.160703) (xy 346.217994 -278.20928) (xy 346.20241 -278.255961)
			(xy 346.179539 -278.299538) (xy 346.149974 -278.338882) (xy 346.114481 -278.372974) (xy 346.073978 -278.40093)
			(xy 346.029516 -278.422028) (xy 345.982245 -278.43572) (xy 345.93339 -278.441652) (xy 345.884215 -278.439671)
			(xy 345.835996 -278.429827) (xy 345.78998 -278.412375) (xy 345.747359 -278.387768) (xy 345.709238 -278.356643)
			(xy 345.676603 -278.319806) (xy 345.6503 -278.27821) (xy 345.631009 -278.232934) (xy 345.619232 -278.18515)
			(xy 345.615272 -278.136096) (xy 345.28633 -278.136096) (xy 345.285835 -278.160703) (xy 345.27794 -278.20928)
			(xy 345.262356 -278.255961) (xy 345.239485 -278.299538) (xy 345.20992 -278.338882) (xy 345.174427 -278.372974)
			(xy 345.133924 -278.40093) (xy 345.089462 -278.422028) (xy 345.042191 -278.43572) (xy 344.993336 -278.441652)
			(xy 344.944161 -278.439671) (xy 344.895942 -278.429827) (xy 344.849926 -278.412375) (xy 344.807305 -278.387768)
			(xy 344.769184 -278.356643) (xy 344.736549 -278.319806) (xy 344.710246 -278.27821) (xy 344.690955 -278.232934)
			(xy 344.679178 -278.18515) (xy 344.675218 -278.136096) (xy 344.356944 -278.136096) (xy 344.356432 -278.161542)
			(xy 344.348268 -278.211776) (xy 344.332152 -278.26005) (xy 344.308501 -278.305113) (xy 344.277928 -278.345799)
			(xy 344.241224 -278.381054) (xy 344.19934 -278.409964) (xy 344.153361 -278.431781) (xy 344.104477 -278.445941)
			(xy 344.053956 -278.452075) (xy 344.003104 -278.450026) (xy 343.95324 -278.439846) (xy 343.905654 -278.421799)
			(xy 343.86158 -278.396353) (xy 343.822158 -278.364166) (xy 343.78841 -278.326072) (xy 343.761209 -278.283058)
			(xy 343.741261 -278.236238) (xy 343.729082 -278.186824) (xy 343.724987 -278.136096) (xy 343.406476 -278.136096)
			(xy 343.405981 -278.160703) (xy 343.398086 -278.20928) (xy 343.382502 -278.255961) (xy 343.359631 -278.299538)
			(xy 343.330066 -278.338882) (xy 343.294573 -278.372974) (xy 343.25407 -278.40093) (xy 343.209608 -278.422028)
			(xy 343.162337 -278.43572) (xy 343.113482 -278.441652) (xy 343.064307 -278.439671) (xy 343.016088 -278.429827)
			(xy 342.970072 -278.412375) (xy 342.927451 -278.387768) (xy 342.88933 -278.356643) (xy 342.856695 -278.319806)
			(xy 342.830392 -278.27821) (xy 342.811101 -278.232934) (xy 342.799324 -278.18515) (xy 342.795364 -278.136096)
			(xy 342.476836 -278.136096) (xy 342.476324 -278.161542) (xy 342.46816 -278.211776) (xy 342.452044 -278.26005)
			(xy 342.428393 -278.305113) (xy 342.39782 -278.345799) (xy 342.361116 -278.381054) (xy 342.319232 -278.409964)
			(xy 342.273253 -278.431781) (xy 342.224369 -278.445941) (xy 342.173848 -278.452075) (xy 342.122996 -278.450026)
			(xy 342.073132 -278.439846) (xy 342.025546 -278.421799) (xy 341.981472 -278.396353) (xy 341.94205 -278.364166)
			(xy 341.908302 -278.326072) (xy 341.881101 -278.283058) (xy 341.861153 -278.236238) (xy 341.848974 -278.186824)
			(xy 341.844879 -278.136096) (xy 341.526368 -278.136096) (xy 341.525873 -278.160703) (xy 341.517978 -278.20928)
			(xy 341.502394 -278.255961) (xy 341.479523 -278.299538) (xy 341.449958 -278.338882) (xy 341.414465 -278.372974)
			(xy 341.373962 -278.40093) (xy 341.3295 -278.422028) (xy 341.282229 -278.43572) (xy 341.233374 -278.441652)
			(xy 341.184199 -278.439671) (xy 341.13598 -278.429827) (xy 341.089964 -278.412375) (xy 341.047343 -278.387768)
			(xy 341.009222 -278.356643) (xy 340.976587 -278.319806) (xy 340.950284 -278.27821) (xy 340.930993 -278.232934)
			(xy 340.919216 -278.18515) (xy 340.915256 -278.136096) (xy 340.596885 -278.136096) (xy 340.596474 -278.1427)
			(xy 340.595532 -278.166906) (xy 340.587139 -278.214614) (xy 340.571549 -278.260477) (xy 340.549129 -278.303417)
			(xy 340.520406 -278.342423) (xy 340.486056 -278.376578) (xy 340.446887 -278.405078) (xy 340.425532 -278.416512)
			(xy 340.420198 -278.428958) (xy 340.415372 -278.44623) (xy 340.402986 -278.487711) (xy 340.37266 -278.568805)
			(xy 340.336164 -278.647315) (xy 340.315296 -278.685244) (xy 340.315042 -278.685498) (xy 340.311994 -278.691086)
			(xy 340.310216 -278.697182) (xy 340.308438 -278.710644) (xy 340.308438 -278.946102) (xy 340.434925 -278.946102)
			(xy 340.43902 -278.895374) (xy 340.451199 -278.84596) (xy 340.471147 -278.79914) (xy 340.498348 -278.756126)
			(xy 340.532096 -278.718032) (xy 340.571518 -278.685845) (xy 340.615592 -278.660399) (xy 340.663178 -278.642352)
			(xy 340.713042 -278.632172) (xy 340.763894 -278.630123) (xy 340.814415 -278.636257) (xy 340.863299 -278.650417)
			(xy 340.909278 -278.672234) (xy 340.951162 -278.701144) (xy 340.987866 -278.736399) (xy 341.018439 -278.777085)
			(xy 341.04209 -278.822148) (xy 341.058206 -278.870422) (xy 341.06637 -278.920656) (xy 341.066882 -278.946102)
			(xy 341.38541 -278.946102) (xy 341.38937 -278.897048) (xy 341.401147 -278.849264) (xy 341.420438 -278.803988)
			(xy 341.446741 -278.762392) (xy 341.479376 -278.725555) (xy 341.517497 -278.69443) (xy 341.560118 -278.669823)
			(xy 341.606134 -278.652371) (xy 341.654353 -278.642527) (xy 341.703528 -278.640546) (xy 341.752383 -278.646478)
			(xy 341.799654 -278.66017) (xy 341.844116 -278.681268) (xy 341.884619 -278.709224) (xy 341.920112 -278.743316)
			(xy 341.949677 -278.78266) (xy 341.972548 -278.826237) (xy 341.988132 -278.872918) (xy 341.996027 -278.921495)
			(xy 341.996522 -278.946102) (xy 342.314779 -278.946102) (xy 342.318874 -278.895374) (xy 342.331053 -278.84596)
			(xy 342.351001 -278.79914) (xy 342.378202 -278.756126) (xy 342.41195 -278.718032) (xy 342.451372 -278.685845)
			(xy 342.495446 -278.660399) (xy 342.543032 -278.642352) (xy 342.592896 -278.632172) (xy 342.643748 -278.630123)
			(xy 342.694269 -278.636257) (xy 342.743153 -278.650417) (xy 342.789132 -278.672234) (xy 342.831016 -278.701144)
			(xy 342.86772 -278.736399) (xy 342.898293 -278.777085) (xy 342.921944 -278.822148) (xy 342.93806 -278.870422)
			(xy 342.946224 -278.920656) (xy 342.946736 -278.946102) (xy 343.254833 -278.946102) (xy 343.258928 -278.895374)
			(xy 343.271107 -278.84596) (xy 343.291055 -278.79914) (xy 343.318256 -278.756126) (xy 343.352004 -278.718032)
			(xy 343.391426 -278.685845) (xy 343.4355 -278.660399) (xy 343.483086 -278.642352) (xy 343.53295 -278.632172)
			(xy 343.583802 -278.630123) (xy 343.634323 -278.636257) (xy 343.683207 -278.650417) (xy 343.729186 -278.672234)
			(xy 343.77107 -278.701144) (xy 343.807774 -278.736399) (xy 343.838347 -278.777085) (xy 343.861998 -278.822148)
			(xy 343.878114 -278.870422) (xy 343.886278 -278.920656) (xy 343.88679 -278.946102) (xy 344.205318 -278.946102)
			(xy 344.209278 -278.897048) (xy 344.221055 -278.849264) (xy 344.240346 -278.803988) (xy 344.266649 -278.762392)
			(xy 344.299284 -278.725555) (xy 344.337405 -278.69443) (xy 344.380026 -278.669823) (xy 344.426042 -278.652371)
			(xy 344.474261 -278.642527) (xy 344.523436 -278.640546) (xy 344.572291 -278.646478) (xy 344.619562 -278.66017)
			(xy 344.664024 -278.681268) (xy 344.704527 -278.709224) (xy 344.74002 -278.743316) (xy 344.769585 -278.78266)
			(xy 344.792456 -278.826237) (xy 344.80804 -278.872918) (xy 344.815935 -278.921495) (xy 344.81643 -278.946102)
			(xy 347.025226 -278.946102) (xy 347.029186 -278.897048) (xy 347.040963 -278.849264) (xy 347.060254 -278.803988)
			(xy 347.086557 -278.762392) (xy 347.119192 -278.725555) (xy 347.157313 -278.69443) (xy 347.199934 -278.669823)
			(xy 347.24595 -278.652371) (xy 347.294169 -278.642527) (xy 347.343344 -278.640546) (xy 347.392199 -278.646478)
			(xy 347.43947 -278.66017) (xy 347.483932 -278.681268) (xy 347.524435 -278.709224) (xy 347.559928 -278.743316)
			(xy 347.589493 -278.78266) (xy 347.612364 -278.826237) (xy 347.627948 -278.872918) (xy 347.635843 -278.921495)
			(xy 347.636338 -278.946102) (xy 349.845388 -278.946102) (xy 349.849348 -278.897048) (xy 349.861125 -278.849264)
			(xy 349.880416 -278.803988) (xy 349.906719 -278.762392) (xy 349.939354 -278.725555) (xy 349.977475 -278.69443)
			(xy 350.020096 -278.669823) (xy 350.066112 -278.652371) (xy 350.114331 -278.642527) (xy 350.163506 -278.640546)
			(xy 350.212361 -278.646478) (xy 350.259632 -278.66017) (xy 350.304094 -278.681268) (xy 350.344597 -278.709224)
			(xy 350.38009 -278.743316) (xy 350.409655 -278.78266) (xy 350.432526 -278.826237) (xy 350.44811 -278.872918)
			(xy 350.456005 -278.921495) (xy 350.4565 -278.946102) (xy 352.665296 -278.946102) (xy 352.669256 -278.897048)
			(xy 352.681033 -278.849264) (xy 352.700324 -278.803988) (xy 352.726627 -278.762392) (xy 352.759262 -278.725555)
			(xy 352.797383 -278.69443) (xy 352.840004 -278.669823) (xy 352.88602 -278.652371) (xy 352.934239 -278.642527)
			(xy 352.983414 -278.640546) (xy 353.032269 -278.646478) (xy 353.07954 -278.66017) (xy 353.124002 -278.681268)
			(xy 353.164505 -278.709224) (xy 353.199998 -278.743316) (xy 353.229563 -278.78266) (xy 353.252434 -278.826237)
			(xy 353.268018 -278.872918) (xy 353.275913 -278.921495) (xy 353.276408 -278.946102) (xy 355.485204 -278.946102)
			(xy 355.489164 -278.897048) (xy 355.500941 -278.849264) (xy 355.520232 -278.803988) (xy 355.546535 -278.762392)
			(xy 355.57917 -278.725555) (xy 355.617291 -278.69443) (xy 355.659912 -278.669823) (xy 355.705928 -278.652371)
			(xy 355.754147 -278.642527) (xy 355.803322 -278.640546) (xy 355.852177 -278.646478) (xy 355.899448 -278.66017)
			(xy 355.94391 -278.681268) (xy 355.984413 -278.709224) (xy 356.019906 -278.743316) (xy 356.049471 -278.78266)
			(xy 356.072342 -278.826237) (xy 356.087926 -278.872918) (xy 356.095821 -278.921495) (xy 356.096316 -278.946102)
			(xy 356.425258 -278.946102) (xy 356.429218 -278.897048) (xy 356.440995 -278.849264) (xy 356.460286 -278.803988)
			(xy 356.486589 -278.762392) (xy 356.519224 -278.725555) (xy 356.557345 -278.69443) (xy 356.599966 -278.669823)
			(xy 356.645982 -278.652371) (xy 356.694201 -278.642527) (xy 356.743376 -278.640546) (xy 356.792231 -278.646478)
			(xy 356.839502 -278.66017) (xy 356.883964 -278.681268) (xy 356.924467 -278.709224) (xy 356.95996 -278.743316)
			(xy 356.989525 -278.78266) (xy 357.012396 -278.826237) (xy 357.02798 -278.872918) (xy 357.035875 -278.921495)
			(xy 357.03637 -278.946102) (xy 357.365312 -278.946102) (xy 357.369272 -278.897048) (xy 357.381049 -278.849264)
			(xy 357.40034 -278.803988) (xy 357.426643 -278.762392) (xy 357.459278 -278.725555) (xy 357.497399 -278.69443)
			(xy 357.54002 -278.669823) (xy 357.586036 -278.652371) (xy 357.634255 -278.642527) (xy 357.68343 -278.640546)
			(xy 357.732285 -278.646478) (xy 357.779556 -278.66017) (xy 357.824018 -278.681268) (xy 357.864521 -278.709224)
			(xy 357.900014 -278.743316) (xy 357.929579 -278.78266) (xy 357.95245 -278.826237) (xy 357.968034 -278.872918)
			(xy 357.975929 -278.921495) (xy 357.976424 -278.946102) (xy 358.305366 -278.946102) (xy 358.309326 -278.897048)
			(xy 358.321103 -278.849264) (xy 358.340394 -278.803988) (xy 358.366697 -278.762392) (xy 358.399332 -278.725555)
			(xy 358.437453 -278.69443) (xy 358.480074 -278.669823) (xy 358.52609 -278.652371) (xy 358.574309 -278.642527)
			(xy 358.623484 -278.640546) (xy 358.672339 -278.646478) (xy 358.71961 -278.66017) (xy 358.764072 -278.681268)
			(xy 358.804575 -278.709224) (xy 358.840068 -278.743316) (xy 358.869633 -278.78266) (xy 358.892504 -278.826237)
			(xy 358.908088 -278.872918) (xy 358.915983 -278.921495) (xy 358.916478 -278.946102) (xy 361.118924 -278.946102)
			(xy 361.122884 -278.897048) (xy 361.134661 -278.849264) (xy 361.153952 -278.803988) (xy 361.180255 -278.762392)
			(xy 361.21289 -278.725555) (xy 361.251011 -278.69443) (xy 361.293632 -278.669823) (xy 361.339648 -278.652371)
			(xy 361.387867 -278.642527) (xy 361.437042 -278.640546) (xy 361.485897 -278.646478) (xy 361.533168 -278.66017)
			(xy 361.57763 -278.681268) (xy 361.618133 -278.709224) (xy 361.653626 -278.743316) (xy 361.683191 -278.78266)
			(xy 361.706062 -278.826237) (xy 361.721646 -278.872918) (xy 361.729541 -278.921495) (xy 361.730036 -278.946102)
			(xy 362.058978 -278.946102) (xy 362.062938 -278.897048) (xy 362.074715 -278.849264) (xy 362.094006 -278.803988)
			(xy 362.120309 -278.762392) (xy 362.152944 -278.725555) (xy 362.191065 -278.69443) (xy 362.233686 -278.669823)
			(xy 362.279702 -278.652371) (xy 362.327921 -278.642527) (xy 362.377096 -278.640546) (xy 362.425951 -278.646478)
			(xy 362.473222 -278.66017) (xy 362.517684 -278.681268) (xy 362.558187 -278.709224) (xy 362.59368 -278.743316)
			(xy 362.623245 -278.78266) (xy 362.646116 -278.826237) (xy 362.6617 -278.872918) (xy 362.669595 -278.921495)
			(xy 362.67009 -278.946102) (xy 362.999032 -278.946102) (xy 363.002992 -278.897048) (xy 363.014769 -278.849264)
			(xy 363.03406 -278.803988) (xy 363.060363 -278.762392) (xy 363.092998 -278.725555) (xy 363.131119 -278.69443)
			(xy 363.17374 -278.669823) (xy 363.219756 -278.652371) (xy 363.267975 -278.642527) (xy 363.31715 -278.640546)
			(xy 363.366005 -278.646478) (xy 363.413276 -278.66017) (xy 363.457738 -278.681268) (xy 363.498241 -278.709224)
			(xy 363.533734 -278.743316) (xy 363.563299 -278.78266) (xy 363.58617 -278.826237) (xy 363.601754 -278.872918)
			(xy 363.609649 -278.921495) (xy 363.610144 -278.946102) (xy 363.939086 -278.946102) (xy 363.943046 -278.897048)
			(xy 363.954823 -278.849264) (xy 363.974114 -278.803988) (xy 364.000417 -278.762392) (xy 364.033052 -278.725555)
			(xy 364.071173 -278.69443) (xy 364.113794 -278.669823) (xy 364.15981 -278.652371) (xy 364.208029 -278.642527)
			(xy 364.257204 -278.640546) (xy 364.306059 -278.646478) (xy 364.35333 -278.66017) (xy 364.397792 -278.681268)
			(xy 364.438295 -278.709224) (xy 364.473788 -278.743316) (xy 364.503353 -278.78266) (xy 364.526224 -278.826237)
			(xy 364.541808 -278.872918) (xy 364.549703 -278.921495) (xy 364.550198 -278.946102) (xy 366.758994 -278.946102)
			(xy 366.762954 -278.897048) (xy 366.774731 -278.849264) (xy 366.794022 -278.803988) (xy 366.820325 -278.762392)
			(xy 366.85296 -278.725555) (xy 366.891081 -278.69443) (xy 366.933702 -278.669823) (xy 366.979718 -278.652371)
			(xy 367.027937 -278.642527) (xy 367.077112 -278.640546) (xy 367.125967 -278.646478) (xy 367.173238 -278.66017)
			(xy 367.2177 -278.681268) (xy 367.258203 -278.709224) (xy 367.293696 -278.743316) (xy 367.323261 -278.78266)
			(xy 367.346132 -278.826237) (xy 367.361716 -278.872918) (xy 367.369611 -278.921495) (xy 367.370106 -278.946102)
			(xy 369.578902 -278.946102) (xy 369.582862 -278.897048) (xy 369.594639 -278.849264) (xy 369.61393 -278.803988)
			(xy 369.640233 -278.762392) (xy 369.672868 -278.725555) (xy 369.710989 -278.69443) (xy 369.75361 -278.669823)
			(xy 369.799626 -278.652371) (xy 369.847845 -278.642527) (xy 369.89702 -278.640546) (xy 369.945875 -278.646478)
			(xy 369.993146 -278.66017) (xy 370.037608 -278.681268) (xy 370.078111 -278.709224) (xy 370.113604 -278.743316)
			(xy 370.143169 -278.78266) (xy 370.16604 -278.826237) (xy 370.181624 -278.872918) (xy 370.189519 -278.921495)
			(xy 370.190014 -278.946102) (xy 372.399064 -278.946102) (xy 372.403024 -278.897048) (xy 372.414801 -278.849264)
			(xy 372.434092 -278.803988) (xy 372.460395 -278.762392) (xy 372.49303 -278.725555) (xy 372.531151 -278.69443)
			(xy 372.573772 -278.669823) (xy 372.619788 -278.652371) (xy 372.668007 -278.642527) (xy 372.717182 -278.640546)
			(xy 372.766037 -278.646478) (xy 372.813308 -278.66017) (xy 372.85777 -278.681268) (xy 372.898273 -278.709224)
			(xy 372.933766 -278.743316) (xy 372.963331 -278.78266) (xy 372.986202 -278.826237) (xy 373.001786 -278.872918)
			(xy 373.009681 -278.921495) (xy 373.010176 -278.946102) (xy 373.009681 -278.970709) (xy 373.001786 -279.019286)
			(xy 372.986202 -279.065967) (xy 372.963331 -279.109544) (xy 372.933766 -279.148888) (xy 372.898273 -279.18298)
			(xy 372.85777 -279.210936) (xy 372.813308 -279.232034) (xy 372.766037 -279.245726) (xy 372.717182 -279.251658)
			(xy 372.668007 -279.249677) (xy 372.619788 -279.239833) (xy 372.573772 -279.222381) (xy 372.531151 -279.197774)
			(xy 372.49303 -279.166649) (xy 372.460395 -279.129812) (xy 372.434092 -279.088216) (xy 372.414801 -279.04294)
			(xy 372.403024 -278.995156) (xy 372.399064 -278.946102) (xy 370.190014 -278.946102) (xy 370.189519 -278.970709)
			(xy 370.181624 -279.019286) (xy 370.16604 -279.065967) (xy 370.143169 -279.109544) (xy 370.113604 -279.148888)
			(xy 370.078111 -279.18298) (xy 370.037608 -279.210936) (xy 369.993146 -279.232034) (xy 369.945875 -279.245726)
			(xy 369.89702 -279.251658) (xy 369.847845 -279.249677) (xy 369.799626 -279.239833) (xy 369.75361 -279.222381)
			(xy 369.710989 -279.197774) (xy 369.672868 -279.166649) (xy 369.640233 -279.129812) (xy 369.61393 -279.088216)
			(xy 369.594639 -279.04294) (xy 369.582862 -278.995156) (xy 369.578902 -278.946102) (xy 367.370106 -278.946102)
			(xy 367.369611 -278.970709) (xy 367.361716 -279.019286) (xy 367.346132 -279.065967) (xy 367.323261 -279.109544)
			(xy 367.293696 -279.148888) (xy 367.258203 -279.18298) (xy 367.2177 -279.210936) (xy 367.173238 -279.232034)
			(xy 367.125967 -279.245726) (xy 367.077112 -279.251658) (xy 367.027937 -279.249677) (xy 366.979718 -279.239833)
			(xy 366.933702 -279.222381) (xy 366.891081 -279.197774) (xy 366.85296 -279.166649) (xy 366.820325 -279.129812)
			(xy 366.794022 -279.088216) (xy 366.774731 -279.04294) (xy 366.762954 -278.995156) (xy 366.758994 -278.946102)
			(xy 364.550198 -278.946102) (xy 364.549703 -278.970709) (xy 364.541808 -279.019286) (xy 364.526224 -279.065967)
			(xy 364.503353 -279.109544) (xy 364.473788 -279.148888) (xy 364.438295 -279.18298) (xy 364.397792 -279.210936)
			(xy 364.35333 -279.232034) (xy 364.306059 -279.245726) (xy 364.257204 -279.251658) (xy 364.208029 -279.249677)
			(xy 364.15981 -279.239833) (xy 364.113794 -279.222381) (xy 364.071173 -279.197774) (xy 364.033052 -279.166649)
			(xy 364.000417 -279.129812) (xy 363.974114 -279.088216) (xy 363.954823 -279.04294) (xy 363.943046 -278.995156)
			(xy 363.939086 -278.946102) (xy 363.610144 -278.946102) (xy 363.609649 -278.970709) (xy 363.601754 -279.019286)
			(xy 363.58617 -279.065967) (xy 363.563299 -279.109544) (xy 363.533734 -279.148888) (xy 363.498241 -279.18298)
			(xy 363.457738 -279.210936) (xy 363.413276 -279.232034) (xy 363.366005 -279.245726) (xy 363.31715 -279.251658)
			(xy 363.267975 -279.249677) (xy 363.219756 -279.239833) (xy 363.17374 -279.222381) (xy 363.131119 -279.197774)
			(xy 363.092998 -279.166649) (xy 363.060363 -279.129812) (xy 363.03406 -279.088216) (xy 363.014769 -279.04294)
			(xy 363.002992 -278.995156) (xy 362.999032 -278.946102) (xy 362.67009 -278.946102) (xy 362.669595 -278.970709)
			(xy 362.6617 -279.019286) (xy 362.646116 -279.065967) (xy 362.623245 -279.109544) (xy 362.59368 -279.148888)
			(xy 362.558187 -279.18298) (xy 362.517684 -279.210936) (xy 362.473222 -279.232034) (xy 362.425951 -279.245726)
			(xy 362.377096 -279.251658) (xy 362.327921 -279.249677) (xy 362.279702 -279.239833) (xy 362.233686 -279.222381)
			(xy 362.191065 -279.197774) (xy 362.152944 -279.166649) (xy 362.120309 -279.129812) (xy 362.094006 -279.088216)
			(xy 362.074715 -279.04294) (xy 362.062938 -278.995156) (xy 362.058978 -278.946102) (xy 361.730036 -278.946102)
			(xy 361.729541 -278.970709) (xy 361.721646 -279.019286) (xy 361.706062 -279.065967) (xy 361.683191 -279.109544)
			(xy 361.653626 -279.148888) (xy 361.618133 -279.18298) (xy 361.57763 -279.210936) (xy 361.533168 -279.232034)
			(xy 361.485897 -279.245726) (xy 361.437042 -279.251658) (xy 361.387867 -279.249677) (xy 361.339648 -279.239833)
			(xy 361.293632 -279.222381) (xy 361.251011 -279.197774) (xy 361.21289 -279.166649) (xy 361.180255 -279.129812)
			(xy 361.153952 -279.088216) (xy 361.134661 -279.04294) (xy 361.122884 -278.995156) (xy 361.118924 -278.946102)
			(xy 358.916478 -278.946102) (xy 358.915983 -278.970709) (xy 358.908088 -279.019286) (xy 358.892504 -279.065967)
			(xy 358.869633 -279.109544) (xy 358.840068 -279.148888) (xy 358.804575 -279.18298) (xy 358.764072 -279.210936)
			(xy 358.71961 -279.232034) (xy 358.672339 -279.245726) (xy 358.623484 -279.251658) (xy 358.574309 -279.249677)
			(xy 358.52609 -279.239833) (xy 358.480074 -279.222381) (xy 358.437453 -279.197774) (xy 358.399332 -279.166649)
			(xy 358.366697 -279.129812) (xy 358.340394 -279.088216) (xy 358.321103 -279.04294) (xy 358.309326 -278.995156)
			(xy 358.305366 -278.946102) (xy 357.976424 -278.946102) (xy 357.975929 -278.970709) (xy 357.968034 -279.019286)
			(xy 357.95245 -279.065967) (xy 357.929579 -279.109544) (xy 357.900014 -279.148888) (xy 357.864521 -279.18298)
			(xy 357.824018 -279.210936) (xy 357.779556 -279.232034) (xy 357.732285 -279.245726) (xy 357.68343 -279.251658)
			(xy 357.634255 -279.249677) (xy 357.586036 -279.239833) (xy 357.54002 -279.222381) (xy 357.497399 -279.197774)
			(xy 357.459278 -279.166649) (xy 357.426643 -279.129812) (xy 357.40034 -279.088216) (xy 357.381049 -279.04294)
			(xy 357.369272 -278.995156) (xy 357.365312 -278.946102) (xy 357.03637 -278.946102) (xy 357.035875 -278.970709)
			(xy 357.02798 -279.019286) (xy 357.012396 -279.065967) (xy 356.989525 -279.109544) (xy 356.95996 -279.148888)
			(xy 356.924467 -279.18298) (xy 356.883964 -279.210936) (xy 356.839502 -279.232034) (xy 356.792231 -279.245726)
			(xy 356.743376 -279.251658) (xy 356.694201 -279.249677) (xy 356.645982 -279.239833) (xy 356.599966 -279.222381)
			(xy 356.557345 -279.197774) (xy 356.519224 -279.166649) (xy 356.486589 -279.129812) (xy 356.460286 -279.088216)
			(xy 356.440995 -279.04294) (xy 356.429218 -278.995156) (xy 356.425258 -278.946102) (xy 356.096316 -278.946102)
			(xy 356.095821 -278.970709) (xy 356.087926 -279.019286) (xy 356.072342 -279.065967) (xy 356.049471 -279.109544)
			(xy 356.019906 -279.148888) (xy 355.984413 -279.18298) (xy 355.94391 -279.210936) (xy 355.899448 -279.232034)
			(xy 355.852177 -279.245726) (xy 355.803322 -279.251658) (xy 355.754147 -279.249677) (xy 355.705928 -279.239833)
			(xy 355.659912 -279.222381) (xy 355.617291 -279.197774) (xy 355.57917 -279.166649) (xy 355.546535 -279.129812)
			(xy 355.520232 -279.088216) (xy 355.500941 -279.04294) (xy 355.489164 -278.995156) (xy 355.485204 -278.946102)
			(xy 353.276408 -278.946102) (xy 353.275913 -278.970709) (xy 353.268018 -279.019286) (xy 353.252434 -279.065967)
			(xy 353.229563 -279.109544) (xy 353.199998 -279.148888) (xy 353.164505 -279.18298) (xy 353.124002 -279.210936)
			(xy 353.07954 -279.232034) (xy 353.032269 -279.245726) (xy 352.983414 -279.251658) (xy 352.934239 -279.249677)
			(xy 352.88602 -279.239833) (xy 352.840004 -279.222381) (xy 352.797383 -279.197774) (xy 352.759262 -279.166649)
			(xy 352.726627 -279.129812) (xy 352.700324 -279.088216) (xy 352.681033 -279.04294) (xy 352.669256 -278.995156)
			(xy 352.665296 -278.946102) (xy 350.4565 -278.946102) (xy 350.456005 -278.970709) (xy 350.44811 -279.019286)
			(xy 350.432526 -279.065967) (xy 350.409655 -279.109544) (xy 350.38009 -279.148888) (xy 350.344597 -279.18298)
			(xy 350.304094 -279.210936) (xy 350.259632 -279.232034) (xy 350.212361 -279.245726) (xy 350.163506 -279.251658)
			(xy 350.114331 -279.249677) (xy 350.066112 -279.239833) (xy 350.020096 -279.222381) (xy 349.977475 -279.197774)
			(xy 349.939354 -279.166649) (xy 349.906719 -279.129812) (xy 349.880416 -279.088216) (xy 349.861125 -279.04294)
			(xy 349.849348 -278.995156) (xy 349.845388 -278.946102) (xy 347.636338 -278.946102) (xy 347.635843 -278.970709)
			(xy 347.627948 -279.019286) (xy 347.612364 -279.065967) (xy 347.589493 -279.109544) (xy 347.559928 -279.148888)
			(xy 347.524435 -279.18298) (xy 347.483932 -279.210936) (xy 347.43947 -279.232034) (xy 347.392199 -279.245726)
			(xy 347.343344 -279.251658) (xy 347.294169 -279.249677) (xy 347.24595 -279.239833) (xy 347.199934 -279.222381)
			(xy 347.157313 -279.197774) (xy 347.119192 -279.166649) (xy 347.086557 -279.129812) (xy 347.060254 -279.088216)
			(xy 347.040963 -279.04294) (xy 347.029186 -278.995156) (xy 347.025226 -278.946102) (xy 344.81643 -278.946102)
			(xy 344.815935 -278.970709) (xy 344.80804 -279.019286) (xy 344.792456 -279.065967) (xy 344.769585 -279.109544)
			(xy 344.74002 -279.148888) (xy 344.704527 -279.18298) (xy 344.664024 -279.210936) (xy 344.619562 -279.232034)
			(xy 344.572291 -279.245726) (xy 344.523436 -279.251658) (xy 344.474261 -279.249677) (xy 344.426042 -279.239833)
			(xy 344.380026 -279.222381) (xy 344.337405 -279.197774) (xy 344.299284 -279.166649) (xy 344.266649 -279.129812)
			(xy 344.240346 -279.088216) (xy 344.221055 -279.04294) (xy 344.209278 -278.995156) (xy 344.205318 -278.946102)
			(xy 343.88679 -278.946102) (xy 343.886278 -278.971548) (xy 343.878114 -279.021782) (xy 343.861998 -279.070056)
			(xy 343.838347 -279.115119) (xy 343.807774 -279.155805) (xy 343.77107 -279.19106) (xy 343.729186 -279.21997)
			(xy 343.683207 -279.241787) (xy 343.634323 -279.255947) (xy 343.583802 -279.262081) (xy 343.53295 -279.260032)
			(xy 343.483086 -279.249852) (xy 343.4355 -279.231805) (xy 343.391426 -279.206359) (xy 343.352004 -279.174172)
			(xy 343.318256 -279.136078) (xy 343.291055 -279.093064) (xy 343.271107 -279.046244) (xy 343.258928 -278.99683)
			(xy 343.254833 -278.946102) (xy 342.946736 -278.946102) (xy 342.946224 -278.971548) (xy 342.93806 -279.021782)
			(xy 342.921944 -279.070056) (xy 342.898293 -279.115119) (xy 342.86772 -279.155805) (xy 342.831016 -279.19106)
			(xy 342.789132 -279.21997) (xy 342.743153 -279.241787) (xy 342.694269 -279.255947) (xy 342.643748 -279.262081)
			(xy 342.592896 -279.260032) (xy 342.543032 -279.249852) (xy 342.495446 -279.231805) (xy 342.451372 -279.206359)
			(xy 342.41195 -279.174172) (xy 342.378202 -279.136078) (xy 342.351001 -279.093064) (xy 342.331053 -279.046244)
			(xy 342.318874 -278.99683) (xy 342.314779 -278.946102) (xy 341.996522 -278.946102) (xy 341.996027 -278.970709)
			(xy 341.988132 -279.019286) (xy 341.972548 -279.065967) (xy 341.949677 -279.109544) (xy 341.920112 -279.148888)
			(xy 341.884619 -279.18298) (xy 341.844116 -279.210936) (xy 341.799654 -279.232034) (xy 341.752383 -279.245726)
			(xy 341.703528 -279.251658) (xy 341.654353 -279.249677) (xy 341.606134 -279.239833) (xy 341.560118 -279.222381)
			(xy 341.517497 -279.197774) (xy 341.479376 -279.166649) (xy 341.446741 -279.129812) (xy 341.420438 -279.088216)
			(xy 341.401147 -279.04294) (xy 341.38937 -278.995156) (xy 341.38541 -278.946102) (xy 341.066882 -278.946102)
			(xy 341.06637 -278.971548) (xy 341.058206 -279.021782) (xy 341.04209 -279.070056) (xy 341.018439 -279.115119)
			(xy 340.987866 -279.155805) (xy 340.951162 -279.19106) (xy 340.909278 -279.21997) (xy 340.863299 -279.241787)
			(xy 340.814415 -279.255947) (xy 340.763894 -279.262081) (xy 340.713042 -279.260032) (xy 340.663178 -279.249852)
			(xy 340.615592 -279.231805) (xy 340.571518 -279.206359) (xy 340.532096 -279.174172) (xy 340.498348 -279.136078)
			(xy 340.471147 -279.093064) (xy 340.451199 -279.046244) (xy 340.43902 -278.99683) (xy 340.434925 -278.946102)
			(xy 340.308438 -278.946102) (xy 340.308438 -279.167082) (xy 340.311994 -279.180036) (xy 340.31555 -279.186132)
			(xy 340.340793 -279.229711) (xy 340.384203 -279.320595) (xy 340.419207 -279.415034) (xy 340.432898 -279.4635)
			(xy 340.434164 -279.467775) (xy 340.437993 -279.475827) (xy 340.440518 -279.479502) (xy 340.445852 -279.487122)
			(xy 340.468481 -279.501617) (xy 340.508891 -279.537035) (xy 340.542725 -279.57878) (xy 340.569006 -279.625649)
			(xy 340.586977 -279.67629) (xy 340.59612 -279.729241) (xy 340.596728 -279.756108) (xy 340.915256 -279.756108)
			(xy 340.919216 -279.707054) (xy 340.930993 -279.65927) (xy 340.950284 -279.613994) (xy 340.976587 -279.572398)
			(xy 341.009222 -279.535561) (xy 341.047343 -279.504436) (xy 341.089964 -279.479829) (xy 341.13598 -279.462377)
			(xy 341.184199 -279.452533) (xy 341.233374 -279.450552) (xy 341.282229 -279.456484) (xy 341.3295 -279.470176)
			(xy 341.373962 -279.491274) (xy 341.414465 -279.51923) (xy 341.449958 -279.553322) (xy 341.479523 -279.592666)
			(xy 341.502394 -279.636243) (xy 341.517978 -279.682924) (xy 341.525873 -279.731501) (xy 341.526368 -279.756108)
			(xy 341.844879 -279.756108) (xy 341.848974 -279.70538) (xy 341.861153 -279.655966) (xy 341.881101 -279.609146)
			(xy 341.908302 -279.566132) (xy 341.94205 -279.528038) (xy 341.981472 -279.495851) (xy 342.025546 -279.470405)
			(xy 342.073132 -279.452358) (xy 342.122996 -279.442178) (xy 342.173848 -279.440129) (xy 342.224369 -279.446263)
			(xy 342.273253 -279.460423) (xy 342.319232 -279.48224) (xy 342.361116 -279.51115) (xy 342.39782 -279.546405)
			(xy 342.428393 -279.587091) (xy 342.452044 -279.632154) (xy 342.46816 -279.680428) (xy 342.476324 -279.730662)
			(xy 342.476836 -279.756108) (xy 342.795364 -279.756108) (xy 342.799324 -279.707054) (xy 342.811101 -279.65927)
			(xy 342.830392 -279.613994) (xy 342.856695 -279.572398) (xy 342.88933 -279.535561) (xy 342.927451 -279.504436)
			(xy 342.970072 -279.479829) (xy 343.016088 -279.462377) (xy 343.064307 -279.452533) (xy 343.113482 -279.450552)
			(xy 343.162337 -279.456484) (xy 343.209608 -279.470176) (xy 343.25407 -279.491274) (xy 343.294573 -279.51923)
			(xy 343.330066 -279.553322) (xy 343.359631 -279.592666) (xy 343.382502 -279.636243) (xy 343.398086 -279.682924)
			(xy 343.405981 -279.731501) (xy 343.406476 -279.756108) (xy 343.724987 -279.756108) (xy 343.729082 -279.70538)
			(xy 343.741261 -279.655966) (xy 343.761209 -279.609146) (xy 343.78841 -279.566132) (xy 343.822158 -279.528038)
			(xy 343.86158 -279.495851) (xy 343.905654 -279.470405) (xy 343.95324 -279.452358) (xy 344.003104 -279.442178)
			(xy 344.053956 -279.440129) (xy 344.104477 -279.446263) (xy 344.153361 -279.460423) (xy 344.19934 -279.48224)
			(xy 344.241224 -279.51115) (xy 344.277928 -279.546405) (xy 344.308501 -279.587091) (xy 344.332152 -279.632154)
			(xy 344.348268 -279.680428) (xy 344.356432 -279.730662) (xy 344.356944 -279.756108) (xy 344.675218 -279.756108)
			(xy 344.679178 -279.707054) (xy 344.690955 -279.65927) (xy 344.710246 -279.613994) (xy 344.736549 -279.572398)
			(xy 344.769184 -279.535561) (xy 344.807305 -279.504436) (xy 344.849926 -279.479829) (xy 344.895942 -279.462377)
			(xy 344.944161 -279.452533) (xy 344.993336 -279.450552) (xy 345.042191 -279.456484) (xy 345.089462 -279.470176)
			(xy 345.133924 -279.491274) (xy 345.174427 -279.51923) (xy 345.20992 -279.553322) (xy 345.239485 -279.592666)
			(xy 345.262356 -279.636243) (xy 345.27794 -279.682924) (xy 345.285835 -279.731501) (xy 345.28633 -279.756108)
			(xy 345.615272 -279.756108) (xy 345.619232 -279.707054) (xy 345.631009 -279.65927) (xy 345.6503 -279.613994)
			(xy 345.676603 -279.572398) (xy 345.709238 -279.535561) (xy 345.747359 -279.504436) (xy 345.78998 -279.479829)
			(xy 345.835996 -279.462377) (xy 345.884215 -279.452533) (xy 345.93339 -279.450552) (xy 345.982245 -279.456484)
			(xy 346.029516 -279.470176) (xy 346.073978 -279.491274) (xy 346.114481 -279.51923) (xy 346.149974 -279.553322)
			(xy 346.179539 -279.592666) (xy 346.20241 -279.636243) (xy 346.217994 -279.682924) (xy 346.225889 -279.731501)
			(xy 346.226384 -279.756108) (xy 346.555326 -279.756108) (xy 346.559286 -279.707054) (xy 346.571063 -279.65927)
			(xy 346.590354 -279.613994) (xy 346.616657 -279.572398) (xy 346.649292 -279.535561) (xy 346.687413 -279.504436)
			(xy 346.730034 -279.479829) (xy 346.77605 -279.462377) (xy 346.824269 -279.452533) (xy 346.873444 -279.450552)
			(xy 346.922299 -279.456484) (xy 346.96957 -279.470176) (xy 347.014032 -279.491274) (xy 347.054535 -279.51923)
			(xy 347.090028 -279.553322) (xy 347.119593 -279.592666) (xy 347.142464 -279.636243) (xy 347.158048 -279.682924)
			(xy 347.165943 -279.731501) (xy 347.166438 -279.756108) (xy 347.49538 -279.756108) (xy 347.49934 -279.707054)
			(xy 347.511117 -279.65927) (xy 347.530408 -279.613994) (xy 347.556711 -279.572398) (xy 347.589346 -279.535561)
			(xy 347.627467 -279.504436) (xy 347.670088 -279.479829) (xy 347.716104 -279.462377) (xy 347.764323 -279.452533)
			(xy 347.813498 -279.450552) (xy 347.862353 -279.456484) (xy 347.909624 -279.470176) (xy 347.954086 -279.491274)
			(xy 347.994589 -279.51923) (xy 348.030082 -279.553322) (xy 348.059647 -279.592666) (xy 348.082518 -279.636243)
			(xy 348.098102 -279.682924) (xy 348.105997 -279.731501) (xy 348.106492 -279.756108) (xy 348.435434 -279.756108)
			(xy 348.439394 -279.707054) (xy 348.451171 -279.65927) (xy 348.470462 -279.613994) (xy 348.496765 -279.572398)
			(xy 348.5294 -279.535561) (xy 348.567521 -279.504436) (xy 348.610142 -279.479829) (xy 348.656158 -279.462377)
			(xy 348.704377 -279.452533) (xy 348.753552 -279.450552) (xy 348.802407 -279.456484) (xy 348.849678 -279.470176)
			(xy 348.89414 -279.491274) (xy 348.934643 -279.51923) (xy 348.970136 -279.553322) (xy 348.999701 -279.592666)
			(xy 349.022572 -279.636243) (xy 349.038156 -279.682924) (xy 349.046051 -279.731501) (xy 349.046546 -279.756108)
			(xy 349.375234 -279.756108) (xy 349.379194 -279.707054) (xy 349.390971 -279.65927) (xy 349.410262 -279.613994)
			(xy 349.436565 -279.572398) (xy 349.4692 -279.535561) (xy 349.507321 -279.504436) (xy 349.549942 -279.479829)
			(xy 349.595958 -279.462377) (xy 349.644177 -279.452533) (xy 349.693352 -279.450552) (xy 349.742207 -279.456484)
			(xy 349.789478 -279.470176) (xy 349.83394 -279.491274) (xy 349.874443 -279.51923) (xy 349.909936 -279.553322)
			(xy 349.939501 -279.592666) (xy 349.962372 -279.636243) (xy 349.977956 -279.682924) (xy 349.985851 -279.731501)
			(xy 349.986346 -279.756108) (xy 350.315288 -279.756108) (xy 350.319248 -279.707054) (xy 350.331025 -279.65927)
			(xy 350.350316 -279.613994) (xy 350.376619 -279.572398) (xy 350.409254 -279.535561) (xy 350.447375 -279.504436)
			(xy 350.489996 -279.479829) (xy 350.536012 -279.462377) (xy 350.584231 -279.452533) (xy 350.633406 -279.450552)
			(xy 350.682261 -279.456484) (xy 350.729532 -279.470176) (xy 350.773994 -279.491274) (xy 350.814497 -279.51923)
			(xy 350.84999 -279.553322) (xy 350.879555 -279.592666) (xy 350.902426 -279.636243) (xy 350.91801 -279.682924)
			(xy 350.925905 -279.731501) (xy 350.9264 -279.756108) (xy 351.255342 -279.756108) (xy 351.259302 -279.707054)
			(xy 351.271079 -279.65927) (xy 351.29037 -279.613994) (xy 351.316673 -279.572398) (xy 351.349308 -279.535561)
			(xy 351.387429 -279.504436) (xy 351.43005 -279.479829) (xy 351.476066 -279.462377) (xy 351.524285 -279.452533)
			(xy 351.57346 -279.450552) (xy 351.622315 -279.456484) (xy 351.669586 -279.470176) (xy 351.714048 -279.491274)
			(xy 351.754551 -279.51923) (xy 351.790044 -279.553322) (xy 351.819609 -279.592666) (xy 351.84248 -279.636243)
			(xy 351.858064 -279.682924) (xy 351.865959 -279.731501) (xy 351.866454 -279.756108) (xy 352.195396 -279.756108)
			(xy 352.199356 -279.707054) (xy 352.211133 -279.65927) (xy 352.230424 -279.613994) (xy 352.256727 -279.572398)
			(xy 352.289362 -279.535561) (xy 352.327483 -279.504436) (xy 352.370104 -279.479829) (xy 352.41612 -279.462377)
			(xy 352.464339 -279.452533) (xy 352.513514 -279.450552) (xy 352.562369 -279.456484) (xy 352.60964 -279.470176)
			(xy 352.654102 -279.491274) (xy 352.694605 -279.51923) (xy 352.730098 -279.553322) (xy 352.759663 -279.592666)
			(xy 352.782534 -279.636243) (xy 352.798118 -279.682924) (xy 352.806013 -279.731501) (xy 352.806508 -279.756108)
			(xy 353.135196 -279.756108) (xy 353.139156 -279.707054) (xy 353.150933 -279.65927) (xy 353.170224 -279.613994)
			(xy 353.196527 -279.572398) (xy 353.229162 -279.535561) (xy 353.267283 -279.504436) (xy 353.309904 -279.479829)
			(xy 353.35592 -279.462377) (xy 353.404139 -279.452533) (xy 353.453314 -279.450552) (xy 353.502169 -279.456484)
			(xy 353.54944 -279.470176) (xy 353.593902 -279.491274) (xy 353.634405 -279.51923) (xy 353.669898 -279.553322)
			(xy 353.699463 -279.592666) (xy 353.722334 -279.636243) (xy 353.737918 -279.682924) (xy 353.745813 -279.731501)
			(xy 353.746308 -279.756108) (xy 354.07525 -279.756108) (xy 354.07921 -279.707054) (xy 354.090987 -279.65927)
			(xy 354.110278 -279.613994) (xy 354.136581 -279.572398) (xy 354.169216 -279.535561) (xy 354.207337 -279.504436)
			(xy 354.249958 -279.479829) (xy 354.295974 -279.462377) (xy 354.344193 -279.452533) (xy 354.393368 -279.450552)
			(xy 354.442223 -279.456484) (xy 354.489494 -279.470176) (xy 354.533956 -279.491274) (xy 354.574459 -279.51923)
			(xy 354.609952 -279.553322) (xy 354.639517 -279.592666) (xy 354.662388 -279.636243) (xy 354.677972 -279.682924)
			(xy 354.685867 -279.731501) (xy 354.686362 -279.756108) (xy 355.015304 -279.756108) (xy 355.019264 -279.707054)
			(xy 355.031041 -279.65927) (xy 355.050332 -279.613994) (xy 355.076635 -279.572398) (xy 355.10927 -279.535561)
			(xy 355.147391 -279.504436) (xy 355.190012 -279.479829) (xy 355.236028 -279.462377) (xy 355.284247 -279.452533)
			(xy 355.333422 -279.450552) (xy 355.382277 -279.456484) (xy 355.429548 -279.470176) (xy 355.47401 -279.491274)
			(xy 355.514513 -279.51923) (xy 355.550006 -279.553322) (xy 355.579571 -279.592666) (xy 355.602442 -279.636243)
			(xy 355.618026 -279.682924) (xy 355.625921 -279.731501) (xy 355.626416 -279.756108) (xy 355.955358 -279.756108)
			(xy 355.959318 -279.707054) (xy 355.971095 -279.65927) (xy 355.990386 -279.613994) (xy 356.016689 -279.572398)
			(xy 356.049324 -279.535561) (xy 356.087445 -279.504436) (xy 356.130066 -279.479829) (xy 356.176082 -279.462377)
			(xy 356.224301 -279.452533) (xy 356.273476 -279.450552) (xy 356.322331 -279.456484) (xy 356.369602 -279.470176)
			(xy 356.414064 -279.491274) (xy 356.454567 -279.51923) (xy 356.49006 -279.553322) (xy 356.519625 -279.592666)
			(xy 356.542496 -279.636243) (xy 356.55808 -279.682924) (xy 356.565975 -279.731501) (xy 356.56647 -279.756108)
			(xy 356.895412 -279.756108) (xy 356.899372 -279.707054) (xy 356.911149 -279.65927) (xy 356.93044 -279.613994)
			(xy 356.956743 -279.572398) (xy 356.989378 -279.535561) (xy 357.027499 -279.504436) (xy 357.07012 -279.479829)
			(xy 357.116136 -279.462377) (xy 357.164355 -279.452533) (xy 357.21353 -279.450552) (xy 357.262385 -279.456484)
			(xy 357.309656 -279.470176) (xy 357.354118 -279.491274) (xy 357.394621 -279.51923) (xy 357.430114 -279.553322)
			(xy 357.459679 -279.592666) (xy 357.48255 -279.636243) (xy 357.498134 -279.682924) (xy 357.506029 -279.731501)
			(xy 357.506524 -279.756108) (xy 357.835212 -279.756108) (xy 357.839172 -279.707054) (xy 357.850949 -279.65927)
			(xy 357.87024 -279.613994) (xy 357.896543 -279.572398) (xy 357.929178 -279.535561) (xy 357.967299 -279.504436)
			(xy 358.00992 -279.479829) (xy 358.055936 -279.462377) (xy 358.104155 -279.452533) (xy 358.15333 -279.450552)
			(xy 358.202185 -279.456484) (xy 358.249456 -279.470176) (xy 358.293918 -279.491274) (xy 358.334421 -279.51923)
			(xy 358.369914 -279.553322) (xy 358.399479 -279.592666) (xy 358.42235 -279.636243) (xy 358.437934 -279.682924)
			(xy 358.445829 -279.731501) (xy 358.446324 -279.756108) (xy 361.589078 -279.756108) (xy 361.593038 -279.707054)
			(xy 361.604815 -279.65927) (xy 361.624106 -279.613994) (xy 361.650409 -279.572398) (xy 361.683044 -279.535561)
			(xy 361.721165 -279.504436) (xy 361.763786 -279.479829) (xy 361.809802 -279.462377) (xy 361.858021 -279.452533)
			(xy 361.907196 -279.450552) (xy 361.956051 -279.456484) (xy 362.003322 -279.470176) (xy 362.047784 -279.491274)
			(xy 362.088287 -279.51923) (xy 362.12378 -279.553322) (xy 362.153345 -279.592666) (xy 362.176216 -279.636243)
			(xy 362.1918 -279.682924) (xy 362.199695 -279.731501) (xy 362.20019 -279.756108) (xy 362.528878 -279.756108)
			(xy 362.532838 -279.707054) (xy 362.544615 -279.65927) (xy 362.563906 -279.613994) (xy 362.590209 -279.572398)
			(xy 362.622844 -279.535561) (xy 362.660965 -279.504436) (xy 362.703586 -279.479829) (xy 362.749602 -279.462377)
			(xy 362.797821 -279.452533) (xy 362.846996 -279.450552) (xy 362.895851 -279.456484) (xy 362.943122 -279.470176)
			(xy 362.987584 -279.491274) (xy 363.028087 -279.51923) (xy 363.06358 -279.553322) (xy 363.093145 -279.592666)
			(xy 363.116016 -279.636243) (xy 363.1316 -279.682924) (xy 363.139495 -279.731501) (xy 363.13999 -279.756108)
			(xy 363.468932 -279.756108) (xy 363.472892 -279.707054) (xy 363.484669 -279.65927) (xy 363.50396 -279.613994)
			(xy 363.530263 -279.572398) (xy 363.562898 -279.535561) (xy 363.601019 -279.504436) (xy 363.64364 -279.479829)
			(xy 363.689656 -279.462377) (xy 363.737875 -279.452533) (xy 363.78705 -279.450552) (xy 363.835905 -279.456484)
			(xy 363.883176 -279.470176) (xy 363.927638 -279.491274) (xy 363.968141 -279.51923) (xy 364.003634 -279.553322)
			(xy 364.033199 -279.592666) (xy 364.05607 -279.636243) (xy 364.071654 -279.682924) (xy 364.079549 -279.731501)
			(xy 364.080044 -279.756108) (xy 364.408986 -279.756108) (xy 364.412946 -279.707054) (xy 364.424723 -279.65927)
			(xy 364.444014 -279.613994) (xy 364.470317 -279.572398) (xy 364.502952 -279.535561) (xy 364.541073 -279.504436)
			(xy 364.583694 -279.479829) (xy 364.62971 -279.462377) (xy 364.677929 -279.452533) (xy 364.727104 -279.450552)
			(xy 364.775959 -279.456484) (xy 364.82323 -279.470176) (xy 364.867692 -279.491274) (xy 364.908195 -279.51923)
			(xy 364.943688 -279.553322) (xy 364.973253 -279.592666) (xy 364.996124 -279.636243) (xy 365.011708 -279.682924)
			(xy 365.019603 -279.731501) (xy 365.020098 -279.756108) (xy 365.34904 -279.756108) (xy 365.353 -279.707054)
			(xy 365.364777 -279.65927) (xy 365.384068 -279.613994) (xy 365.410371 -279.572398) (xy 365.443006 -279.535561)
			(xy 365.481127 -279.504436) (xy 365.523748 -279.479829) (xy 365.569764 -279.462377) (xy 365.617983 -279.452533)
			(xy 365.667158 -279.450552) (xy 365.716013 -279.456484) (xy 365.763284 -279.470176) (xy 365.807746 -279.491274)
			(xy 365.848249 -279.51923) (xy 365.883742 -279.553322) (xy 365.913307 -279.592666) (xy 365.936178 -279.636243)
			(xy 365.951762 -279.682924) (xy 365.959657 -279.731501) (xy 365.960152 -279.756108) (xy 366.289094 -279.756108)
			(xy 366.293054 -279.707054) (xy 366.304831 -279.65927) (xy 366.324122 -279.613994) (xy 366.350425 -279.572398)
			(xy 366.38306 -279.535561) (xy 366.421181 -279.504436) (xy 366.463802 -279.479829) (xy 366.509818 -279.462377)
			(xy 366.558037 -279.452533) (xy 366.607212 -279.450552) (xy 366.656067 -279.456484) (xy 366.703338 -279.470176)
			(xy 366.7478 -279.491274) (xy 366.788303 -279.51923) (xy 366.823796 -279.553322) (xy 366.853361 -279.592666)
			(xy 366.876232 -279.636243) (xy 366.891816 -279.682924) (xy 366.899711 -279.731501) (xy 366.900206 -279.756108)
			(xy 367.228894 -279.756108) (xy 367.232854 -279.707054) (xy 367.244631 -279.65927) (xy 367.263922 -279.613994)
			(xy 367.290225 -279.572398) (xy 367.32286 -279.535561) (xy 367.360981 -279.504436) (xy 367.403602 -279.479829)
			(xy 367.449618 -279.462377) (xy 367.497837 -279.452533) (xy 367.547012 -279.450552) (xy 367.595867 -279.456484)
			(xy 367.643138 -279.470176) (xy 367.6876 -279.491274) (xy 367.728103 -279.51923) (xy 367.763596 -279.553322)
			(xy 367.793161 -279.592666) (xy 367.816032 -279.636243) (xy 367.831616 -279.682924) (xy 367.839511 -279.731501)
			(xy 367.840006 -279.756108) (xy 368.168948 -279.756108) (xy 368.172908 -279.707054) (xy 368.184685 -279.65927)
			(xy 368.203976 -279.613994) (xy 368.230279 -279.572398) (xy 368.262914 -279.535561) (xy 368.301035 -279.504436)
			(xy 368.343656 -279.479829) (xy 368.389672 -279.462377) (xy 368.437891 -279.452533) (xy 368.487066 -279.450552)
			(xy 368.535921 -279.456484) (xy 368.583192 -279.470176) (xy 368.627654 -279.491274) (xy 368.668157 -279.51923)
			(xy 368.70365 -279.553322) (xy 368.733215 -279.592666) (xy 368.756086 -279.636243) (xy 368.77167 -279.682924)
			(xy 368.779565 -279.731501) (xy 368.78006 -279.756108) (xy 369.109002 -279.756108) (xy 369.112962 -279.707054)
			(xy 369.124739 -279.65927) (xy 369.14403 -279.613994) (xy 369.170333 -279.572398) (xy 369.202968 -279.535561)
			(xy 369.241089 -279.504436) (xy 369.28371 -279.479829) (xy 369.329726 -279.462377) (xy 369.377945 -279.452533)
			(xy 369.42712 -279.450552) (xy 369.475975 -279.456484) (xy 369.523246 -279.470176) (xy 369.567708 -279.491274)
			(xy 369.608211 -279.51923) (xy 369.643704 -279.553322) (xy 369.673269 -279.592666) (xy 369.69614 -279.636243)
			(xy 369.711724 -279.682924) (xy 369.719619 -279.731501) (xy 369.720114 -279.756108) (xy 370.049056 -279.756108)
			(xy 370.053016 -279.707054) (xy 370.064793 -279.65927) (xy 370.084084 -279.613994) (xy 370.110387 -279.572398)
			(xy 370.143022 -279.535561) (xy 370.181143 -279.504436) (xy 370.223764 -279.479829) (xy 370.26978 -279.462377)
			(xy 370.317999 -279.452533) (xy 370.367174 -279.450552) (xy 370.416029 -279.456484) (xy 370.4633 -279.470176)
			(xy 370.507762 -279.491274) (xy 370.548265 -279.51923) (xy 370.583758 -279.553322) (xy 370.613323 -279.592666)
			(xy 370.636194 -279.636243) (xy 370.651778 -279.682924) (xy 370.659673 -279.731501) (xy 370.660168 -279.756108)
			(xy 370.98911 -279.756108) (xy 370.99307 -279.707054) (xy 371.004847 -279.65927) (xy 371.024138 -279.613994)
			(xy 371.050441 -279.572398) (xy 371.083076 -279.535561) (xy 371.121197 -279.504436) (xy 371.163818 -279.479829)
			(xy 371.209834 -279.462377) (xy 371.258053 -279.452533) (xy 371.307228 -279.450552) (xy 371.356083 -279.456484)
			(xy 371.403354 -279.470176) (xy 371.447816 -279.491274) (xy 371.488319 -279.51923) (xy 371.523812 -279.553322)
			(xy 371.553377 -279.592666) (xy 371.576248 -279.636243) (xy 371.591832 -279.682924) (xy 371.599727 -279.731501)
			(xy 371.600222 -279.756108) (xy 371.92891 -279.756108) (xy 371.93287 -279.707054) (xy 371.944647 -279.65927)
			(xy 371.963938 -279.613994) (xy 371.990241 -279.572398) (xy 372.022876 -279.535561) (xy 372.060997 -279.504436)
			(xy 372.103618 -279.479829) (xy 372.149634 -279.462377) (xy 372.197853 -279.452533) (xy 372.247028 -279.450552)
			(xy 372.295883 -279.456484) (xy 372.343154 -279.470176) (xy 372.387616 -279.491274) (xy 372.428119 -279.51923)
			(xy 372.463612 -279.553322) (xy 372.493177 -279.592666) (xy 372.516048 -279.636243) (xy 372.531632 -279.682924)
			(xy 372.539527 -279.731501) (xy 372.540022 -279.756108) (xy 372.868964 -279.756108) (xy 372.872924 -279.707054)
			(xy 372.884701 -279.65927) (xy 372.903992 -279.613994) (xy 372.930295 -279.572398) (xy 372.96293 -279.535561)
			(xy 373.001051 -279.504436) (xy 373.043672 -279.479829) (xy 373.089688 -279.462377) (xy 373.137907 -279.452533)
			(xy 373.187082 -279.450552) (xy 373.235937 -279.456484) (xy 373.283208 -279.470176) (xy 373.32767 -279.491274)
			(xy 373.368173 -279.51923) (xy 373.403666 -279.553322) (xy 373.433231 -279.592666) (xy 373.456102 -279.636243)
			(xy 373.471686 -279.682924) (xy 373.479581 -279.731501) (xy 373.480076 -279.756108) (xy 373.479581 -279.780715)
			(xy 373.471686 -279.829292) (xy 373.456102 -279.875973) (xy 373.433231 -279.91955) (xy 373.403666 -279.958894)
			(xy 373.368173 -279.992986) (xy 373.32767 -280.020942) (xy 373.283208 -280.04204) (xy 373.235937 -280.055732)
			(xy 373.187082 -280.061664) (xy 373.137907 -280.059683) (xy 373.089688 -280.049839) (xy 373.043672 -280.032387)
			(xy 373.001051 -280.00778) (xy 372.96293 -279.976655) (xy 372.930295 -279.939818) (xy 372.903992 -279.898222)
			(xy 372.884701 -279.852946) (xy 372.872924 -279.805162) (xy 372.868964 -279.756108) (xy 372.540022 -279.756108)
			(xy 372.539527 -279.780715) (xy 372.531632 -279.829292) (xy 372.516048 -279.875973) (xy 372.493177 -279.91955)
			(xy 372.463612 -279.958894) (xy 372.428119 -279.992986) (xy 372.387616 -280.020942) (xy 372.343154 -280.04204)
			(xy 372.295883 -280.055732) (xy 372.247028 -280.061664) (xy 372.197853 -280.059683) (xy 372.149634 -280.049839)
			(xy 372.103618 -280.032387) (xy 372.060997 -280.00778) (xy 372.022876 -279.976655) (xy 371.990241 -279.939818)
			(xy 371.963938 -279.898222) (xy 371.944647 -279.852946) (xy 371.93287 -279.805162) (xy 371.92891 -279.756108)
			(xy 371.600222 -279.756108) (xy 371.599727 -279.780715) (xy 371.591832 -279.829292) (xy 371.576248 -279.875973)
			(xy 371.553377 -279.91955) (xy 371.523812 -279.958894) (xy 371.488319 -279.992986) (xy 371.447816 -280.020942)
			(xy 371.403354 -280.04204) (xy 371.356083 -280.055732) (xy 371.307228 -280.061664) (xy 371.258053 -280.059683)
			(xy 371.209834 -280.049839) (xy 371.163818 -280.032387) (xy 371.121197 -280.00778) (xy 371.083076 -279.976655)
			(xy 371.050441 -279.939818) (xy 371.024138 -279.898222) (xy 371.004847 -279.852946) (xy 370.99307 -279.805162)
			(xy 370.98911 -279.756108) (xy 370.660168 -279.756108) (xy 370.659673 -279.780715) (xy 370.651778 -279.829292)
			(xy 370.636194 -279.875973) (xy 370.613323 -279.91955) (xy 370.583758 -279.958894) (xy 370.548265 -279.992986)
			(xy 370.507762 -280.020942) (xy 370.4633 -280.04204) (xy 370.416029 -280.055732) (xy 370.367174 -280.061664)
			(xy 370.317999 -280.059683) (xy 370.26978 -280.049839) (xy 370.223764 -280.032387) (xy 370.181143 -280.00778)
			(xy 370.143022 -279.976655) (xy 370.110387 -279.939818) (xy 370.084084 -279.898222) (xy 370.064793 -279.852946)
			(xy 370.053016 -279.805162) (xy 370.049056 -279.756108) (xy 369.720114 -279.756108) (xy 369.719619 -279.780715)
			(xy 369.711724 -279.829292) (xy 369.69614 -279.875973) (xy 369.673269 -279.91955) (xy 369.643704 -279.958894)
			(xy 369.608211 -279.992986) (xy 369.567708 -280.020942) (xy 369.523246 -280.04204) (xy 369.475975 -280.055732)
			(xy 369.42712 -280.061664) (xy 369.377945 -280.059683) (xy 369.329726 -280.049839) (xy 369.28371 -280.032387)
			(xy 369.241089 -280.00778) (xy 369.202968 -279.976655) (xy 369.170333 -279.939818) (xy 369.14403 -279.898222)
			(xy 369.124739 -279.852946) (xy 369.112962 -279.805162) (xy 369.109002 -279.756108) (xy 368.78006 -279.756108)
			(xy 368.779565 -279.780715) (xy 368.77167 -279.829292) (xy 368.756086 -279.875973) (xy 368.733215 -279.91955)
			(xy 368.70365 -279.958894) (xy 368.668157 -279.992986) (xy 368.627654 -280.020942) (xy 368.583192 -280.04204)
			(xy 368.535921 -280.055732) (xy 368.487066 -280.061664) (xy 368.437891 -280.059683) (xy 368.389672 -280.049839)
			(xy 368.343656 -280.032387) (xy 368.301035 -280.00778) (xy 368.262914 -279.976655) (xy 368.230279 -279.939818)
			(xy 368.203976 -279.898222) (xy 368.184685 -279.852946) (xy 368.172908 -279.805162) (xy 368.168948 -279.756108)
			(xy 367.840006 -279.756108) (xy 367.839511 -279.780715) (xy 367.831616 -279.829292) (xy 367.816032 -279.875973)
			(xy 367.793161 -279.91955) (xy 367.763596 -279.958894) (xy 367.728103 -279.992986) (xy 367.6876 -280.020942)
			(xy 367.643138 -280.04204) (xy 367.595867 -280.055732) (xy 367.547012 -280.061664) (xy 367.497837 -280.059683)
			(xy 367.449618 -280.049839) (xy 367.403602 -280.032387) (xy 367.360981 -280.00778) (xy 367.32286 -279.976655)
			(xy 367.290225 -279.939818) (xy 367.263922 -279.898222) (xy 367.244631 -279.852946) (xy 367.232854 -279.805162)
			(xy 367.228894 -279.756108) (xy 366.900206 -279.756108) (xy 366.899711 -279.780715) (xy 366.891816 -279.829292)
			(xy 366.876232 -279.875973) (xy 366.853361 -279.91955) (xy 366.823796 -279.958894) (xy 366.788303 -279.992986)
			(xy 366.7478 -280.020942) (xy 366.703338 -280.04204) (xy 366.656067 -280.055732) (xy 366.607212 -280.061664)
			(xy 366.558037 -280.059683) (xy 366.509818 -280.049839) (xy 366.463802 -280.032387) (xy 366.421181 -280.00778)
			(xy 366.38306 -279.976655) (xy 366.350425 -279.939818) (xy 366.324122 -279.898222) (xy 366.304831 -279.852946)
			(xy 366.293054 -279.805162) (xy 366.289094 -279.756108) (xy 365.960152 -279.756108) (xy 365.959657 -279.780715)
			(xy 365.951762 -279.829292) (xy 365.936178 -279.875973) (xy 365.913307 -279.91955) (xy 365.883742 -279.958894)
			(xy 365.848249 -279.992986) (xy 365.807746 -280.020942) (xy 365.763284 -280.04204) (xy 365.716013 -280.055732)
			(xy 365.667158 -280.061664) (xy 365.617983 -280.059683) (xy 365.569764 -280.049839) (xy 365.523748 -280.032387)
			(xy 365.481127 -280.00778) (xy 365.443006 -279.976655) (xy 365.410371 -279.939818) (xy 365.384068 -279.898222)
			(xy 365.364777 -279.852946) (xy 365.353 -279.805162) (xy 365.34904 -279.756108) (xy 365.020098 -279.756108)
			(xy 365.019603 -279.780715) (xy 365.011708 -279.829292) (xy 364.996124 -279.875973) (xy 364.973253 -279.91955)
			(xy 364.943688 -279.958894) (xy 364.908195 -279.992986) (xy 364.867692 -280.020942) (xy 364.82323 -280.04204)
			(xy 364.775959 -280.055732) (xy 364.727104 -280.061664) (xy 364.677929 -280.059683) (xy 364.62971 -280.049839)
			(xy 364.583694 -280.032387) (xy 364.541073 -280.00778) (xy 364.502952 -279.976655) (xy 364.470317 -279.939818)
			(xy 364.444014 -279.898222) (xy 364.424723 -279.852946) (xy 364.412946 -279.805162) (xy 364.408986 -279.756108)
			(xy 364.080044 -279.756108) (xy 364.079549 -279.780715) (xy 364.071654 -279.829292) (xy 364.05607 -279.875973)
			(xy 364.033199 -279.91955) (xy 364.003634 -279.958894) (xy 363.968141 -279.992986) (xy 363.927638 -280.020942)
			(xy 363.883176 -280.04204) (xy 363.835905 -280.055732) (xy 363.78705 -280.061664) (xy 363.737875 -280.059683)
			(xy 363.689656 -280.049839) (xy 363.64364 -280.032387) (xy 363.601019 -280.00778) (xy 363.562898 -279.976655)
			(xy 363.530263 -279.939818) (xy 363.50396 -279.898222) (xy 363.484669 -279.852946) (xy 363.472892 -279.805162)
			(xy 363.468932 -279.756108) (xy 363.13999 -279.756108) (xy 363.139495 -279.780715) (xy 363.1316 -279.829292)
			(xy 363.116016 -279.875973) (xy 363.093145 -279.91955) (xy 363.06358 -279.958894) (xy 363.028087 -279.992986)
			(xy 362.987584 -280.020942) (xy 362.943122 -280.04204) (xy 362.895851 -280.055732) (xy 362.846996 -280.061664)
			(xy 362.797821 -280.059683) (xy 362.749602 -280.049839) (xy 362.703586 -280.032387) (xy 362.660965 -280.00778)
			(xy 362.622844 -279.976655) (xy 362.590209 -279.939818) (xy 362.563906 -279.898222) (xy 362.544615 -279.852946)
			(xy 362.532838 -279.805162) (xy 362.528878 -279.756108) (xy 362.20019 -279.756108) (xy 362.199695 -279.780715)
			(xy 362.1918 -279.829292) (xy 362.176216 -279.875973) (xy 362.153345 -279.91955) (xy 362.12378 -279.958894)
			(xy 362.088287 -279.992986) (xy 362.047784 -280.020942) (xy 362.003322 -280.04204) (xy 361.956051 -280.055732)
			(xy 361.907196 -280.061664) (xy 361.858021 -280.059683) (xy 361.809802 -280.049839) (xy 361.763786 -280.032387)
			(xy 361.721165 -280.00778) (xy 361.683044 -279.976655) (xy 361.650409 -279.939818) (xy 361.624106 -279.898222)
			(xy 361.604815 -279.852946) (xy 361.593038 -279.805162) (xy 361.589078 -279.756108) (xy 358.446324 -279.756108)
			(xy 358.445829 -279.780715) (xy 358.437934 -279.829292) (xy 358.42235 -279.875973) (xy 358.399479 -279.91955)
			(xy 358.369914 -279.958894) (xy 358.334421 -279.992986) (xy 358.293918 -280.020942) (xy 358.249456 -280.04204)
			(xy 358.202185 -280.055732) (xy 358.15333 -280.061664) (xy 358.104155 -280.059683) (xy 358.055936 -280.049839)
			(xy 358.00992 -280.032387) (xy 357.967299 -280.00778) (xy 357.929178 -279.976655) (xy 357.896543 -279.939818)
			(xy 357.87024 -279.898222) (xy 357.850949 -279.852946) (xy 357.839172 -279.805162) (xy 357.835212 -279.756108)
			(xy 357.506524 -279.756108) (xy 357.506029 -279.780715) (xy 357.498134 -279.829292) (xy 357.48255 -279.875973)
			(xy 357.459679 -279.91955) (xy 357.430114 -279.958894) (xy 357.394621 -279.992986) (xy 357.354118 -280.020942)
			(xy 357.309656 -280.04204) (xy 357.262385 -280.055732) (xy 357.21353 -280.061664) (xy 357.164355 -280.059683)
			(xy 357.116136 -280.049839) (xy 357.07012 -280.032387) (xy 357.027499 -280.00778) (xy 356.989378 -279.976655)
			(xy 356.956743 -279.939818) (xy 356.93044 -279.898222) (xy 356.911149 -279.852946) (xy 356.899372 -279.805162)
			(xy 356.895412 -279.756108) (xy 356.56647 -279.756108) (xy 356.565975 -279.780715) (xy 356.55808 -279.829292)
			(xy 356.542496 -279.875973) (xy 356.519625 -279.91955) (xy 356.49006 -279.958894) (xy 356.454567 -279.992986)
			(xy 356.414064 -280.020942) (xy 356.369602 -280.04204) (xy 356.322331 -280.055732) (xy 356.273476 -280.061664)
			(xy 356.224301 -280.059683) (xy 356.176082 -280.049839) (xy 356.130066 -280.032387) (xy 356.087445 -280.00778)
			(xy 356.049324 -279.976655) (xy 356.016689 -279.939818) (xy 355.990386 -279.898222) (xy 355.971095 -279.852946)
			(xy 355.959318 -279.805162) (xy 355.955358 -279.756108) (xy 355.626416 -279.756108) (xy 355.625921 -279.780715)
			(xy 355.618026 -279.829292) (xy 355.602442 -279.875973) (xy 355.579571 -279.91955) (xy 355.550006 -279.958894)
			(xy 355.514513 -279.992986) (xy 355.47401 -280.020942) (xy 355.429548 -280.04204) (xy 355.382277 -280.055732)
			(xy 355.333422 -280.061664) (xy 355.284247 -280.059683) (xy 355.236028 -280.049839) (xy 355.190012 -280.032387)
			(xy 355.147391 -280.00778) (xy 355.10927 -279.976655) (xy 355.076635 -279.939818) (xy 355.050332 -279.898222)
			(xy 355.031041 -279.852946) (xy 355.019264 -279.805162) (xy 355.015304 -279.756108) (xy 354.686362 -279.756108)
			(xy 354.685867 -279.780715) (xy 354.677972 -279.829292) (xy 354.662388 -279.875973) (xy 354.639517 -279.91955)
			(xy 354.609952 -279.958894) (xy 354.574459 -279.992986) (xy 354.533956 -280.020942) (xy 354.489494 -280.04204)
			(xy 354.442223 -280.055732) (xy 354.393368 -280.061664) (xy 354.344193 -280.059683) (xy 354.295974 -280.049839)
			(xy 354.249958 -280.032387) (xy 354.207337 -280.00778) (xy 354.169216 -279.976655) (xy 354.136581 -279.939818)
			(xy 354.110278 -279.898222) (xy 354.090987 -279.852946) (xy 354.07921 -279.805162) (xy 354.07525 -279.756108)
			(xy 353.746308 -279.756108) (xy 353.745813 -279.780715) (xy 353.737918 -279.829292) (xy 353.722334 -279.875973)
			(xy 353.699463 -279.91955) (xy 353.669898 -279.958894) (xy 353.634405 -279.992986) (xy 353.593902 -280.020942)
			(xy 353.54944 -280.04204) (xy 353.502169 -280.055732) (xy 353.453314 -280.061664) (xy 353.404139 -280.059683)
			(xy 353.35592 -280.049839) (xy 353.309904 -280.032387) (xy 353.267283 -280.00778) (xy 353.229162 -279.976655)
			(xy 353.196527 -279.939818) (xy 353.170224 -279.898222) (xy 353.150933 -279.852946) (xy 353.139156 -279.805162)
			(xy 353.135196 -279.756108) (xy 352.806508 -279.756108) (xy 352.806013 -279.780715) (xy 352.798118 -279.829292)
			(xy 352.782534 -279.875973) (xy 352.759663 -279.91955) (xy 352.730098 -279.958894) (xy 352.694605 -279.992986)
			(xy 352.654102 -280.020942) (xy 352.60964 -280.04204) (xy 352.562369 -280.055732) (xy 352.513514 -280.061664)
			(xy 352.464339 -280.059683) (xy 352.41612 -280.049839) (xy 352.370104 -280.032387) (xy 352.327483 -280.00778)
			(xy 352.289362 -279.976655) (xy 352.256727 -279.939818) (xy 352.230424 -279.898222) (xy 352.211133 -279.852946)
			(xy 352.199356 -279.805162) (xy 352.195396 -279.756108) (xy 351.866454 -279.756108) (xy 351.865959 -279.780715)
			(xy 351.858064 -279.829292) (xy 351.84248 -279.875973) (xy 351.819609 -279.91955) (xy 351.790044 -279.958894)
			(xy 351.754551 -279.992986) (xy 351.714048 -280.020942) (xy 351.669586 -280.04204) (xy 351.622315 -280.055732)
			(xy 351.57346 -280.061664) (xy 351.524285 -280.059683) (xy 351.476066 -280.049839) (xy 351.43005 -280.032387)
			(xy 351.387429 -280.00778) (xy 351.349308 -279.976655) (xy 351.316673 -279.939818) (xy 351.29037 -279.898222)
			(xy 351.271079 -279.852946) (xy 351.259302 -279.805162) (xy 351.255342 -279.756108) (xy 350.9264 -279.756108)
			(xy 350.925905 -279.780715) (xy 350.91801 -279.829292) (xy 350.902426 -279.875973) (xy 350.879555 -279.91955)
			(xy 350.84999 -279.958894) (xy 350.814497 -279.992986) (xy 350.773994 -280.020942) (xy 350.729532 -280.04204)
			(xy 350.682261 -280.055732) (xy 350.633406 -280.061664) (xy 350.584231 -280.059683) (xy 350.536012 -280.049839)
			(xy 350.489996 -280.032387) (xy 350.447375 -280.00778) (xy 350.409254 -279.976655) (xy 350.376619 -279.939818)
			(xy 350.350316 -279.898222) (xy 350.331025 -279.852946) (xy 350.319248 -279.805162) (xy 350.315288 -279.756108)
			(xy 349.986346 -279.756108) (xy 349.985851 -279.780715) (xy 349.977956 -279.829292) (xy 349.962372 -279.875973)
			(xy 349.939501 -279.91955) (xy 349.909936 -279.958894) (xy 349.874443 -279.992986) (xy 349.83394 -280.020942)
			(xy 349.789478 -280.04204) (xy 349.742207 -280.055732) (xy 349.693352 -280.061664) (xy 349.644177 -280.059683)
			(xy 349.595958 -280.049839) (xy 349.549942 -280.032387) (xy 349.507321 -280.00778) (xy 349.4692 -279.976655)
			(xy 349.436565 -279.939818) (xy 349.410262 -279.898222) (xy 349.390971 -279.852946) (xy 349.379194 -279.805162)
			(xy 349.375234 -279.756108) (xy 349.046546 -279.756108) (xy 349.046051 -279.780715) (xy 349.038156 -279.829292)
			(xy 349.022572 -279.875973) (xy 348.999701 -279.91955) (xy 348.970136 -279.958894) (xy 348.934643 -279.992986)
			(xy 348.89414 -280.020942) (xy 348.849678 -280.04204) (xy 348.802407 -280.055732) (xy 348.753552 -280.061664)
			(xy 348.704377 -280.059683) (xy 348.656158 -280.049839) (xy 348.610142 -280.032387) (xy 348.567521 -280.00778)
			(xy 348.5294 -279.976655) (xy 348.496765 -279.939818) (xy 348.470462 -279.898222) (xy 348.451171 -279.852946)
			(xy 348.439394 -279.805162) (xy 348.435434 -279.756108) (xy 348.106492 -279.756108) (xy 348.105997 -279.780715)
			(xy 348.098102 -279.829292) (xy 348.082518 -279.875973) (xy 348.059647 -279.91955) (xy 348.030082 -279.958894)
			(xy 347.994589 -279.992986) (xy 347.954086 -280.020942) (xy 347.909624 -280.04204) (xy 347.862353 -280.055732)
			(xy 347.813498 -280.061664) (xy 347.764323 -280.059683) (xy 347.716104 -280.049839) (xy 347.670088 -280.032387)
			(xy 347.627467 -280.00778) (xy 347.589346 -279.976655) (xy 347.556711 -279.939818) (xy 347.530408 -279.898222)
			(xy 347.511117 -279.852946) (xy 347.49934 -279.805162) (xy 347.49538 -279.756108) (xy 347.166438 -279.756108)
			(xy 347.165943 -279.780715) (xy 347.158048 -279.829292) (xy 347.142464 -279.875973) (xy 347.119593 -279.91955)
			(xy 347.090028 -279.958894) (xy 347.054535 -279.992986) (xy 347.014032 -280.020942) (xy 346.96957 -280.04204)
			(xy 346.922299 -280.055732) (xy 346.873444 -280.061664) (xy 346.824269 -280.059683) (xy 346.77605 -280.049839)
			(xy 346.730034 -280.032387) (xy 346.687413 -280.00778) (xy 346.649292 -279.976655) (xy 346.616657 -279.939818)
			(xy 346.590354 -279.898222) (xy 346.571063 -279.852946) (xy 346.559286 -279.805162) (xy 346.555326 -279.756108)
			(xy 346.226384 -279.756108) (xy 346.225889 -279.780715) (xy 346.217994 -279.829292) (xy 346.20241 -279.875973)
			(xy 346.179539 -279.91955) (xy 346.149974 -279.958894) (xy 346.114481 -279.992986) (xy 346.073978 -280.020942)
			(xy 346.029516 -280.04204) (xy 345.982245 -280.055732) (xy 345.93339 -280.061664) (xy 345.884215 -280.059683)
			(xy 345.835996 -280.049839) (xy 345.78998 -280.032387) (xy 345.747359 -280.00778) (xy 345.709238 -279.976655)
			(xy 345.676603 -279.939818) (xy 345.6503 -279.898222) (xy 345.631009 -279.852946) (xy 345.619232 -279.805162)
			(xy 345.615272 -279.756108) (xy 345.28633 -279.756108) (xy 345.285835 -279.780715) (xy 345.27794 -279.829292)
			(xy 345.262356 -279.875973) (xy 345.239485 -279.91955) (xy 345.20992 -279.958894) (xy 345.174427 -279.992986)
			(xy 345.133924 -280.020942) (xy 345.089462 -280.04204) (xy 345.042191 -280.055732) (xy 344.993336 -280.061664)
			(xy 344.944161 -280.059683) (xy 344.895942 -280.049839) (xy 344.849926 -280.032387) (xy 344.807305 -280.00778)
			(xy 344.769184 -279.976655) (xy 344.736549 -279.939818) (xy 344.710246 -279.898222) (xy 344.690955 -279.852946)
			(xy 344.679178 -279.805162) (xy 344.675218 -279.756108) (xy 344.356944 -279.756108) (xy 344.356432 -279.781554)
			(xy 344.348268 -279.831788) (xy 344.332152 -279.880062) (xy 344.308501 -279.925125) (xy 344.277928 -279.965811)
			(xy 344.241224 -280.001066) (xy 344.19934 -280.029976) (xy 344.153361 -280.051793) (xy 344.104477 -280.065953)
			(xy 344.053956 -280.072087) (xy 344.003104 -280.070038) (xy 343.95324 -280.059858) (xy 343.905654 -280.041811)
			(xy 343.86158 -280.016365) (xy 343.822158 -279.984178) (xy 343.78841 -279.946084) (xy 343.761209 -279.90307)
			(xy 343.741261 -279.85625) (xy 343.729082 -279.806836) (xy 343.724987 -279.756108) (xy 343.406476 -279.756108)
			(xy 343.405981 -279.780715) (xy 343.398086 -279.829292) (xy 343.382502 -279.875973) (xy 343.359631 -279.91955)
			(xy 343.330066 -279.958894) (xy 343.294573 -279.992986) (xy 343.25407 -280.020942) (xy 343.209608 -280.04204)
			(xy 343.162337 -280.055732) (xy 343.113482 -280.061664) (xy 343.064307 -280.059683) (xy 343.016088 -280.049839)
			(xy 342.970072 -280.032387) (xy 342.927451 -280.00778) (xy 342.88933 -279.976655) (xy 342.856695 -279.939818)
			(xy 342.830392 -279.898222) (xy 342.811101 -279.852946) (xy 342.799324 -279.805162) (xy 342.795364 -279.756108)
			(xy 342.476836 -279.756108) (xy 342.476324 -279.781554) (xy 342.46816 -279.831788) (xy 342.452044 -279.880062)
			(xy 342.428393 -279.925125) (xy 342.39782 -279.965811) (xy 342.361116 -280.001066) (xy 342.319232 -280.029976)
			(xy 342.273253 -280.051793) (xy 342.224369 -280.065953) (xy 342.173848 -280.072087) (xy 342.122996 -280.070038)
			(xy 342.073132 -280.059858) (xy 342.025546 -280.041811) (xy 341.981472 -280.016365) (xy 341.94205 -279.984178)
			(xy 341.908302 -279.946084) (xy 341.881101 -279.90307) (xy 341.861153 -279.85625) (xy 341.848974 -279.806836)
			(xy 341.844879 -279.756108) (xy 341.526368 -279.756108) (xy 341.525873 -279.780715) (xy 341.517978 -279.829292)
			(xy 341.502394 -279.875973) (xy 341.479523 -279.91955) (xy 341.449958 -279.958894) (xy 341.414465 -279.992986)
			(xy 341.373962 -280.020942) (xy 341.3295 -280.04204) (xy 341.282229 -280.055732) (xy 341.233374 -280.061664)
			(xy 341.184199 -280.059683) (xy 341.13598 -280.049839) (xy 341.089964 -280.032387) (xy 341.047343 -280.00778)
			(xy 341.009222 -279.976655) (xy 340.976587 -279.939818) (xy 340.950284 -279.898222) (xy 340.930993 -279.852946)
			(xy 340.919216 -279.805162) (xy 340.915256 -279.756108) (xy 340.596728 -279.756108) (xy 340.596215 -279.782339)
			(xy 340.587547 -279.834081) (xy 340.570436 -279.883675) (xy 340.545353 -279.929752) (xy 340.51299 -279.971043)
			(xy 340.474239 -280.006409) (xy 340.452456 -280.02103) (xy 340.44849 -280.023725) (xy 340.441587 -280.030379)
			(xy 340.43874 -280.034238) (xy 340.43366 -280.04135) (xy 340.42481 -280.073115) (xy 340.403844 -280.135641)
			(xy 340.39175 -280.166318) (xy 340.39175 -280.166572) (xy 340.375347 -280.206309) (xy 340.3372 -280.283357)
			(xy 340.31555 -280.320496) (xy 340.311994 -280.326592) (xy 340.308438 -280.339546) (xy 340.308438 -280.566114)
			(xy 340.434925 -280.566114) (xy 340.43902 -280.515386) (xy 340.451199 -280.465972) (xy 340.471147 -280.419152)
			(xy 340.498348 -280.376138) (xy 340.532096 -280.338044) (xy 340.571518 -280.305857) (xy 340.615592 -280.280411)
			(xy 340.663178 -280.262364) (xy 340.713042 -280.252184) (xy 340.763894 -280.250135) (xy 340.814415 -280.256269)
			(xy 340.863299 -280.270429) (xy 340.909278 -280.292246) (xy 340.951162 -280.321156) (xy 340.987866 -280.356411)
			(xy 341.018439 -280.397097) (xy 341.04209 -280.44216) (xy 341.058206 -280.490434) (xy 341.06637 -280.540668)
			(xy 341.066882 -280.566114) (xy 341.38541 -280.566114) (xy 341.38937 -280.51706) (xy 341.401147 -280.469276)
			(xy 341.420438 -280.424) (xy 341.446741 -280.382404) (xy 341.479376 -280.345567) (xy 341.517497 -280.314442)
			(xy 341.560118 -280.289835) (xy 341.606134 -280.272383) (xy 341.654353 -280.262539) (xy 341.703528 -280.260558)
			(xy 341.752383 -280.26649) (xy 341.799654 -280.280182) (xy 341.844116 -280.30128) (xy 341.884619 -280.329236)
			(xy 341.920112 -280.363328) (xy 341.949677 -280.402672) (xy 341.972548 -280.446249) (xy 341.988132 -280.49293)
			(xy 341.996027 -280.541507) (xy 341.996522 -280.566114) (xy 342.314779 -280.566114) (xy 342.318874 -280.515386)
			(xy 342.331053 -280.465972) (xy 342.351001 -280.419152) (xy 342.378202 -280.376138) (xy 342.41195 -280.338044)
			(xy 342.451372 -280.305857) (xy 342.495446 -280.280411) (xy 342.543032 -280.262364) (xy 342.592896 -280.252184)
			(xy 342.643748 -280.250135) (xy 342.694269 -280.256269) (xy 342.743153 -280.270429) (xy 342.789132 -280.292246)
			(xy 342.831016 -280.321156) (xy 342.86772 -280.356411) (xy 342.898293 -280.397097) (xy 342.921944 -280.44216)
			(xy 342.93806 -280.490434) (xy 342.946224 -280.540668) (xy 342.946736 -280.566114) (xy 343.254833 -280.566114)
			(xy 343.258928 -280.515386) (xy 343.271107 -280.465972) (xy 343.291055 -280.419152) (xy 343.318256 -280.376138)
			(xy 343.352004 -280.338044) (xy 343.391426 -280.305857) (xy 343.4355 -280.280411) (xy 343.483086 -280.262364)
			(xy 343.53295 -280.252184) (xy 343.583802 -280.250135) (xy 343.634323 -280.256269) (xy 343.683207 -280.270429)
			(xy 343.729186 -280.292246) (xy 343.77107 -280.321156) (xy 343.807774 -280.356411) (xy 343.838347 -280.397097)
			(xy 343.861998 -280.44216) (xy 343.878114 -280.490434) (xy 343.886278 -280.540668) (xy 343.88679 -280.566114)
			(xy 344.205318 -280.566114) (xy 344.209278 -280.51706) (xy 344.221055 -280.469276) (xy 344.240346 -280.424)
			(xy 344.266649 -280.382404) (xy 344.299284 -280.345567) (xy 344.337405 -280.314442) (xy 344.380026 -280.289835)
			(xy 344.426042 -280.272383) (xy 344.474261 -280.262539) (xy 344.523436 -280.260558) (xy 344.572291 -280.26649)
			(xy 344.619562 -280.280182) (xy 344.664024 -280.30128) (xy 344.704527 -280.329236) (xy 344.74002 -280.363328)
			(xy 344.769585 -280.402672) (xy 344.792456 -280.446249) (xy 344.80804 -280.49293) (xy 344.815935 -280.541507)
			(xy 344.81643 -280.566114) (xy 344.815935 -280.590721) (xy 344.80804 -280.639298) (xy 344.792456 -280.685979)
			(xy 344.769585 -280.729556) (xy 344.74002 -280.7689) (xy 344.704527 -280.802992) (xy 344.664024 -280.830948)
			(xy 344.619562 -280.852046) (xy 344.572291 -280.865738) (xy 344.523436 -280.87167) (xy 344.474261 -280.869689)
			(xy 344.426042 -280.859845) (xy 344.380026 -280.842393) (xy 344.337405 -280.817786) (xy 344.299284 -280.786661)
			(xy 344.266649 -280.749824) (xy 344.240346 -280.708228) (xy 344.221055 -280.662952) (xy 344.209278 -280.615168)
			(xy 344.205318 -280.566114) (xy 343.88679 -280.566114) (xy 343.886278 -280.59156) (xy 343.878114 -280.641794)
			(xy 343.861998 -280.690068) (xy 343.838347 -280.735131) (xy 343.807774 -280.775817) (xy 343.77107 -280.811072)
			(xy 343.729186 -280.839982) (xy 343.683207 -280.861799) (xy 343.634323 -280.875959) (xy 343.583802 -280.882093)
			(xy 343.53295 -280.880044) (xy 343.483086 -280.869864) (xy 343.4355 -280.851817) (xy 343.391426 -280.826371)
			(xy 343.352004 -280.794184) (xy 343.318256 -280.75609) (xy 343.291055 -280.713076) (xy 343.271107 -280.666256)
			(xy 343.258928 -280.616842) (xy 343.254833 -280.566114) (xy 342.946736 -280.566114) (xy 342.946224 -280.59156)
			(xy 342.93806 -280.641794) (xy 342.921944 -280.690068) (xy 342.898293 -280.735131) (xy 342.86772 -280.775817)
			(xy 342.831016 -280.811072) (xy 342.789132 -280.839982) (xy 342.743153 -280.861799) (xy 342.694269 -280.875959)
			(xy 342.643748 -280.882093) (xy 342.592896 -280.880044) (xy 342.543032 -280.869864) (xy 342.495446 -280.851817)
			(xy 342.451372 -280.826371) (xy 342.41195 -280.794184) (xy 342.378202 -280.75609) (xy 342.351001 -280.713076)
			(xy 342.331053 -280.666256) (xy 342.318874 -280.616842) (xy 342.314779 -280.566114) (xy 341.996522 -280.566114)
			(xy 341.996027 -280.590721) (xy 341.988132 -280.639298) (xy 341.972548 -280.685979) (xy 341.949677 -280.729556)
			(xy 341.920112 -280.7689) (xy 341.884619 -280.802992) (xy 341.844116 -280.830948) (xy 341.799654 -280.852046)
			(xy 341.752383 -280.865738) (xy 341.703528 -280.87167) (xy 341.654353 -280.869689) (xy 341.606134 -280.859845)
			(xy 341.560118 -280.842393) (xy 341.517497 -280.817786) (xy 341.479376 -280.786661) (xy 341.446741 -280.749824)
			(xy 341.420438 -280.708228) (xy 341.401147 -280.662952) (xy 341.38937 -280.615168) (xy 341.38541 -280.566114)
			(xy 341.066882 -280.566114) (xy 341.06637 -280.59156) (xy 341.058206 -280.641794) (xy 341.04209 -280.690068)
			(xy 341.018439 -280.735131) (xy 340.987866 -280.775817) (xy 340.951162 -280.811072) (xy 340.909278 -280.839982)
			(xy 340.863299 -280.861799) (xy 340.814415 -280.875959) (xy 340.763894 -280.882093) (xy 340.713042 -280.880044)
			(xy 340.663178 -280.869864) (xy 340.615592 -280.851817) (xy 340.571518 -280.826371) (xy 340.532096 -280.794184)
			(xy 340.498348 -280.75609) (xy 340.471147 -280.713076) (xy 340.451199 -280.666256) (xy 340.43902 -280.616842)
			(xy 340.434925 -280.566114) (xy 340.308438 -280.566114) (xy 340.308438 -280.79573) (xy 340.311994 -280.808684)
			(xy 340.315296 -280.814526) (xy 340.335106 -280.848945) (xy 340.37032 -280.920133) (xy 340.385654 -280.956766)
			(xy 340.398926 -280.989942) (xy 340.42168 -281.057685) (xy 340.43112 -281.092148) (xy 340.43493 -281.10053)
			(xy 340.455616 -281.112598) (xy 340.493414 -281.142004) (xy 340.526341 -281.176778) (xy 340.553642 -281.216124)
			(xy 340.574692 -281.259139) (xy 340.589008 -281.304839) (xy 340.596263 -281.352175) (xy 340.596728 -281.37612)
			(xy 340.915256 -281.37612) (xy 340.919216 -281.327066) (xy 340.930993 -281.279282) (xy 340.950284 -281.234006)
			(xy 340.976587 -281.19241) (xy 341.009222 -281.155573) (xy 341.047343 -281.124448) (xy 341.089964 -281.099841)
			(xy 341.13598 -281.082389) (xy 341.184199 -281.072545) (xy 341.233374 -281.070564) (xy 341.282229 -281.076496)
			(xy 341.3295 -281.090188) (xy 341.373962 -281.111286) (xy 341.414465 -281.139242) (xy 341.449958 -281.173334)
			(xy 341.479523 -281.212678) (xy 341.502394 -281.256255) (xy 341.517978 -281.302936) (xy 341.525873 -281.351513)
			(xy 341.526368 -281.37612) (xy 341.844879 -281.37612) (xy 341.848974 -281.325392) (xy 341.861153 -281.275978)
			(xy 341.881101 -281.229158) (xy 341.908302 -281.186144) (xy 341.94205 -281.14805) (xy 341.981472 -281.115863)
			(xy 342.025546 -281.090417) (xy 342.073132 -281.07237) (xy 342.122996 -281.06219) (xy 342.173848 -281.060141)
			(xy 342.224369 -281.066275) (xy 342.273253 -281.080435) (xy 342.319232 -281.102252) (xy 342.361116 -281.131162)
			(xy 342.39782 -281.166417) (xy 342.428393 -281.207103) (xy 342.452044 -281.252166) (xy 342.46816 -281.30044)
			(xy 342.476324 -281.350674) (xy 342.476836 -281.37612) (xy 342.795364 -281.37612) (xy 342.799324 -281.327066)
			(xy 342.811101 -281.279282) (xy 342.830392 -281.234006) (xy 342.856695 -281.19241) (xy 342.88933 -281.155573)
			(xy 342.927451 -281.124448) (xy 342.970072 -281.099841) (xy 343.016088 -281.082389) (xy 343.064307 -281.072545)
			(xy 343.113482 -281.070564) (xy 343.162337 -281.076496) (xy 343.209608 -281.090188) (xy 343.25407 -281.111286)
			(xy 343.294573 -281.139242) (xy 343.330066 -281.173334) (xy 343.359631 -281.212678) (xy 343.382502 -281.256255)
			(xy 343.398086 -281.302936) (xy 343.405981 -281.351513) (xy 343.406476 -281.37612) (xy 343.724987 -281.37612)
			(xy 343.729082 -281.325392) (xy 343.741261 -281.275978) (xy 343.761209 -281.229158) (xy 343.78841 -281.186144)
			(xy 343.822158 -281.14805) (xy 343.86158 -281.115863) (xy 343.905654 -281.090417) (xy 343.95324 -281.07237)
			(xy 344.003104 -281.06219) (xy 344.053956 -281.060141) (xy 344.104477 -281.066275) (xy 344.153361 -281.080435)
			(xy 344.19934 -281.102252) (xy 344.241224 -281.131162) (xy 344.277928 -281.166417) (xy 344.308501 -281.207103)
			(xy 344.332152 -281.252166) (xy 344.348268 -281.30044) (xy 344.356432 -281.350674) (xy 344.356944 -281.37612)
			(xy 344.356432 -281.401566) (xy 344.348268 -281.4518) (xy 344.332152 -281.500074) (xy 344.308501 -281.545137)
			(xy 344.277928 -281.585823) (xy 344.241224 -281.621078) (xy 344.19934 -281.649988) (xy 344.153361 -281.671805)
			(xy 344.104477 -281.685965) (xy 344.053956 -281.692099) (xy 344.003104 -281.69005) (xy 343.95324 -281.67987)
			(xy 343.905654 -281.661823) (xy 343.86158 -281.636377) (xy 343.822158 -281.60419) (xy 343.78841 -281.566096)
			(xy 343.761209 -281.523082) (xy 343.741261 -281.476262) (xy 343.729082 -281.426848) (xy 343.724987 -281.37612)
			(xy 343.406476 -281.37612) (xy 343.405981 -281.400727) (xy 343.398086 -281.449304) (xy 343.382502 -281.495985)
			(xy 343.359631 -281.539562) (xy 343.330066 -281.578906) (xy 343.294573 -281.612998) (xy 343.25407 -281.640954)
			(xy 343.209608 -281.662052) (xy 343.162337 -281.675744) (xy 343.113482 -281.681676) (xy 343.064307 -281.679695)
			(xy 343.016088 -281.669851) (xy 342.970072 -281.652399) (xy 342.927451 -281.627792) (xy 342.88933 -281.596667)
			(xy 342.856695 -281.55983) (xy 342.830392 -281.518234) (xy 342.811101 -281.472958) (xy 342.799324 -281.425174)
			(xy 342.795364 -281.37612) (xy 342.476836 -281.37612) (xy 342.476324 -281.401566) (xy 342.46816 -281.4518)
			(xy 342.452044 -281.500074) (xy 342.428393 -281.545137) (xy 342.39782 -281.585823) (xy 342.361116 -281.621078)
			(xy 342.319232 -281.649988) (xy 342.273253 -281.671805) (xy 342.224369 -281.685965) (xy 342.173848 -281.692099)
			(xy 342.122996 -281.69005) (xy 342.073132 -281.67987) (xy 342.025546 -281.661823) (xy 341.981472 -281.636377)
			(xy 341.94205 -281.60419) (xy 341.908302 -281.566096) (xy 341.881101 -281.523082) (xy 341.861153 -281.476262)
			(xy 341.848974 -281.426848) (xy 341.844879 -281.37612) (xy 341.526368 -281.37612) (xy 341.525873 -281.400727)
			(xy 341.517978 -281.449304) (xy 341.502394 -281.495985) (xy 341.479523 -281.539562) (xy 341.449958 -281.578906)
			(xy 341.414465 -281.612998) (xy 341.373962 -281.640954) (xy 341.3295 -281.662052) (xy 341.282229 -281.675744)
			(xy 341.233374 -281.681676) (xy 341.184199 -281.679695) (xy 341.13598 -281.669851) (xy 341.089964 -281.652399)
			(xy 341.047343 -281.627792) (xy 341.009222 -281.596667) (xy 340.976587 -281.55983) (xy 340.950284 -281.518234)
			(xy 340.930993 -281.472958) (xy 340.919216 -281.425174) (xy 340.915256 -281.37612) (xy 340.596728 -281.37612)
			(xy 340.596283 -281.400038) (xy 340.589055 -281.447326) (xy 340.574766 -281.492979) (xy 340.553746 -281.53595)
			(xy 340.526476 -281.575254) (xy 340.493583 -281.609987) (xy 340.45582 -281.639353) (xy 340.435184 -281.651456)
			(xy 340.430612 -281.662378) (xy 340.424262 -281.684984) (xy 340.411039 -281.729104) (xy 340.378244 -281.815182)
			(xy 340.338427 -281.898246) (xy 340.31555 -281.938222) (xy 340.311994 -281.944064) (xy 340.308438 -281.957018)
			(xy 340.308438 -282.186126) (xy 340.434925 -282.186126) (xy 340.43902 -282.135398) (xy 340.451199 -282.085984)
			(xy 340.471147 -282.039164) (xy 340.498348 -281.99615) (xy 340.532096 -281.958056) (xy 340.571518 -281.925869)
			(xy 340.615592 -281.900423) (xy 340.663178 -281.882376) (xy 340.713042 -281.872196) (xy 340.763894 -281.870147)
			(xy 340.814415 -281.876281) (xy 340.863299 -281.890441) (xy 340.909278 -281.912258) (xy 340.951162 -281.941168)
			(xy 340.987866 -281.976423) (xy 341.018439 -282.017109) (xy 341.04209 -282.062172) (xy 341.058206 -282.110446)
			(xy 341.06637 -282.16068) (xy 341.066882 -282.186126) (xy 341.38541 -282.186126) (xy 341.38937 -282.137072)
			(xy 341.401147 -282.089288) (xy 341.420438 -282.044012) (xy 341.446741 -282.002416) (xy 341.479376 -281.965579)
			(xy 341.517497 -281.934454) (xy 341.560118 -281.909847) (xy 341.606134 -281.892395) (xy 341.654353 -281.882551)
			(xy 341.703528 -281.88057) (xy 341.752383 -281.886502) (xy 341.799654 -281.900194) (xy 341.844116 -281.921292)
			(xy 341.884619 -281.949248) (xy 341.920112 -281.98334) (xy 341.949677 -282.022684) (xy 341.972548 -282.066261)
			(xy 341.988132 -282.112942) (xy 341.996027 -282.161519) (xy 341.996522 -282.186126) (xy 342.314779 -282.186126)
			(xy 342.318874 -282.135398) (xy 342.331053 -282.085984) (xy 342.351001 -282.039164) (xy 342.378202 -281.99615)
			(xy 342.41195 -281.958056) (xy 342.451372 -281.925869) (xy 342.495446 -281.900423) (xy 342.543032 -281.882376)
			(xy 342.592896 -281.872196) (xy 342.643748 -281.870147) (xy 342.694269 -281.876281) (xy 342.743153 -281.890441)
			(xy 342.789132 -281.912258) (xy 342.831016 -281.941168) (xy 342.86772 -281.976423) (xy 342.898293 -282.017109)
			(xy 342.921944 -282.062172) (xy 342.93806 -282.110446) (xy 342.946224 -282.16068) (xy 342.946736 -282.186126)
			(xy 343.254833 -282.186126) (xy 343.258928 -282.135398) (xy 343.271107 -282.085984) (xy 343.291055 -282.039164)
			(xy 343.318256 -281.99615) (xy 343.352004 -281.958056) (xy 343.391426 -281.925869) (xy 343.4355 -281.900423)
			(xy 343.483086 -281.882376) (xy 343.53295 -281.872196) (xy 343.583802 -281.870147) (xy 343.634323 -281.876281)
			(xy 343.683207 -281.890441) (xy 343.729186 -281.912258) (xy 343.77107 -281.941168) (xy 343.807774 -281.976423)
			(xy 343.838347 -282.017109) (xy 343.861998 -282.062172) (xy 343.878114 -282.110446) (xy 343.886278 -282.16068)
			(xy 343.88679 -282.186126) (xy 344.205318 -282.186126) (xy 344.209278 -282.137072) (xy 344.221055 -282.089288)
			(xy 344.240346 -282.044012) (xy 344.266649 -282.002416) (xy 344.299284 -281.965579) (xy 344.337405 -281.934454)
			(xy 344.380026 -281.909847) (xy 344.426042 -281.892395) (xy 344.474261 -281.882551) (xy 344.523436 -281.88057)
			(xy 344.572291 -281.886502) (xy 344.619562 -281.900194) (xy 344.664024 -281.921292) (xy 344.704527 -281.949248)
			(xy 344.74002 -281.98334) (xy 344.769585 -282.022684) (xy 344.792456 -282.066261) (xy 344.80804 -282.112942)
			(xy 344.815935 -282.161519) (xy 344.81643 -282.186126) (xy 344.815935 -282.210733) (xy 344.80804 -282.25931)
			(xy 344.792456 -282.305991) (xy 344.769585 -282.349568) (xy 344.74002 -282.388912) (xy 344.704527 -282.423004)
			(xy 344.664024 -282.45096) (xy 344.619562 -282.472058) (xy 344.572291 -282.48575) (xy 344.523436 -282.491682)
			(xy 344.474261 -282.489701) (xy 344.426042 -282.479857) (xy 344.380026 -282.462405) (xy 344.337405 -282.437798)
			(xy 344.299284 -282.406673) (xy 344.266649 -282.369836) (xy 344.240346 -282.32824) (xy 344.221055 -282.282964)
			(xy 344.209278 -282.23518) (xy 344.205318 -282.186126) (xy 343.88679 -282.186126) (xy 343.886278 -282.211572)
			(xy 343.878114 -282.261806) (xy 343.861998 -282.31008) (xy 343.838347 -282.355143) (xy 343.807774 -282.395829)
			(xy 343.77107 -282.431084) (xy 343.729186 -282.459994) (xy 343.683207 -282.481811) (xy 343.634323 -282.495971)
			(xy 343.583802 -282.502105) (xy 343.53295 -282.500056) (xy 343.483086 -282.489876) (xy 343.4355 -282.471829)
			(xy 343.391426 -282.446383) (xy 343.352004 -282.414196) (xy 343.318256 -282.376102) (xy 343.291055 -282.333088)
			(xy 343.271107 -282.286268) (xy 343.258928 -282.236854) (xy 343.254833 -282.186126) (xy 342.946736 -282.186126)
			(xy 342.946224 -282.211572) (xy 342.93806 -282.261806) (xy 342.921944 -282.31008) (xy 342.898293 -282.355143)
			(xy 342.86772 -282.395829) (xy 342.831016 -282.431084) (xy 342.789132 -282.459994) (xy 342.743153 -282.481811)
			(xy 342.694269 -282.495971) (xy 342.643748 -282.502105) (xy 342.592896 -282.500056) (xy 342.543032 -282.489876)
			(xy 342.495446 -282.471829) (xy 342.451372 -282.446383) (xy 342.41195 -282.414196) (xy 342.378202 -282.376102)
			(xy 342.351001 -282.333088) (xy 342.331053 -282.286268) (xy 342.318874 -282.236854) (xy 342.314779 -282.186126)
			(xy 341.996522 -282.186126) (xy 341.996027 -282.210733) (xy 341.988132 -282.25931) (xy 341.972548 -282.305991)
			(xy 341.949677 -282.349568) (xy 341.920112 -282.388912) (xy 341.884619 -282.423004) (xy 341.844116 -282.45096)
			(xy 341.799654 -282.472058) (xy 341.752383 -282.48575) (xy 341.703528 -282.491682) (xy 341.654353 -282.489701)
			(xy 341.606134 -282.479857) (xy 341.560118 -282.462405) (xy 341.517497 -282.437798) (xy 341.479376 -282.406673)
			(xy 341.446741 -282.369836) (xy 341.420438 -282.32824) (xy 341.401147 -282.282964) (xy 341.38937 -282.23518)
			(xy 341.38541 -282.186126) (xy 341.066882 -282.186126) (xy 341.06637 -282.211572) (xy 341.058206 -282.261806)
			(xy 341.04209 -282.31008) (xy 341.018439 -282.355143) (xy 340.987866 -282.395829) (xy 340.951162 -282.431084)
			(xy 340.909278 -282.459994) (xy 340.863299 -282.481811) (xy 340.814415 -282.495971) (xy 340.763894 -282.502105)
			(xy 340.713042 -282.500056) (xy 340.663178 -282.489876) (xy 340.615592 -282.471829) (xy 340.571518 -282.446383)
			(xy 340.532096 -282.414196) (xy 340.498348 -282.376102) (xy 340.471147 -282.333088) (xy 340.451199 -282.286268)
			(xy 340.43902 -282.236854) (xy 340.434925 -282.186126) (xy 340.308438 -282.186126) (xy 340.308438 -282.410408)
			(xy 340.311994 -282.423616) (xy 340.31555 -282.429712) (xy 340.340592 -282.472644) (xy 340.383739 -282.562188)
			(xy 340.418658 -282.655249) (xy 340.43239 -282.703016) (xy 340.43364 -282.707204) (xy 340.43734 -282.715122)
			(xy 340.439756 -282.718764) (xy 340.445344 -282.726892) (xy 340.468051 -282.741355) (xy 340.508612 -282.776749)
			(xy 340.542575 -282.818515) (xy 340.568953 -282.865442) (xy 340.58698 -282.916167) (xy 340.596132 -282.969216)
			(xy 340.596728 -282.996132) (xy 340.915256 -282.996132) (xy 340.919216 -282.947078) (xy 340.930993 -282.899294)
			(xy 340.950284 -282.854018) (xy 340.976587 -282.812422) (xy 341.009222 -282.775585) (xy 341.047343 -282.74446)
			(xy 341.089964 -282.719853) (xy 341.13598 -282.702401) (xy 341.184199 -282.692557) (xy 341.233374 -282.690576)
			(xy 341.282229 -282.696508) (xy 341.3295 -282.7102) (xy 341.373962 -282.731298) (xy 341.414465 -282.759254)
			(xy 341.449958 -282.793346) (xy 341.479523 -282.83269) (xy 341.502394 -282.876267) (xy 341.517978 -282.922948)
			(xy 341.525873 -282.971525) (xy 341.526368 -282.996132) (xy 341.844879 -282.996132) (xy 341.848974 -282.945404)
			(xy 341.861153 -282.89599) (xy 341.881101 -282.84917) (xy 341.908302 -282.806156) (xy 341.94205 -282.768062)
			(xy 341.981472 -282.735875) (xy 342.025546 -282.710429) (xy 342.073132 -282.692382) (xy 342.122996 -282.682202)
			(xy 342.173848 -282.680153) (xy 342.224369 -282.686287) (xy 342.273253 -282.700447) (xy 342.319232 -282.722264)
			(xy 342.361116 -282.751174) (xy 342.39782 -282.786429) (xy 342.428393 -282.827115) (xy 342.452044 -282.872178)
			(xy 342.46816 -282.920452) (xy 342.476324 -282.970686) (xy 342.476836 -282.996132) (xy 342.795364 -282.996132)
			(xy 342.799324 -282.947078) (xy 342.811101 -282.899294) (xy 342.830392 -282.854018) (xy 342.856695 -282.812422)
			(xy 342.88933 -282.775585) (xy 342.927451 -282.74446) (xy 342.970072 -282.719853) (xy 343.016088 -282.702401)
			(xy 343.064307 -282.692557) (xy 343.113482 -282.690576) (xy 343.162337 -282.696508) (xy 343.209608 -282.7102)
			(xy 343.25407 -282.731298) (xy 343.294573 -282.759254) (xy 343.330066 -282.793346) (xy 343.359631 -282.83269)
			(xy 343.382502 -282.876267) (xy 343.398086 -282.922948) (xy 343.405981 -282.971525) (xy 343.406476 -282.996132)
			(xy 343.724987 -282.996132) (xy 343.729082 -282.945404) (xy 343.741261 -282.89599) (xy 343.761209 -282.84917)
			(xy 343.78841 -282.806156) (xy 343.822158 -282.768062) (xy 343.86158 -282.735875) (xy 343.905654 -282.710429)
			(xy 343.95324 -282.692382) (xy 344.003104 -282.682202) (xy 344.053956 -282.680153) (xy 344.104477 -282.686287)
			(xy 344.153361 -282.700447) (xy 344.19934 -282.722264) (xy 344.241224 -282.751174) (xy 344.277928 -282.786429)
			(xy 344.308501 -282.827115) (xy 344.332152 -282.872178) (xy 344.348268 -282.920452) (xy 344.356432 -282.970686)
			(xy 344.356944 -282.996132) (xy 344.356432 -283.021578) (xy 344.348268 -283.071812) (xy 344.332152 -283.120086)
			(xy 344.308501 -283.165149) (xy 344.277928 -283.205835) (xy 344.241224 -283.24109) (xy 344.19934 -283.27)
			(xy 344.153361 -283.291817) (xy 344.104477 -283.305977) (xy 344.053956 -283.312111) (xy 344.003104 -283.310062)
			(xy 343.95324 -283.299882) (xy 343.905654 -283.281835) (xy 343.86158 -283.256389) (xy 343.822158 -283.224202)
			(xy 343.78841 -283.186108) (xy 343.761209 -283.143094) (xy 343.741261 -283.096274) (xy 343.729082 -283.04686)
			(xy 343.724987 -282.996132) (xy 343.406476 -282.996132) (xy 343.405981 -283.020739) (xy 343.398086 -283.069316)
			(xy 343.382502 -283.115997) (xy 343.359631 -283.159574) (xy 343.330066 -283.198918) (xy 343.294573 -283.23301)
			(xy 343.25407 -283.260966) (xy 343.209608 -283.282064) (xy 343.162337 -283.295756) (xy 343.113482 -283.301688)
			(xy 343.064307 -283.299707) (xy 343.016088 -283.289863) (xy 342.970072 -283.272411) (xy 342.927451 -283.247804)
			(xy 342.88933 -283.216679) (xy 342.856695 -283.179842) (xy 342.830392 -283.138246) (xy 342.811101 -283.09297)
			(xy 342.799324 -283.045186) (xy 342.795364 -282.996132) (xy 342.476836 -282.996132) (xy 342.476324 -283.021578)
			(xy 342.46816 -283.071812) (xy 342.452044 -283.120086) (xy 342.428393 -283.165149) (xy 342.39782 -283.205835)
			(xy 342.361116 -283.24109) (xy 342.319232 -283.27) (xy 342.273253 -283.291817) (xy 342.224369 -283.305977)
			(xy 342.173848 -283.312111) (xy 342.122996 -283.310062) (xy 342.073132 -283.299882) (xy 342.025546 -283.281835)
			(xy 341.981472 -283.256389) (xy 341.94205 -283.224202) (xy 341.908302 -283.186108) (xy 341.881101 -283.143094)
			(xy 341.861153 -283.096274) (xy 341.848974 -283.04686) (xy 341.844879 -282.996132) (xy 341.526368 -282.996132)
			(xy 341.525873 -283.020739) (xy 341.517978 -283.069316) (xy 341.502394 -283.115997) (xy 341.479523 -283.159574)
			(xy 341.449958 -283.198918) (xy 341.414465 -283.23301) (xy 341.373962 -283.260966) (xy 341.3295 -283.282064)
			(xy 341.282229 -283.295756) (xy 341.233374 -283.301688) (xy 341.184199 -283.299707) (xy 341.13598 -283.289863)
			(xy 341.089964 -283.272411) (xy 341.047343 -283.247804) (xy 341.009222 -283.216679) (xy 340.976587 -283.179842)
			(xy 340.950284 -283.138246) (xy 340.930993 -283.09297) (xy 340.919216 -283.045186) (xy 340.915256 -282.996132)
			(xy 340.596728 -282.996132) (xy 340.596215 -283.022349) (xy 340.587562 -283.074063) (xy 340.570481 -283.123636)
			(xy 340.545444 -283.169705) (xy 340.513137 -283.211003) (xy 340.47445 -283.246394) (xy 340.45271 -283.261054)
			(xy 340.448761 -283.26377) (xy 340.441862 -283.270421) (xy 340.438994 -283.274262) (xy 340.434168 -283.280866)
			(xy 340.422564 -283.322414) (xy 340.393722 -283.403723) (xy 340.358618 -283.48253) (xy 340.33841 -283.520642)
			(xy 340.31555 -283.560774) (xy 340.311994 -283.56687) (xy 340.308438 -283.580078) (xy 340.308438 -283.806138)
			(xy 340.434925 -283.806138) (xy 340.43902 -283.75541) (xy 340.451199 -283.705996) (xy 340.471147 -283.659176)
			(xy 340.498348 -283.616162) (xy 340.532096 -283.578068) (xy 340.571518 -283.545881) (xy 340.615592 -283.520435)
			(xy 340.663178 -283.502388) (xy 340.713042 -283.492208) (xy 340.763894 -283.490159) (xy 340.814415 -283.496293)
			(xy 340.863299 -283.510453) (xy 340.909278 -283.53227) (xy 340.951162 -283.56118) (xy 340.987866 -283.596435)
			(xy 341.018439 -283.637121) (xy 341.04209 -283.682184) (xy 341.058206 -283.730458) (xy 341.06637 -283.780692)
			(xy 341.066882 -283.806138) (xy 341.38541 -283.806138) (xy 341.38937 -283.757084) (xy 341.401147 -283.7093)
			(xy 341.420438 -283.664024) (xy 341.446741 -283.622428) (xy 341.479376 -283.585591) (xy 341.517497 -283.554466)
			(xy 341.560118 -283.529859) (xy 341.606134 -283.512407) (xy 341.654353 -283.502563) (xy 341.703528 -283.500582)
			(xy 341.752383 -283.506514) (xy 341.799654 -283.520206) (xy 341.844116 -283.541304) (xy 341.884619 -283.56926)
			(xy 341.920112 -283.603352) (xy 341.949677 -283.642696) (xy 341.972548 -283.686273) (xy 341.988132 -283.732954)
			(xy 341.996027 -283.781531) (xy 341.996522 -283.806138) (xy 342.314779 -283.806138) (xy 342.318874 -283.75541)
			(xy 342.331053 -283.705996) (xy 342.351001 -283.659176) (xy 342.378202 -283.616162) (xy 342.41195 -283.578068)
			(xy 342.451372 -283.545881) (xy 342.495446 -283.520435) (xy 342.543032 -283.502388) (xy 342.592896 -283.492208)
			(xy 342.643748 -283.490159) (xy 342.694269 -283.496293) (xy 342.743153 -283.510453) (xy 342.789132 -283.53227)
			(xy 342.831016 -283.56118) (xy 342.86772 -283.596435) (xy 342.898293 -283.637121) (xy 342.921944 -283.682184)
			(xy 342.93806 -283.730458) (xy 342.946224 -283.780692) (xy 342.946736 -283.806138) (xy 343.254833 -283.806138)
			(xy 343.258928 -283.75541) (xy 343.271107 -283.705996) (xy 343.291055 -283.659176) (xy 343.318256 -283.616162)
			(xy 343.352004 -283.578068) (xy 343.391426 -283.545881) (xy 343.4355 -283.520435) (xy 343.483086 -283.502388)
			(xy 343.53295 -283.492208) (xy 343.583802 -283.490159) (xy 343.634323 -283.496293) (xy 343.683207 -283.510453)
			(xy 343.729186 -283.53227) (xy 343.77107 -283.56118) (xy 343.807774 -283.596435) (xy 343.838347 -283.637121)
			(xy 343.861998 -283.682184) (xy 343.878114 -283.730458) (xy 343.886278 -283.780692) (xy 343.88679 -283.806138)
			(xy 343.886278 -283.831584) (xy 343.878114 -283.881818) (xy 343.861998 -283.930092) (xy 343.838347 -283.975155)
			(xy 343.807774 -284.015841) (xy 343.77107 -284.051096) (xy 343.729186 -284.080006) (xy 343.683207 -284.101823)
			(xy 343.634323 -284.115983) (xy 343.583802 -284.122117) (xy 343.53295 -284.120068) (xy 343.483086 -284.109888)
			(xy 343.4355 -284.091841) (xy 343.391426 -284.066395) (xy 343.352004 -284.034208) (xy 343.318256 -283.996114)
			(xy 343.291055 -283.9531) (xy 343.271107 -283.90628) (xy 343.258928 -283.856866) (xy 343.254833 -283.806138)
			(xy 342.946736 -283.806138) (xy 342.946224 -283.831584) (xy 342.93806 -283.881818) (xy 342.921944 -283.930092)
			(xy 342.898293 -283.975155) (xy 342.86772 -284.015841) (xy 342.831016 -284.051096) (xy 342.789132 -284.080006)
			(xy 342.743153 -284.101823) (xy 342.694269 -284.115983) (xy 342.643748 -284.122117) (xy 342.592896 -284.120068)
			(xy 342.543032 -284.109888) (xy 342.495446 -284.091841) (xy 342.451372 -284.066395) (xy 342.41195 -284.034208)
			(xy 342.378202 -283.996114) (xy 342.351001 -283.9531) (xy 342.331053 -283.90628) (xy 342.318874 -283.856866)
			(xy 342.314779 -283.806138) (xy 341.996522 -283.806138) (xy 341.996027 -283.830745) (xy 341.988132 -283.879322)
			(xy 341.972548 -283.926003) (xy 341.949677 -283.96958) (xy 341.920112 -284.008924) (xy 341.884619 -284.043016)
			(xy 341.844116 -284.070972) (xy 341.799654 -284.09207) (xy 341.752383 -284.105762) (xy 341.703528 -284.111694)
			(xy 341.654353 -284.109713) (xy 341.606134 -284.099869) (xy 341.560118 -284.082417) (xy 341.517497 -284.05781)
			(xy 341.479376 -284.026685) (xy 341.446741 -283.989848) (xy 341.420438 -283.948252) (xy 341.401147 -283.902976)
			(xy 341.38937 -283.855192) (xy 341.38541 -283.806138) (xy 341.066882 -283.806138) (xy 341.06637 -283.831584)
			(xy 341.058206 -283.881818) (xy 341.04209 -283.930092) (xy 341.018439 -283.975155) (xy 340.987866 -284.015841)
			(xy 340.951162 -284.051096) (xy 340.909278 -284.080006) (xy 340.863299 -284.101823) (xy 340.814415 -284.115983)
			(xy 340.763894 -284.122117) (xy 340.713042 -284.120068) (xy 340.663178 -284.109888) (xy 340.615592 -284.091841)
			(xy 340.571518 -284.066395) (xy 340.532096 -284.034208) (xy 340.498348 -283.996114) (xy 340.471147 -283.9531)
			(xy 340.451199 -283.90628) (xy 340.43902 -283.856866) (xy 340.434925 -283.806138) (xy 340.308438 -283.806138)
			(xy 340.308438 -284.035754) (xy 340.311994 -284.048708) (xy 340.315296 -284.05455) (xy 340.340003 -284.097955)
			(xy 340.382415 -284.188385) (xy 340.416542 -284.282256) (xy 340.42985 -284.330394) (xy 340.434168 -284.3403)
			(xy 340.454935 -284.352332) (xy 340.492897 -284.381698) (xy 340.525977 -284.416471) (xy 340.553413 -284.45585)
			(xy 340.574574 -284.498928) (xy 340.588971 -284.544712) (xy 340.596273 -284.592147) (xy 340.596728 -284.616144)
			(xy 340.915256 -284.616144) (xy 340.919216 -284.56709) (xy 340.930993 -284.519306) (xy 340.950284 -284.47403)
			(xy 340.976587 -284.432434) (xy 341.009222 -284.395597) (xy 341.047343 -284.364472) (xy 341.089964 -284.339865)
			(xy 341.13598 -284.322413) (xy 341.184199 -284.312569) (xy 341.233374 -284.310588) (xy 341.282229 -284.31652)
			(xy 341.3295 -284.330212) (xy 341.373962 -284.35131) (xy 341.414465 -284.379266) (xy 341.449958 -284.413358)
			(xy 341.479523 -284.452702) (xy 341.502394 -284.496279) (xy 341.517978 -284.54296) (xy 341.525873 -284.591537)
			(xy 341.526368 -284.616144) (xy 341.844879 -284.616144) (xy 341.848974 -284.565416) (xy 341.861153 -284.516002)
			(xy 341.881101 -284.469182) (xy 341.908302 -284.426168) (xy 341.94205 -284.388074) (xy 341.981472 -284.355887)
			(xy 342.025546 -284.330441) (xy 342.073132 -284.312394) (xy 342.122996 -284.302214) (xy 342.173848 -284.300165)
			(xy 342.224369 -284.306299) (xy 342.273253 -284.320459) (xy 342.319232 -284.342276) (xy 342.361116 -284.371186)
			(xy 342.39782 -284.406441) (xy 342.428393 -284.447127) (xy 342.452044 -284.49219) (xy 342.46816 -284.540464)
			(xy 342.476324 -284.590698) (xy 342.476836 -284.616144) (xy 342.795364 -284.616144) (xy 342.799324 -284.56709)
			(xy 342.811101 -284.519306) (xy 342.830392 -284.47403) (xy 342.856695 -284.432434) (xy 342.88933 -284.395597)
			(xy 342.927451 -284.364472) (xy 342.970072 -284.339865) (xy 343.016088 -284.322413) (xy 343.064307 -284.312569)
			(xy 343.113482 -284.310588) (xy 343.162337 -284.31652) (xy 343.209608 -284.330212) (xy 343.25407 -284.35131)
			(xy 343.294573 -284.379266) (xy 343.330066 -284.413358) (xy 343.359631 -284.452702) (xy 343.382502 -284.496279)
			(xy 343.398086 -284.54296) (xy 343.405981 -284.591537) (xy 343.406476 -284.616144) (xy 343.405981 -284.640751)
			(xy 343.398086 -284.689328) (xy 343.382502 -284.736009) (xy 343.359631 -284.779586) (xy 343.330066 -284.81893)
			(xy 343.294573 -284.853022) (xy 343.25407 -284.880978) (xy 343.209608 -284.902076) (xy 343.162337 -284.915768)
			(xy 343.113482 -284.9217) (xy 343.064307 -284.919719) (xy 343.016088 -284.909875) (xy 342.970072 -284.892423)
			(xy 342.927451 -284.867816) (xy 342.88933 -284.836691) (xy 342.856695 -284.799854) (xy 342.830392 -284.758258)
			(xy 342.811101 -284.712982) (xy 342.799324 -284.665198) (xy 342.795364 -284.616144) (xy 342.476836 -284.616144)
			(xy 342.476324 -284.64159) (xy 342.46816 -284.691824) (xy 342.452044 -284.740098) (xy 342.428393 -284.785161)
			(xy 342.39782 -284.825847) (xy 342.361116 -284.861102) (xy 342.319232 -284.890012) (xy 342.273253 -284.911829)
			(xy 342.224369 -284.925989) (xy 342.173848 -284.932123) (xy 342.122996 -284.930074) (xy 342.073132 -284.919894)
			(xy 342.025546 -284.901847) (xy 341.981472 -284.876401) (xy 341.94205 -284.844214) (xy 341.908302 -284.80612)
			(xy 341.881101 -284.763106) (xy 341.861153 -284.716286) (xy 341.848974 -284.666872) (xy 341.844879 -284.616144)
			(xy 341.526368 -284.616144) (xy 341.525873 -284.640751) (xy 341.517978 -284.689328) (xy 341.502394 -284.736009)
			(xy 341.479523 -284.779586) (xy 341.449958 -284.81893) (xy 341.414465 -284.853022) (xy 341.373962 -284.880978)
			(xy 341.3295 -284.902076) (xy 341.282229 -284.915768) (xy 341.233374 -284.9217) (xy 341.184199 -284.919719)
			(xy 341.13598 -284.909875) (xy 341.089964 -284.892423) (xy 341.047343 -284.867816) (xy 341.009222 -284.836691)
			(xy 340.976587 -284.799854) (xy 340.950284 -284.758258) (xy 340.930993 -284.712982) (xy 340.919216 -284.665198)
			(xy 340.915256 -284.616144) (xy 340.596728 -284.616144) (xy 340.596271 -284.640209) (xy 340.588952 -284.687779)
			(xy 340.574492 -284.733686) (xy 340.553225 -284.776862) (xy 340.525646 -284.816307) (xy 340.492395 -284.851104)
			(xy 340.454243 -284.880446) (xy 340.433406 -284.892496) (xy 340.429088 -284.902148) (xy 340.415781 -284.949784)
			(xy 340.381823 -285.042686) (xy 340.33975 -285.132206) (xy 340.315296 -285.175198) (xy 340.311994 -285.18104)
			(xy 340.308438 -285.193994) (xy 340.308438 -285.42615) (xy 340.434925 -285.42615) (xy 340.43902 -285.375422)
			(xy 340.451199 -285.326008) (xy 340.471147 -285.279188) (xy 340.498348 -285.236174) (xy 340.532096 -285.19808)
			(xy 340.571518 -285.165893) (xy 340.615592 -285.140447) (xy 340.663178 -285.1224) (xy 340.713042 -285.11222)
			(xy 340.763894 -285.110171) (xy 340.814415 -285.116305) (xy 340.863299 -285.130465) (xy 340.909278 -285.152282)
			(xy 340.951162 -285.181192) (xy 340.987866 -285.216447) (xy 341.018439 -285.257133) (xy 341.04209 -285.302196)
			(xy 341.058206 -285.35047) (xy 341.06637 -285.400704) (xy 341.066882 -285.42615) (xy 341.38541 -285.42615)
			(xy 341.38937 -285.377096) (xy 341.401147 -285.329312) (xy 341.420438 -285.284036) (xy 341.446741 -285.24244)
			(xy 341.479376 -285.205603) (xy 341.517497 -285.174478) (xy 341.560118 -285.149871) (xy 341.606134 -285.132419)
			(xy 341.654353 -285.122575) (xy 341.703528 -285.120594) (xy 341.752383 -285.126526) (xy 341.799654 -285.140218)
			(xy 341.844116 -285.161316) (xy 341.884619 -285.189272) (xy 341.920112 -285.223364) (xy 341.949677 -285.262708)
			(xy 341.972548 -285.306285) (xy 341.988132 -285.352966) (xy 341.996027 -285.401543) (xy 341.996522 -285.42615)
			(xy 342.314779 -285.42615) (xy 342.318874 -285.375422) (xy 342.331053 -285.326008) (xy 342.351001 -285.279188)
			(xy 342.378202 -285.236174) (xy 342.41195 -285.19808) (xy 342.451372 -285.165893) (xy 342.495446 -285.140447)
			(xy 342.543032 -285.1224) (xy 342.592896 -285.11222) (xy 342.643748 -285.110171) (xy 342.694269 -285.116305)
			(xy 342.743153 -285.130465) (xy 342.789132 -285.152282) (xy 342.831016 -285.181192) (xy 342.86772 -285.216447)
			(xy 342.898293 -285.257133) (xy 342.921944 -285.302196) (xy 342.93806 -285.35047) (xy 342.946224 -285.400704)
			(xy 342.946736 -285.42615) (xy 342.946224 -285.451596) (xy 342.93806 -285.50183) (xy 342.921944 -285.550104)
			(xy 342.898293 -285.595167) (xy 342.86772 -285.635853) (xy 342.831016 -285.671108) (xy 342.789132 -285.700018)
			(xy 342.743153 -285.721835) (xy 342.694269 -285.735995) (xy 342.643748 -285.742129) (xy 342.592896 -285.74008)
			(xy 342.543032 -285.7299) (xy 342.495446 -285.711853) (xy 342.451372 -285.686407) (xy 342.41195 -285.65422)
			(xy 342.378202 -285.616126) (xy 342.351001 -285.573112) (xy 342.331053 -285.526292) (xy 342.318874 -285.476878)
			(xy 342.314779 -285.42615) (xy 341.996522 -285.42615) (xy 341.996027 -285.450757) (xy 341.988132 -285.499334)
			(xy 341.972548 -285.546015) (xy 341.949677 -285.589592) (xy 341.920112 -285.628936) (xy 341.884619 -285.663028)
			(xy 341.844116 -285.690984) (xy 341.799654 -285.712082) (xy 341.752383 -285.725774) (xy 341.703528 -285.731706)
			(xy 341.654353 -285.729725) (xy 341.606134 -285.719881) (xy 341.560118 -285.702429) (xy 341.517497 -285.677822)
			(xy 341.479376 -285.646697) (xy 341.446741 -285.60986) (xy 341.420438 -285.568264) (xy 341.401147 -285.522988)
			(xy 341.38937 -285.475204) (xy 341.38541 -285.42615) (xy 341.066882 -285.42615) (xy 341.06637 -285.451596)
			(xy 341.058206 -285.50183) (xy 341.04209 -285.550104) (xy 341.018439 -285.595167) (xy 340.987866 -285.635853)
			(xy 340.951162 -285.671108) (xy 340.909278 -285.700018) (xy 340.863299 -285.721835) (xy 340.814415 -285.735995)
			(xy 340.763894 -285.742129) (xy 340.713042 -285.74008) (xy 340.663178 -285.7299) (xy 340.615592 -285.711853)
			(xy 340.571518 -285.686407) (xy 340.532096 -285.65422) (xy 340.498348 -285.616126) (xy 340.471147 -285.573112)
			(xy 340.451199 -285.526292) (xy 340.43902 -285.476878) (xy 340.434925 -285.42615) (xy 340.308438 -285.42615)
			(xy 340.308438 -285.661608) (xy 340.308649 -285.668188) (xy 340.311994 -285.680918) (xy 340.315042 -285.686754)
			(xy 340.338156 -285.72968) (xy 340.363655 -285.781605) (xy 340.405017 -285.889646) (xy 340.420706 -285.945326)
			(xy 340.425532 -285.95574) (xy 340.447265 -285.967472) (xy 340.487112 -285.996646) (xy 340.521933 -286.031667)
			(xy 340.550878 -286.071681) (xy 340.573242 -286.115713) (xy 340.58848 -286.162689) (xy 340.59622 -286.211464)
			(xy 340.596728 -286.236156) (xy 340.915256 -286.236156) (xy 340.919216 -286.187102) (xy 340.930993 -286.139318)
			(xy 340.950284 -286.094042) (xy 340.976587 -286.052446) (xy 341.009222 -286.015609) (xy 341.047343 -285.984484)
			(xy 341.089964 -285.959877) (xy 341.13598 -285.942425) (xy 341.184199 -285.932581) (xy 341.233374 -285.9306)
			(xy 341.282229 -285.936532) (xy 341.3295 -285.950224) (xy 341.373962 -285.971322) (xy 341.414465 -285.999278)
			(xy 341.449958 -286.03337) (xy 341.479523 -286.072714) (xy 341.502394 -286.116291) (xy 341.517978 -286.162972)
			(xy 341.525873 -286.211549) (xy 341.526368 -286.236156) (xy 341.844879 -286.236156) (xy 341.848974 -286.185428)
			(xy 341.861153 -286.136014) (xy 341.881101 -286.089194) (xy 341.908302 -286.04618) (xy 341.94205 -286.008086)
			(xy 341.981472 -285.975899) (xy 342.025546 -285.950453) (xy 342.073132 -285.932406) (xy 342.122996 -285.922226)
			(xy 342.173848 -285.920177) (xy 342.224369 -285.926311) (xy 342.273253 -285.940471) (xy 342.319232 -285.962288)
			(xy 342.361116 -285.991198) (xy 342.39782 -286.026453) (xy 342.428393 -286.067139) (xy 342.452044 -286.112202)
			(xy 342.46816 -286.160476) (xy 342.476324 -286.21071) (xy 342.476836 -286.236156) (xy 342.795364 -286.236156)
			(xy 342.799324 -286.187102) (xy 342.811101 -286.139318) (xy 342.830392 -286.094042) (xy 342.856695 -286.052446)
			(xy 342.88933 -286.015609) (xy 342.927451 -285.984484) (xy 342.970072 -285.959877) (xy 343.016088 -285.942425)
			(xy 343.064307 -285.932581) (xy 343.113482 -285.9306) (xy 343.162337 -285.936532) (xy 343.209608 -285.950224)
			(xy 343.25407 -285.971322) (xy 343.294573 -285.999278) (xy 343.330066 -286.03337) (xy 343.359631 -286.072714)
			(xy 343.382502 -286.116291) (xy 343.398086 -286.162972) (xy 343.405981 -286.211549) (xy 343.406476 -286.236156)
			(xy 343.405981 -286.260763) (xy 343.398086 -286.30934) (xy 343.382502 -286.356021) (xy 343.359631 -286.399598)
			(xy 343.330066 -286.438942) (xy 343.294573 -286.473034) (xy 343.25407 -286.50099) (xy 343.209608 -286.522088)
			(xy 343.162337 -286.53578) (xy 343.113482 -286.541712) (xy 343.064307 -286.539731) (xy 343.016088 -286.529887)
			(xy 342.970072 -286.512435) (xy 342.927451 -286.487828) (xy 342.88933 -286.456703) (xy 342.856695 -286.419866)
			(xy 342.830392 -286.37827) (xy 342.811101 -286.332994) (xy 342.799324 -286.28521) (xy 342.795364 -286.236156)
			(xy 342.476836 -286.236156) (xy 342.476324 -286.261602) (xy 342.46816 -286.311836) (xy 342.452044 -286.36011)
			(xy 342.428393 -286.405173) (xy 342.39782 -286.445859) (xy 342.361116 -286.481114) (xy 342.319232 -286.510024)
			(xy 342.273253 -286.531841) (xy 342.224369 -286.546001) (xy 342.173848 -286.552135) (xy 342.122996 -286.550086)
			(xy 342.073132 -286.539906) (xy 342.025546 -286.521859) (xy 341.981472 -286.496413) (xy 341.94205 -286.464226)
			(xy 341.908302 -286.426132) (xy 341.881101 -286.383118) (xy 341.861153 -286.336298) (xy 341.848974 -286.286884)
			(xy 341.844879 -286.236156) (xy 341.526368 -286.236156) (xy 341.525873 -286.260763) (xy 341.517978 -286.30934)
			(xy 341.502394 -286.356021) (xy 341.479523 -286.399598) (xy 341.449958 -286.438942) (xy 341.414465 -286.473034)
			(xy 341.373962 -286.50099) (xy 341.3295 -286.522088) (xy 341.282229 -286.53578) (xy 341.233374 -286.541712)
			(xy 341.184199 -286.539731) (xy 341.13598 -286.529887) (xy 341.089964 -286.512435) (xy 341.047343 -286.487828)
			(xy 341.009222 -286.456703) (xy 340.976587 -286.419866) (xy 340.950284 -286.37827) (xy 340.930993 -286.332994)
			(xy 340.919216 -286.28521) (xy 340.915256 -286.236156) (xy 340.596728 -286.236156) (xy 340.59623 -286.260849)
			(xy 340.588498 -286.309627) (xy 340.573263 -286.356606) (xy 340.550898 -286.400638) (xy 340.521946 -286.44065)
			(xy 340.487117 -286.475663) (xy 340.447258 -286.504825) (xy 340.425532 -286.516572) (xy 340.420706 -286.527748)
			(xy 340.413872 -286.552372) (xy 340.398244 -286.601031) (xy 340.389464 -286.62503) (xy 340.37373 -286.66634)
			(xy 340.336604 -286.746573) (xy 340.315296 -286.785304) (xy 340.315042 -286.785558) (xy 340.311994 -286.791146)
			(xy 340.310216 -286.797242) (xy 340.308438 -286.810704) (xy 340.308438 -287.045908) (xy 340.434925 -287.045908)
			(xy 340.43902 -286.99518) (xy 340.451199 -286.945766) (xy 340.471147 -286.898946) (xy 340.498348 -286.855932)
			(xy 340.532096 -286.817838) (xy 340.571518 -286.785651) (xy 340.615592 -286.760205) (xy 340.663178 -286.742158)
			(xy 340.713042 -286.731978) (xy 340.763894 -286.729929) (xy 340.814415 -286.736063) (xy 340.863299 -286.750223)
			(xy 340.909278 -286.77204) (xy 340.951162 -286.80095) (xy 340.987866 -286.836205) (xy 341.018439 -286.876891)
			(xy 341.04209 -286.921954) (xy 341.058206 -286.970228) (xy 341.06637 -287.020462) (xy 341.066882 -287.045908)
			(xy 341.38541 -287.045908) (xy 341.38937 -286.996854) (xy 341.401147 -286.94907) (xy 341.420438 -286.903794)
			(xy 341.446741 -286.862198) (xy 341.479376 -286.825361) (xy 341.517497 -286.794236) (xy 341.560118 -286.769629)
			(xy 341.606134 -286.752177) (xy 341.654353 -286.742333) (xy 341.703528 -286.740352) (xy 341.752383 -286.746284)
			(xy 341.799654 -286.759976) (xy 341.844116 -286.781074) (xy 341.884619 -286.80903) (xy 341.920112 -286.843122)
			(xy 341.949677 -286.882466) (xy 341.972548 -286.926043) (xy 341.988132 -286.972724) (xy 341.996027 -287.021301)
			(xy 341.996522 -287.045908) (xy 342.314779 -287.045908) (xy 342.318874 -286.99518) (xy 342.331053 -286.945766)
			(xy 342.351001 -286.898946) (xy 342.378202 -286.855932) (xy 342.41195 -286.817838) (xy 342.451372 -286.785651)
			(xy 342.495446 -286.760205) (xy 342.543032 -286.742158) (xy 342.592896 -286.731978) (xy 342.643748 -286.729929)
			(xy 342.694269 -286.736063) (xy 342.743153 -286.750223) (xy 342.789132 -286.77204) (xy 342.831016 -286.80095)
			(xy 342.86772 -286.836205) (xy 342.898293 -286.876891) (xy 342.921944 -286.921954) (xy 342.93806 -286.970228)
			(xy 342.946224 -287.020462) (xy 342.946736 -287.045908) (xy 343.254833 -287.045908) (xy 343.258928 -286.99518)
			(xy 343.271107 -286.945766) (xy 343.291055 -286.898946) (xy 343.318256 -286.855932) (xy 343.352004 -286.817838)
			(xy 343.391426 -286.785651) (xy 343.4355 -286.760205) (xy 343.483086 -286.742158) (xy 343.53295 -286.731978)
			(xy 343.583802 -286.729929) (xy 343.634323 -286.736063) (xy 343.683207 -286.750223) (xy 343.729186 -286.77204)
			(xy 343.77107 -286.80095) (xy 343.807774 -286.836205) (xy 343.838347 -286.876891) (xy 343.861998 -286.921954)
			(xy 343.878114 -286.970228) (xy 343.886278 -287.020462) (xy 343.88679 -287.045908) (xy 343.886278 -287.071354)
			(xy 343.878114 -287.121588) (xy 343.861998 -287.169862) (xy 343.838347 -287.214925) (xy 343.807774 -287.255611)
			(xy 343.77107 -287.290866) (xy 343.729186 -287.319776) (xy 343.683207 -287.341593) (xy 343.634323 -287.355753)
			(xy 343.583802 -287.361887) (xy 343.53295 -287.359838) (xy 343.483086 -287.349658) (xy 343.4355 -287.331611)
			(xy 343.391426 -287.306165) (xy 343.352004 -287.273978) (xy 343.318256 -287.235884) (xy 343.291055 -287.19287)
			(xy 343.271107 -287.14605) (xy 343.258928 -287.096636) (xy 343.254833 -287.045908) (xy 342.946736 -287.045908)
			(xy 342.946224 -287.071354) (xy 342.93806 -287.121588) (xy 342.921944 -287.169862) (xy 342.898293 -287.214925)
			(xy 342.86772 -287.255611) (xy 342.831016 -287.290866) (xy 342.789132 -287.319776) (xy 342.743153 -287.341593)
			(xy 342.694269 -287.355753) (xy 342.643748 -287.361887) (xy 342.592896 -287.359838) (xy 342.543032 -287.349658)
			(xy 342.495446 -287.331611) (xy 342.451372 -287.306165) (xy 342.41195 -287.273978) (xy 342.378202 -287.235884)
			(xy 342.351001 -287.19287) (xy 342.331053 -287.14605) (xy 342.318874 -287.096636) (xy 342.314779 -287.045908)
			(xy 341.996522 -287.045908) (xy 341.996027 -287.070515) (xy 341.988132 -287.119092) (xy 341.972548 -287.165773)
			(xy 341.949677 -287.20935) (xy 341.920112 -287.248694) (xy 341.884619 -287.282786) (xy 341.844116 -287.310742)
			(xy 341.799654 -287.33184) (xy 341.752383 -287.345532) (xy 341.703528 -287.351464) (xy 341.654353 -287.349483)
			(xy 341.606134 -287.339639) (xy 341.560118 -287.322187) (xy 341.517497 -287.29758) (xy 341.479376 -287.266455)
			(xy 341.446741 -287.229618) (xy 341.420438 -287.188022) (xy 341.401147 -287.142746) (xy 341.38937 -287.094962)
			(xy 341.38541 -287.045908) (xy 341.066882 -287.045908) (xy 341.06637 -287.071354) (xy 341.058206 -287.121588)
			(xy 341.04209 -287.169862) (xy 341.018439 -287.214925) (xy 340.987866 -287.255611) (xy 340.951162 -287.290866)
			(xy 340.909278 -287.319776) (xy 340.863299 -287.341593) (xy 340.814415 -287.355753) (xy 340.763894 -287.361887)
			(xy 340.713042 -287.359838) (xy 340.663178 -287.349658) (xy 340.615592 -287.331611) (xy 340.571518 -287.306165)
			(xy 340.532096 -287.273978) (xy 340.498348 -287.235884) (xy 340.471147 -287.19287) (xy 340.451199 -287.14605)
			(xy 340.43902 -287.096636) (xy 340.434925 -287.045908) (xy 340.308438 -287.045908) (xy 340.308438 -287.281366)
			(xy 340.310216 -287.294828) (xy 340.311994 -287.300924) (xy 340.315042 -287.306512) (xy 340.315296 -287.306766)
			(xy 340.336341 -287.345087) (xy 340.373085 -287.424427) (xy 340.388702 -287.465262) (xy 340.397647 -287.489757)
			(xy 340.413527 -287.539435) (xy 340.420452 -287.564576) (xy 340.425532 -287.575752) (xy 340.447264 -287.587484)
			(xy 340.487111 -287.616659) (xy 340.52193 -287.65168) (xy 340.550873 -287.691694) (xy 340.573236 -287.735726)
			(xy 340.588472 -287.782701) (xy 340.59621 -287.831476) (xy 340.596728 -287.856168) (xy 340.915256 -287.856168)
			(xy 340.919216 -287.807114) (xy 340.930993 -287.75933) (xy 340.950284 -287.714054) (xy 340.976587 -287.672458)
			(xy 341.009222 -287.635621) (xy 341.047343 -287.604496) (xy 341.089964 -287.579889) (xy 341.13598 -287.562437)
			(xy 341.184199 -287.552593) (xy 341.233374 -287.550612) (xy 341.282229 -287.556544) (xy 341.3295 -287.570236)
			(xy 341.373962 -287.591334) (xy 341.414465 -287.61929) (xy 341.449958 -287.653382) (xy 341.479523 -287.692726)
			(xy 341.502394 -287.736303) (xy 341.517978 -287.782984) (xy 341.525873 -287.831561) (xy 341.526368 -287.856168)
			(xy 341.844879 -287.856168) (xy 341.848974 -287.80544) (xy 341.861153 -287.756026) (xy 341.881101 -287.709206)
			(xy 341.908302 -287.666192) (xy 341.94205 -287.628098) (xy 341.981472 -287.595911) (xy 342.025546 -287.570465)
			(xy 342.073132 -287.552418) (xy 342.122996 -287.542238) (xy 342.173848 -287.540189) (xy 342.224369 -287.546323)
			(xy 342.273253 -287.560483) (xy 342.319232 -287.5823) (xy 342.361116 -287.61121) (xy 342.39782 -287.646465)
			(xy 342.428393 -287.687151) (xy 342.452044 -287.732214) (xy 342.46816 -287.780488) (xy 342.476324 -287.830722)
			(xy 342.476836 -287.856168) (xy 342.795364 -287.856168) (xy 342.799324 -287.807114) (xy 342.811101 -287.75933)
			(xy 342.830392 -287.714054) (xy 342.856695 -287.672458) (xy 342.88933 -287.635621) (xy 342.927451 -287.604496)
			(xy 342.970072 -287.579889) (xy 343.016088 -287.562437) (xy 343.064307 -287.552593) (xy 343.113482 -287.550612)
			(xy 343.162337 -287.556544) (xy 343.209608 -287.570236) (xy 343.25407 -287.591334) (xy 343.294573 -287.61929)
			(xy 343.330066 -287.653382) (xy 343.359631 -287.692726) (xy 343.382502 -287.736303) (xy 343.398086 -287.782984)
			(xy 343.405981 -287.831561) (xy 343.406476 -287.856168) (xy 343.405981 -287.880775) (xy 343.398086 -287.929352)
			(xy 343.382502 -287.976033) (xy 343.359631 -288.01961) (xy 343.330066 -288.058954) (xy 343.294573 -288.093046)
			(xy 343.25407 -288.121002) (xy 343.209608 -288.1421) (xy 343.162337 -288.155792) (xy 343.113482 -288.161724)
			(xy 343.064307 -288.159743) (xy 343.016088 -288.149899) (xy 342.970072 -288.132447) (xy 342.927451 -288.10784)
			(xy 342.88933 -288.076715) (xy 342.856695 -288.039878) (xy 342.830392 -287.998282) (xy 342.811101 -287.953006)
			(xy 342.799324 -287.905222) (xy 342.795364 -287.856168) (xy 342.476836 -287.856168) (xy 342.476324 -287.881614)
			(xy 342.46816 -287.931848) (xy 342.452044 -287.980122) (xy 342.428393 -288.025185) (xy 342.39782 -288.065871)
			(xy 342.361116 -288.101126) (xy 342.319232 -288.130036) (xy 342.273253 -288.151853) (xy 342.224369 -288.166013)
			(xy 342.173848 -288.172147) (xy 342.122996 -288.170098) (xy 342.073132 -288.159918) (xy 342.025546 -288.141871)
			(xy 341.981472 -288.116425) (xy 341.94205 -288.084238) (xy 341.908302 -288.046144) (xy 341.881101 -288.00313)
			(xy 341.861153 -287.95631) (xy 341.848974 -287.906896) (xy 341.844879 -287.856168) (xy 341.526368 -287.856168)
			(xy 341.525873 -287.880775) (xy 341.517978 -287.929352) (xy 341.502394 -287.976033) (xy 341.479523 -288.01961)
			(xy 341.449958 -288.058954) (xy 341.414465 -288.093046) (xy 341.373962 -288.121002) (xy 341.3295 -288.1421)
			(xy 341.282229 -288.155792) (xy 341.233374 -288.161724) (xy 341.184199 -288.159743) (xy 341.13598 -288.149899)
			(xy 341.089964 -288.132447) (xy 341.047343 -288.10784) (xy 341.009222 -288.076715) (xy 340.976587 -288.039878)
			(xy 340.950284 -287.998282) (xy 340.930993 -287.953006) (xy 340.919216 -287.905222) (xy 340.915256 -287.856168)
			(xy 340.596728 -287.856168) (xy 340.596229 -287.880861) (xy 340.588496 -287.929638) (xy 340.57326 -287.976615)
			(xy 340.550893 -288.020646) (xy 340.521941 -288.060656) (xy 340.487111 -288.095668) (xy 340.447253 -288.124828)
			(xy 340.425532 -288.136584) (xy 340.420198 -288.149284) (xy 340.407589 -288.193791) (xy 340.376008 -288.280745)
			(xy 340.337358 -288.364796) (xy 340.315042 -288.405316) (xy 340.31174 -288.411158) (xy 340.308438 -288.423604)
			(xy 340.308438 -288.66592) (xy 340.434925 -288.66592) (xy 340.43902 -288.615192) (xy 340.451199 -288.565778)
			(xy 340.471147 -288.518958) (xy 340.498348 -288.475944) (xy 340.532096 -288.43785) (xy 340.571518 -288.405663)
			(xy 340.615592 -288.380217) (xy 340.663178 -288.36217) (xy 340.713042 -288.35199) (xy 340.763894 -288.349941)
			(xy 340.814415 -288.356075) (xy 340.863299 -288.370235) (xy 340.909278 -288.392052) (xy 340.951162 -288.420962)
			(xy 340.987866 -288.456217) (xy 341.018439 -288.496903) (xy 341.04209 -288.541966) (xy 341.058206 -288.59024)
			(xy 341.06637 -288.640474) (xy 341.066882 -288.66592) (xy 341.38541 -288.66592) (xy 341.38937 -288.616866)
			(xy 341.401147 -288.569082) (xy 341.420438 -288.523806) (xy 341.446741 -288.48221) (xy 341.479376 -288.445373)
			(xy 341.517497 -288.414248) (xy 341.560118 -288.389641) (xy 341.606134 -288.372189) (xy 341.654353 -288.362345)
			(xy 341.703528 -288.360364) (xy 341.752383 -288.366296) (xy 341.799654 -288.379988) (xy 341.844116 -288.401086)
			(xy 341.884619 -288.429042) (xy 341.920112 -288.463134) (xy 341.949677 -288.502478) (xy 341.972548 -288.546055)
			(xy 341.988132 -288.592736) (xy 341.996027 -288.641313) (xy 341.996522 -288.66592) (xy 342.314779 -288.66592)
			(xy 342.318874 -288.615192) (xy 342.331053 -288.565778) (xy 342.351001 -288.518958) (xy 342.378202 -288.475944)
			(xy 342.41195 -288.43785) (xy 342.451372 -288.405663) (xy 342.495446 -288.380217) (xy 342.543032 -288.36217)
			(xy 342.592896 -288.35199) (xy 342.643748 -288.349941) (xy 342.694269 -288.356075) (xy 342.743153 -288.370235)
			(xy 342.789132 -288.392052) (xy 342.831016 -288.420962) (xy 342.86772 -288.456217) (xy 342.898293 -288.496903)
			(xy 342.921944 -288.541966) (xy 342.93806 -288.59024) (xy 342.946224 -288.640474) (xy 342.946736 -288.66592)
			(xy 343.254833 -288.66592) (xy 343.258928 -288.615192) (xy 343.271107 -288.565778) (xy 343.291055 -288.518958)
			(xy 343.318256 -288.475944) (xy 343.352004 -288.43785) (xy 343.391426 -288.405663) (xy 343.4355 -288.380217)
			(xy 343.483086 -288.36217) (xy 343.53295 -288.35199) (xy 343.583802 -288.349941) (xy 343.634323 -288.356075)
			(xy 343.683207 -288.370235) (xy 343.729186 -288.392052) (xy 343.77107 -288.420962) (xy 343.807774 -288.456217)
			(xy 343.838347 -288.496903) (xy 343.861998 -288.541966) (xy 343.878114 -288.59024) (xy 343.886278 -288.640474)
			(xy 343.88679 -288.66592) (xy 343.886278 -288.691366) (xy 343.878114 -288.7416) (xy 343.861998 -288.789874)
			(xy 343.838347 -288.834937) (xy 343.807774 -288.875623) (xy 343.77107 -288.910878) (xy 343.729186 -288.939788)
			(xy 343.683207 -288.961605) (xy 343.634323 -288.975765) (xy 343.583802 -288.981899) (xy 343.53295 -288.97985)
			(xy 343.483086 -288.96967) (xy 343.4355 -288.951623) (xy 343.391426 -288.926177) (xy 343.352004 -288.89399)
			(xy 343.318256 -288.855896) (xy 343.291055 -288.812882) (xy 343.271107 -288.766062) (xy 343.258928 -288.716648)
			(xy 343.254833 -288.66592) (xy 342.946736 -288.66592) (xy 342.946224 -288.691366) (xy 342.93806 -288.7416)
			(xy 342.921944 -288.789874) (xy 342.898293 -288.834937) (xy 342.86772 -288.875623) (xy 342.831016 -288.910878)
			(xy 342.789132 -288.939788) (xy 342.743153 -288.961605) (xy 342.694269 -288.975765) (xy 342.643748 -288.981899)
			(xy 342.592896 -288.97985) (xy 342.543032 -288.96967) (xy 342.495446 -288.951623) (xy 342.451372 -288.926177)
			(xy 342.41195 -288.89399) (xy 342.378202 -288.855896) (xy 342.351001 -288.812882) (xy 342.331053 -288.766062)
			(xy 342.318874 -288.716648) (xy 342.314779 -288.66592) (xy 341.996522 -288.66592) (xy 341.996027 -288.690527)
			(xy 341.988132 -288.739104) (xy 341.972548 -288.785785) (xy 341.949677 -288.829362) (xy 341.920112 -288.868706)
			(xy 341.884619 -288.902798) (xy 341.844116 -288.930754) (xy 341.799654 -288.951852) (xy 341.752383 -288.965544)
			(xy 341.703528 -288.971476) (xy 341.654353 -288.969495) (xy 341.606134 -288.959651) (xy 341.560118 -288.942199)
			(xy 341.517497 -288.917592) (xy 341.479376 -288.886467) (xy 341.446741 -288.84963) (xy 341.420438 -288.808034)
			(xy 341.401147 -288.762758) (xy 341.38937 -288.714974) (xy 341.38541 -288.66592) (xy 341.066882 -288.66592)
			(xy 341.06637 -288.691366) (xy 341.058206 -288.7416) (xy 341.04209 -288.789874) (xy 341.018439 -288.834937)
			(xy 340.987866 -288.875623) (xy 340.951162 -288.910878) (xy 340.909278 -288.939788) (xy 340.863299 -288.961605)
			(xy 340.814415 -288.975765) (xy 340.763894 -288.981899) (xy 340.713042 -288.97985) (xy 340.663178 -288.96967)
			(xy 340.615592 -288.951623) (xy 340.571518 -288.926177) (xy 340.532096 -288.89399) (xy 340.498348 -288.855896)
			(xy 340.471147 -288.812882) (xy 340.451199 -288.766062) (xy 340.43902 -288.716648) (xy 340.434925 -288.66592)
			(xy 340.308438 -288.66592) (xy 340.308438 -288.901378) (xy 340.308645 -288.90796) (xy 340.311984 -288.920693)
			(xy 340.315042 -288.926524) (xy 340.323245 -288.941238) (xy 340.338868 -288.971088) (xy 340.346284 -288.986214)
			(xy 340.368995 -289.034302) (xy 340.406272 -289.133911) (xy 340.420706 -289.185096) (xy 340.425532 -289.19551)
			(xy 340.447262 -289.207244) (xy 340.487102 -289.23642) (xy 340.521915 -289.271442) (xy 340.550851 -289.311457)
			(xy 340.573205 -289.355489) (xy 340.588433 -289.402463) (xy 340.596163 -289.451236) (xy 340.596728 -289.475926)
			(xy 340.915256 -289.475926) (xy 340.919216 -289.426872) (xy 340.930993 -289.379088) (xy 340.950284 -289.333812)
			(xy 340.976587 -289.292216) (xy 341.009222 -289.255379) (xy 341.047343 -289.224254) (xy 341.089964 -289.199647)
			(xy 341.13598 -289.182195) (xy 341.184199 -289.172351) (xy 341.233374 -289.17037) (xy 341.282229 -289.176302)
			(xy 341.3295 -289.189994) (xy 341.373962 -289.211092) (xy 341.414465 -289.239048) (xy 341.449958 -289.27314)
			(xy 341.479523 -289.312484) (xy 341.502394 -289.356061) (xy 341.517978 -289.402742) (xy 341.525873 -289.451319)
			(xy 341.526368 -289.475926) (xy 341.844879 -289.475926) (xy 341.848974 -289.425198) (xy 341.861153 -289.375784)
			(xy 341.881101 -289.328964) (xy 341.908302 -289.28595) (xy 341.94205 -289.247856) (xy 341.981472 -289.215669)
			(xy 342.025546 -289.190223) (xy 342.073132 -289.172176) (xy 342.122996 -289.161996) (xy 342.173848 -289.159947)
			(xy 342.224369 -289.166081) (xy 342.273253 -289.180241) (xy 342.319232 -289.202058) (xy 342.361116 -289.230968)
			(xy 342.39782 -289.266223) (xy 342.428393 -289.306909) (xy 342.452044 -289.351972) (xy 342.46816 -289.400246)
			(xy 342.476324 -289.45048) (xy 342.476836 -289.475926) (xy 342.795364 -289.475926) (xy 342.799324 -289.426872)
			(xy 342.811101 -289.379088) (xy 342.830392 -289.333812) (xy 342.856695 -289.292216) (xy 342.88933 -289.255379)
			(xy 342.927451 -289.224254) (xy 342.970072 -289.199647) (xy 343.016088 -289.182195) (xy 343.064307 -289.172351)
			(xy 343.113482 -289.17037) (xy 343.162337 -289.176302) (xy 343.209608 -289.189994) (xy 343.25407 -289.211092)
			(xy 343.294573 -289.239048) (xy 343.330066 -289.27314) (xy 343.359631 -289.312484) (xy 343.382502 -289.356061)
			(xy 343.398086 -289.402742) (xy 343.405981 -289.451319) (xy 343.406476 -289.475926) (xy 343.405981 -289.500533)
			(xy 343.398086 -289.54911) (xy 343.382502 -289.595791) (xy 343.359631 -289.639368) (xy 343.330066 -289.678712)
			(xy 343.294573 -289.712804) (xy 343.25407 -289.74076) (xy 343.209608 -289.761858) (xy 343.162337 -289.77555)
			(xy 343.113482 -289.781482) (xy 343.064307 -289.779501) (xy 343.016088 -289.769657) (xy 342.970072 -289.752205)
			(xy 342.927451 -289.727598) (xy 342.88933 -289.696473) (xy 342.856695 -289.659636) (xy 342.830392 -289.61804)
			(xy 342.811101 -289.572764) (xy 342.799324 -289.52498) (xy 342.795364 -289.475926) (xy 342.476836 -289.475926)
			(xy 342.476324 -289.501372) (xy 342.46816 -289.551606) (xy 342.452044 -289.59988) (xy 342.428393 -289.644943)
			(xy 342.39782 -289.685629) (xy 342.361116 -289.720884) (xy 342.319232 -289.749794) (xy 342.273253 -289.771611)
			(xy 342.224369 -289.785771) (xy 342.173848 -289.791905) (xy 342.122996 -289.789856) (xy 342.073132 -289.779676)
			(xy 342.025546 -289.761629) (xy 341.981472 -289.736183) (xy 341.94205 -289.703996) (xy 341.908302 -289.665902)
			(xy 341.881101 -289.622888) (xy 341.861153 -289.576068) (xy 341.848974 -289.526654) (xy 341.844879 -289.475926)
			(xy 341.526368 -289.475926) (xy 341.525873 -289.500533) (xy 341.517978 -289.54911) (xy 341.502394 -289.595791)
			(xy 341.479523 -289.639368) (xy 341.449958 -289.678712) (xy 341.414465 -289.712804) (xy 341.373962 -289.74076)
			(xy 341.3295 -289.761858) (xy 341.282229 -289.77555) (xy 341.233374 -289.781482) (xy 341.184199 -289.779501)
			(xy 341.13598 -289.769657) (xy 341.089964 -289.752205) (xy 341.047343 -289.727598) (xy 341.009222 -289.696473)
			(xy 340.976587 -289.659636) (xy 340.950284 -289.61804) (xy 340.930993 -289.572764) (xy 340.919216 -289.52498)
			(xy 340.915256 -289.475926) (xy 340.596728 -289.475926) (xy 340.596232 -289.50062) (xy 340.588504 -289.549401)
			(xy 340.573273 -289.596383) (xy 340.550909 -289.640419) (xy 340.521959 -289.680435) (xy 340.48713 -289.715452)
			(xy 340.447271 -289.744617) (xy 340.425532 -289.756342) (xy 340.420706 -289.766756) (xy 340.406299 -289.81795)
			(xy 340.369026 -289.917563) (xy 340.346284 -289.965638) (xy 340.338868 -289.980764) (xy 340.323244 -290.010614)
			(xy 340.315042 -290.025328) (xy 340.31174 -290.03117) (xy 340.308438 -290.043616) (xy 340.308438 -290.285932)
			(xy 340.434925 -290.285932) (xy 340.43902 -290.235204) (xy 340.451199 -290.18579) (xy 340.471147 -290.13897)
			(xy 340.498348 -290.095956) (xy 340.532096 -290.057862) (xy 340.571518 -290.025675) (xy 340.615592 -290.000229)
			(xy 340.663178 -289.982182) (xy 340.713042 -289.972002) (xy 340.763894 -289.969953) (xy 340.814415 -289.976087)
			(xy 340.863299 -289.990247) (xy 340.909278 -290.012064) (xy 340.951162 -290.040974) (xy 340.987866 -290.076229)
			(xy 341.018439 -290.116915) (xy 341.04209 -290.161978) (xy 341.058206 -290.210252) (xy 341.06637 -290.260486)
			(xy 341.066882 -290.285932) (xy 341.38541 -290.285932) (xy 341.38937 -290.236878) (xy 341.401147 -290.189094)
			(xy 341.420438 -290.143818) (xy 341.446741 -290.102222) (xy 341.479376 -290.065385) (xy 341.517497 -290.03426)
			(xy 341.560118 -290.009653) (xy 341.606134 -289.992201) (xy 341.654353 -289.982357) (xy 341.703528 -289.980376)
			(xy 341.752383 -289.986308) (xy 341.799654 -290) (xy 341.844116 -290.021098) (xy 341.884619 -290.049054)
			(xy 341.920112 -290.083146) (xy 341.949677 -290.12249) (xy 341.972548 -290.166067) (xy 341.988132 -290.212748)
			(xy 341.996027 -290.261325) (xy 341.996522 -290.285932) (xy 342.314779 -290.285932) (xy 342.318874 -290.235204)
			(xy 342.331053 -290.18579) (xy 342.351001 -290.13897) (xy 342.378202 -290.095956) (xy 342.41195 -290.057862)
			(xy 342.451372 -290.025675) (xy 342.495446 -290.000229) (xy 342.543032 -289.982182) (xy 342.592896 -289.972002)
			(xy 342.643748 -289.969953) (xy 342.694269 -289.976087) (xy 342.743153 -289.990247) (xy 342.789132 -290.012064)
			(xy 342.831016 -290.040974) (xy 342.86772 -290.076229) (xy 342.898293 -290.116915) (xy 342.921944 -290.161978)
			(xy 342.93806 -290.210252) (xy 342.946224 -290.260486) (xy 342.946736 -290.285932) (xy 343.254833 -290.285932)
			(xy 343.258928 -290.235204) (xy 343.271107 -290.18579) (xy 343.291055 -290.13897) (xy 343.318256 -290.095956)
			(xy 343.352004 -290.057862) (xy 343.391426 -290.025675) (xy 343.4355 -290.000229) (xy 343.483086 -289.982182)
			(xy 343.53295 -289.972002) (xy 343.583802 -289.969953) (xy 343.634323 -289.976087) (xy 343.683207 -289.990247)
			(xy 343.729186 -290.012064) (xy 343.77107 -290.040974) (xy 343.807774 -290.076229) (xy 343.838347 -290.116915)
			(xy 343.861998 -290.161978) (xy 343.878114 -290.210252) (xy 343.886278 -290.260486) (xy 343.88679 -290.285932)
			(xy 343.886278 -290.311378) (xy 343.878114 -290.361612) (xy 343.861998 -290.409886) (xy 343.838347 -290.454949)
			(xy 343.807774 -290.495635) (xy 343.77107 -290.53089) (xy 343.729186 -290.5598) (xy 343.683207 -290.581617)
			(xy 343.634323 -290.595777) (xy 343.583802 -290.601911) (xy 343.53295 -290.599862) (xy 343.483086 -290.589682)
			(xy 343.4355 -290.571635) (xy 343.391426 -290.546189) (xy 343.352004 -290.514002) (xy 343.318256 -290.475908)
			(xy 343.291055 -290.432894) (xy 343.271107 -290.386074) (xy 343.258928 -290.33666) (xy 343.254833 -290.285932)
			(xy 342.946736 -290.285932) (xy 342.946224 -290.311378) (xy 342.93806 -290.361612) (xy 342.921944 -290.409886)
			(xy 342.898293 -290.454949) (xy 342.86772 -290.495635) (xy 342.831016 -290.53089) (xy 342.789132 -290.5598)
			(xy 342.743153 -290.581617) (xy 342.694269 -290.595777) (xy 342.643748 -290.601911) (xy 342.592896 -290.599862)
			(xy 342.543032 -290.589682) (xy 342.495446 -290.571635) (xy 342.451372 -290.546189) (xy 342.41195 -290.514002)
			(xy 342.378202 -290.475908) (xy 342.351001 -290.432894) (xy 342.331053 -290.386074) (xy 342.318874 -290.33666)
			(xy 342.314779 -290.285932) (xy 341.996522 -290.285932) (xy 341.996027 -290.310539) (xy 341.988132 -290.359116)
			(xy 341.972548 -290.405797) (xy 341.949677 -290.449374) (xy 341.920112 -290.488718) (xy 341.884619 -290.52281)
			(xy 341.844116 -290.550766) (xy 341.799654 -290.571864) (xy 341.752383 -290.585556) (xy 341.703528 -290.591488)
			(xy 341.654353 -290.589507) (xy 341.606134 -290.579663) (xy 341.560118 -290.562211) (xy 341.517497 -290.537604)
			(xy 341.479376 -290.506479) (xy 341.446741 -290.469642) (xy 341.420438 -290.428046) (xy 341.401147 -290.38277)
			(xy 341.38937 -290.334986) (xy 341.38541 -290.285932) (xy 341.066882 -290.285932) (xy 341.06637 -290.311378)
			(xy 341.058206 -290.361612) (xy 341.04209 -290.409886) (xy 341.018439 -290.454949) (xy 340.987866 -290.495635)
			(xy 340.951162 -290.53089) (xy 340.909278 -290.5598) (xy 340.863299 -290.581617) (xy 340.814415 -290.595777)
			(xy 340.763894 -290.601911) (xy 340.713042 -290.599862) (xy 340.663178 -290.589682) (xy 340.615592 -290.571635)
			(xy 340.571518 -290.546189) (xy 340.532096 -290.514002) (xy 340.498348 -290.475908) (xy 340.471147 -290.432894)
			(xy 340.451199 -290.386074) (xy 340.43902 -290.33666) (xy 340.434925 -290.285932) (xy 340.308438 -290.285932)
			(xy 340.308438 -290.516056) (xy 340.311994 -290.52901) (xy 340.315296 -290.534852) (xy 340.338925 -290.576471)
			(xy 340.37979 -290.663022) (xy 340.413076 -290.75276) (xy 340.426294 -290.798758) (xy 340.429148 -290.807744)
			(xy 340.44037 -290.822879) (xy 340.448138 -290.828222) (xy 340.470466 -290.842795) (xy 340.510327 -290.878201)
			(xy 340.543667 -290.919804) (xy 340.569539 -290.966421) (xy 340.587204 -291.016724) (xy 340.596161 -291.069281)
			(xy 340.596728 -291.095938) (xy 340.915256 -291.095938) (xy 340.919216 -291.046884) (xy 340.930993 -290.9991)
			(xy 340.950284 -290.953824) (xy 340.976587 -290.912228) (xy 341.009222 -290.875391) (xy 341.047343 -290.844266)
			(xy 341.089964 -290.819659) (xy 341.13598 -290.802207) (xy 341.184199 -290.792363) (xy 341.233374 -290.790382)
			(xy 341.282229 -290.796314) (xy 341.3295 -290.810006) (xy 341.373962 -290.831104) (xy 341.414465 -290.85906)
			(xy 341.449958 -290.893152) (xy 341.479523 -290.932496) (xy 341.502394 -290.976073) (xy 341.517978 -291.022754)
			(xy 341.525873 -291.071331) (xy 341.526368 -291.095938) (xy 341.844879 -291.095938) (xy 341.848974 -291.04521)
			(xy 341.861153 -290.995796) (xy 341.881101 -290.948976) (xy 341.908302 -290.905962) (xy 341.94205 -290.867868)
			(xy 341.981472 -290.835681) (xy 342.025546 -290.810235) (xy 342.073132 -290.792188) (xy 342.122996 -290.782008)
			(xy 342.173848 -290.779959) (xy 342.224369 -290.786093) (xy 342.273253 -290.800253) (xy 342.319232 -290.82207)
			(xy 342.361116 -290.85098) (xy 342.39782 -290.886235) (xy 342.428393 -290.926921) (xy 342.452044 -290.971984)
			(xy 342.46816 -291.020258) (xy 342.476324 -291.070492) (xy 342.476836 -291.095938) (xy 342.795364 -291.095938)
			(xy 342.799324 -291.046884) (xy 342.811101 -290.9991) (xy 342.830392 -290.953824) (xy 342.856695 -290.912228)
			(xy 342.88933 -290.875391) (xy 342.927451 -290.844266) (xy 342.970072 -290.819659) (xy 343.016088 -290.802207)
			(xy 343.064307 -290.792363) (xy 343.113482 -290.790382) (xy 343.162337 -290.796314) (xy 343.209608 -290.810006)
			(xy 343.25407 -290.831104) (xy 343.294573 -290.85906) (xy 343.330066 -290.893152) (xy 343.359631 -290.932496)
			(xy 343.382502 -290.976073) (xy 343.398086 -291.022754) (xy 343.405981 -291.071331) (xy 343.406476 -291.095938)
			(xy 343.405981 -291.120545) (xy 343.398086 -291.169122) (xy 343.382502 -291.215803) (xy 343.359631 -291.25938)
			(xy 343.330066 -291.298724) (xy 343.294573 -291.332816) (xy 343.25407 -291.360772) (xy 343.209608 -291.38187)
			(xy 343.162337 -291.395562) (xy 343.113482 -291.401494) (xy 343.064307 -291.399513) (xy 343.016088 -291.389669)
			(xy 342.970072 -291.372217) (xy 342.927451 -291.34761) (xy 342.88933 -291.316485) (xy 342.856695 -291.279648)
			(xy 342.830392 -291.238052) (xy 342.811101 -291.192776) (xy 342.799324 -291.144992) (xy 342.795364 -291.095938)
			(xy 342.476836 -291.095938) (xy 342.476324 -291.121384) (xy 342.46816 -291.171618) (xy 342.452044 -291.219892)
			(xy 342.428393 -291.264955) (xy 342.39782 -291.305641) (xy 342.361116 -291.340896) (xy 342.319232 -291.369806)
			(xy 342.273253 -291.391623) (xy 342.224369 -291.405783) (xy 342.173848 -291.411917) (xy 342.122996 -291.409868)
			(xy 342.073132 -291.399688) (xy 342.025546 -291.381641) (xy 341.981472 -291.356195) (xy 341.94205 -291.324008)
			(xy 341.908302 -291.285914) (xy 341.881101 -291.2429) (xy 341.861153 -291.19608) (xy 341.848974 -291.146666)
			(xy 341.844879 -291.095938) (xy 341.526368 -291.095938) (xy 341.525873 -291.120545) (xy 341.517978 -291.169122)
			(xy 341.502394 -291.215803) (xy 341.479523 -291.25938) (xy 341.449958 -291.298724) (xy 341.414465 -291.332816)
			(xy 341.373962 -291.360772) (xy 341.3295 -291.38187) (xy 341.282229 -291.395562) (xy 341.233374 -291.401494)
			(xy 341.184199 -291.399513) (xy 341.13598 -291.389669) (xy 341.089964 -291.372217) (xy 341.047343 -291.34761)
			(xy 341.009222 -291.316485) (xy 340.976587 -291.279648) (xy 340.950284 -291.238052) (xy 340.930993 -291.192776)
			(xy 340.919216 -291.144992) (xy 340.915256 -291.095938) (xy 340.596728 -291.095938) (xy 340.596163 -291.122672)
			(xy 340.587148 -291.175376) (xy 340.569381 -291.225806) (xy 340.543371 -291.272522) (xy 340.509862 -291.314188)
			(xy 340.469811 -291.349612) (xy 340.447376 -291.364162) (xy 340.439458 -291.369434) (xy 340.427979 -291.384583)
			(xy 340.425024 -291.393626) (xy 340.411869 -291.438941) (xy 340.378909 -291.527365) (xy 340.338574 -291.612677)
			(xy 340.315296 -291.653722) (xy 340.311994 -291.659564) (xy 340.308438 -291.672518) (xy 340.308438 -291.905944)
			(xy 340.434925 -291.905944) (xy 340.43902 -291.855216) (xy 340.451199 -291.805802) (xy 340.471147 -291.758982)
			(xy 340.498348 -291.715968) (xy 340.532096 -291.677874) (xy 340.571518 -291.645687) (xy 340.615592 -291.620241)
			(xy 340.663178 -291.602194) (xy 340.713042 -291.592014) (xy 340.763894 -291.589965) (xy 340.814415 -291.596099)
			(xy 340.863299 -291.610259) (xy 340.909278 -291.632076) (xy 340.951162 -291.660986) (xy 340.987866 -291.696241)
			(xy 341.018439 -291.736927) (xy 341.04209 -291.78199) (xy 341.058206 -291.830264) (xy 341.06637 -291.880498)
			(xy 341.066882 -291.905944) (xy 341.38541 -291.905944) (xy 341.38937 -291.85689) (xy 341.401147 -291.809106)
			(xy 341.420438 -291.76383) (xy 341.446741 -291.722234) (xy 341.479376 -291.685397) (xy 341.517497 -291.654272)
			(xy 341.560118 -291.629665) (xy 341.606134 -291.612213) (xy 341.654353 -291.602369) (xy 341.703528 -291.600388)
			(xy 341.752383 -291.60632) (xy 341.799654 -291.620012) (xy 341.844116 -291.64111) (xy 341.884619 -291.669066)
			(xy 341.920112 -291.703158) (xy 341.949677 -291.742502) (xy 341.972548 -291.786079) (xy 341.988132 -291.83276)
			(xy 341.996027 -291.881337) (xy 341.996522 -291.905944) (xy 342.314779 -291.905944) (xy 342.318874 -291.855216)
			(xy 342.331053 -291.805802) (xy 342.351001 -291.758982) (xy 342.378202 -291.715968) (xy 342.41195 -291.677874)
			(xy 342.451372 -291.645687) (xy 342.495446 -291.620241) (xy 342.543032 -291.602194) (xy 342.592896 -291.592014)
			(xy 342.643748 -291.589965) (xy 342.694269 -291.596099) (xy 342.743153 -291.610259) (xy 342.789132 -291.632076)
			(xy 342.831016 -291.660986) (xy 342.86772 -291.696241) (xy 342.898293 -291.736927) (xy 342.921944 -291.78199)
			(xy 342.93806 -291.830264) (xy 342.946224 -291.880498) (xy 342.946736 -291.905944) (xy 343.254833 -291.905944)
			(xy 343.258928 -291.855216) (xy 343.271107 -291.805802) (xy 343.291055 -291.758982) (xy 343.318256 -291.715968)
			(xy 343.352004 -291.677874) (xy 343.391426 -291.645687) (xy 343.4355 -291.620241) (xy 343.483086 -291.602194)
			(xy 343.53295 -291.592014) (xy 343.583802 -291.589965) (xy 343.634323 -291.596099) (xy 343.683207 -291.610259)
			(xy 343.729186 -291.632076) (xy 343.77107 -291.660986) (xy 343.807774 -291.696241) (xy 343.838347 -291.736927)
			(xy 343.861998 -291.78199) (xy 343.878114 -291.830264) (xy 343.886278 -291.880498) (xy 343.88679 -291.905944)
			(xy 343.886278 -291.93139) (xy 343.878114 -291.981624) (xy 343.861998 -292.029898) (xy 343.838347 -292.074961)
			(xy 343.807774 -292.115647) (xy 343.77107 -292.150902) (xy 343.729186 -292.179812) (xy 343.683207 -292.201629)
			(xy 343.634323 -292.215789) (xy 343.583802 -292.221923) (xy 343.53295 -292.219874) (xy 343.483086 -292.209694)
			(xy 343.4355 -292.191647) (xy 343.391426 -292.166201) (xy 343.352004 -292.134014) (xy 343.318256 -292.09592)
			(xy 343.291055 -292.052906) (xy 343.271107 -292.006086) (xy 343.258928 -291.956672) (xy 343.254833 -291.905944)
			(xy 342.946736 -291.905944) (xy 342.946224 -291.93139) (xy 342.93806 -291.981624) (xy 342.921944 -292.029898)
			(xy 342.898293 -292.074961) (xy 342.86772 -292.115647) (xy 342.831016 -292.150902) (xy 342.789132 -292.179812)
			(xy 342.743153 -292.201629) (xy 342.694269 -292.215789) (xy 342.643748 -292.221923) (xy 342.592896 -292.219874)
			(xy 342.543032 -292.209694) (xy 342.495446 -292.191647) (xy 342.451372 -292.166201) (xy 342.41195 -292.134014)
			(xy 342.378202 -292.09592) (xy 342.351001 -292.052906) (xy 342.331053 -292.006086) (xy 342.318874 -291.956672)
			(xy 342.314779 -291.905944) (xy 341.996522 -291.905944) (xy 341.996027 -291.930551) (xy 341.988132 -291.979128)
			(xy 341.972548 -292.025809) (xy 341.949677 -292.069386) (xy 341.920112 -292.10873) (xy 341.884619 -292.142822)
			(xy 341.844116 -292.170778) (xy 341.799654 -292.191876) (xy 341.752383 -292.205568) (xy 341.703528 -292.2115)
			(xy 341.654353 -292.209519) (xy 341.606134 -292.199675) (xy 341.560118 -292.182223) (xy 341.517497 -292.157616)
			(xy 341.479376 -292.126491) (xy 341.446741 -292.089654) (xy 341.420438 -292.048058) (xy 341.401147 -292.002782)
			(xy 341.38937 -291.954998) (xy 341.38541 -291.905944) (xy 341.066882 -291.905944) (xy 341.06637 -291.93139)
			(xy 341.058206 -291.981624) (xy 341.04209 -292.029898) (xy 341.018439 -292.074961) (xy 340.987866 -292.115647)
			(xy 340.951162 -292.150902) (xy 340.909278 -292.179812) (xy 340.863299 -292.201629) (xy 340.814415 -292.215789)
			(xy 340.763894 -292.221923) (xy 340.713042 -292.219874) (xy 340.663178 -292.209694) (xy 340.615592 -292.191647)
			(xy 340.571518 -292.166201) (xy 340.532096 -292.134014) (xy 340.498348 -292.09592) (xy 340.471147 -292.052906)
			(xy 340.451199 -292.006086) (xy 340.43902 -291.956672) (xy 340.434925 -291.905944) (xy 340.308438 -291.905944)
			(xy 340.308438 -292.13302) (xy 340.311994 -292.146228) (xy 340.31555 -292.15207) (xy 340.339857 -292.194375)
			(xy 340.381813 -292.282469) (xy 340.415876 -292.373906) (xy 340.429342 -292.420802) (xy 340.430609 -292.425077)
			(xy 340.434441 -292.433127) (xy 340.436962 -292.436804) (xy 340.44255 -292.444932) (xy 340.465624 -292.459334)
			(xy 340.506895 -292.494757) (xy 340.541489 -292.536725) (xy 340.568382 -292.583998) (xy 340.58678 -292.63518)
			(xy 340.596139 -292.688756) (xy 340.596728 -292.71595) (xy 340.915256 -292.71595) (xy 340.919216 -292.666896)
			(xy 340.930993 -292.619112) (xy 340.950284 -292.573836) (xy 340.976587 -292.53224) (xy 341.009222 -292.495403)
			(xy 341.047343 -292.464278) (xy 341.089964 -292.439671) (xy 341.13598 -292.422219) (xy 341.184199 -292.412375)
			(xy 341.233374 -292.410394) (xy 341.282229 -292.416326) (xy 341.3295 -292.430018) (xy 341.373962 -292.451116)
			(xy 341.414465 -292.479072) (xy 341.449958 -292.513164) (xy 341.479523 -292.552508) (xy 341.502394 -292.596085)
			(xy 341.517978 -292.642766) (xy 341.525873 -292.691343) (xy 341.526368 -292.71595) (xy 341.844879 -292.71595)
			(xy 341.848974 -292.665222) (xy 341.861153 -292.615808) (xy 341.881101 -292.568988) (xy 341.908302 -292.525974)
			(xy 341.94205 -292.48788) (xy 341.981472 -292.455693) (xy 342.025546 -292.430247) (xy 342.073132 -292.4122)
			(xy 342.122996 -292.40202) (xy 342.173848 -292.399971) (xy 342.224369 -292.406105) (xy 342.273253 -292.420265)
			(xy 342.319232 -292.442082) (xy 342.361116 -292.470992) (xy 342.39782 -292.506247) (xy 342.428393 -292.546933)
			(xy 342.452044 -292.591996) (xy 342.46816 -292.64027) (xy 342.476324 -292.690504) (xy 342.476836 -292.71595)
			(xy 342.795364 -292.71595) (xy 342.799324 -292.666896) (xy 342.811101 -292.619112) (xy 342.830392 -292.573836)
			(xy 342.856695 -292.53224) (xy 342.88933 -292.495403) (xy 342.927451 -292.464278) (xy 342.970072 -292.439671)
			(xy 343.016088 -292.422219) (xy 343.064307 -292.412375) (xy 343.113482 -292.410394) (xy 343.162337 -292.416326)
			(xy 343.209608 -292.430018) (xy 343.25407 -292.451116) (xy 343.294573 -292.479072) (xy 343.330066 -292.513164)
			(xy 343.359631 -292.552508) (xy 343.382502 -292.596085) (xy 343.398086 -292.642766) (xy 343.405981 -292.691343)
			(xy 343.406476 -292.71595) (xy 343.405981 -292.740557) (xy 343.398086 -292.789134) (xy 343.382502 -292.835815)
			(xy 343.359631 -292.879392) (xy 343.330066 -292.918736) (xy 343.294573 -292.952828) (xy 343.25407 -292.980784)
			(xy 343.209608 -293.001882) (xy 343.162337 -293.015574) (xy 343.113482 -293.021506) (xy 343.064307 -293.019525)
			(xy 343.016088 -293.009681) (xy 342.970072 -292.992229) (xy 342.927451 -292.967622) (xy 342.88933 -292.936497)
			(xy 342.856695 -292.89966) (xy 342.830392 -292.858064) (xy 342.811101 -292.812788) (xy 342.799324 -292.765004)
			(xy 342.795364 -292.71595) (xy 342.476836 -292.71595) (xy 342.476324 -292.741396) (xy 342.46816 -292.79163)
			(xy 342.452044 -292.839904) (xy 342.428393 -292.884967) (xy 342.39782 -292.925653) (xy 342.361116 -292.960908)
			(xy 342.319232 -292.989818) (xy 342.273253 -293.011635) (xy 342.224369 -293.025795) (xy 342.173848 -293.031929)
			(xy 342.122996 -293.02988) (xy 342.073132 -293.0197) (xy 342.025546 -293.001653) (xy 341.981472 -292.976207)
			(xy 341.94205 -292.94402) (xy 341.908302 -292.905926) (xy 341.881101 -292.862912) (xy 341.861153 -292.816092)
			(xy 341.848974 -292.766678) (xy 341.844879 -292.71595) (xy 341.526368 -292.71595) (xy 341.525873 -292.740557)
			(xy 341.517978 -292.789134) (xy 341.502394 -292.835815) (xy 341.479523 -292.879392) (xy 341.449958 -292.918736)
			(xy 341.414465 -292.952828) (xy 341.373962 -292.980784) (xy 341.3295 -293.001882) (xy 341.282229 -293.015574)
			(xy 341.233374 -293.021506) (xy 341.184199 -293.019525) (xy 341.13598 -293.009681) (xy 341.089964 -292.992229)
			(xy 341.047343 -292.967622) (xy 341.009222 -292.936497) (xy 340.976587 -292.89966) (xy 340.950284 -292.858064)
			(xy 340.930993 -292.812788) (xy 340.919216 -292.765004) (xy 340.915256 -292.71595) (xy 340.596728 -292.71595)
			(xy 340.596292 -292.739832) (xy 340.589098 -292.787051) (xy 340.574867 -292.832645) (xy 340.553925 -292.875573)
			(xy 340.526749 -292.914853) (xy 340.493962 -292.949586) (xy 340.456314 -292.978979) (xy 340.435692 -292.991032)
			(xy 340.431882 -292.999922) (xy 340.419784 -293.043526) (xy 340.389441 -293.128786) (xy 340.352267 -293.211298)
			(xy 340.33079 -293.251128) (xy 340.31555 -293.278306) (xy 340.311994 -293.284148) (xy 340.308438 -293.297102)
			(xy 340.308438 -293.525956) (xy 340.445356 -293.525956) (xy 340.449316 -293.476902) (xy 340.461093 -293.429118)
			(xy 340.480384 -293.383842) (xy 340.506687 -293.342246) (xy 340.539322 -293.305409) (xy 340.577443 -293.274284)
			(xy 340.620064 -293.249677) (xy 340.66608 -293.232225) (xy 340.714299 -293.222381) (xy 340.763474 -293.2204)
			(xy 340.812329 -293.226332) (xy 340.8596 -293.240024) (xy 340.904062 -293.261122) (xy 340.944565 -293.289078)
			(xy 340.980058 -293.32317) (xy 341.009623 -293.362514) (xy 341.032494 -293.406091) (xy 341.048078 -293.452772)
			(xy 341.055973 -293.501349) (xy 341.056468 -293.525956) (xy 341.38541 -293.525956) (xy 341.38937 -293.476902)
			(xy 341.401147 -293.429118) (xy 341.420438 -293.383842) (xy 341.446741 -293.342246) (xy 341.479376 -293.305409)
			(xy 341.517497 -293.274284) (xy 341.560118 -293.249677) (xy 341.606134 -293.232225) (xy 341.654353 -293.222381)
			(xy 341.703528 -293.2204) (xy 341.752383 -293.226332) (xy 341.799654 -293.240024) (xy 341.844116 -293.261122)
			(xy 341.884619 -293.289078) (xy 341.920112 -293.32317) (xy 341.949677 -293.362514) (xy 341.972548 -293.406091)
			(xy 341.988132 -293.452772) (xy 341.996027 -293.501349) (xy 341.996522 -293.525956) (xy 342.32521 -293.525956)
			(xy 342.32917 -293.476902) (xy 342.340947 -293.429118) (xy 342.360238 -293.383842) (xy 342.386541 -293.342246)
			(xy 342.419176 -293.305409) (xy 342.457297 -293.274284) (xy 342.499918 -293.249677) (xy 342.545934 -293.232225)
			(xy 342.594153 -293.222381) (xy 342.643328 -293.2204) (xy 342.692183 -293.226332) (xy 342.739454 -293.240024)
			(xy 342.783916 -293.261122) (xy 342.824419 -293.289078) (xy 342.859912 -293.32317) (xy 342.889477 -293.362514)
			(xy 342.912348 -293.406091) (xy 342.927932 -293.452772) (xy 342.935827 -293.501349) (xy 342.936322 -293.525956)
			(xy 343.254833 -293.525956) (xy 343.258928 -293.475228) (xy 343.271107 -293.425814) (xy 343.291055 -293.378994)
			(xy 343.318256 -293.33598) (xy 343.352004 -293.297886) (xy 343.391426 -293.265699) (xy 343.4355 -293.240253)
			(xy 343.483086 -293.222206) (xy 343.53295 -293.212026) (xy 343.583802 -293.209977) (xy 343.634323 -293.216111)
			(xy 343.683207 -293.230271) (xy 343.729186 -293.252088) (xy 343.77107 -293.280998) (xy 343.807774 -293.316253)
			(xy 343.838347 -293.356939) (xy 343.861998 -293.402002) (xy 343.878114 -293.450276) (xy 343.886278 -293.50051)
			(xy 343.88679 -293.525956) (xy 343.886278 -293.551402) (xy 343.878114 -293.601636) (xy 343.861998 -293.64991)
			(xy 343.838347 -293.694973) (xy 343.807774 -293.735659) (xy 343.77107 -293.770914) (xy 343.729186 -293.799824)
			(xy 343.683207 -293.821641) (xy 343.634323 -293.835801) (xy 343.583802 -293.841935) (xy 343.53295 -293.839886)
			(xy 343.483086 -293.829706) (xy 343.4355 -293.811659) (xy 343.391426 -293.786213) (xy 343.352004 -293.754026)
			(xy 343.318256 -293.715932) (xy 343.291055 -293.672918) (xy 343.271107 -293.626098) (xy 343.258928 -293.576684)
			(xy 343.254833 -293.525956) (xy 342.936322 -293.525956) (xy 342.935827 -293.550563) (xy 342.927932 -293.59914)
			(xy 342.912348 -293.645821) (xy 342.889477 -293.689398) (xy 342.859912 -293.728742) (xy 342.824419 -293.762834)
			(xy 342.783916 -293.79079) (xy 342.739454 -293.811888) (xy 342.692183 -293.82558) (xy 342.643328 -293.831512)
			(xy 342.594153 -293.829531) (xy 342.545934 -293.819687) (xy 342.499918 -293.802235) (xy 342.457297 -293.777628)
			(xy 342.419176 -293.746503) (xy 342.386541 -293.709666) (xy 342.360238 -293.66807) (xy 342.340947 -293.622794)
			(xy 342.32917 -293.57501) (xy 342.32521 -293.525956) (xy 341.996522 -293.525956) (xy 341.996027 -293.550563)
			(xy 341.988132 -293.59914) (xy 341.972548 -293.645821) (xy 341.949677 -293.689398) (xy 341.920112 -293.728742)
			(xy 341.884619 -293.762834) (xy 341.844116 -293.79079) (xy 341.799654 -293.811888) (xy 341.752383 -293.82558)
			(xy 341.703528 -293.831512) (xy 341.654353 -293.829531) (xy 341.606134 -293.819687) (xy 341.560118 -293.802235)
			(xy 341.517497 -293.777628) (xy 341.479376 -293.746503) (xy 341.446741 -293.709666) (xy 341.420438 -293.66807)
			(xy 341.401147 -293.622794) (xy 341.38937 -293.57501) (xy 341.38541 -293.525956) (xy 341.056468 -293.525956)
			(xy 341.055973 -293.550563) (xy 341.048078 -293.59914) (xy 341.032494 -293.645821) (xy 341.009623 -293.689398)
			(xy 340.980058 -293.728742) (xy 340.944565 -293.762834) (xy 340.904062 -293.79079) (xy 340.8596 -293.811888)
			(xy 340.812329 -293.82558) (xy 340.763474 -293.831512) (xy 340.714299 -293.829531) (xy 340.66608 -293.819687)
			(xy 340.620064 -293.802235) (xy 340.577443 -293.777628) (xy 340.539322 -293.746503) (xy 340.506687 -293.709666)
			(xy 340.480384 -293.66807) (xy 340.461093 -293.622794) (xy 340.449316 -293.57501) (xy 340.445356 -293.525956)
			(xy 340.308438 -293.525956) (xy 340.308438 -293.770558) (xy 340.308003 -293.780622) (xy 340.300266 -293.799205)
			(xy 340.293452 -293.806626) (xy 340.241382 -293.858696) (xy 340.234885 -293.865834) (xy 340.227299 -293.883564)
			(xy 340.226766 -293.902842) (xy 340.229698 -293.912036) (xy 340.256622 -293.98468) (xy 340.259347 -293.991391)
			(xy 340.267996 -294.003001) (xy 340.27364 -294.00754) (xy 340.304882 -294.031162) (xy 340.318344 -294.03294)
			(xy 340.342678 -294.036435) (xy 340.389872 -294.050185) (xy 340.434255 -294.071318) (xy 340.474678 -294.099289)
			(xy 340.510098 -294.133374) (xy 340.539601 -294.172693) (xy 340.562423 -294.216231) (xy 340.577975 -294.262863)
			(xy 340.585856 -294.311384) (xy 340.586314 -294.335962) (xy 340.915256 -294.335962) (xy 340.919216 -294.286908)
			(xy 340.930993 -294.239124) (xy 340.950284 -294.193848) (xy 340.976587 -294.152252) (xy 341.009222 -294.115415)
			(xy 341.047343 -294.08429) (xy 341.089964 -294.059683) (xy 341.13598 -294.042231) (xy 341.184199 -294.032387)
			(xy 341.233374 -294.030406) (xy 341.282229 -294.036338) (xy 341.3295 -294.05003) (xy 341.373962 -294.071128)
			(xy 341.414465 -294.099084) (xy 341.449958 -294.133176) (xy 341.479523 -294.17252) (xy 341.502394 -294.216097)
			(xy 341.517978 -294.262778) (xy 341.525873 -294.311355) (xy 341.526368 -294.335962) (xy 342.795364 -294.335962)
			(xy 342.799324 -294.286908) (xy 342.811101 -294.239124) (xy 342.830392 -294.193848) (xy 342.856695 -294.152252)
			(xy 342.88933 -294.115415) (xy 342.927451 -294.08429) (xy 342.970072 -294.059683) (xy 343.016088 -294.042231)
			(xy 343.064307 -294.032387) (xy 343.113482 -294.030406) (xy 343.162337 -294.036338) (xy 343.209608 -294.05003)
			(xy 343.25407 -294.071128) (xy 343.294573 -294.099084) (xy 343.330066 -294.133176) (xy 343.359631 -294.17252)
			(xy 343.382502 -294.216097) (xy 343.398086 -294.262778) (xy 343.405981 -294.311355) (xy 343.406476 -294.335962)
			(xy 343.405981 -294.360569) (xy 343.398086 -294.409146) (xy 343.382502 -294.455827) (xy 343.359631 -294.499404)
			(xy 343.330066 -294.538748) (xy 343.294573 -294.57284) (xy 343.25407 -294.600796) (xy 343.209608 -294.621894)
			(xy 343.162337 -294.635586) (xy 343.113482 -294.641518) (xy 343.064307 -294.639537) (xy 343.016088 -294.629693)
			(xy 342.970072 -294.612241) (xy 342.927451 -294.587634) (xy 342.88933 -294.556509) (xy 342.856695 -294.519672)
			(xy 342.830392 -294.478076) (xy 342.811101 -294.4328) (xy 342.799324 -294.385016) (xy 342.795364 -294.335962)
			(xy 341.526368 -294.335962) (xy 341.525873 -294.360569) (xy 341.517978 -294.409146) (xy 341.502394 -294.455827)
			(xy 341.479523 -294.499404) (xy 341.449958 -294.538748) (xy 341.414465 -294.57284) (xy 341.373962 -294.600796)
			(xy 341.3295 -294.621894) (xy 341.282229 -294.635586) (xy 341.233374 -294.641518) (xy 341.184199 -294.639537)
			(xy 341.13598 -294.629693) (xy 341.089964 -294.612241) (xy 341.047343 -294.587634) (xy 341.009222 -294.556509)
			(xy 340.976587 -294.519672) (xy 340.950284 -294.478076) (xy 340.930993 -294.4328) (xy 340.919216 -294.385016)
			(xy 340.915256 -294.335962) (xy 340.586314 -294.335962) (xy 340.585871 -294.359957) (xy 340.578369 -294.407358)
			(xy 340.563544 -294.453001) (xy 340.54176 -294.495763) (xy 340.513555 -294.53459) (xy 340.479624 -294.568527)
			(xy 340.4408 -294.596737) (xy 340.398042 -294.618527) (xy 340.352401 -294.633358) (xy 340.305001 -294.640867)
			(xy 340.281006 -294.64127) (xy 340.256427 -294.640778) (xy 340.207904 -294.632904) (xy 340.161269 -294.617358)
			(xy 340.117726 -294.594543) (xy 340.078401 -294.565046) (xy 340.044309 -294.529631) (xy 340.016331 -294.489212)
			(xy 339.995189 -294.444833) (xy 339.98143 -294.39764) (xy 339.977984 -294.3733) (xy 339.976206 -294.359838)
			(xy 339.952584 -294.328596) (xy 339.948018 -294.32298) (xy 339.936413 -294.314344) (xy 339.929724 -294.311578)
			(xy 339.85708 -294.284654) (xy 339.847884 -294.281726) (xy 339.828607 -294.282245) (xy 339.810887 -294.289851)
			(xy 339.80374 -294.296338) (xy 339.596476 -294.503602) (xy 339.593682 -294.507666) (xy 339.576972 -294.53107)
			(xy 339.536318 -294.571733) (xy 339.51291 -294.588438) (xy 339.505544 -294.594534) (xy 339.488526 -294.611552)
			(xy 339.481922 -294.622982) (xy 339.480144 -294.629332) (xy 339.46693 -294.675986) (xy 339.433494 -294.767011)
			(xy 339.392298 -294.854798) (xy 339.343654 -294.938687) (xy 339.287926 -295.018047) (xy 339.225534 -295.092282)
			(xy 339.1916 -295.126918) (xy 339.184792 -295.134264) (xy 339.179895 -295.145968) (xy 339.505302 -295.145968)
			(xy 339.509262 -295.096914) (xy 339.521039 -295.04913) (xy 339.54033 -295.003854) (xy 339.566633 -294.962258)
			(xy 339.599268 -294.925421) (xy 339.637389 -294.894296) (xy 339.68001 -294.869689) (xy 339.726026 -294.852237)
			(xy 339.774245 -294.842393) (xy 339.82342 -294.840412) (xy 339.872275 -294.846344) (xy 339.919546 -294.860036)
			(xy 339.964008 -294.881134) (xy 340.004511 -294.90909) (xy 340.040004 -294.943182) (xy 340.069569 -294.982526)
			(xy 340.09244 -295.026103) (xy 340.108024 -295.072784) (xy 340.115919 -295.121361) (xy 340.116414 -295.145968)
			(xy 340.445356 -295.145968) (xy 340.449316 -295.096914) (xy 340.461093 -295.04913) (xy 340.480384 -295.003854)
			(xy 340.506687 -294.962258) (xy 340.539322 -294.925421) (xy 340.577443 -294.894296) (xy 340.620064 -294.869689)
			(xy 340.66608 -294.852237) (xy 340.714299 -294.842393) (xy 340.763474 -294.840412) (xy 340.812329 -294.846344)
			(xy 340.8596 -294.860036) (xy 340.904062 -294.881134) (xy 340.944565 -294.90909) (xy 340.980058 -294.943182)
			(xy 341.009623 -294.982526) (xy 341.032494 -295.026103) (xy 341.048078 -295.072784) (xy 341.055973 -295.121361)
			(xy 341.056468 -295.145968) (xy 343.265264 -295.145968) (xy 343.269224 -295.096914) (xy 343.281001 -295.04913)
			(xy 343.300292 -295.003854) (xy 343.326595 -294.962258) (xy 343.35923 -294.925421) (xy 343.397351 -294.894296)
			(xy 343.439972 -294.869689) (xy 343.485988 -294.852237) (xy 343.534207 -294.842393) (xy 343.583382 -294.840412)
			(xy 343.632237 -294.846344) (xy 343.679508 -294.860036) (xy 343.72397 -294.881134) (xy 343.764473 -294.90909)
			(xy 343.799966 -294.943182) (xy 343.829531 -294.982526) (xy 343.852402 -295.026103) (xy 343.867986 -295.072784)
			(xy 343.875881 -295.121361) (xy 343.876376 -295.145968) (xy 343.875881 -295.170575) (xy 343.867986 -295.219152)
			(xy 343.852402 -295.265833) (xy 343.829531 -295.30941) (xy 343.799966 -295.348754) (xy 343.764473 -295.382846)
			(xy 343.72397 -295.410802) (xy 343.679508 -295.4319) (xy 343.632237 -295.445592) (xy 343.583382 -295.451524)
			(xy 343.534207 -295.449543) (xy 343.485988 -295.439699) (xy 343.439972 -295.422247) (xy 343.397351 -295.39764)
			(xy 343.35923 -295.366515) (xy 343.326595 -295.329678) (xy 343.300292 -295.288082) (xy 343.281001 -295.242806)
			(xy 343.269224 -295.195022) (xy 343.265264 -295.145968) (xy 341.056468 -295.145968) (xy 341.055973 -295.170575)
			(xy 341.048078 -295.219152) (xy 341.032494 -295.265833) (xy 341.009623 -295.30941) (xy 340.980058 -295.348754)
			(xy 340.944565 -295.382846) (xy 340.904062 -295.410802) (xy 340.8596 -295.4319) (xy 340.812329 -295.445592)
			(xy 340.763474 -295.451524) (xy 340.714299 -295.449543) (xy 340.66608 -295.439699) (xy 340.620064 -295.422247)
			(xy 340.577443 -295.39764) (xy 340.539322 -295.366515) (xy 340.506687 -295.329678) (xy 340.480384 -295.288082)
			(xy 340.461093 -295.242806) (xy 340.449316 -295.195022) (xy 340.445356 -295.145968) (xy 340.116414 -295.145968)
			(xy 340.115919 -295.170575) (xy 340.108024 -295.219152) (xy 340.09244 -295.265833) (xy 340.069569 -295.30941)
			(xy 340.040004 -295.348754) (xy 340.004511 -295.382846) (xy 339.964008 -295.410802) (xy 339.919546 -295.4319)
			(xy 339.872275 -295.445592) (xy 339.82342 -295.451524) (xy 339.774245 -295.449543) (xy 339.726026 -295.439699)
			(xy 339.68001 -295.422247) (xy 339.637389 -295.39764) (xy 339.599268 -295.366515) (xy 339.566633 -295.329678)
			(xy 339.54033 -295.288082) (xy 339.521039 -295.242806) (xy 339.509262 -295.195022) (xy 339.505302 -295.145968)
			(xy 339.179895 -295.145968) (xy 339.177067 -295.152727) (xy 339.176614 -295.162732) (xy 339.176614 -295.528492)
			(xy 339.177153 -295.539511) (xy 339.186372 -295.559527) (xy 339.194394 -295.5671) (xy 339.25256 -295.617138)
			(xy 339.261228 -295.623863) (xy 339.282287 -295.629936) (xy 339.2932 -295.628822) (xy 339.305134 -295.627175)
			(xy 339.32916 -295.625394) (xy 339.341206 -295.625266) (xy 339.367195 -295.625776) (xy 339.418533 -295.633908)
			(xy 339.467966 -295.649971) (xy 339.514279 -295.673569) (xy 339.556329 -295.704121) (xy 339.593083 -295.740875)
			(xy 339.623634 -295.782926) (xy 339.647232 -295.829239) (xy 339.663293 -295.878673) (xy 339.671424 -295.930011)
			(xy 339.671424 -295.955974) (xy 339.975202 -295.955974) (xy 339.979162 -295.90692) (xy 339.990939 -295.859136)
			(xy 340.01023 -295.81386) (xy 340.036533 -295.772264) (xy 340.069168 -295.735427) (xy 340.107289 -295.704302)
			(xy 340.14991 -295.679695) (xy 340.195926 -295.662243) (xy 340.244145 -295.652399) (xy 340.29332 -295.650418)
			(xy 340.342175 -295.65635) (xy 340.389446 -295.670042) (xy 340.433908 -295.69114) (xy 340.474411 -295.719096)
			(xy 340.509904 -295.753188) (xy 340.539469 -295.792532) (xy 340.56234 -295.836109) (xy 340.577924 -295.88279)
			(xy 340.585819 -295.931367) (xy 340.586314 -295.955974) (xy 340.585819 -295.980581) (xy 340.577924 -296.029158)
			(xy 340.56234 -296.075839) (xy 340.539469 -296.119416) (xy 340.509904 -296.15876) (xy 340.474411 -296.192852)
			(xy 340.433908 -296.220808) (xy 340.389446 -296.241906) (xy 340.342175 -296.255598) (xy 340.29332 -296.26153)
			(xy 340.244145 -296.259549) (xy 340.195926 -296.249705) (xy 340.14991 -296.232253) (xy 340.107289 -296.207646)
			(xy 340.069168 -296.176521) (xy 340.036533 -296.139684) (xy 340.01023 -296.098088) (xy 339.990939 -296.052812)
			(xy 339.979162 -296.005028) (xy 339.975202 -295.955974) (xy 339.671424 -295.955974) (xy 339.671424 -295.981989)
			(xy 339.663293 -296.033327) (xy 339.647232 -296.082761) (xy 339.623634 -296.129074) (xy 339.593083 -296.171125)
			(xy 339.556329 -296.207879) (xy 339.514279 -296.238431) (xy 339.467966 -296.262029) (xy 339.418533 -296.278092)
			(xy 339.367195 -296.286224) (xy 339.341206 -296.286682) (xy 339.32916 -296.286566) (xy 339.305133 -296.284783)
			(xy 339.2932 -296.283126) (xy 339.282285 -296.282009) (xy 339.261224 -296.288076) (xy 339.25256 -296.29481)
			(xy 339.194394 -296.344848) (xy 339.186324 -296.352468) (xy 339.177082 -296.372622) (xy 339.176614 -296.38371)
			(xy 339.176614 -297.065192) (xy 339.176193 -297.075263) (xy 339.168482 -297.093871) (xy 339.161628 -297.10126)
			(xy 337.79968 -298.463208) (xy 337.79228 -298.47005) (xy 337.773682 -298.477776) (xy 337.763612 -298.478194)
			(xy 330.717144 -298.478194) (xy 330.698348 -298.485814) (xy 330.691236 -298.49318) (xy 329.945461 -299.238946)
			(xy 339.464724 -299.238946) (xy 339.464724 -299.184454) (xy 339.472478 -299.130518) (xy 339.487829 -299.078233)
			(xy 339.510464 -299.028665) (xy 339.539922 -298.982823) (xy 339.575604 -298.941639) (xy 339.616783 -298.905952)
			(xy 339.662621 -298.876488) (xy 339.712186 -298.853847) (xy 339.764469 -298.838489) (xy 339.818404 -298.830728)
			(xy 339.84565 -298.830238) (xy 339.87107 -298.83063) (xy 339.921462 -298.837361) (xy 339.970511 -298.850735)
			(xy 340.017345 -298.870516) (xy 340.039452 -298.88307) (xy 340.048088 -298.88815) (xy 340.067138 -298.891198)
			(xy 340.154768 -298.870878) (xy 340.170516 -298.859702) (xy 340.176104 -298.851574) (xy 340.193776 -298.825571)
			(xy 340.234518 -298.777686) (xy 340.280856 -298.735193) (xy 340.332082 -298.698741) (xy 340.387414 -298.668888)
			(xy 340.446007 -298.64609) (xy 340.506965 -298.630694) (xy 340.569356 -298.622936) (xy 340.600792 -298.622466)
			(xy 340.631522 -298.622964) (xy 340.692533 -298.630371) (xy 340.752208 -298.645078) (xy 340.809674 -298.66687)
			(xy 340.864094 -298.69543) (xy 340.914676 -298.730342) (xy 340.96068 -298.771096) (xy 341.001437 -298.817098)
			(xy 341.036352 -298.867676) (xy 341.064916 -298.922095) (xy 341.086712 -298.97956) (xy 341.101423 -299.039233)
			(xy 341.108834 -299.100244) (xy 341.1093 -299.130974) (xy 341.108704 -299.165929) (xy 341.099146 -299.235181)
			(xy 341.080192 -299.302472) (xy 341.0522 -299.366533) (xy 341.015698 -299.426156) (xy 340.993984 -299.453554)
			(xy 340.988706 -299.460566) (xy 340.98272 -299.477047) (xy 340.9823 -299.485812) (xy 340.9823 -299.792136)
			(xy 340.982643 -299.800915) (xy 340.988641 -299.817418) (xy 340.993984 -299.824394) (xy 341.015692 -299.851797)
			(xy 341.052191 -299.911422) (xy 341.080185 -299.975481) (xy 341.099147 -300.042769) (xy 341.108719 -300.11202)
			(xy 341.1093 -300.146974) (xy 341.108838 -300.177706) (xy 341.101432 -300.238722) (xy 341.086725 -300.2984)
			(xy 341.064932 -300.35587) (xy 341.03637 -300.410295) (xy 341.001456 -300.460879) (xy 340.960699 -300.506886)
			(xy 340.914693 -300.547645) (xy 340.86411 -300.582561) (xy 340.809687 -300.611125) (xy 340.752217 -300.63292)
			(xy 340.692539 -300.647629) (xy 340.631524 -300.655037) (xy 340.600792 -300.655482) (xy 340.568296 -300.654941)
			(xy 340.503832 -300.646666) (xy 340.440951 -300.630239) (xy 340.380676 -300.605928) (xy 340.323994 -300.57413)
			(xy 340.271829 -300.535364) (xy 340.225032 -300.490263) (xy 340.204298 -300.465236) (xy 340.197967 -300.457981)
			(xy 340.181254 -300.44845) (xy 340.171786 -300.446694) (xy 340.140798 -300.442376) (xy 340.13137 -300.441495)
			(xy 340.112973 -300.445928) (xy 340.104984 -300.451012) (xy 340.080943 -300.466974) (xy 340.029068 -300.492251)
			(xy 339.973974 -300.509414) (xy 339.916921 -300.518069) (xy 339.888068 -300.518576) (xy 339.860816 -300.518152)
			(xy 339.806867 -300.510391) (xy 339.754572 -300.495032) (xy 339.704995 -300.472387) (xy 339.659144 -300.442917)
			(xy 339.617954 -300.407223) (xy 339.582263 -300.36603) (xy 339.552798 -300.320177) (xy 339.530157 -300.270598)
			(xy 339.514802 -300.218302) (xy 339.507046 -300.164352) (xy 339.507046 -300.109848) (xy 339.514802 -300.055898)
			(xy 339.530157 -300.003602) (xy 339.552798 -299.954023) (xy 339.582263 -299.90817) (xy 339.617954 -299.866977)
			(xy 339.659144 -299.831283) (xy 339.704995 -299.801813) (xy 339.754572 -299.779168) (xy 339.806867 -299.763809)
			(xy 339.860816 -299.756048) (xy 339.888068 -299.75556) (xy 339.918245 -299.756119) (xy 339.977849 -299.765595)
			(xy 340.035221 -299.784331) (xy 340.088929 -299.811862) (xy 340.11362 -299.82922) (xy 340.121498 -299.834459)
			(xy 340.139736 -299.839419) (xy 340.14918 -299.838872) (xy 340.200742 -299.83303) (xy 340.2076 -299.824394)
			(xy 340.212909 -299.817403) (xy 340.218875 -299.800905) (xy 340.219284 -299.792136) (xy 340.219284 -299.611034)
			(xy 340.218927 -299.601799) (xy 340.212359 -299.584534) (xy 340.200101 -299.570717) (xy 340.192106 -299.566076)
			(xy 340.100158 -299.517562) (xy 340.072218 -299.519086) (xy 340.06028 -299.52696) (xy 340.036419 -299.542582)
			(xy 339.985043 -299.567341) (xy 339.930554 -299.584174) (xy 339.874165 -299.592704) (xy 339.84565 -299.593254)
			(xy 339.818404 -299.592672) (xy 339.764469 -299.584911) (xy 339.712186 -299.569553) (xy 339.662621 -299.546912)
			(xy 339.616783 -299.517448) (xy 339.575604 -299.481761) (xy 339.539922 -299.440577) (xy 339.510464 -299.394735)
			(xy 339.487829 -299.345167) (xy 339.472478 -299.292882) (xy 339.464724 -299.238946) (xy 329.945461 -299.238946)
			(xy 327.439022 -301.745353) (xy 340.488772 -301.745353) (xy 340.488772 -301.681431) (xy 340.496783 -301.618013)
			(xy 340.51268 -301.556099) (xy 340.536212 -301.496666) (xy 340.567006 -301.440651) (xy 340.604579 -301.388936)
			(xy 340.648336 -301.342339) (xy 340.697589 -301.301594) (xy 340.75156 -301.267343) (xy 340.809399 -301.240126)
			(xy 340.870192 -301.220373) (xy 340.932982 -301.208395) (xy 340.996778 -301.204382) (xy 341.060574 -301.208395)
			(xy 341.123364 -301.220373) (xy 341.184157 -301.240126) (xy 341.241996 -301.267343) (xy 341.295967 -301.301594)
			(xy 341.34522 -301.342339) (xy 341.388977 -301.388936) (xy 341.42655 -301.440651) (xy 341.457344 -301.496666)
			(xy 341.480876 -301.556099) (xy 341.496773 -301.618013) (xy 341.504784 -301.681431) (xy 341.505286 -301.713392)
			(xy 341.504784 -301.745353) (xy 341.496773 -301.808771) (xy 341.480876 -301.870685) (xy 341.457344 -301.930118)
			(xy 341.42655 -301.986133) (xy 341.388977 -302.037848) (xy 341.34522 -302.084445) (xy 341.295967 -302.12519)
			(xy 341.241996 -302.159441) (xy 341.184157 -302.186658) (xy 341.123364 -302.206411) (xy 341.060574 -302.218389)
			(xy 340.996778 -302.222403) (xy 340.932982 -302.218389) (xy 340.870192 -302.206411) (xy 340.809399 -302.186658)
			(xy 340.75156 -302.159441) (xy 340.697589 -302.12519) (xy 340.648336 -302.084445) (xy 340.604579 -302.037848)
			(xy 340.567006 -301.986133) (xy 340.536212 -301.930118) (xy 340.51268 -301.870685) (xy 340.496783 -301.808771)
			(xy 340.488772 -301.745353) (xy 327.439022 -301.745353) (xy 324.404148 -304.780188) (xy 326.752462 -304.780188)
			(xy 326.756491 -304.637867) (xy 326.768566 -304.496002) (xy 326.788647 -304.355048) (xy 326.81667 -304.215455)
			(xy 326.852546 -304.077671) (xy 326.89616 -303.942138) (xy 326.947372 -303.809289) (xy 327.006018 -303.67955)
			(xy 327.071909 -303.553337) (xy 327.144836 -303.431054) (xy 327.224564 -303.313092) (xy 327.310838 -303.19983)
			(xy 327.403382 -303.091631) (xy 327.501898 -302.98884) (xy 327.606073 -302.891788) (xy 327.715571 -302.800784)
			(xy 327.830042 -302.716122) (xy 327.94912 -302.638071) (xy 328.072423 -302.566882) (xy 328.199556 -302.502783)
			(xy 328.330112 -302.445979) (xy 328.463672 -302.396653) (xy 328.599809 -302.354961) (xy 328.738087 -302.321038)
			(xy 328.878062 -302.294993) (xy 329.019287 -302.276908) (xy 329.161308 -302.266843) (xy 329.303672 -302.264828)
			(xy 329.445922 -302.270871) (xy 329.587602 -302.284951) (xy 329.728258 -302.307025) (xy 329.86744 -302.337021)
			(xy 330.004702 -302.374843) (xy 330.139605 -302.420371) (xy 330.271716 -302.473457) (xy 330.400612 -302.533933)
			(xy 330.52588 -302.601604) (xy 330.647119 -302.676254) (xy 330.76394 -302.757643) (xy 330.87597 -302.845511)
			(xy 330.982849 -302.939577) (xy 331.084235 -303.039538) (xy 331.179804 -303.145076) (xy 331.269249 -303.255851)
			(xy 331.352283 -303.371509) (xy 331.428641 -303.491679) (xy 331.498078 -303.615977) (xy 331.560371 -303.744004)
			(xy 331.615322 -303.875351) (xy 331.662754 -304.009596) (xy 331.702515 -304.146309) (xy 331.734477 -304.285053)
			(xy 331.758539 -304.425383) (xy 331.774623 -304.566849) (xy 331.782679 -304.708999) (xy 331.783182 -304.780188)
			(xy 331.782679 -304.851377) (xy 331.774623 -304.993527) (xy 331.767594 -305.055351) (xy 333.14867 -305.055351)
			(xy 333.14867 -305.000849) (xy 333.156426 -304.946901) (xy 333.171781 -304.894606) (xy 333.194421 -304.845029)
			(xy 333.223887 -304.799178) (xy 333.259578 -304.757988) (xy 333.300767 -304.722295) (xy 333.346617 -304.692828)
			(xy 333.396193 -304.670186) (xy 333.448487 -304.654829) (xy 333.502435 -304.647071) (xy 333.529686 -304.646584)
			(xy 333.539931 -304.646673) (xy 333.560389 -304.647819) (xy 333.57058 -304.64887) (xy 333.579978 -304.649886)
			(xy 333.598012 -304.64506) (xy 333.66837 -304.594768) (xy 333.67853 -304.579274) (xy 333.680562 -304.569876)
			(xy 333.687473 -304.541019) (xy 333.707125 -304.485027) (xy 333.733149 -304.431698) (xy 333.765193 -304.381754)
			(xy 333.783686 -304.358548) (xy 333.788935 -304.351534) (xy 333.794795 -304.335043) (xy 333.795116 -304.32629)
			(xy 333.795116 -304.172366) (xy 333.794764 -304.163618) (xy 333.788919 -304.147127) (xy 333.783686 -304.140108)
			(xy 333.764796 -304.116355) (xy 333.732197 -304.065163) (xy 333.718662 -304.038) (xy 333.714459 -304.030064)
			(xy 333.70158 -304.017567) (xy 333.693516 -304.013616) (xy 333.666084 -304.001424) (xy 333.65788 -303.998021)
			(xy 333.640186 -303.996596) (xy 333.63154 -303.99863) (xy 333.606578 -304.005128) (xy 333.555476 -304.012138)
			(xy 333.529686 -304.0126) (xy 333.502435 -304.012129) (xy 333.448487 -304.004371) (xy 333.396193 -303.989014)
			(xy 333.346617 -303.966372) (xy 333.300767 -303.936905) (xy 333.259578 -303.901212) (xy 333.223887 -303.860022)
			(xy 333.194421 -303.814171) (xy 333.171781 -303.764594) (xy 333.156426 -303.712299) (xy 333.14867 -303.658351)
			(xy 333.14867 -303.603849) (xy 333.156426 -303.549901) (xy 333.171781 -303.497606) (xy 333.194421 -303.448029)
			(xy 333.223887 -303.402178) (xy 333.259578 -303.360988) (xy 333.300767 -303.325295) (xy 333.346617 -303.295828)
			(xy 333.396193 -303.273186) (xy 333.448487 -303.257829) (xy 333.502435 -303.250071) (xy 333.529686 -303.249584)
			(xy 333.556134 -303.250062) (xy 333.608525 -303.257356) (xy 333.659405 -303.27182) (xy 333.707797 -303.293177)
			(xy 333.752775 -303.321016) (xy 333.793473 -303.354804) (xy 333.811626 -303.374044) (xy 333.817809 -303.380336)
			(xy 333.833415 -303.388535) (xy 333.842106 -303.390046) (xy 333.872078 -303.394364) (xy 333.88096 -303.395259)
			(xy 333.898396 -303.391485) (xy 333.906114 -303.386998) (xy 333.936652 -303.368487) (xy 334.001832 -303.33931)
			(xy 334.070456 -303.319551) (xy 334.141172 -303.3096) (xy 334.176878 -303.30902) (xy 334.207611 -303.309458)
			(xy 334.268628 -303.316865) (xy 334.328308 -303.331573) (xy 334.38578 -303.353368) (xy 334.440205 -303.381931)
			(xy 334.49079 -303.416847) (xy 334.536798 -303.457607) (xy 334.577556 -303.503615) (xy 334.612472 -303.5542)
			(xy 334.641035 -303.608626) (xy 334.662829 -303.666098) (xy 334.677536 -303.725778) (xy 334.684942 -303.786795)
			(xy 334.685386 -303.817528) (xy 334.684824 -303.852484) (xy 334.675258 -303.921738) (xy 334.656296 -303.989029)
			(xy 334.628297 -304.053089) (xy 334.591787 -304.112711) (xy 334.57007 -304.140108) (xy 334.564793 -304.147103)
			(xy 334.558951 -304.163609) (xy 334.55864 -304.172366) (xy 334.55864 -304.32629) (xy 334.559001 -304.335037)
			(xy 334.564838 -304.351529) (xy 334.57007 -304.358548) (xy 334.591755 -304.385969) (xy 334.628258 -304.445588)
			(xy 334.656256 -304.509643) (xy 334.675223 -304.576927) (xy 334.684802 -304.646175) (xy 334.685386 -304.681128)
			(xy 334.68497 -304.71186) (xy 334.677558 -304.772877) (xy 334.662845 -304.832555) (xy 334.641047 -304.890024)
			(xy 334.61248 -304.944447) (xy 334.591765 -304.974455) (xy 343.718382 -304.974455) (xy 343.718382 -304.910533)
			(xy 343.726393 -304.847115) (xy 343.74229 -304.785201) (xy 343.765822 -304.725768) (xy 343.796616 -304.669753)
			(xy 343.834189 -304.618038) (xy 343.877946 -304.571441) (xy 343.927199 -304.530696) (xy 343.98117 -304.496445)
			(xy 344.039009 -304.469228) (xy 344.099802 -304.449475) (xy 344.162592 -304.437497) (xy 344.226388 -304.433484)
			(xy 344.290184 -304.437497) (xy 344.352974 -304.449475) (xy 344.413767 -304.469228) (xy 344.471606 -304.496445)
			(xy 344.525577 -304.530696) (xy 344.57483 -304.571441) (xy 344.618587 -304.618038) (xy 344.65616 -304.669753)
			(xy 344.686954 -304.725768) (xy 344.710486 -304.785201) (xy 344.726383 -304.847115) (xy 344.734394 -304.910533)
			(xy 344.734896 -304.942494) (xy 344.734394 -304.974455) (xy 344.726383 -305.037873) (xy 344.710486 -305.099787)
			(xy 344.686954 -305.15922) (xy 344.65616 -305.215235) (xy 344.618587 -305.26695) (xy 344.57483 -305.313547)
			(xy 344.525577 -305.354292) (xy 344.471606 -305.388543) (xy 344.413767 -305.41576) (xy 344.352974 -305.435513)
			(xy 344.290184 -305.447491) (xy 344.226388 -305.451505) (xy 344.162592 -305.447491) (xy 344.099802 -305.435513)
			(xy 344.039009 -305.41576) (xy 343.98117 -305.388543) (xy 343.927199 -305.354292) (xy 343.877946 -305.313547)
			(xy 343.834189 -305.26695) (xy 343.796616 -305.215235) (xy 343.765822 -305.15922) (xy 343.74229 -305.099787)
			(xy 343.726393 -305.037873) (xy 343.718382 -304.974455) (xy 334.591765 -304.974455) (xy 334.577561 -304.99503)
			(xy 334.5368 -305.041035) (xy 334.490791 -305.081792) (xy 334.440205 -305.116706) (xy 334.385779 -305.145267)
			(xy 334.328307 -305.16706) (xy 334.268628 -305.181767) (xy 334.20761 -305.189173) (xy 334.176878 -305.189636)
			(xy 334.145823 -305.189181) (xy 334.084176 -305.181607) (xy 334.023915 -305.166562) (xy 333.99476 -305.155854)
			(xy 333.98587 -305.152552) (xy 333.967328 -305.152552) (xy 333.886556 -305.183286) (xy 333.872586 -305.195478)
			(xy 333.868268 -305.20386) (xy 333.855857 -305.226764) (xy 333.825796 -305.269308) (xy 333.790225 -305.307365)
			(xy 333.749805 -305.340226) (xy 333.705288 -305.367279) (xy 333.657503 -305.388023) (xy 333.60734 -305.402069)
			(xy 333.555732 -305.409157) (xy 333.529686 -305.4096) (xy 333.502435 -305.409129) (xy 333.448487 -305.401371)
			(xy 333.396193 -305.386014) (xy 333.346617 -305.363372) (xy 333.300767 -305.333905) (xy 333.259578 -305.298212)
			(xy 333.223887 -305.257022) (xy 333.194421 -305.211171) (xy 333.171781 -305.161594) (xy 333.156426 -305.109299)
			(xy 333.14867 -305.055351) (xy 331.767594 -305.055351) (xy 331.758539 -305.134993) (xy 331.734477 -305.275323)
			(xy 331.703418 -305.410147) (xy 339.849008 -305.410147) (xy 339.849008 -305.355653) (xy 339.856763 -305.301714)
			(xy 339.872114 -305.249427) (xy 339.89475 -305.199857) (xy 339.924209 -305.154013) (xy 339.959893 -305.112827)
			(xy 340.001074 -305.077138) (xy 340.046915 -305.047673) (xy 340.096482 -305.025031) (xy 340.148767 -305.009673)
			(xy 340.202705 -305.001911) (xy 340.229952 -305.001422) (xy 340.256402 -305.001843) (xy 340.308796 -305.009147)
			(xy 340.359677 -305.023622) (xy 340.40807 -305.044989) (xy 340.453046 -305.072839) (xy 340.493741 -305.106637)
			(xy 340.511892 -305.125882) (xy 340.518081 -305.132167) (xy 340.533683 -305.140369) (xy 340.542372 -305.141884)
			(xy 340.572344 -305.146202) (xy 340.581227 -305.147075) (xy 340.598661 -305.143315) (xy 340.60638 -305.138836)
			(xy 340.636929 -305.120342) (xy 340.702104 -305.09116) (xy 340.770725 -305.071396) (xy 340.841438 -305.06144)
			(xy 340.877144 -305.060858) (xy 340.907875 -305.061314) (xy 340.968887 -305.068727) (xy 341.028562 -305.083439)
			(xy 341.086028 -305.105237) (xy 341.140448 -305.133802) (xy 341.191029 -305.168717) (xy 341.237033 -305.209474)
			(xy 341.277789 -305.255479) (xy 341.312704 -305.30606) (xy 341.341267 -305.360481) (xy 341.363063 -305.417948)
			(xy 341.377775 -305.477623) (xy 341.385186 -305.538635) (xy 341.385652 -305.569366) (xy 341.385096 -305.604322)
			(xy 341.375526 -305.673576) (xy 341.356563 -305.740867) (xy 341.328562 -305.804927) (xy 341.292053 -305.864548)
			(xy 341.270336 -305.891946) (xy 341.265056 -305.898956) (xy 341.259072 -305.915439) (xy 341.258652 -305.924204)
			(xy 341.258652 -306.062634) (xy 342.14054 -306.062634) (xy 342.141042 -306.030119) (xy 342.149316 -305.965619)
			(xy 342.165747 -305.9027) (xy 342.190065 -305.842389) (xy 342.221875 -305.785671) (xy 342.260657 -305.733472)
			(xy 342.305777 -305.686643) (xy 342.356501 -305.64595) (xy 342.411998 -305.612056) (xy 342.471364 -305.585514)
			(xy 342.53363 -305.566758) (xy 342.597779 -305.556095) (xy 342.630252 -305.55438) (xy 342.64092 -305.554126)
			(xy 342.660224 -305.544728) (xy 342.722708 -305.470814) (xy 342.72855 -305.450494) (xy 342.72728 -305.439826)
			(xy 342.725742 -305.427437) (xy 342.724087 -305.402525) (xy 342.723978 -305.390042) (xy 342.724464 -305.362791)
			(xy 342.73222 -305.308843) (xy 342.747575 -305.256548) (xy 342.770217 -305.206971) (xy 342.799683 -305.161121)
			(xy 342.835374 -305.11993) (xy 342.876565 -305.084239) (xy 342.922415 -305.054773) (xy 342.971992 -305.032131)
			(xy 343.024287 -305.016776) (xy 343.078235 -305.00902) (xy 343.132737 -305.00902) (xy 343.186685 -305.016776)
			(xy 343.23898 -305.032131) (xy 343.288557 -305.054773) (xy 343.334407 -305.084239) (xy 343.375598 -305.11993)
			(xy 343.411289 -305.161121) (xy 343.440755 -305.206971) (xy 343.463397 -305.256548) (xy 343.478752 -305.308843)
			(xy 343.486508 -305.362791) (xy 343.486994 -305.390042) (xy 343.486505 -305.418099) (xy 343.478267 -305.473605)
			(xy 343.46199 -305.527306) (xy 343.438024 -305.578044) (xy 343.406885 -305.624726) (xy 343.369247 -305.666344)
			(xy 343.325919 -305.702002) (xy 343.277837 -305.730931) (xy 343.226037 -305.752506) (xy 343.198958 -305.759866)
			(xy 343.188544 -305.76266) (xy 343.17178 -305.775614) (xy 343.126314 -305.860958) (xy 343.124536 -305.882294)
			(xy 343.128092 -305.892454) (xy 343.137391 -305.919854) (xy 343.150486 -305.976218) (xy 343.157114 -306.033702)
			(xy 343.157556 -306.062634) (xy 343.157054 -306.094595) (xy 343.149043 -306.158013) (xy 343.133146 -306.219927)
			(xy 343.109614 -306.27936) (xy 343.07882 -306.335375) (xy 343.041247 -306.38709) (xy 342.99749 -306.433687)
			(xy 342.948237 -306.474432) (xy 342.894266 -306.508683) (xy 342.836427 -306.5359) (xy 342.775634 -306.555653)
			(xy 342.712844 -306.567631) (xy 342.649048 -306.571645) (xy 342.585252 -306.567631) (xy 342.522462 -306.555653)
			(xy 342.461669 -306.5359) (xy 342.40383 -306.508683) (xy 342.349859 -306.474432) (xy 342.300606 -306.433687)
			(xy 342.256849 -306.38709) (xy 342.219276 -306.335375) (xy 342.188482 -306.27936) (xy 342.16495 -306.219927)
			(xy 342.149053 -306.158013) (xy 342.141042 -306.094595) (xy 342.14054 -306.062634) (xy 341.258652 -306.062634)
			(xy 341.258652 -306.078128) (xy 341.25901 -306.086905) (xy 341.264999 -306.103407) (xy 341.270336 -306.110386)
			(xy 341.292048 -306.137786) (xy 341.328544 -306.197412) (xy 341.356537 -306.261472) (xy 341.375498 -306.328761)
			(xy 341.385071 -306.398011) (xy 341.385652 -306.432966) (xy 341.385137 -306.466018) (xy 341.376563 -306.531564)
			(xy 341.359569 -306.595447) (xy 341.334441 -306.65659) (xy 341.301603 -306.713961) (xy 341.261608 -306.766594)
			(xy 341.215131 -306.813601) (xy 341.162955 -306.85419) (xy 341.10596 -306.887676) (xy 341.045106 -306.913496)
			(xy 340.98142 -306.931213) (xy 340.948772 -306.936394) (xy 340.938866 -306.937918) (xy 340.922102 -306.94757)
			(xy 340.866476 -307.018944) (xy 340.861142 -307.037486) (xy 340.862158 -307.047646) (xy 340.863117 -307.057588)
			(xy 340.864136 -307.077536) (xy 340.86419 -307.087524) (xy 340.863704 -307.114775) (xy 340.855948 -307.168723)
			(xy 340.840593 -307.221018) (xy 340.817951 -307.270595) (xy 340.788485 -307.316445) (xy 340.752794 -307.357636)
			(xy 340.711603 -307.393327) (xy 340.665753 -307.422793) (xy 340.616176 -307.445435) (xy 340.563881 -307.46079)
			(xy 340.509933 -307.468546) (xy 340.455431 -307.468546) (xy 340.401483 -307.46079) (xy 340.349188 -307.445435)
			(xy 340.299611 -307.422793) (xy 340.253761 -307.393327) (xy 340.21257 -307.357636) (xy 340.176879 -307.316445)
			(xy 340.147413 -307.270595) (xy 340.124771 -307.221018) (xy 340.109416 -307.168723) (xy 340.10166 -307.114775)
			(xy 340.101174 -307.087524) (xy 340.101665 -307.05915) (xy 340.110081 -307.003028) (xy 340.126717 -306.948772)
			(xy 340.151204 -306.897579) (xy 340.183005 -306.850577) (xy 340.221416 -306.808803) (xy 340.26559 -306.773179)
			(xy 340.314553 -306.744491) (xy 340.340696 -306.733448) (xy 340.350094 -306.729638) (xy 340.364064 -306.716176)
			(xy 340.401148 -306.633626) (xy 340.40191 -306.614322) (xy 340.398608 -306.60467) (xy 340.389101 -306.577055)
			(xy 340.375772 -306.520189) (xy 340.369054 -306.462169) (xy 340.368636 -306.432966) (xy 340.369213 -306.398011)
			(xy 340.378778 -306.328758) (xy 340.397737 -306.261467) (xy 340.425733 -306.197407) (xy 340.462237 -306.137785)
			(xy 340.483952 -306.110386) (xy 340.489259 -306.103394) (xy 340.495227 -306.086897) (xy 340.495636 -306.078128)
			(xy 340.495636 -305.924204) (xy 340.495266 -305.915428) (xy 340.489286 -305.898925) (xy 340.483952 -305.891946)
			(xy 340.465064 -305.868191) (xy 340.432464 -305.817) (xy 340.418928 -305.789838) (xy 340.41472 -305.781905)
			(xy 340.401843 -305.769408) (xy 340.393782 -305.765454) (xy 340.36635 -305.753262) (xy 340.358135 -305.749892)
			(xy 340.340451 -305.748445) (xy 340.331806 -305.750468) (xy 340.306845 -305.756971) (xy 340.255742 -305.763978)
			(xy 340.229952 -305.764438) (xy 340.202705 -305.763889) (xy 340.148767 -305.756127) (xy 340.096482 -305.740769)
			(xy 340.046915 -305.718127) (xy 340.001074 -305.688662) (xy 339.959893 -305.652973) (xy 339.924209 -305.611787)
			(xy 339.89475 -305.565943) (xy 339.872114 -305.516373) (xy 339.856763 -305.464086) (xy 339.849008 -305.410147)
			(xy 331.703418 -305.410147) (xy 331.702515 -305.414067) (xy 331.662754 -305.55078) (xy 331.615322 -305.685025)
			(xy 331.560371 -305.816372) (xy 331.498078 -305.944399) (xy 331.428641 -306.068697) (xy 331.352283 -306.188867)
			(xy 331.269249 -306.304525) (xy 331.179804 -306.4153) (xy 331.084235 -306.520838) (xy 330.982849 -306.620799)
			(xy 330.87597 -306.714865) (xy 330.76394 -306.802733) (xy 330.647119 -306.884122) (xy 330.52588 -306.958772)
			(xy 330.400612 -307.026443) (xy 330.271716 -307.086919) (xy 330.139605 -307.140005) (xy 330.004702 -307.185533)
			(xy 329.86744 -307.223355) (xy 329.728258 -307.253351) (xy 329.587602 -307.275425) (xy 329.445922 -307.289505)
			(xy 329.303672 -307.295548) (xy 329.161308 -307.293533) (xy 329.019287 -307.283468) (xy 328.878062 -307.265383)
			(xy 328.738087 -307.239338) (xy 328.599809 -307.205415) (xy 328.463672 -307.163723) (xy 328.330112 -307.114397)
			(xy 328.199556 -307.057593) (xy 328.072423 -306.993494) (xy 327.94912 -306.922305) (xy 327.830042 -306.844254)
			(xy 327.715571 -306.759592) (xy 327.606073 -306.668588) (xy 327.501898 -306.571536) (xy 327.403382 -306.468745)
			(xy 327.310838 -306.360546) (xy 327.224564 -306.247284) (xy 327.144836 -306.129322) (xy 327.071909 -306.007039)
			(xy 327.006018 -305.880826) (xy 326.947372 -305.751087) (xy 326.89616 -305.618238) (xy 326.852546 -305.482705)
			(xy 326.81667 -305.344921) (xy 326.788647 -305.205328) (xy 326.768566 -305.064374) (xy 326.756491 -304.922509)
			(xy 326.752462 -304.780188) (xy 324.404148 -304.780188) (xy 319.007638 -310.176629) (xy 332.667604 -310.176629)
			(xy 332.667604 -310.112707) (xy 332.675615 -310.049289) (xy 332.691512 -309.987375) (xy 332.715044 -309.927942)
			(xy 332.745838 -309.871927) (xy 332.783411 -309.820212) (xy 332.827168 -309.773615) (xy 332.876421 -309.73287)
			(xy 332.930392 -309.698619) (xy 332.988231 -309.671402) (xy 333.049024 -309.651649) (xy 333.111814 -309.639671)
			(xy 333.17561 -309.635658) (xy 333.239406 -309.639671) (xy 333.302196 -309.651649) (xy 333.362989 -309.671402)
			(xy 333.420828 -309.698619) (xy 333.474799 -309.73287) (xy 333.506735 -309.759289) (xy 334.460162 -309.759289)
			(xy 334.465371 -309.696417) (xy 334.478316 -309.634671) (xy 334.4988 -309.575002) (xy 334.526507 -309.518324)
			(xy 334.561012 -309.465509) (xy 334.601786 -309.417368) (xy 334.6482 -309.374639) (xy 334.699544 -309.337981)
			(xy 334.755028 -309.307954) (xy 334.8138 -309.285021) (xy 334.874957 -309.269535) (xy 334.93756 -309.261732)
			(xy 334.969104 -309.261256) (xy 335.004096 -309.261834) (xy 335.073421 -309.271427) (xy 335.140775 -309.290432)
			(xy 335.173066 -309.303928) (xy 335.185004 -309.309008) (xy 335.21015 -309.306976) (xy 335.303114 -309.24627)
			(xy 335.315306 -309.223918) (xy 335.315306 -309.21071) (xy 335.315747 -309.179978) (xy 335.323155 -309.118961)
			(xy 335.337864 -309.059282) (xy 335.359659 -309.001811) (xy 335.388223 -308.947386) (xy 335.423139 -308.896802)
			(xy 335.463897 -308.850795) (xy 335.509905 -308.810036) (xy 335.56049 -308.775121) (xy 335.614915 -308.746557)
			(xy 335.672386 -308.724762) (xy 335.732065 -308.710054) (xy 335.793082 -308.702647) (xy 335.823814 -308.702202)
			(xy 335.854235 -308.70268) (xy 335.914638 -308.709987) (xy 335.97374 -308.724436) (xy 336.002376 -308.734714)
			(xy 336.010738 -308.737373) (xy 336.028269 -308.73751) (xy 336.036666 -308.734968) (xy 336.06486 -308.725316)
			(xy 336.073109 -308.722239) (xy 336.086893 -308.711302) (xy 336.091784 -308.70398) (xy 336.10951 -308.676098)
			(xy 336.151114 -308.624769) (xy 336.199019 -308.579265) (xy 336.252418 -308.540353) (xy 336.310409 -308.50869)
			(xy 336.372014 -308.484809) (xy 336.436195 -308.469114) (xy 336.468974 -308.464966) (xy 336.477527 -308.463631)
			(xy 336.493109 -308.45612) (xy 336.499454 -308.450234) (xy 336.520282 -308.429152) (xy 336.526099 -308.422856)
			(xy 336.533495 -308.407404) (xy 336.53476 -308.398926) (xy 336.53864 -308.369149) (xy 336.554497 -308.311235)
			(xy 336.579231 -308.256519) (xy 336.612231 -308.206354) (xy 336.632042 -308.183788) (xy 336.642202 -308.172612)
			(xy 336.647282 -308.14391) (xy 336.600546 -308.031388) (xy 336.57667 -308.014624) (xy 336.561684 -308.013862)
			(xy 336.529231 -308.011815) (xy 336.465183 -308.00058) (xy 336.40309 -307.981274) (xy 336.343963 -307.954212)
			(xy 336.288767 -307.919836) (xy 336.238403 -307.878705) (xy 336.193691 -307.831491) (xy 336.155361 -307.778963)
			(xy 336.124038 -307.721979) (xy 336.100233 -307.661468) (xy 336.091784 -307.630068) (xy 336.088668 -307.619885)
			(xy 336.075625 -307.60309) (xy 336.056882 -307.593044) (xy 336.046318 -307.591714) (xy 336.014763 -307.588842)
			(xy 335.952666 -307.576231) (xy 335.892618 -307.556) (xy 335.835549 -307.528464) (xy 335.782345 -307.494049)
			(xy 335.73383 -307.453288) (xy 335.690757 -307.406815) (xy 335.653794 -307.355349) (xy 335.623512 -307.299689)
			(xy 335.600383 -307.240696) (xy 335.584764 -307.179287) (xy 335.576898 -307.116412) (xy 335.576418 -307.08473)
			(xy 335.576866 -307.053998) (xy 335.584272 -306.99298) (xy 335.598979 -306.933301) (xy 335.620772 -306.87583)
			(xy 335.649335 -306.821404) (xy 335.68425 -306.770819) (xy 335.725009 -306.724812) (xy 335.771016 -306.684053)
			(xy 335.821601 -306.649137) (xy 335.876026 -306.620574) (xy 335.933497 -306.59878) (xy 335.993176 -306.584072)
			(xy 336.054194 -306.576666) (xy 336.084926 -306.576222) (xy 336.115533 -306.57669) (xy 336.176303 -306.584063)
			(xy 336.235748 -306.598677) (xy 336.29301 -306.620319) (xy 336.34726 -306.648677) (xy 336.397715 -306.683341)
			(xy 336.443645 -306.723809) (xy 336.484387 -306.769497) (xy 336.519351 -306.819745) (xy 336.548031 -306.873825)
			(xy 336.570014 -306.930957) (xy 336.57794 -306.960524) (xy 336.581042 -306.970713) (xy 336.59409 -306.98751)
			(xy 336.61284 -306.997552) (xy 336.623406 -306.998878) (xy 336.644318 -307.000687) (xy 336.685773 -307.007296)
			(xy 336.70621 -307.012086) (xy 336.715912 -307.014046) (xy 336.735481 -307.01118) (xy 336.752512 -307.001124)
			(xy 336.764474 -306.985373) (xy 336.769589 -306.966268) (xy 336.767098 -306.946647) (xy 336.75737 -306.929427)
			(xy 336.749898 -306.922932) (xy 336.724514 -306.902221) (xy 336.678772 -306.855319) (xy 336.639434 -306.802929)
			(xy 336.607153 -306.74592) (xy 336.582464 -306.685235) (xy 336.565776 -306.621882) (xy 336.557365 -306.556909)
			(xy 336.556858 -306.524152) (xy 336.55731 -306.493421) (xy 336.564724 -306.432408) (xy 336.579437 -306.372734)
			(xy 336.601234 -306.315268) (xy 336.6298 -306.260847) (xy 336.664715 -306.210267) (xy 336.705473 -306.164263)
			(xy 336.751478 -306.123507) (xy 336.802059 -306.088592) (xy 336.85648 -306.060029) (xy 336.913947 -306.038232)
			(xy 336.973622 -306.023521) (xy 337.034635 -306.01611) (xy 337.065366 -306.015644) (xy 337.096619 -306.016114)
			(xy 337.158653 -306.023783) (xy 337.219279 -306.038996) (xy 337.277584 -306.061525) (xy 337.332688 -306.09103)
			(xy 337.383761 -306.127066) (xy 337.430032 -306.16909) (xy 337.470804 -306.216468) (xy 337.48853 -306.242212)
			(xy 337.496404 -306.253896) (xy 337.520788 -306.265834) (xy 337.636866 -306.257198) (xy 337.659218 -306.241704)
			(xy 337.66506 -306.229258) (xy 337.679112 -306.200524) (xy 337.713341 -306.146488) (xy 337.754078 -306.097172)
			(xy 337.800679 -306.053356) (xy 337.852408 -306.015732) (xy 337.908448 -305.984893) (xy 337.967914 -305.961328)
			(xy 338.029866 -305.945409) (xy 338.093326 -305.937386) (xy 338.125308 -305.936904) (xy 338.156041 -305.93733)
			(xy 338.217058 -305.94474) (xy 338.276737 -305.959451) (xy 338.334208 -305.981248) (xy 338.388632 -306.009813)
			(xy 338.439217 -306.04473) (xy 338.485224 -306.08549) (xy 338.525982 -306.131499) (xy 338.560897 -306.182085)
			(xy 338.589461 -306.23651) (xy 338.611255 -306.293982) (xy 338.625964 -306.353662) (xy 338.633371 -306.414679)
			(xy 338.633816 -306.445412) (xy 338.63329 -306.47859) (xy 338.624658 -306.544382) (xy 338.607541 -306.608492)
			(xy 338.582231 -306.669831) (xy 338.549158 -306.727357) (xy 338.508884 -306.780093) (xy 338.462092 -306.827142)
			(xy 338.409578 -306.867705) (xy 338.352234 -306.901093) (xy 338.291035 -306.926739) (xy 338.22702 -306.944207)
			(xy 338.161276 -306.9532) (xy 338.128102 -306.95392) (xy 338.115402 -306.95392) (xy 338.093304 -306.965858)
			(xy 338.032344 -307.057044) (xy 338.029804 -307.08219) (xy 338.03463 -307.093874) (xy 338.045381 -307.121376)
			(xy 338.061219 -307.178263) (xy 338.070372 -307.236601) (xy 338.071968 -307.266086) (xy 338.072743 -307.275619)
			(xy 338.080451 -307.293108) (xy 338.086954 -307.300122) (xy 338.109052 -307.32222) (xy 338.116 -307.328559)
			(xy 338.133211 -307.336109) (xy 338.14258 -307.336952) (xy 338.168995 -307.338604) (xy 338.221032 -307.348264)
			(xy 338.271232 -307.365027) (xy 338.318632 -307.388572) (xy 338.362321 -307.418445) (xy 338.401458 -307.454074)
			(xy 338.435292 -307.494772) (xy 338.463172 -307.539758) (xy 338.464674 -307.543157) (xy 343.824808 -307.543157)
			(xy 343.824808 -307.479235) (xy 343.832819 -307.415817) (xy 343.848716 -307.353903) (xy 343.872248 -307.29447)
			(xy 343.903042 -307.238455) (xy 343.940615 -307.18674) (xy 343.984372 -307.140143) (xy 344.033625 -307.099398)
			(xy 344.087596 -307.065147) (xy 344.145435 -307.03793) (xy 344.206228 -307.018177) (xy 344.269018 -307.006199)
			(xy 344.332814 -307.002186) (xy 344.39661 -307.006199) (xy 344.4594 -307.018177) (xy 344.520193 -307.03793)
			(xy 344.578032 -307.065147) (xy 344.632003 -307.099398) (xy 344.681256 -307.140143) (xy 344.725013 -307.18674)
			(xy 344.762586 -307.238455) (xy 344.79338 -307.29447) (xy 344.816912 -307.353903) (xy 344.832809 -307.415817)
			(xy 344.84082 -307.479235) (xy 344.841322 -307.511196) (xy 344.84082 -307.543157) (xy 344.832809 -307.606575)
			(xy 344.816912 -307.668489) (xy 344.79338 -307.727922) (xy 344.762586 -307.783937) (xy 344.725013 -307.835652)
			(xy 344.681256 -307.882249) (xy 344.632003 -307.922994) (xy 344.578032 -307.957245) (xy 344.520193 -307.984462)
			(xy 344.4594 -308.004215) (xy 344.39661 -308.016193) (xy 344.332814 -308.020207) (xy 344.269018 -308.016193)
			(xy 344.206228 -308.004215) (xy 344.145435 -307.984462) (xy 344.087596 -307.957245) (xy 344.033625 -307.922994)
			(xy 343.984372 -307.882249) (xy 343.940615 -307.835652) (xy 343.903042 -307.783937) (xy 343.872248 -307.727922)
			(xy 343.848716 -307.668489) (xy 343.832819 -307.606575) (xy 343.824808 -307.543157) (xy 338.464674 -307.543157)
			(xy 338.484564 -307.588168) (xy 338.499055 -307.639071) (xy 338.506367 -307.691489) (xy 338.506816 -307.717952)
			(xy 338.5063 -307.745203) (xy 338.49855 -307.799152) (xy 338.4832 -307.851448) (xy 338.460564 -307.901028)
			(xy 338.431102 -307.946881) (xy 338.395413 -307.988074) (xy 338.354226 -308.023768) (xy 338.308377 -308.053237)
			(xy 338.258801 -308.075881) (xy 338.206507 -308.091238) (xy 338.152559 -308.098996) (xy 338.125308 -308.09946)
			(xy 338.098461 -308.098997) (xy 338.045295 -308.091494) (xy 337.993707 -308.076608) (xy 337.944717 -308.054632)
			(xy 337.899294 -308.026002) (xy 337.858336 -307.991283) (xy 337.822653 -307.951162) (xy 337.792951 -307.906432)
			(xy 337.769817 -307.857978) (xy 337.761326 -307.832506) (xy 337.758185 -307.82361) (xy 337.746425 -307.808871)
			(xy 337.738466 -307.803804) (xy 337.711796 -307.788056) (xy 337.703327 -307.783565) (xy 337.684388 -307.780698)
			(xy 337.674966 -307.782468) (xy 337.647574 -307.788186) (xy 337.591948 -307.794292) (xy 337.563968 -307.79466)
			(xy 337.532396 -307.794194) (xy 337.469736 -307.786382) (xy 337.408527 -307.77087) (xy 337.34971 -307.747897)
			(xy 337.294191 -307.717816) (xy 337.242825 -307.681091) (xy 337.21929 -307.66004) (xy 337.209892 -307.651404)
			(xy 337.186016 -307.645054) (xy 337.079844 -307.66893) (xy 337.061048 -307.684932) (xy 337.056222 -307.696616)
			(xy 337.044755 -307.723791) (xy 337.016464 -307.775549) (xy 336.982372 -307.823684) (xy 336.942937 -307.867549)
			(xy 336.921094 -307.88737) (xy 336.909918 -307.897276) (xy 336.90179 -307.925216) (xy 336.935826 -308.04231)
			(xy 336.957924 -308.061614) (xy 336.972656 -308.0639) (xy 336.999301 -308.068469) (xy 337.051011 -308.084241)
			(xy 337.099977 -308.107155) (xy 337.145217 -308.136752) (xy 337.185826 -308.17244) (xy 337.22099 -308.213504)
			(xy 337.250004 -308.25912) (xy 337.272288 -308.308376) (xy 337.287395 -308.360284) (xy 337.295022 -308.413805)
			(xy 337.29549 -308.440836) (xy 337.295021 -308.468432) (xy 337.28705 -308.523047) (xy 337.271295 -308.575943)
			(xy 337.248085 -308.626018) (xy 337.217902 -308.672227) (xy 337.181378 -308.713606) (xy 337.139274 -308.749292)
			(xy 337.092468 -308.77854) (xy 337.067398 -308.790086) (xy 337.059656 -308.793824) (xy 337.047054 -308.805499)
			(xy 337.04276 -308.812946) (xy 337.02879 -308.839362) (xy 337.025092 -308.847197) (xy 337.02262 -308.864332)
			(xy 337.023964 -308.87289) (xy 337.028378 -308.897031) (xy 337.033082 -308.945886) (xy 337.033362 -308.970426)
			(xy 337.032987 -309.00116) (xy 337.025574 -309.062181) (xy 337.01086 -309.121863) (xy 336.98906 -309.179336)
			(xy 336.96049 -309.233762) (xy 336.925568 -309.284348) (xy 336.908895 -309.303166) (xy 341.391494 -309.303166)
			(xy 341.392058 -309.26821) (xy 341.401624 -309.198956) (xy 341.420585 -309.131665) (xy 341.448584 -309.067605)
			(xy 341.485093 -309.007984) (xy 341.50681 -308.980586) (xy 341.512087 -308.973591) (xy 341.51793 -308.957085)
			(xy 341.51824 -308.948328) (xy 341.51824 -308.794404) (xy 341.517885 -308.785656) (xy 341.512044 -308.769164)
			(xy 341.50681 -308.762146) (xy 341.48512 -308.73473) (xy 341.448618 -308.675109) (xy 341.420621 -308.611053)
			(xy 341.401655 -308.543768) (xy 341.392077 -308.47452) (xy 341.391494 -308.439566) (xy 341.391924 -308.408834)
			(xy 341.399336 -308.347819) (xy 341.414049 -308.288142) (xy 341.435847 -308.230674) (xy 341.464413 -308.176252)
			(xy 341.499331 -308.12567) (xy 341.54009 -308.079665) (xy 341.586098 -308.038909) (xy 341.636683 -308.003995)
			(xy 341.691107 -307.975432) (xy 341.748577 -307.953638) (xy 341.808255 -307.93893) (xy 341.86927 -307.931521)
			(xy 341.900002 -307.931058) (xy 341.931057 -307.931519) (xy 341.992704 -307.939091) (xy 342.052965 -307.954134)
			(xy 342.08212 -307.96484) (xy 342.09101 -307.968142) (xy 342.109552 -307.968142) (xy 342.190324 -307.937408)
			(xy 342.204294 -307.925216) (xy 342.208612 -307.916834) (xy 342.221035 -307.893937) (xy 342.251095 -307.851394)
			(xy 342.286665 -307.813337) (xy 342.327083 -307.780476) (xy 342.371598 -307.753421) (xy 342.41938 -307.732677)
			(xy 342.469542 -307.718629) (xy 342.521148 -307.711538) (xy 342.547194 -307.711094) (xy 342.574447 -307.711553)
			(xy 342.628399 -307.719309) (xy 342.680698 -307.734665) (xy 342.730279 -307.757307) (xy 342.776133 -307.786775)
			(xy 342.817327 -307.822469) (xy 342.853021 -307.863662) (xy 342.88249 -307.909516) (xy 342.905133 -307.959096)
			(xy 342.920489 -308.011395) (xy 342.928247 -308.065347) (xy 342.928247 -308.119853) (xy 342.920489 -308.173805)
			(xy 342.905133 -308.226104) (xy 342.88249 -308.275684) (xy 342.853021 -308.321538) (xy 342.817327 -308.362731)
			(xy 342.776133 -308.398425) (xy 342.730279 -308.427893) (xy 342.680698 -308.450535) (xy 342.628399 -308.465891)
			(xy 342.574447 -308.473647) (xy 342.547194 -308.47411) (xy 342.536949 -308.474015) (xy 342.516491 -308.472873)
			(xy 342.5063 -308.471824) (xy 342.496902 -308.470808) (xy 342.478868 -308.475634) (xy 342.40851 -308.525926)
			(xy 342.39835 -308.54142) (xy 342.396318 -308.550818) (xy 342.389409 -308.579675) (xy 342.369756 -308.635667)
			(xy 342.343732 -308.688996) (xy 342.311687 -308.738941) (xy 342.293194 -308.762146) (xy 342.287945 -308.76916)
			(xy 342.282086 -308.785651) (xy 342.281764 -308.794404) (xy 342.281764 -308.948328) (xy 342.282123 -308.957075)
			(xy 342.287963 -308.973566) (xy 342.293194 -308.980586) (xy 342.312082 -309.004341) (xy 342.344682 -309.055532)
			(xy 342.358218 -309.082694) (xy 342.362401 -309.090642) (xy 342.375295 -309.103131) (xy 342.383364 -309.107078)
			(xy 342.410796 -309.11927) (xy 342.419003 -309.122663) (xy 342.436694 -309.124094) (xy 342.44534 -309.122064)
			(xy 342.470303 -309.11557) (xy 342.521404 -309.108557) (xy 342.547194 -309.108094) (xy 342.574447 -309.108553)
			(xy 342.628399 -309.116309) (xy 342.680698 -309.131665) (xy 342.730279 -309.154307) (xy 342.776133 -309.183775)
			(xy 342.817327 -309.219469) (xy 342.853021 -309.260662) (xy 342.88249 -309.306516) (xy 342.905133 -309.356096)
			(xy 342.920489 -309.408395) (xy 342.928247 -309.462347) (xy 342.928247 -309.516853) (xy 342.920489 -309.570805)
			(xy 342.905133 -309.623104) (xy 342.88249 -309.672684) (xy 342.853021 -309.718538) (xy 342.817327 -309.759731)
			(xy 342.776133 -309.795425) (xy 342.730279 -309.824893) (xy 342.680698 -309.847535) (xy 342.628399 -309.862891)
			(xy 342.574447 -309.870647) (xy 342.547194 -309.87111) (xy 342.520745 -309.870648) (xy 342.468354 -309.863351)
			(xy 342.417474 -309.848884) (xy 342.369081 -309.827524) (xy 342.324104 -309.799682) (xy 342.283406 -309.765891)
			(xy 342.265254 -309.74665) (xy 342.259078 -309.74035) (xy 342.243467 -309.732155) (xy 342.234774 -309.730648)
			(xy 342.204802 -309.72633) (xy 342.19592 -309.725425) (xy 342.178483 -309.729206) (xy 342.170766 -309.733696)
			(xy 342.140208 -309.752174) (xy 342.075036 -309.781359) (xy 342.006418 -309.801127) (xy 341.935707 -309.811088)
			(xy 341.900002 -309.811674) (xy 341.869269 -309.81126) (xy 341.80825 -309.803851) (xy 341.74857 -309.789141)
			(xy 341.691097 -309.767344) (xy 341.636672 -309.738778) (xy 341.586086 -309.70386) (xy 341.540079 -309.663098)
			(xy 341.499321 -309.617088) (xy 341.464406 -309.566501) (xy 341.435843 -309.512073) (xy 341.41405 -309.4546)
			(xy 341.399343 -309.394918) (xy 341.391938 -309.333899) (xy 341.391494 -309.303166) (xy 336.908895 -309.303166)
			(xy 336.884804 -309.330355) (xy 336.838791 -309.371113) (xy 336.7882 -309.406027) (xy 336.73377 -309.434589)
			(xy 336.676294 -309.456382) (xy 336.61661 -309.471087) (xy 336.555588 -309.478491) (xy 336.524854 -309.478934)
			(xy 336.494433 -309.478463) (xy 336.43403 -309.471153) (xy 336.374928 -309.456701) (xy 336.346292 -309.446422)
			(xy 336.337935 -309.443747) (xy 336.320399 -309.44362) (xy 336.312002 -309.446168) (xy 336.283808 -309.45582)
			(xy 336.275565 -309.458909) (xy 336.261776 -309.469837) (xy 336.256884 -309.477156) (xy 336.239492 -309.504503)
			(xy 336.198801 -309.554947) (xy 336.152028 -309.599811) (xy 336.099932 -309.638364) (xy 336.043358 -309.669983)
			(xy 335.983224 -309.694155) (xy 335.920505 -309.710487) (xy 335.856219 -309.718714) (xy 335.823814 -309.719218)
			(xy 335.788822 -309.718636) (xy 335.719498 -309.709045) (xy 335.652143 -309.690041) (xy 335.619852 -309.676546)
			(xy 335.607914 -309.671466) (xy 335.582768 -309.673498) (xy 335.489804 -309.734204) (xy 335.477612 -309.756556)
			(xy 335.477612 -309.769764) (xy 335.47717 -309.801308) (xy 335.469371 -309.863911) (xy 335.453888 -309.92507)
			(xy 335.430959 -309.983843) (xy 335.400936 -310.039329) (xy 335.364281 -310.090675) (xy 335.321555 -310.137092)
			(xy 335.273417 -310.177868) (xy 335.220604 -310.212377) (xy 335.163928 -310.240088) (xy 335.104259 -310.260575)
			(xy 335.042515 -310.273525) (xy 334.979643 -310.278737) (xy 334.916609 -310.276133) (xy 334.854382 -310.265752)
			(xy 334.793916 -310.247753) (xy 334.736141 -310.222413) (xy 334.681945 -310.190121) (xy 334.632158 -310.151374)
			(xy 334.587547 -310.106766) (xy 334.548797 -310.056982) (xy 334.516502 -310.002787) (xy 334.491158 -309.945014)
			(xy 334.473156 -309.884549) (xy 334.46277 -309.822322) (xy 334.460162 -309.759289) (xy 333.506735 -309.759289)
			(xy 333.524052 -309.773615) (xy 333.567809 -309.820212) (xy 333.605382 -309.871927) (xy 333.636176 -309.927942)
			(xy 333.659708 -309.987375) (xy 333.675605 -310.049289) (xy 333.683616 -310.112707) (xy 333.684118 -310.144668)
			(xy 333.683616 -310.176629) (xy 333.675605 -310.240047) (xy 333.659708 -310.301961) (xy 333.636176 -310.361394)
			(xy 333.605382 -310.417409) (xy 333.597591 -310.428132) (xy 337.30514 -310.428132) (xy 337.309211 -310.37251)
			(xy 337.321337 -310.318073) (xy 337.34126 -310.265982) (xy 337.368556 -310.217347) (xy 337.402642 -310.173204)
			(xy 337.442791 -310.134495) (xy 337.488149 -310.102044) (xy 337.537749 -310.076543) (xy 337.590533 -310.058536)
			(xy 337.645376 -310.048406) (xy 337.70111 -310.046369) (xy 337.756547 -310.052469) (xy 337.810504 -310.066575)
			(xy 337.861833 -310.088387) (xy 337.909439 -310.117441) (xy 337.952307 -310.153116) (xy 337.989524 -310.194653)
			(xy 338.020297 -310.241166) (xy 338.043969 -310.291663) (xy 338.060037 -310.34507) (xy 338.068157 -310.400246)
			(xy 338.068665 -310.4281) (xy 338.321221 -310.4281) (xy 338.325235 -310.364311) (xy 338.33721 -310.301529)
			(xy 338.35696 -310.240742) (xy 338.384172 -310.18291) (xy 338.418418 -310.128944) (xy 338.459157 -310.079695)
			(xy 338.505747 -310.03594) (xy 338.557453 -309.99837) (xy 338.61346 -309.967575) (xy 338.672885 -309.944043)
			(xy 338.734791 -309.928144) (xy 338.798201 -309.920128) (xy 338.830158 -309.919624) (xy 338.860799 -309.920055)
			(xy 338.921636 -309.92743) (xy 338.981144 -309.942067) (xy 339.038462 -309.963751) (xy 339.092756 -309.99217)
			(xy 339.143239 -310.026911) (xy 339.18918 -310.067469) (xy 339.209888 -310.090058) (xy 339.216238 -310.096916)
			(xy 339.232494 -310.105552) (xy 339.318346 -310.115458) (xy 339.33638 -310.11114) (xy 339.344 -310.105552)
			(xy 339.368184 -310.089318) (xy 339.420443 -310.063598) (xy 339.476002 -310.046113) (xy 339.533571 -310.037267)
			(xy 339.562694 -310.036718) (xy 339.589949 -310.037128) (xy 339.643904 -310.044885) (xy 339.696207 -310.060242)
			(xy 339.745791 -310.082886) (xy 339.791648 -310.112355) (xy 339.832844 -310.148052) (xy 339.868541 -310.189247)
			(xy 339.898012 -310.235104) (xy 339.920656 -310.284688) (xy 339.936013 -310.33699) (xy 339.943771 -310.390945)
			(xy 339.943771 -310.445455) (xy 339.936013 -310.49941) (xy 339.920656 -310.551712) (xy 339.898012 -310.601296)
			(xy 339.868541 -310.647153) (xy 339.832844 -310.688348) (xy 339.791648 -310.724045) (xy 339.745791 -310.753514)
			(xy 339.696207 -310.776158) (xy 339.643904 -310.791515) (xy 339.589949 -310.799272) (xy 339.562694 -310.799734)
			(xy 339.534878 -310.799218) (xy 339.479835 -310.791143) (xy 339.426546 -310.775167) (xy 339.376141 -310.751626)
			(xy 339.352636 -310.736742) (xy 339.344762 -310.731408) (xy 339.326728 -310.727344) (xy 339.24113 -310.73979)
			(xy 339.224874 -310.74868) (xy 339.219032 -310.756046) (xy 339.198244 -310.779884) (xy 339.151785 -310.822803)
			(xy 339.10036 -310.859626) (xy 339.044765 -310.889785) (xy 338.985857 -310.912814) (xy 338.924547 -310.928357)
			(xy 338.861783 -310.936174) (xy 338.830158 -310.93664) (xy 338.798201 -310.936072) (xy 338.734791 -310.928056)
			(xy 338.672885 -310.912157) (xy 338.61346 -310.888625) (xy 338.557453 -310.85783) (xy 338.505747 -310.82026)
			(xy 338.459157 -310.776505) (xy 338.418418 -310.727256) (xy 338.384172 -310.67329) (xy 338.35696 -310.615458)
			(xy 338.33721 -310.554671) (xy 338.325235 -310.491889) (xy 338.321221 -310.4281) (xy 338.068665 -310.4281)
			(xy 338.068666 -310.428132) (xy 338.068157 -310.456018) (xy 338.060037 -310.511194) (xy 338.043969 -310.564601)
			(xy 338.020297 -310.615098) (xy 337.989524 -310.661611) (xy 337.952307 -310.703148) (xy 337.909439 -310.738823)
			(xy 337.861833 -310.767877) (xy 337.810504 -310.789689) (xy 337.756547 -310.803795) (xy 337.70111 -310.809895)
			(xy 337.645376 -310.807858) (xy 337.590533 -310.797728) (xy 337.537749 -310.779721) (xy 337.488149 -310.75422)
			(xy 337.442791 -310.721769) (xy 337.402642 -310.68306) (xy 337.368556 -310.638917) (xy 337.34126 -310.590282)
			(xy 337.321337 -310.538191) (xy 337.309211 -310.483754) (xy 337.30514 -310.428132) (xy 333.597591 -310.428132)
			(xy 333.567809 -310.469124) (xy 333.524052 -310.515721) (xy 333.474799 -310.556466) (xy 333.420828 -310.590717)
			(xy 333.362989 -310.617934) (xy 333.302196 -310.637687) (xy 333.239406 -310.649665) (xy 333.17561 -310.653679)
			(xy 333.111814 -310.649665) (xy 333.049024 -310.637687) (xy 332.988231 -310.617934) (xy 332.930392 -310.590717)
			(xy 332.876421 -310.556466) (xy 332.827168 -310.515721) (xy 332.783411 -310.469124) (xy 332.745838 -310.417409)
			(xy 332.715044 -310.361394) (xy 332.691512 -310.301961) (xy 332.675615 -310.240047) (xy 332.667604 -310.176629)
			(xy 319.007638 -310.176629) (xy 310.852058 -318.332104) (xy 310.846858 -318.33855) (xy 310.840524 -318.353843)
			(xy 310.839612 -318.362076) (xy 310.839612 -319.475612) (xy 310.839612 -321.644264) (xy 310.839178 -321.654329)
			(xy 310.831448 -321.672918) (xy 310.824626 -321.680332) (xy 305.57089 -326.934068) (xy 305.564045 -326.941466)
			(xy 305.556321 -326.960065) (xy 305.555904 -326.970136) (xy 305.555904 -334.812386) (xy 305.556343 -334.822449)
			(xy 305.56408 -334.84103) (xy 305.57089 -334.848454) (xy 305.797204 -335.074768) (xy 305.804601 -335.081617)
			(xy 305.8232 -335.089355) (xy 305.833272 -335.089754)
		)
		(stroke
			(width 0)
			(type solid)
		)
		(fill yes)
		(layer "In6.Cu")
		(net "PVDDCR_CPU1_P0")
	)
	(gr_poly
		(pts
			(xy 385.84632 -302.20031) (xy 385.854769 -302.199949) (xy 385.870718 -302.194356) (xy 385.877562 -302.189388)
			(xy 385.883658 -302.184816) (xy 385.892802 -302.170592) (xy 385.895088 -302.161702) (xy 385.903224 -302.130491)
			(xy 385.926327 -302.070269) (xy 385.956859 -302.013453) (xy 385.99433 -301.960953) (xy 386.03814 -301.913612)
			(xy 386.087583 -301.872192) (xy 386.141868 -301.837355) (xy 386.200121 -301.809663) (xy 386.261409 -301.789559)
			(xy 386.324747 -301.777366) (xy 386.389118 -301.77328) (xy 386.453489 -301.777366) (xy 386.516827 -301.789559)
			(xy 386.578115 -301.809663) (xy 386.636368 -301.837355) (xy 386.690653 -301.872192) (xy 386.740096 -301.913612)
			(xy 386.783906 -301.960953) (xy 386.821377 -302.013453) (xy 386.851909 -302.070269) (xy 386.875012 -302.130491)
			(xy 386.883148 -302.161702) (xy 386.884164 -302.165512) (xy 386.886694 -302.172701) (xy 386.895363 -302.185227)
			(xy 386.901182 -302.19015) (xy 386.907278 -302.194722) (xy 386.915152 -302.197516) (xy 386.919221 -302.198818)
			(xy 386.927645 -302.200227) (xy 386.931916 -302.20031) (xy 390.70788 -302.20031) (xy 390.717717 -302.199773)
			(xy 390.735876 -302.192184) (xy 390.743186 -302.185578) (xy 392.66368 -300.265084) (xy 392.670239 -300.257837)
			(xy 392.677705 -300.239795) (xy 392.678158 -300.230032) (xy 392.678158 -296.520362) (xy 392.678369 -296.498046)
			(xy 392.681805 -296.453547) (xy 392.685016 -296.431462) (xy 392.687525 -296.416013) (xy 392.694005 -296.385389)
			(xy 392.69797 -296.370248) (xy 392.698224 -296.369486) (xy 392.700002 -296.362882) (xy 392.700002 -296.202608)
			(xy 392.699904 -296.197855) (xy 392.698112 -296.188519) (xy 392.696446 -296.184066) (xy 392.687048 -296.159682)
			(xy 392.68146 -296.153078) (xy 392.675612 -296.146007) (xy 392.664683 -296.131265) (xy 392.659616 -296.123614)
			(xy 392.647027 -296.10364) (xy 392.627498 -296.060657) (xy 392.614822 -296.015179) (xy 392.61161 -295.991788)
			(xy 392.610848 -295.986962) (xy 392.59637 -295.956482) (xy 392.590274 -295.95064) (xy 392.556033 -295.916139)
			(xy 392.492941 -295.842184) (xy 392.43644 -295.763079) (xy 392.386946 -295.679411) (xy 392.344828 -295.591798)
			(xy 392.32713 -295.546526) (xy 392.311822 -295.5049) (xy 392.286991 -295.419746) (xy 392.268911 -295.332908)
			(xy 392.262868 -295.28897) (xy 392.262106 -295.284144) (xy 392.258296 -295.273476) (xy 392.256518 -295.270174)
			(xy 392.24712 -295.253918) (xy 392.24585 -295.25214) (xy 392.243388 -295.2484) (xy 392.237391 -295.241751)
			(xy 392.233912 -295.238932) (xy 392.233658 -295.238678) (xy 392.196231 -295.209811) (xy 392.125803 -295.146762)
			(xy 392.060886 -295.078052) (xy 392.001934 -295.00416) (xy 391.949358 -294.925603) (xy 391.903526 -294.842931)
			(xy 391.864759 -294.756719) (xy 391.833326 -294.667572) (xy 391.820908 -294.621966) (xy 391.819827 -294.618144)
			(xy 391.816641 -294.610869) (xy 391.814558 -294.607488) (xy 391.807192 -294.596058) (xy 391.80458 -294.592147)
			(xy 391.798187 -294.585252) (xy 391.794492 -294.582342) (xy 391.774718 -294.567256) (xy 391.739878 -294.531766)
			(xy 391.711239 -294.491106) (xy 391.689556 -294.446349) (xy 391.675401 -294.398672) (xy 391.67181 -294.374062)
			(xy 391.670794 -294.365934) (xy 391.659618 -294.34282) (xy 391.657645 -294.338891) (xy 391.652536 -294.331736)
			(xy 391.649458 -294.328596) (xy 391.625111 -294.304193) (xy 391.579105 -294.252849) (xy 391.55751 -294.22598)
			(xy 391.541702 -294.205756) (xy 391.511717 -294.164084) (xy 391.497566 -294.142668) (xy 391.494772 -294.13835)
			(xy 391.20826 -293.851838) (xy 391.204058 -293.847802) (xy 391.194178 -293.841633) (xy 391.188702 -293.839646)
			(xy 391.178288 -293.83609) (xy 391.166858 -293.83736) (xy 391.133958 -293.840968) (xy 391.067875 -293.844782)
			(xy 391.034778 -293.84498) (xy 391.033508 -293.84498) (xy 390.98197 -293.844395) (xy 390.879325 -293.834969)
			(xy 390.77797 -293.816213) (xy 390.7282 -293.802816) (xy 390.726422 -293.802308) (xy 390.72439 -293.8018)
			(xy 390.716008 -293.80053) (xy 390.711944 -293.800022) (xy 390.711436 -293.800022) (xy 390.710674 -293.799768)
			(xy 390.690862 -293.80434) (xy 390.68629 -293.806372) (xy 390.675019 -293.811053) (xy 390.651878 -293.818813)
			(xy 390.640062 -293.821866) (xy 390.634982 -293.823136) (xy 390.634474 -293.823136) (xy 390.617388 -293.826921)
			(xy 390.58263 -293.830999) (xy 390.565132 -293.831264) (xy 390.562338 -293.831264) (xy 390.532016 -293.830318)
			(xy 390.472644 -293.817904) (xy 390.444482 -293.806626) (xy 390.443974 -293.806372) (xy 390.442196 -293.80561)
			(xy 390.439402 -293.80434) (xy 390.419336 -293.800022) (xy 390.417812 -293.800022) (xy 390.4107 -293.801038)
			(xy 390.40562 -293.8018) (xy 390.366121 -293.812661) (xy 390.285904 -293.829313) (xy 390.245346 -293.835074)
			(xy 390.215626 -293.838807) (xy 390.155904 -293.843511) (xy 390.125966 -293.844472) (xy 390.11479 -293.84625)
			(xy 390.103868 -293.849044) (xy 390.093708 -293.852854) (xy 390.069578 -293.864792) (xy 390.064498 -293.87165)
			(xy 390.06018 -293.877238) (xy 390.054846 -293.88943) (xy 390.054084 -293.895526) (xy 390.053438 -293.901627)
			(xy 390.054719 -293.913825) (xy 390.056624 -293.919656) (xy 390.0805 -293.977314) (xy 390.09066 -294.001952)
			(xy 390.093962 -294.00881) (xy 390.096225 -294.012359) (xy 390.101714 -294.01874) (xy 390.104884 -294.02151)
			(xy 390.106916 -294.023288) (xy 390.11733 -294.031162) (xy 390.124696 -294.032178) (xy 390.125712 -294.032178)
			(xy 390.131554 -294.03294) (xy 390.155918 -294.0364) (xy 390.203182 -294.050094) (xy 390.247638 -294.071189)
			(xy 390.288137 -294.09914) (xy 390.32363 -294.133223) (xy 390.353198 -294.172556) (xy 390.376077 -294.216121)
			(xy 390.391674 -294.262791) (xy 390.399587 -294.311358) (xy 390.400032 -294.335962) (xy 390.39951 -294.361217)
			(xy 390.391197 -294.411039) (xy 390.374796 -294.458813) (xy 390.350755 -294.503236) (xy 390.319731 -294.543096)
			(xy 390.282569 -294.577306) (xy 390.240283 -294.604932) (xy 390.194027 -294.625222) (xy 390.145062 -294.637622)
			(xy 390.094724 -294.641793) (xy 390.044386 -294.637622) (xy 389.995421 -294.625222) (xy 389.949165 -294.604932)
			(xy 389.906879 -294.577306) (xy 389.869717 -294.543096) (xy 389.838693 -294.503236) (xy 389.814652 -294.458813)
			(xy 389.798251 -294.411039) (xy 389.789938 -294.361217) (xy 389.789416 -294.335962) (xy 389.789416 -294.335454)
			(xy 389.790131 -294.305445) (xy 389.801911 -294.246593) (xy 389.812784 -294.218614) (xy 389.813292 -294.217344)
			(xy 389.813546 -294.216836) (xy 389.813546 -294.216582) (xy 389.815918 -294.210328) (xy 389.817718 -294.19708)
			(xy 389.817102 -294.19042) (xy 389.815324 -294.177974) (xy 389.813546 -294.175688) (xy 389.753602 -294.097964)
			(xy 389.749284 -294.092761) (xy 389.738468 -294.084654) (xy 389.732266 -294.081962) (xy 389.726678 -294.079676)
			(xy 389.71347 -294.078152) (xy 389.706612 -294.079168) (xy 389.686284 -294.082005) (xy 389.645348 -294.08506)
			(xy 389.624824 -294.085264) (xy 389.6043 -294.085059) (xy 389.563364 -294.082007) (xy 389.543036 -294.079168)
			(xy 389.542782 -294.079168) (xy 389.536151 -294.078417) (xy 389.5229 -294.079958) (xy 389.51662 -294.082216)
			(xy 389.510778 -294.084502) (xy 389.505698 -294.088312) (xy 389.4963 -294.09771) (xy 389.442706 -294.167306)
			(xy 389.438825 -294.172684) (xy 389.433678 -294.184902) (xy 389.432546 -294.191436) (xy 389.430768 -294.204136)
			(xy 389.436356 -294.217598) (xy 389.447473 -294.245917) (xy 389.459494 -294.305547) (xy 389.460232 -294.335962)
			(xy 389.45971 -294.361217) (xy 389.451397 -294.411039) (xy 389.434996 -294.458813) (xy 389.410955 -294.503236)
			(xy 389.379931 -294.543096) (xy 389.342769 -294.577306) (xy 389.300483 -294.604932) (xy 389.254227 -294.625222)
			(xy 389.205262 -294.637622) (xy 389.154924 -294.641793) (xy 389.104586 -294.637622) (xy 389.055621 -294.625222)
			(xy 389.009365 -294.604932) (xy 388.967079 -294.577306) (xy 388.929917 -294.543096) (xy 388.898893 -294.503236)
			(xy 388.874852 -294.458813) (xy 388.858451 -294.411039) (xy 388.850138 -294.361217) (xy 388.849616 -294.335962)
			(xy 388.85008 -294.311355) (xy 388.857967 -294.262777) (xy 388.873547 -294.216094) (xy 388.896416 -294.172516)
			(xy 388.925981 -294.133172) (xy 388.961476 -294.099082) (xy 389.001981 -294.07113) (xy 389.046447 -294.050039)
			(xy 389.093721 -294.036357) (xy 389.118094 -294.03294) (xy 389.123936 -294.032178) (xy 389.124952 -294.032178)
			(xy 389.132318 -294.031162) (xy 389.142732 -294.023288) (xy 389.145018 -294.02151) (xy 389.149484 -294.017467)
			(xy 389.156545 -294.007712) (xy 389.158988 -294.002206) (xy 389.160004 -293.999666) (xy 389.197342 -293.908988)
			(xy 389.195564 -293.896288) (xy 389.194605 -293.890305) (xy 389.190248 -293.879004) (xy 389.186928 -293.873936)
			(xy 389.184896 -293.871396) (xy 389.172995 -293.855952) (xy 389.151133 -293.823663) (xy 389.141208 -293.80688)
			(xy 389.092186 -293.722044) (xy 389.085258 -293.712131) (xy 389.064563 -293.699687) (xy 389.052562 -293.698168)
			(xy 388.969758 -293.69258) (xy 388.956042 -293.693596) (xy 388.945628 -293.696898) (xy 388.935214 -293.70147)
			(xy 388.926832 -293.712392) (xy 388.912265 -293.730535) (xy 388.878572 -293.76262) (xy 388.840407 -293.789232)
			(xy 388.798653 -293.809756) (xy 388.754271 -293.82372) (xy 388.708287 -293.8308) (xy 388.685024 -293.831264)
			(xy 388.68477 -293.831264) (xy 388.66078 -293.830816) (xy 388.61339 -293.823305) (xy 388.56776 -293.808473)
			(xy 388.525011 -293.786685) (xy 388.486197 -293.758478) (xy 388.452273 -293.724547) (xy 388.424076 -293.685726)
			(xy 388.402299 -293.642972) (xy 388.387478 -293.597338) (xy 388.379979 -293.549946) (xy 388.379462 -293.525956)
			(xy 388.379601 -293.513193) (xy 388.381764 -293.487759) (xy 388.38378 -293.475156) (xy 388.383526 -293.475156)
			(xy 388.387991 -293.451411) (xy 388.403419 -293.405627) (xy 388.425863 -293.362842) (xy 388.454762 -293.324125)
			(xy 388.489397 -293.29044) (xy 388.528903 -293.262629) (xy 388.572295 -293.241383) (xy 388.618491 -293.227235)
			(xy 388.642352 -293.223442) (xy 388.650226 -293.22268) (xy 388.655814 -293.221664) (xy 388.665466 -293.214552)
			(xy 388.670456 -293.210791) (xy 388.678565 -293.201289) (xy 388.681468 -293.195756) (xy 388.718044 -293.12108)
			(xy 388.722878 -293.10971) (xy 388.721966 -293.085049) (xy 388.716266 -293.07409) (xy 388.671308 -292.996874)
			(xy 388.660766 -292.978272) (xy 388.642207 -292.939748) (xy 388.634224 -292.919912) (xy 388.632192 -292.914832)
			(xy 388.630668 -292.910768) (xy 388.629398 -292.907212) (xy 388.618984 -292.899084) (xy 388.613726 -292.895242)
			(xy 388.601767 -292.8901) (xy 388.595362 -292.888924) (xy 388.594092 -292.88867) (xy 388.507478 -292.87724)
			(xy 388.500741 -292.876663) (xy 388.487363 -292.878595) (xy 388.481062 -292.88105) (xy 388.46887 -292.88613)
			(xy 388.465314 -292.890702) (xy 388.460234 -292.89756) (xy 388.445731 -292.916392) (xy 388.411877 -292.949752)
			(xy 388.373265 -292.977467) (xy 388.330827 -292.998867) (xy 388.285586 -293.013437) (xy 388.238634 -293.020824)
			(xy 388.21487 -293.021258) (xy 388.189612 -293.020734) (xy 388.139786 -293.012415) (xy 388.092009 -292.996009)
			(xy 388.047583 -292.971963) (xy 388.00772 -292.940934) (xy 387.973509 -292.903766) (xy 387.945881 -292.861475)
			(xy 387.92559 -292.815214) (xy 387.91319 -292.766243) (xy 387.909018 -292.7159) (xy 387.91319 -292.665557)
			(xy 387.92559 -292.616586) (xy 387.945881 -292.570325) (xy 387.973509 -292.528034) (xy 388.00772 -292.490866)
			(xy 388.047583 -292.459837) (xy 388.092009 -292.435791) (xy 388.139786 -292.419385) (xy 388.189612 -292.411066)
			(xy 388.21487 -292.410642) (xy 388.215124 -292.410642) (xy 388.23889 -292.41109) (xy 388.285849 -292.418451)
			(xy 388.331097 -292.433006) (xy 388.373541 -292.454403) (xy 388.412152 -292.482123) (xy 388.445997 -292.515498)
			(xy 388.460488 -292.53434) (xy 388.464552 -292.539928) (xy 388.475474 -292.548564) (xy 388.481062 -292.55085)
			(xy 388.487114 -292.553239) (xy 388.499976 -292.555172) (xy 388.506462 -292.55466) (xy 388.530846 -292.551612)
			(xy 388.531354 -292.551612) (xy 388.594092 -292.54323) (xy 388.595362 -292.542976) (xy 388.60177 -292.541809)
			(xy 388.613733 -292.53667) (xy 388.618984 -292.532816) (xy 388.629398 -292.524688) (xy 388.630668 -292.521132)
			(xy 388.632192 -292.517068) (xy 388.634224 -292.511988) (xy 388.64491 -292.485735) (xy 388.670866 -292.435344)
			(xy 388.68604 -292.411404) (xy 388.69789 -292.393523) (xy 388.723952 -292.359447) (xy 388.73811 -292.343332)
			(xy 388.738364 -292.343078) (xy 388.740142 -292.341046) (xy 388.744968 -292.335458) (xy 388.74827 -292.326822)
			(xy 388.749032 -292.325044) (xy 388.750265 -292.321096) (xy 388.751544 -292.312924) (xy 388.751572 -292.308788)
			(xy 388.751572 -292.282118) (xy 388.75109 -292.272547) (xy 388.743902 -292.254797) (xy 388.737602 -292.247574)
			(xy 388.718806 -292.229794) (xy 388.70763 -292.222682) (xy 388.691882 -292.216078) (xy 388.690866 -292.21557)
			(xy 388.680452 -292.211506) (xy 388.673594 -292.210998) (xy 388.671308 -292.210998) (xy 388.646802 -292.209424)
			(xy 388.598727 -292.199434) (xy 388.552869 -292.18188) (xy 388.510411 -292.157215) (xy 388.472447 -292.126074)
			(xy 388.439954 -292.08926) (xy 388.41377 -292.047722) (xy 388.39457 -292.002529) (xy 388.382848 -291.954846)
			(xy 388.378907 -291.905902) (xy 388.382848 -291.856958) (xy 388.394569 -291.809275) (xy 388.413768 -291.764082)
			(xy 388.439952 -291.722543) (xy 388.472444 -291.685728) (xy 388.510408 -291.654587) (xy 388.552866 -291.629922)
			(xy 388.598723 -291.612367) (xy 388.646799 -291.602376) (xy 388.671308 -291.60089) (xy 388.673594 -291.60089)
			(xy 388.680452 -291.600382) (xy 388.690866 -291.596318) (xy 388.691882 -291.59581) (xy 388.70763 -291.589206)
			(xy 388.718806 -291.582094) (xy 388.737602 -291.564314) (xy 388.743958 -291.557125) (xy 388.751151 -291.539355)
			(xy 388.751572 -291.52977) (xy 388.751572 -291.514784) (xy 388.671308 -291.376862) (xy 388.660763 -291.358261)
			(xy 388.642199 -291.319739) (xy 388.634224 -291.2999) (xy 388.632192 -291.29482) (xy 388.630668 -291.290756)
			(xy 388.629398 -291.2872) (xy 388.618984 -291.279072) (xy 388.613726 -291.275231) (xy 388.601766 -291.27009)
			(xy 388.595362 -291.268912) (xy 388.594092 -291.268658) (xy 388.507478 -291.257228) (xy 388.500741 -291.25665)
			(xy 388.487363 -291.258582) (xy 388.481062 -291.261038) (xy 388.46887 -291.266118) (xy 388.465314 -291.27069)
			(xy 388.460234 -291.277548) (xy 388.445732 -291.29638) (xy 388.411878 -291.329742) (xy 388.373266 -291.357458)
			(xy 388.330828 -291.378859) (xy 388.285586 -291.393429) (xy 388.238635 -291.400817) (xy 388.21487 -291.401246)
			(xy 388.189613 -291.400722) (xy 388.139789 -291.392403) (xy 388.092014 -291.375998) (xy 388.04759 -291.351953)
			(xy 388.007729 -291.320924) (xy 387.973519 -291.283759) (xy 387.945892 -291.241469) (xy 387.925602 -291.19521)
			(xy 387.913202 -291.146241) (xy 387.909031 -291.0959) (xy 387.913202 -291.045559) (xy 387.925602 -290.99659)
			(xy 387.945892 -290.950331) (xy 387.973519 -290.908041) (xy 388.007729 -290.870876) (xy 388.04759 -290.839847)
			(xy 388.092014 -290.815802) (xy 388.139789 -290.799397) (xy 388.189613 -290.791078) (xy 388.21487 -290.79063)
			(xy 388.215124 -290.79063) (xy 388.23889 -290.791078) (xy 388.285849 -290.798439) (xy 388.331098 -290.812993)
			(xy 388.373542 -290.834389) (xy 388.412155 -290.86211) (xy 388.446 -290.895483) (xy 388.460488 -290.914328)
			(xy 388.464552 -290.919916) (xy 388.475474 -290.928552) (xy 388.481062 -290.930838) (xy 388.487114 -290.933227)
			(xy 388.499976 -290.93516) (xy 388.506462 -290.934648) (xy 388.530846 -290.9316) (xy 388.531354 -290.9316)
			(xy 388.594092 -290.923218) (xy 388.595362 -290.922964) (xy 388.60177 -290.921797) (xy 388.613733 -290.916656)
			(xy 388.618984 -290.912804) (xy 388.629398 -290.904676) (xy 388.630668 -290.90112) (xy 388.632192 -290.897056)
			(xy 388.634224 -290.891976) (xy 388.64491 -290.865724) (xy 388.670868 -290.815333) (xy 388.68604 -290.791392)
			(xy 388.69789 -290.773511) (xy 388.723953 -290.739436) (xy 388.73811 -290.72332) (xy 388.738364 -290.723066)
			(xy 388.740142 -290.721034) (xy 388.744968 -290.715446) (xy 388.74827 -290.70681) (xy 388.749032 -290.705032)
			(xy 388.750264 -290.701083) (xy 388.751541 -290.692912) (xy 388.751572 -290.688776) (xy 388.751572 -290.662106)
			(xy 388.751087 -290.652535) (xy 388.743897 -290.634789) (xy 388.737602 -290.627562) (xy 388.718806 -290.609782)
			(xy 388.70763 -290.60267) (xy 388.691882 -290.596066) (xy 388.690866 -290.595558) (xy 388.680452 -290.591494)
			(xy 388.673594 -290.590986) (xy 388.671308 -290.590986) (xy 388.646803 -290.589412) (xy 388.59873 -290.579422)
			(xy 388.552874 -290.561868) (xy 388.510418 -290.537204) (xy 388.472455 -290.506065) (xy 388.439964 -290.469252)
			(xy 388.413781 -290.427715) (xy 388.394582 -290.382524) (xy 388.38286 -290.334843) (xy 388.378919 -290.285901)
			(xy 388.38286 -290.236959) (xy 388.394581 -290.189278) (xy 388.41378 -290.144087) (xy 388.439962 -290.10255)
			(xy 388.472453 -290.065737) (xy 388.510416 -290.034597) (xy 388.552872 -290.009933) (xy 388.598727 -289.992379)
			(xy 388.646801 -289.982389) (xy 388.671308 -289.980878) (xy 388.673594 -289.980878) (xy 388.680452 -289.98037)
			(xy 388.690866 -289.976306) (xy 388.691882 -289.975798) (xy 388.70763 -289.969194) (xy 388.718806 -289.962082)
			(xy 388.737602 -289.944302) (xy 388.743956 -289.937113) (xy 388.751145 -289.919343) (xy 388.751572 -289.909758)
			(xy 388.751572 -289.894772) (xy 388.671308 -289.75685) (xy 388.660764 -289.738249) (xy 388.6422 -289.699727)
			(xy 388.634224 -289.679888) (xy 388.632192 -289.674808) (xy 388.630668 -289.670744) (xy 388.629398 -289.667188)
			(xy 388.618984 -289.65906) (xy 388.613726 -289.65522) (xy 388.601766 -289.65008) (xy 388.595362 -289.6489)
			(xy 388.594092 -289.648646) (xy 388.507478 -289.637216) (xy 388.500741 -289.636638) (xy 388.487362 -289.63857)
			(xy 388.481062 -289.641026) (xy 388.46887 -289.646106) (xy 388.465314 -289.650678) (xy 388.460234 -289.657536)
			(xy 388.445732 -289.676369) (xy 388.411879 -289.709732) (xy 388.373268 -289.737449) (xy 388.330829 -289.758851)
			(xy 388.285587 -289.773422) (xy 388.238635 -289.78081) (xy 388.21487 -289.781234) (xy 388.189614 -289.78071)
			(xy 388.139792 -289.772392) (xy 388.092018 -289.755987) (xy 388.047596 -289.731943) (xy 388.007737 -289.700916)
			(xy 387.973528 -289.663751) (xy 387.945902 -289.621463) (xy 387.925613 -289.575206) (xy 387.913214 -289.526239)
			(xy 387.909043 -289.4759) (xy 387.913214 -289.425561) (xy 387.925613 -289.376594) (xy 387.945902 -289.330337)
			(xy 387.973528 -289.288049) (xy 388.007737 -289.250884) (xy 388.047596 -289.219857) (xy 388.092018 -289.195813)
			(xy 388.139792 -289.179408) (xy 388.189614 -289.17109) (xy 388.21487 -289.170618) (xy 388.215124 -289.170618)
			(xy 388.23889 -289.171066) (xy 388.28585 -289.178426) (xy 388.331099 -289.19298) (xy 388.373544 -289.214376)
			(xy 388.412157 -289.242096) (xy 388.446004 -289.275468) (xy 388.460488 -289.294316) (xy 388.464552 -289.299904)
			(xy 388.475474 -289.30854) (xy 388.481062 -289.310826) (xy 388.487114 -289.313215) (xy 388.499976 -289.315149)
			(xy 388.506462 -289.314636) (xy 388.530846 -289.311588) (xy 388.531354 -289.311588) (xy 388.594092 -289.303206)
			(xy 388.595362 -289.302952) (xy 388.601771 -289.301787) (xy 388.613739 -289.296654) (xy 388.618984 -289.292792)
			(xy 388.629398 -289.284664) (xy 388.630668 -289.281108) (xy 388.632192 -289.277044) (xy 388.634224 -289.271964)
			(xy 388.644911 -289.245712) (xy 388.670869 -289.195322) (xy 388.68604 -289.17138) (xy 388.697891 -289.1535)
			(xy 388.723953 -289.119424) (xy 388.73811 -289.103308) (xy 388.738364 -289.103054) (xy 388.740142 -289.101022)
			(xy 388.744968 -289.095434) (xy 388.74827 -289.086798) (xy 388.749032 -289.08502) (xy 388.750263 -289.081071)
			(xy 388.751538 -289.0729) (xy 388.751572 -289.068764) (xy 388.751572 -289.042094) (xy 388.751085 -289.032524)
			(xy 388.743892 -289.014781) (xy 388.737602 -289.00755) (xy 388.718806 -288.98977) (xy 388.70763 -288.982658)
			(xy 388.691882 -288.976054) (xy 388.690866 -288.975546) (xy 388.680452 -288.971482) (xy 388.673594 -288.970974)
			(xy 388.671308 -288.970974) (xy 388.646804 -288.9694) (xy 388.598733 -288.95941) (xy 388.552879 -288.941857)
			(xy 388.510424 -288.917194) (xy 388.472463 -288.886056) (xy 388.439973 -288.849245) (xy 388.413791 -288.807709)
			(xy 388.394593 -288.76252) (xy 388.382872 -288.714841) (xy 388.378931 -288.665901) (xy 388.382872 -288.616961)
			(xy 388.394592 -288.569282) (xy 388.41379 -288.524092) (xy 388.439972 -288.482557) (xy 388.472462 -288.445745)
			(xy 388.510423 -288.414607) (xy 388.552877 -288.389943) (xy 388.598731 -288.372391) (xy 388.646803 -288.362401)
			(xy 388.671308 -288.360866) (xy 388.673594 -288.360866) (xy 388.680452 -288.360358) (xy 388.690866 -288.356294)
			(xy 388.691882 -288.355786) (xy 388.70763 -288.349182) (xy 388.718806 -288.34207) (xy 388.737602 -288.32429)
			(xy 388.743954 -288.3171) (xy 388.751139 -288.29933) (xy 388.751572 -288.289746) (xy 388.751572 -288.275014)
			(xy 388.671308 -288.137092) (xy 388.660766 -288.11849) (xy 388.642205 -288.079966) (xy 388.634224 -288.06013)
			(xy 388.632192 -288.05505) (xy 388.630668 -288.050732) (xy 388.629398 -288.04743) (xy 388.618984 -288.039302)
			(xy 388.613727 -288.035459) (xy 388.601768 -288.030315) (xy 388.595362 -288.029142) (xy 388.594092 -288.028888)
			(xy 388.507478 -288.017458) (xy 388.500741 -288.016881) (xy 388.487362 -288.01881) (xy 388.481062 -288.021268)
			(xy 388.46887 -288.026348) (xy 388.465314 -288.03092) (xy 388.460234 -288.037778) (xy 388.445731 -288.056609)
			(xy 388.411876 -288.089967) (xy 388.373264 -288.117681) (xy 388.330825 -288.13908) (xy 388.285585 -288.153648)
			(xy 388.238634 -288.161035) (xy 388.21487 -288.161476) (xy 388.189619 -288.160952) (xy 388.139806 -288.152635)
			(xy 388.092042 -288.136234) (xy 388.047628 -288.112194) (xy 388.007776 -288.081173) (xy 387.973574 -288.044016)
			(xy 387.945953 -288.001736) (xy 387.925668 -287.955487) (xy 387.913271 -287.90653) (xy 387.909101 -287.8562)
			(xy 387.913271 -287.80587) (xy 387.925668 -287.756913) (xy 387.945953 -287.710664) (xy 387.973574 -287.668384)
			(xy 388.007776 -287.631227) (xy 388.047628 -287.600206) (xy 388.092042 -287.576166) (xy 388.139806 -287.559765)
			(xy 388.189619 -287.551448) (xy 388.21487 -287.55086) (xy 388.215124 -287.55086) (xy 388.238891 -287.551308)
			(xy 388.285852 -287.558667) (xy 388.331103 -287.573219) (xy 388.373551 -287.594612) (xy 388.412168 -287.622328)
			(xy 388.44602 -287.655698) (xy 388.460488 -287.674558) (xy 388.464552 -287.680146) (xy 388.475474 -287.688782)
			(xy 388.481062 -287.691068) (xy 388.487113 -287.69346) (xy 388.499976 -287.695396) (xy 388.506462 -287.694878)
			(xy 388.530846 -287.69183) (xy 388.531354 -287.69183) (xy 388.594092 -287.683448) (xy 388.595362 -287.683194)
			(xy 388.60177 -287.682028) (xy 388.613735 -287.67689) (xy 388.618984 -287.673034) (xy 388.629398 -287.664906)
			(xy 388.630668 -287.66135) (xy 388.632192 -287.657286) (xy 388.634224 -287.652206) (xy 388.644909 -287.625953)
			(xy 388.670864 -287.575561) (xy 388.68604 -287.551622) (xy 388.697892 -287.533743) (xy 388.723958 -287.49967)
			(xy 388.73811 -287.48355) (xy 388.738364 -287.483296) (xy 388.740142 -287.481264) (xy 388.744968 -287.475676)
			(xy 388.74827 -287.46704) (xy 388.749032 -287.465262) (xy 388.750266 -287.461314) (xy 388.751548 -287.453142)
			(xy 388.751572 -287.449006) (xy 388.751572 -287.422082) (xy 388.751101 -287.412506) (xy 388.743929 -287.39474)
			(xy 388.737602 -287.387538) (xy 388.718806 -287.369758) (xy 388.70763 -287.362646) (xy 388.691882 -287.356042)
			(xy 388.690866 -287.355534) (xy 388.680452 -287.35147) (xy 388.673594 -287.350962) (xy 388.671308 -287.350962)
			(xy 388.646805 -287.349388) (xy 388.598736 -287.339398) (xy 388.552884 -287.321846) (xy 388.510431 -287.297184)
			(xy 388.472471 -287.266047) (xy 388.439982 -287.229237) (xy 388.413802 -287.187703) (xy 388.394604 -287.142516)
			(xy 388.382884 -287.094839) (xy 388.378943 -287.0459) (xy 388.382884 -286.996962) (xy 388.394604 -286.949285)
			(xy 388.413801 -286.904097) (xy 388.439982 -286.862563) (xy 388.47247 -286.825754) (xy 388.51043 -286.794616)
			(xy 388.552883 -286.769954) (xy 388.598735 -286.752402) (xy 388.646805 -286.742412) (xy 388.671308 -286.740854)
			(xy 388.673594 -286.740854) (xy 388.680452 -286.740346) (xy 388.690866 -286.736282) (xy 388.691882 -286.735774)
			(xy 388.70763 -286.72917) (xy 388.718806 -286.722058) (xy 388.737602 -286.704278) (xy 388.743952 -286.697088)
			(xy 388.751133 -286.679318) (xy 388.751572 -286.669734) (xy 388.751572 -286.655002) (xy 388.671308 -286.51708)
			(xy 388.660766 -286.498478) (xy 388.642206 -286.459954) (xy 388.634224 -286.440118) (xy 388.632192 -286.435038)
			(xy 388.630668 -286.43072) (xy 388.629398 -286.427418) (xy 388.618984 -286.41929) (xy 388.613727 -286.415448)
			(xy 388.601767 -286.410305) (xy 388.595362 -286.40913) (xy 388.594092 -286.408876) (xy 388.507478 -286.397446)
			(xy 388.500741 -286.396869) (xy 388.487363 -286.398801) (xy 388.481062 -286.401256) (xy 388.46887 -286.406336)
			(xy 388.465314 -286.410908) (xy 388.460234 -286.417766) (xy 388.445731 -286.436597) (xy 388.411877 -286.469957)
			(xy 388.373265 -286.497671) (xy 388.330826 -286.519071) (xy 388.285585 -286.533641) (xy 388.238634 -286.541028)
			(xy 388.21487 -286.541464) (xy 388.18962 -286.54094) (xy 388.139809 -286.532624) (xy 388.092046 -286.516223)
			(xy 388.047634 -286.492184) (xy 388.007784 -286.461164) (xy 387.973583 -286.424008) (xy 387.945964 -286.38173)
			(xy 387.925679 -286.335483) (xy 387.913283 -286.286528) (xy 387.909113 -286.2362) (xy 387.913283 -286.185872)
			(xy 387.925679 -286.136917) (xy 387.945964 -286.09067) (xy 387.973583 -286.048392) (xy 388.007784 -286.011236)
			(xy 388.047634 -285.980216) (xy 388.092046 -285.956177) (xy 388.139809 -285.939776) (xy 388.18962 -285.93146)
			(xy 388.21487 -285.930848) (xy 388.215124 -285.930848) (xy 388.23889 -285.931296) (xy 388.285848 -285.938657)
			(xy 388.331097 -285.953212) (xy 388.37354 -285.974609) (xy 388.412151 -286.00233) (xy 388.445995 -286.035705)
			(xy 388.460488 -286.054546) (xy 388.464552 -286.060134) (xy 388.475474 -286.06877) (xy 388.481062 -286.071056)
			(xy 388.487114 -286.073444) (xy 388.499976 -286.075377) (xy 388.506462 -286.074866) (xy 388.530846 -286.071818)
			(xy 388.531354 -286.071818) (xy 388.594092 -286.063436) (xy 388.595362 -286.063182) (xy 388.60177 -286.062016)
			(xy 388.613734 -286.056876) (xy 388.618984 -286.053022) (xy 388.629398 -286.044894) (xy 388.630668 -286.041338)
			(xy 388.632192 -286.037274) (xy 388.634224 -286.032194) (xy 388.644909 -286.005941) (xy 388.670866 -285.95555)
			(xy 388.68604 -285.93161) (xy 388.69789 -285.913729) (xy 388.723951 -285.879652) (xy 388.73811 -285.863538)
			(xy 388.738364 -285.863284) (xy 388.740142 -285.861252) (xy 388.744968 -285.855664) (xy 388.74827 -285.847028)
			(xy 388.749032 -285.84525) (xy 388.750265 -285.841302) (xy 388.751546 -285.83313) (xy 388.751572 -285.828994)
			(xy 388.751572 -285.802324) (xy 388.751091 -285.792752) (xy 388.743905 -285.775001) (xy 388.737602 -285.76778)
			(xy 388.718806 -285.75) (xy 388.70763 -285.742888) (xy 388.691882 -285.736284) (xy 388.690866 -285.735776)
			(xy 388.680452 -285.731712) (xy 388.673594 -285.731204) (xy 388.671308 -285.731204) (xy 388.646802 -285.72963)
			(xy 388.598726 -285.71964) (xy 388.552867 -285.702086) (xy 388.510408 -285.67742) (xy 388.472443 -285.646279)
			(xy 388.439949 -285.609464) (xy 388.413765 -285.567925) (xy 388.394564 -285.522731) (xy 388.382842 -285.475047)
			(xy 388.378901 -285.426102) (xy 388.382842 -285.377157) (xy 388.394563 -285.329473) (xy 388.413763 -285.284279)
			(xy 388.439947 -285.242739) (xy 388.47244 -285.205924) (xy 388.510404 -285.174782) (xy 388.552863 -285.150116)
			(xy 388.598721 -285.132562) (xy 388.646798 -285.122571) (xy 388.671308 -285.121096) (xy 388.673594 -285.121096)
			(xy 388.680452 -285.120588) (xy 388.690866 -285.116524) (xy 388.691882 -285.116016) (xy 388.70763 -285.109412)
			(xy 388.718806 -285.1023) (xy 388.737602 -285.08452) (xy 388.743959 -285.077332) (xy 388.751154 -285.059562)
			(xy 388.751572 -285.049976) (xy 388.751572 -285.03499) (xy 388.671308 -284.897068) (xy 388.660766 -284.878466)
			(xy 388.642207 -284.839941) (xy 388.634224 -284.820106) (xy 388.632192 -284.815026) (xy 388.630668 -284.810708)
			(xy 388.629398 -284.807406) (xy 388.618984 -284.799278) (xy 388.613726 -284.795436) (xy 388.601767 -284.790295)
			(xy 388.595362 -284.789118) (xy 388.594092 -284.788864) (xy 388.507478 -284.777434) (xy 388.500741 -284.776857)
			(xy 388.487363 -284.778789) (xy 388.481062 -284.781244) (xy 388.46887 -284.786324) (xy 388.465314 -284.790896)
			(xy 388.460234 -284.797754) (xy 388.445732 -284.816586) (xy 388.411878 -284.849947) (xy 388.373266 -284.877662)
			(xy 388.330827 -284.899063) (xy 388.285586 -284.913633) (xy 388.238634 -284.921021) (xy 388.21487 -284.921452)
			(xy 388.189613 -284.920928) (xy 388.139787 -284.91261) (xy 388.092011 -284.896204) (xy 388.047586 -284.872158)
			(xy 388.007725 -284.841129) (xy 387.973513 -284.803963) (xy 387.945886 -284.761672) (xy 387.925596 -284.715412)
			(xy 387.913196 -284.666442) (xy 387.909024 -284.6161) (xy 387.913196 -284.565758) (xy 387.925596 -284.516788)
			(xy 387.945886 -284.470528) (xy 387.973513 -284.428237) (xy 388.007725 -284.391071) (xy 388.047586 -284.360042)
			(xy 388.092011 -284.335996) (xy 388.139787 -284.31959) (xy 388.189613 -284.311272) (xy 388.21487 -284.310836)
			(xy 388.215124 -284.310836) (xy 388.23889 -284.311284) (xy 388.285849 -284.318645) (xy 388.331098 -284.333199)
			(xy 388.373542 -284.354596) (xy 388.412154 -284.382317) (xy 388.445999 -284.41569) (xy 388.460488 -284.434534)
			(xy 388.464552 -284.440122) (xy 388.475474 -284.448758) (xy 388.481062 -284.451044) (xy 388.487114 -284.453433)
			(xy 388.499976 -284.455366) (xy 388.506462 -284.454854) (xy 388.530846 -284.451806) (xy 388.531354 -284.451806)
			(xy 388.594092 -284.443424) (xy 388.595362 -284.44317) (xy 388.60177 -284.442003) (xy 388.613733 -284.436863)
			(xy 388.618984 -284.43301) (xy 388.629398 -284.424882) (xy 388.630668 -284.421326) (xy 388.632192 -284.417262)
			(xy 388.634224 -284.412182) (xy 388.64491 -284.38593) (xy 388.670867 -284.335539) (xy 388.68604 -284.311598)
			(xy 388.69789 -284.293717) (xy 388.723952 -284.259641) (xy 388.73811 -284.243526) (xy 388.738364 -284.243272)
			(xy 388.740142 -284.24124) (xy 388.744968 -284.235652) (xy 388.74827 -284.227016) (xy 388.749032 -284.225238)
			(xy 388.750264 -284.22129) (xy 388.751543 -284.213118) (xy 388.751572 -284.208982) (xy 388.751572 -284.182312)
			(xy 388.751089 -284.172741) (xy 388.743899 -284.154993) (xy 388.737602 -284.147768) (xy 388.718806 -284.129988)
			(xy 388.70763 -284.122876) (xy 388.691882 -284.116272) (xy 388.690866 -284.115764) (xy 388.680452 -284.1117)
			(xy 388.673594 -284.111192) (xy 388.671308 -284.111192) (xy 388.646803 -284.109618) (xy 388.598728 -284.099628)
			(xy 388.552872 -284.082074) (xy 388.510415 -284.05741) (xy 388.472451 -284.02627) (xy 388.439959 -283.989457)
			(xy 388.413775 -283.947919) (xy 388.394576 -283.902727) (xy 388.382854 -283.855045) (xy 388.378913 -283.806102)
			(xy 388.382853 -283.757159) (xy 388.394574 -283.709477) (xy 388.413774 -283.664284) (xy 388.439957 -283.622746)
			(xy 388.472448 -283.585933) (xy 388.510412 -283.554792) (xy 388.552869 -283.530127) (xy 388.598725 -283.512573)
			(xy 388.6468 -283.502582) (xy 388.671308 -283.501084) (xy 388.673594 -283.501084) (xy 388.680452 -283.500576)
			(xy 388.690866 -283.496512) (xy 388.691882 -283.496004) (xy 388.70763 -283.4894) (xy 388.718806 -283.482288)
			(xy 388.737602 -283.464508) (xy 388.743957 -283.457319) (xy 388.751148 -283.439549) (xy 388.751572 -283.429964)
			(xy 388.751572 -283.414978) (xy 388.671308 -283.277056) (xy 388.660764 -283.258455) (xy 388.642199 -283.219933)
			(xy 388.634224 -283.200094) (xy 388.632192 -283.195014) (xy 388.630668 -283.190696) (xy 388.629398 -283.187394)
			(xy 388.618984 -283.179266) (xy 388.613726 -283.175425) (xy 388.601766 -283.170285) (xy 388.595362 -283.169106)
			(xy 388.594092 -283.168852) (xy 388.507478 -283.157422) (xy 388.500741 -283.156844) (xy 388.487362 -283.158776)
			(xy 388.481062 -283.161232) (xy 388.46887 -283.166312) (xy 388.465314 -283.170884) (xy 388.460234 -283.177742)
			(xy 388.445732 -283.196575) (xy 388.411879 -283.229937) (xy 388.373267 -283.257653) (xy 388.330828 -283.279055)
			(xy 388.285587 -283.293626) (xy 388.238635 -283.301013) (xy 388.21487 -283.30144) (xy 388.189614 -283.300916)
			(xy 388.139791 -283.292597) (xy 388.092016 -283.276192) (xy 388.047593 -283.252148) (xy 388.007733 -283.22112)
			(xy 387.973523 -283.183955) (xy 387.945897 -283.141666) (xy 387.925607 -283.095408) (xy 387.913208 -283.04644)
			(xy 387.909037 -282.9961) (xy 387.913208 -282.94576) (xy 387.925607 -282.896792) (xy 387.945897 -282.850534)
			(xy 387.973523 -282.808245) (xy 388.007733 -282.77108) (xy 388.047593 -282.740052) (xy 388.092016 -282.716008)
			(xy 388.139791 -282.699603) (xy 388.189614 -282.691284) (xy 388.21487 -282.690824) (xy 388.215124 -282.690824)
			(xy 388.23889 -282.691272) (xy 388.285849 -282.698633) (xy 388.331099 -282.713187) (xy 388.373543 -282.734583)
			(xy 388.412156 -282.762303) (xy 388.446002 -282.795676) (xy 388.460488 -282.814522) (xy 388.464552 -282.82011)
			(xy 388.475474 -282.828746) (xy 388.481062 -282.831032) (xy 388.487114 -282.833421) (xy 388.499976 -282.835355)
			(xy 388.506462 -282.834842) (xy 388.530846 -282.831794) (xy 388.531354 -282.831794) (xy 388.594092 -282.823412)
			(xy 388.595362 -282.823158) (xy 388.60177 -282.821991) (xy 388.613732 -282.81685) (xy 388.618984 -282.812998)
			(xy 388.629398 -282.80487) (xy 388.630668 -282.801314) (xy 388.632192 -282.79725) (xy 388.634224 -282.79217)
			(xy 388.64491 -282.765918) (xy 388.670869 -282.715528) (xy 388.68604 -282.691586) (xy 388.69789 -282.673706)
			(xy 388.723953 -282.63963) (xy 388.73811 -282.623514) (xy 388.738364 -282.62326) (xy 388.740142 -282.621228)
			(xy 388.744968 -282.61564) (xy 388.74827 -282.607004) (xy 388.749032 -282.605226) (xy 388.750263 -282.601277)
			(xy 388.75154 -282.593106) (xy 388.751572 -282.58897) (xy 388.751572 -282.5623) (xy 388.751086 -282.55273)
			(xy 388.743894 -282.534985) (xy 388.737602 -282.527756) (xy 388.718806 -282.509976) (xy 388.70763 -282.502864)
			(xy 388.691882 -282.49626) (xy 388.690866 -282.495752) (xy 388.680452 -282.491688) (xy 388.673594 -282.49118)
			(xy 388.671308 -282.49118) (xy 388.646804 -282.489606) (xy 388.598731 -282.479616) (xy 388.552877 -282.462063)
			(xy 388.510421 -282.437399) (xy 388.472459 -282.40626) (xy 388.439968 -282.369449) (xy 388.413786 -282.327912)
			(xy 388.394587 -282.282722) (xy 388.382866 -282.235042) (xy 388.378925 -282.186101) (xy 388.382866 -282.13716)
			(xy 388.394586 -282.08948) (xy 388.413785 -282.04429) (xy 388.439967 -282.002753) (xy 388.472457 -281.965941)
			(xy 388.510419 -281.934802) (xy 388.552875 -281.910138) (xy 388.598729 -281.892585) (xy 388.646802 -281.882595)
			(xy 388.671308 -281.881072) (xy 388.673594 -281.881072) (xy 388.680452 -281.880564) (xy 388.690866 -281.8765)
			(xy 388.691882 -281.875992) (xy 388.70763 -281.869388) (xy 388.718806 -281.862276) (xy 388.737602 -281.844496)
			(xy 388.743955 -281.837306) (xy 388.751142 -281.819537) (xy 388.751572 -281.809952) (xy 388.751572 -281.794966)
			(xy 388.671308 -281.657044) (xy 388.660764 -281.638443) (xy 388.6422 -281.59992) (xy 388.634224 -281.580082)
			(xy 388.632192 -281.575002) (xy 388.630668 -281.570684) (xy 388.629398 -281.567382) (xy 388.618984 -281.559254)
			(xy 388.613725 -281.555414) (xy 388.601766 -281.550275) (xy 388.595362 -281.549094) (xy 388.594092 -281.54884)
			(xy 388.507478 -281.53741) (xy 388.500741 -281.536832) (xy 388.487362 -281.538764) (xy 388.481062 -281.54122)
			(xy 388.46887 -281.5463) (xy 388.465314 -281.550872) (xy 388.460234 -281.55773) (xy 388.445732 -281.576563)
			(xy 388.41188 -281.609927) (xy 388.373268 -281.637644) (xy 388.330829 -281.659047) (xy 388.285588 -281.673618)
			(xy 388.238635 -281.681006) (xy 388.21487 -281.681428) (xy 388.189615 -281.680904) (xy 388.139793 -281.672586)
			(xy 388.092021 -281.656181) (xy 388.047599 -281.632138) (xy 388.007741 -281.601111) (xy 387.973533 -281.563948)
			(xy 387.945908 -281.521661) (xy 387.925619 -281.475404) (xy 387.91322 -281.426438) (xy 387.909049 -281.3761)
			(xy 387.91322 -281.325762) (xy 387.925619 -281.276796) (xy 387.945908 -281.230539) (xy 387.973533 -281.188252)
			(xy 388.007741 -281.151089) (xy 388.047599 -281.120062) (xy 388.092021 -281.096019) (xy 388.139793 -281.079614)
			(xy 388.189615 -281.071296) (xy 388.21487 -281.070812) (xy 388.215124 -281.070812) (xy 388.23889 -281.07126)
			(xy 388.28585 -281.07862) (xy 388.331099 -281.093174) (xy 388.373545 -281.11457) (xy 388.412158 -281.142289)
			(xy 388.446005 -281.175661) (xy 388.460488 -281.19451) (xy 388.464552 -281.200098) (xy 388.475474 -281.208734)
			(xy 388.481062 -281.21102) (xy 388.487114 -281.213409) (xy 388.499976 -281.215344) (xy 388.506462 -281.21483)
			(xy 388.530846 -281.211782) (xy 388.531354 -281.211782) (xy 388.594092 -281.2034) (xy 388.595362 -281.203146)
			(xy 388.601771 -281.201981) (xy 388.613738 -281.196847) (xy 388.618984 -281.192986) (xy 388.629398 -281.184858)
			(xy 388.630668 -281.181302) (xy 388.632192 -281.177238) (xy 388.634224 -281.172158) (xy 388.644911 -281.145906)
			(xy 388.67087 -281.095516) (xy 388.68604 -281.071574) (xy 388.697891 -281.053694) (xy 388.723954 -281.019619)
			(xy 388.73811 -281.003502) (xy 388.738364 -281.003248) (xy 388.740142 -281.001216) (xy 388.744968 -280.995628)
			(xy 388.74827 -280.986992) (xy 388.749032 -280.985214) (xy 388.750262 -280.981265) (xy 388.751537 -280.973094)
			(xy 388.751572 -280.968958) (xy 388.751572 -280.942288) (xy 388.751084 -280.932719) (xy 388.743889 -280.914977)
			(xy 388.737602 -280.907744) (xy 388.718806 -280.889964) (xy 388.70763 -280.882852) (xy 388.691882 -280.876248)
			(xy 388.690866 -280.87574) (xy 388.680452 -280.871676) (xy 388.673594 -280.871168) (xy 388.671308 -280.871168)
			(xy 388.646805 -280.869594) (xy 388.598734 -280.859604) (xy 388.552881 -280.842052) (xy 388.510428 -280.817389)
			(xy 388.472467 -280.786251) (xy 388.439978 -280.749441) (xy 388.413796 -280.707906) (xy 388.394598 -280.662718)
			(xy 388.382878 -280.61504) (xy 388.378937 -280.566101) (xy 388.382878 -280.517161) (xy 388.394598 -280.469483)
			(xy 388.413796 -280.424295) (xy 388.439977 -280.38276) (xy 388.472466 -280.345949) (xy 388.510427 -280.314812)
			(xy 388.55288 -280.290149) (xy 388.598733 -280.272596) (xy 388.646804 -280.262607) (xy 388.671308 -280.26106)
			(xy 388.673594 -280.26106) (xy 388.680452 -280.260552) (xy 388.690866 -280.256488) (xy 388.691882 -280.25598)
			(xy 388.70763 -280.249376) (xy 388.718806 -280.242264) (xy 388.737602 -280.224484) (xy 388.743953 -280.217294)
			(xy 388.751136 -280.199524) (xy 388.751572 -280.18994) (xy 388.751572 -280.174954) (xy 388.671308 -280.037032)
			(xy 388.660764 -280.018431) (xy 388.642201 -279.979908) (xy 388.634224 -279.96007) (xy 388.632192 -279.95499)
			(xy 388.630668 -279.950672) (xy 388.629398 -279.94737) (xy 388.618984 -279.939242) (xy 388.613725 -279.935403)
			(xy 388.601765 -279.930265) (xy 388.595362 -279.929082) (xy 388.594092 -279.928828) (xy 388.507478 -279.917398)
			(xy 388.500741 -279.91682) (xy 388.487362 -279.918751) (xy 388.481062 -279.921208) (xy 388.46887 -279.926288)
			(xy 388.465314 -279.93086) (xy 388.460234 -279.937718) (xy 388.445729 -279.956547) (xy 388.411873 -279.989901)
			(xy 388.37326 -280.017611) (xy 388.330822 -280.039007) (xy 388.285582 -280.053573) (xy 388.238633 -280.060959)
			(xy 388.21487 -280.061416) (xy 388.189616 -280.060892) (xy 388.139796 -280.052574) (xy 388.092026 -280.03617)
			(xy 388.047606 -280.012128) (xy 388.007749 -279.981102) (xy 387.973542 -279.94394) (xy 387.945918 -279.901655)
			(xy 387.92563 -279.8554) (xy 387.913232 -279.806436) (xy 387.909061 -279.7561) (xy 387.913232 -279.705764)
			(xy 387.92563 -279.6568) (xy 387.945918 -279.610545) (xy 387.973542 -279.56826) (xy 388.007749 -279.531098)
			(xy 388.047606 -279.500072) (xy 388.092026 -279.47603) (xy 388.139796 -279.459626) (xy 388.189616 -279.451308)
			(xy 388.21487 -279.4508) (xy 388.215124 -279.4508) (xy 388.238891 -279.451248) (xy 388.28585 -279.458608)
			(xy 388.3311 -279.473161) (xy 388.373546 -279.494556) (xy 388.41216 -279.522275) (xy 388.446008 -279.555647)
			(xy 388.460488 -279.574498) (xy 388.464552 -279.580086) (xy 388.475474 -279.588722) (xy 388.481062 -279.591008)
			(xy 388.487114 -279.593398) (xy 388.499976 -279.595333) (xy 388.506462 -279.594818) (xy 388.530846 -279.59177)
			(xy 388.531354 -279.59177) (xy 388.594092 -279.583388) (xy 388.595362 -279.583134) (xy 388.601771 -279.581969)
			(xy 388.613738 -279.576834) (xy 388.618984 -279.572974) (xy 388.629398 -279.564846) (xy 388.630668 -279.56129)
			(xy 388.632192 -279.557226) (xy 388.634224 -279.552146) (xy 388.644911 -279.525894) (xy 388.670871 -279.475505)
			(xy 388.68604 -279.451562) (xy 388.697891 -279.433682) (xy 388.723955 -279.399607) (xy 388.73811 -279.38349)
			(xy 388.738364 -279.383236) (xy 388.740142 -279.381204) (xy 388.744968 -279.375616) (xy 388.74827 -279.36698)
			(xy 388.749032 -279.365202) (xy 388.750261 -279.361253) (xy 388.751534 -279.353082) (xy 388.751572 -279.348946)
			(xy 388.751572 -279.322276) (xy 388.7511 -279.3127) (xy 388.743927 -279.294936) (xy 388.737602 -279.287732)
			(xy 388.718806 -279.269952) (xy 388.70763 -279.26284) (xy 388.691882 -279.256236) (xy 388.690866 -279.255728)
			(xy 388.680452 -279.251664) (xy 388.673594 -279.251156) (xy 388.671308 -279.251156) (xy 388.646806 -279.249582)
			(xy 388.598737 -279.239592) (xy 388.552886 -279.222041) (xy 388.510434 -279.197379) (xy 388.472475 -279.166242)
			(xy 388.439987 -279.129433) (xy 388.413807 -279.0879) (xy 388.39461 -279.042714) (xy 388.38289 -278.995037)
			(xy 388.378949 -278.9461) (xy 388.38289 -278.897163) (xy 388.39461 -278.849487) (xy 388.413807 -278.8043)
			(xy 388.439987 -278.762767) (xy 388.472475 -278.725958) (xy 388.510434 -278.694821) (xy 388.552886 -278.670159)
			(xy 388.598737 -278.652608) (xy 388.646806 -278.642618) (xy 388.671308 -278.641048) (xy 388.673594 -278.641048)
			(xy 388.680452 -278.64054) (xy 388.690866 -278.636476) (xy 388.691882 -278.635968) (xy 388.70763 -278.629364)
			(xy 388.718806 -278.622252) (xy 388.737602 -278.604472) (xy 388.743951 -278.597281) (xy 388.75113 -278.579511)
			(xy 388.751572 -278.569928) (xy 388.751572 -278.554942) (xy 388.671308 -278.41702) (xy 388.660765 -278.398418)
			(xy 388.642202 -278.359895) (xy 388.634224 -278.340058) (xy 388.632192 -278.334978) (xy 388.630668 -278.33066)
			(xy 388.629398 -278.327358) (xy 388.618984 -278.31923) (xy 388.613725 -278.315392) (xy 388.601765 -278.310255)
			(xy 388.595362 -278.30907) (xy 388.594092 -278.308816) (xy 388.507478 -278.297386) (xy 388.500741 -278.296808)
			(xy 388.487362 -278.298739) (xy 388.481062 -278.301196) (xy 388.46887 -278.306276) (xy 388.465314 -278.310848)
			(xy 388.460234 -278.317706) (xy 388.44573 -278.336535) (xy 388.411874 -278.369891) (xy 388.373261 -278.397602)
			(xy 388.330823 -278.418999) (xy 388.285583 -278.433566) (xy 388.238633 -278.440952) (xy 388.21487 -278.441404)
			(xy 388.189617 -278.44088) (xy 388.139799 -278.432563) (xy 388.09203 -278.416159) (xy 388.047613 -278.392118)
			(xy 388.007757 -278.361094) (xy 387.973552 -278.323933) (xy 387.945929 -278.281649) (xy 387.925641 -278.235396)
			(xy 387.913244 -278.186434) (xy 387.909073 -278.1361) (xy 387.913244 -278.085766) (xy 387.925641 -278.036804)
			(xy 387.945929 -277.990551) (xy 387.973552 -277.948267) (xy 388.007757 -277.911106) (xy 388.047613 -277.880082)
			(xy 388.09203 -277.856041) (xy 388.139799 -277.839637) (xy 388.189617 -277.83132) (xy 388.21487 -277.830788)
			(xy 388.215124 -277.830788) (xy 388.238891 -277.831236) (xy 388.285851 -277.838596) (xy 388.331101 -277.853149)
			(xy 388.373547 -277.874543) (xy 388.412162 -277.902261) (xy 388.446012 -277.935632) (xy 388.460488 -277.954486)
			(xy 388.464552 -277.960074) (xy 388.475474 -277.96871) (xy 388.481062 -277.970996) (xy 388.487114 -277.973387)
			(xy 388.499976 -277.975322) (xy 388.506462 -277.974806) (xy 388.530846 -277.971758) (xy 388.531354 -277.971758)
			(xy 388.594092 -277.963376) (xy 388.595362 -277.963122) (xy 388.601771 -277.961957) (xy 388.613737 -277.956821)
			(xy 388.618984 -277.952962) (xy 388.629398 -277.944834) (xy 388.630668 -277.941278) (xy 388.632192 -277.937214)
			(xy 388.634224 -277.932134) (xy 388.644912 -277.905883) (xy 388.670873 -277.855494) (xy 388.68604 -277.83155)
			(xy 388.697891 -277.81367) (xy 388.723956 -277.779596) (xy 388.73811 -277.763478) (xy 388.738364 -277.763224)
			(xy 388.740142 -277.761192) (xy 388.744968 -277.755604) (xy 388.74827 -277.746968) (xy 388.749032 -277.74519)
			(xy 388.75026 -277.741241) (xy 388.751531 -277.73307) (xy 388.751572 -277.728934) (xy 388.751572 -277.702264)
			(xy 388.751098 -277.692689) (xy 388.743922 -277.674928) (xy 388.737602 -277.66772) (xy 388.718806 -277.64994)
			(xy 388.70763 -277.642828) (xy 388.691882 -277.636224) (xy 388.690866 -277.635716) (xy 388.680452 -277.631652)
			(xy 388.673594 -277.631144) (xy 388.671308 -277.631144) (xy 388.646807 -277.62957) (xy 388.59874 -277.619581)
			(xy 388.552891 -277.60203) (xy 388.51044 -277.577369) (xy 388.472483 -277.546233) (xy 388.439996 -277.509426)
			(xy 388.413817 -277.467894) (xy 388.394621 -277.422709) (xy 388.382902 -277.375035) (xy 388.378961 -277.3261)
			(xy 388.382902 -277.277164) (xy 388.394621 -277.22949) (xy 388.413818 -277.184305) (xy 388.439997 -277.142773)
			(xy 388.472483 -277.105966) (xy 388.510441 -277.074831) (xy 388.552892 -277.05017) (xy 388.598741 -277.032619)
			(xy 388.646808 -277.02263) (xy 388.671308 -277.021036) (xy 388.673594 -277.021036) (xy 388.680452 -277.020528)
			(xy 388.690866 -277.016464) (xy 388.691882 -277.015956) (xy 388.70763 -277.009352) (xy 388.718806 -277.00224)
			(xy 388.737602 -276.98446) (xy 388.743949 -276.977269) (xy 388.751123 -276.959499) (xy 388.751572 -276.949916)
			(xy 388.751572 -276.93493) (xy 388.671308 -276.797008) (xy 388.660765 -276.778406) (xy 388.642204 -276.739883)
			(xy 388.634224 -276.720046) (xy 388.632192 -276.714966) (xy 388.630668 -276.710648) (xy 388.629398 -276.707346)
			(xy 388.618984 -276.699218) (xy 388.613727 -276.695374) (xy 388.601768 -276.690229) (xy 388.595362 -276.689058)
			(xy 388.594092 -276.688804) (xy 388.507478 -276.677374) (xy 388.500741 -276.676797) (xy 388.487362 -276.678727)
			(xy 388.481062 -276.681184) (xy 388.46887 -276.686264) (xy 388.465314 -276.690836) (xy 388.460234 -276.697694)
			(xy 388.44573 -276.716524) (xy 388.411875 -276.749881) (xy 388.373262 -276.777593) (xy 388.330824 -276.79899)
			(xy 388.285584 -276.813558) (xy 388.238634 -276.820944) (xy 388.21487 -276.821392) (xy 388.189618 -276.820868)
			(xy 388.139802 -276.812551) (xy 388.092035 -276.796148) (xy 388.047619 -276.772108) (xy 388.007765 -276.741085)
			(xy 387.973561 -276.703925) (xy 387.945939 -276.661644) (xy 387.925653 -276.615392) (xy 387.913255 -276.566432)
			(xy 387.909085 -276.5161) (xy 387.913255 -276.465768) (xy 387.925653 -276.416808) (xy 387.945939 -276.370556)
			(xy 387.973561 -276.328275) (xy 388.007766 -276.291115) (xy 388.047619 -276.260092) (xy 388.092035 -276.236052)
			(xy 388.139802 -276.219649) (xy 388.189618 -276.211332) (xy 388.21487 -276.210776) (xy 388.215124 -276.210776)
			(xy 388.238891 -276.211224) (xy 388.285851 -276.218583) (xy 388.331102 -276.233136) (xy 388.373549 -276.25453)
			(xy 388.412165 -276.282247) (xy 388.446015 -276.315617) (xy 388.460488 -276.334474) (xy 388.464552 -276.340062)
			(xy 388.475474 -276.348698) (xy 388.481062 -276.350984) (xy 388.487114 -276.353375) (xy 388.499976 -276.355311)
			(xy 388.506462 -276.354794) (xy 388.530846 -276.351746) (xy 388.531354 -276.351746) (xy 388.594092 -276.343364)
			(xy 388.595362 -276.34311) (xy 388.601771 -276.341944) (xy 388.613736 -276.336807) (xy 388.618984 -276.33295)
			(xy 388.629398 -276.324822) (xy 388.630668 -276.321266) (xy 388.632192 -276.317202) (xy 388.634224 -276.312122)
			(xy 388.644912 -276.285871) (xy 388.670874 -276.235483) (xy 388.68604 -276.211538) (xy 388.697892 -276.193658)
			(xy 388.723956 -276.159585) (xy 388.73811 -276.143466) (xy 388.738364 -276.143212) (xy 388.740142 -276.14118)
			(xy 388.744968 -276.135592) (xy 388.74827 -276.126956) (xy 388.749032 -276.125178) (xy 388.750259 -276.121229)
			(xy 388.751528 -276.113058) (xy 388.751572 -276.108922) (xy 388.751572 -276.082252) (xy 388.751096 -276.072678)
			(xy 388.743917 -276.05492) (xy 388.737602 -276.047708) (xy 388.718806 -276.029928) (xy 388.70763 -276.022816)
			(xy 388.691882 -276.016212) (xy 388.690866 -276.015704) (xy 388.680452 -276.01164) (xy 388.673594 -276.011132)
			(xy 388.671308 -276.011132) (xy 388.646808 -276.009558) (xy 388.598743 -275.999569) (xy 388.552895 -275.982019)
			(xy 388.510447 -275.957359) (xy 388.472491 -275.926224) (xy 388.440005 -275.889418) (xy 388.413828 -275.847888)
			(xy 388.394632 -275.802705) (xy 388.382913 -275.755032) (xy 388.378973 -275.706099) (xy 388.382914 -275.657166)
			(xy 388.394633 -275.609493) (xy 388.413828 -275.56431) (xy 388.440007 -275.52278) (xy 388.472492 -275.485974)
			(xy 388.510448 -275.45484) (xy 388.552897 -275.43018) (xy 388.598745 -275.41263) (xy 388.64681 -275.402642)
			(xy 388.671308 -275.401024) (xy 388.673594 -275.401024) (xy 388.680452 -275.400516) (xy 388.690866 -275.396452)
			(xy 388.691882 -275.395944) (xy 388.70763 -275.38934) (xy 388.718806 -275.382228) (xy 388.737602 -275.364448)
			(xy 388.743948 -275.357256) (xy 388.751117 -275.339486) (xy 388.751572 -275.329904) (xy 388.751572 -275.314918)
			(xy 388.671308 -275.176996) (xy 388.660765 -275.158394) (xy 388.642205 -275.119871) (xy 388.634224 -275.100034)
			(xy 388.632192 -275.094954) (xy 388.630668 -275.090636) (xy 388.629398 -275.087334) (xy 388.618984 -275.079206)
			(xy 388.613727 -275.075363) (xy 388.601768 -275.070219) (xy 388.595362 -275.069046) (xy 388.594092 -275.068792)
			(xy 388.507478 -275.057362) (xy 388.500741 -275.056785) (xy 388.487362 -275.058714) (xy 388.481062 -275.061172)
			(xy 388.46887 -275.066252) (xy 388.465314 -275.070824) (xy 388.460234 -275.077682) (xy 388.445731 -275.096513)
			(xy 388.411876 -275.129871) (xy 388.373263 -275.157584) (xy 388.330825 -275.178982) (xy 388.285584 -275.193551)
			(xy 388.238634 -275.200937) (xy 388.21487 -275.20138) (xy 388.189619 -275.200856) (xy 388.139805 -275.192539)
			(xy 388.09204 -275.176137) (xy 388.047626 -275.152098) (xy 388.007774 -275.121076) (xy 387.973571 -275.083918)
			(xy 387.94595 -275.041638) (xy 387.925664 -274.995388) (xy 387.913267 -274.94643) (xy 387.909097 -274.8961)
			(xy 387.913267 -274.84577) (xy 387.925664 -274.796812) (xy 387.94595 -274.750562) (xy 387.973571 -274.708282)
			(xy 388.007774 -274.671124) (xy 388.047626 -274.640102) (xy 388.09204 -274.616063) (xy 388.139805 -274.599661)
			(xy 388.189619 -274.591344) (xy 388.21487 -274.590764) (xy 388.215124 -274.590764) (xy 388.238891 -274.591212)
			(xy 388.285852 -274.598571) (xy 388.331103 -274.613123) (xy 388.37355 -274.634516) (xy 388.412167 -274.662233)
			(xy 388.446019 -274.695603) (xy 388.460488 -274.714462) (xy 388.464552 -274.72005) (xy 388.475474 -274.728686)
			(xy 388.481062 -274.730972) (xy 388.487113 -274.733364) (xy 388.499976 -274.7353) (xy 388.506462 -274.734782)
			(xy 388.530846 -274.731734) (xy 388.531354 -274.731734) (xy 388.594092 -274.723352) (xy 388.595362 -274.723098)
			(xy 388.60177 -274.721932) (xy 388.613735 -274.716794) (xy 388.618984 -274.712938) (xy 388.629398 -274.70481)
			(xy 388.630668 -274.701254) (xy 388.632192 -274.69719) (xy 388.634224 -274.69211) (xy 388.644913 -274.665859)
			(xy 388.670876 -274.615472) (xy 388.68604 -274.591526) (xy 388.697892 -274.573647) (xy 388.723957 -274.539574)
			(xy 388.73811 -274.523454) (xy 388.738364 -274.5232) (xy 388.740142 -274.521168) (xy 388.744968 -274.51558)
			(xy 388.74827 -274.506944) (xy 388.749032 -274.505166) (xy 388.750266 -274.501218) (xy 388.751549 -274.493046)
			(xy 388.751572 -274.48891) (xy 388.751572 -274.46224) (xy 388.751093 -274.452667) (xy 388.743911 -274.434912)
			(xy 388.737602 -274.427696) (xy 388.718806 -274.409916) (xy 388.70763 -274.402804) (xy 388.691882 -274.3962)
			(xy 388.690866 -274.395692) (xy 388.680452 -274.391628) (xy 388.673594 -274.39112) (xy 388.671308 -274.39112)
			(xy 388.646809 -274.389546) (xy 388.598746 -274.379558) (xy 388.5529 -274.362008) (xy 388.510453 -274.337349)
			(xy 388.472499 -274.306215) (xy 388.440015 -274.269411) (xy 388.413838 -274.227882) (xy 388.394643 -274.182701)
			(xy 388.382925 -274.13503) (xy 388.378985 -274.086098) (xy 388.382925 -274.037167) (xy 388.394644 -273.989496)
			(xy 388.413839 -273.944315) (xy 388.440016 -273.902787) (xy 388.472501 -273.865982) (xy 388.510456 -273.83485)
			(xy 388.552903 -273.810191) (xy 388.598749 -273.792642) (xy 388.646812 -273.782654) (xy 388.671308 -273.781012)
			(xy 388.673594 -273.781012) (xy 388.680452 -273.780504) (xy 388.690866 -273.77644) (xy 388.691882 -273.775932)
			(xy 388.70763 -273.769328) (xy 388.718806 -273.762216) (xy 388.737602 -273.744436) (xy 388.743961 -273.737249)
			(xy 388.751162 -273.719479) (xy 388.751572 -273.709892) (xy 388.751572 -273.694906) (xy 388.671308 -273.556984)
			(xy 388.660766 -273.538382) (xy 388.642206 -273.499858) (xy 388.634224 -273.480022) (xy 388.632192 -273.474942)
			(xy 388.630668 -273.470624) (xy 388.629398 -273.467322) (xy 388.618984 -273.459194) (xy 388.613727 -273.455351)
			(xy 388.601767 -273.450209) (xy 388.595362 -273.449034) (xy 388.594092 -273.44878) (xy 388.507478 -273.43735)
			(xy 388.500741 -273.436773) (xy 388.487362 -273.438702) (xy 388.481062 -273.44116) (xy 388.46887 -273.44624)
			(xy 388.465314 -273.450812) (xy 388.460234 -273.45767) (xy 388.445731 -273.476501) (xy 388.411877 -273.509861)
			(xy 388.373264 -273.537574) (xy 388.330826 -273.558974) (xy 388.285585 -273.573543) (xy 388.238634 -273.58093)
			(xy 388.21487 -273.581368) (xy 388.18962 -273.580844) (xy 388.139808 -273.572528) (xy 388.092045 -273.556126)
			(xy 388.047632 -273.532088) (xy 388.007782 -273.501067) (xy 387.97358 -273.463911) (xy 387.94596 -273.421632)
			(xy 387.925676 -273.375384) (xy 387.913279 -273.326428) (xy 387.909109 -273.2761) (xy 387.913279 -273.225772)
			(xy 387.925676 -273.176816) (xy 387.94596 -273.130568) (xy 387.97358 -273.088289) (xy 388.007782 -273.051133)
			(xy 388.047632 -273.020112) (xy 388.092045 -272.996074) (xy 388.139808 -272.979672) (xy 388.18962 -272.971356)
			(xy 388.21487 -272.970752) (xy 388.215124 -272.970752) (xy 388.23889 -272.9712) (xy 388.285848 -272.978561)
			(xy 388.331097 -272.993116) (xy 388.37354 -273.014513) (xy 388.412151 -273.042235) (xy 388.445994 -273.07561)
			(xy 388.460488 -273.09445) (xy 388.464552 -273.100038) (xy 388.475474 -273.108674) (xy 388.481062 -273.11096)
			(xy 388.487114 -273.113348) (xy 388.499976 -273.115281) (xy 388.506462 -273.11477) (xy 388.530846 -273.111722)
			(xy 388.531354 -273.111722) (xy 388.594092 -273.10334) (xy 388.595362 -273.103086) (xy 388.60177 -273.10192)
			(xy 388.613734 -273.096781) (xy 388.618984 -273.092926) (xy 388.629398 -273.084798) (xy 388.630668 -273.081242)
			(xy 388.632192 -273.077178) (xy 388.634224 -273.072098) (xy 388.644909 -273.045845) (xy 388.670865 -272.995454)
			(xy 388.68604 -272.971514) (xy 388.697892 -272.953635) (xy 388.723958 -272.919562) (xy 388.73811 -272.903442)
			(xy 388.738364 -272.903188) (xy 388.740142 -272.901156) (xy 388.744968 -272.895568) (xy 388.74827 -272.886932)
			(xy 388.749032 -272.885154) (xy 388.750265 -272.881206) (xy 388.751546 -272.873034) (xy 388.751572 -272.868898)
			(xy 388.751572 -272.842228) (xy 388.751091 -272.832656) (xy 388.743906 -272.814904) (xy 388.737602 -272.807684)
			(xy 388.718806 -272.789904) (xy 388.70763 -272.782792) (xy 388.691882 -272.776188) (xy 388.690866 -272.77568)
			(xy 388.680452 -272.771616) (xy 388.673594 -272.771108) (xy 388.671308 -272.771108) (xy 388.64681 -272.769534)
			(xy 388.598749 -272.759546) (xy 388.552905 -272.741997) (xy 388.51046 -272.717338) (xy 388.472507 -272.686206)
			(xy 388.440024 -272.649403) (xy 388.413848 -272.607876) (xy 388.394654 -272.562696) (xy 388.382937 -272.515028)
			(xy 388.378997 -272.466098) (xy 388.382937 -272.417168) (xy 388.394656 -272.3695) (xy 388.41385 -272.32432)
			(xy 388.440026 -272.282794) (xy 388.47251 -272.245991) (xy 388.510463 -272.214859) (xy 388.552908 -272.190202)
			(xy 388.598752 -272.172653) (xy 388.646814 -272.162666) (xy 388.671308 -272.161) (xy 388.673594 -272.161)
			(xy 388.680452 -272.160492) (xy 388.690866 -272.156428) (xy 388.691882 -272.15592) (xy 388.70763 -272.149316)
			(xy 388.718806 -272.142204) (xy 388.737602 -272.124424) (xy 388.743959 -272.117236) (xy 388.751156 -272.099466)
			(xy 388.751572 -272.08988) (xy 388.751572 -272.074894) (xy 388.671308 -271.936972) (xy 388.660766 -271.91837)
			(xy 388.642207 -271.879846) (xy 388.634224 -271.86001) (xy 388.632192 -271.85493) (xy 388.630668 -271.850612)
			(xy 388.629398 -271.84731) (xy 388.618984 -271.839182) (xy 388.613726 -271.83534) (xy 388.601767 -271.830199)
			(xy 388.595362 -271.829022) (xy 388.594092 -271.828768) (xy 388.507478 -271.817338) (xy 388.500741 -271.816761)
			(xy 388.487363 -271.818693) (xy 388.481062 -271.821148) (xy 388.46887 -271.826228) (xy 388.465314 -271.8308)
			(xy 388.460234 -271.837658) (xy 388.445732 -271.85649) (xy 388.411878 -271.88985) (xy 388.373265 -271.917565)
			(xy 388.330827 -271.938966) (xy 388.285586 -271.953536) (xy 388.238634 -271.960923) (xy 388.21487 -271.961356)
			(xy 388.189612 -271.960832) (xy 388.139786 -271.952513) (xy 388.092009 -271.936107) (xy 388.047584 -271.912062)
			(xy 388.007722 -271.881032) (xy 387.97351 -271.843865) (xy 387.945882 -271.801574) (xy 387.925592 -271.755313)
			(xy 387.913192 -271.706343) (xy 387.90902 -271.656) (xy 387.913192 -271.605657) (xy 387.925592 -271.556687)
			(xy 387.945882 -271.510426) (xy 387.97351 -271.468135) (xy 388.007722 -271.430968) (xy 388.047584 -271.399938)
			(xy 388.092009 -271.375893) (xy 388.139786 -271.359487) (xy 388.189612 -271.351168) (xy 388.21487 -271.35074)
			(xy 388.215124 -271.35074) (xy 388.23889 -271.351188) (xy 388.285849 -271.358549) (xy 388.331098 -271.373104)
			(xy 388.373541 -271.3945) (xy 388.412153 -271.422221) (xy 388.445998 -271.455595) (xy 388.460488 -271.474438)
			(xy 388.464552 -271.480026) (xy 388.475474 -271.488662) (xy 388.481062 -271.490948) (xy 388.487114 -271.493337)
			(xy 388.499976 -271.49527) (xy 388.506462 -271.494758) (xy 388.530846 -271.49171) (xy 388.531354 -271.49171)
			(xy 388.594092 -271.483328) (xy 388.595362 -271.483074) (xy 388.60177 -271.481907) (xy 388.613733 -271.476767)
			(xy 388.618984 -271.472914) (xy 388.629398 -271.464786) (xy 388.630668 -271.46123) (xy 388.632192 -271.457166)
			(xy 388.634224 -271.452086) (xy 388.64491 -271.425834) (xy 388.670867 -271.375442) (xy 388.68604 -271.351502)
			(xy 388.69789 -271.333621) (xy 388.723952 -271.299545) (xy 388.73811 -271.28343) (xy 388.738364 -271.283176)
			(xy 388.740142 -271.281144) (xy 388.744968 -271.275556) (xy 388.74827 -271.26692) (xy 388.749032 -271.265142)
			(xy 388.750264 -271.261194) (xy 388.751544 -271.253022) (xy 388.751572 -271.248886) (xy 388.751572 -271.222216)
			(xy 388.751089 -271.212645) (xy 388.743901 -271.194896) (xy 388.737602 -271.187672) (xy 388.718806 -271.169892)
			(xy 388.70763 -271.16278) (xy 388.691882 -271.156176) (xy 388.690866 -271.155668) (xy 388.680452 -271.151604)
			(xy 388.673594 -271.151096) (xy 388.671308 -271.151096) (xy 388.646803 -271.149522) (xy 388.598727 -271.139532)
			(xy 388.55287 -271.121978) (xy 388.510412 -271.097313) (xy 388.472448 -271.066173) (xy 388.439955 -271.029359)
			(xy 388.413772 -270.987821) (xy 388.394572 -270.942628) (xy 388.38285 -270.894946) (xy 388.378909 -270.846002)
			(xy 388.38285 -270.797058) (xy 388.394571 -270.749375) (xy 388.41377 -270.704183) (xy 388.439953 -270.662644)
			(xy 388.472445 -270.62583) (xy 388.510409 -270.594689) (xy 388.552867 -270.570023) (xy 388.598724 -270.552469)
			(xy 388.646799 -270.542478) (xy 388.671308 -270.540988) (xy 388.673594 -270.540988) (xy 388.680452 -270.54048)
			(xy 388.690866 -270.536416) (xy 388.691882 -270.535908) (xy 388.70763 -270.529304) (xy 388.718806 -270.522192)
			(xy 388.737602 -270.504412) (xy 388.743957 -270.497223) (xy 388.75115 -270.479453) (xy 388.751572 -270.469868)
			(xy 388.751572 -270.454882) (xy 388.671308 -270.31696) (xy 388.660763 -270.298359) (xy 388.642199 -270.259837)
			(xy 388.634224 -270.239998) (xy 388.632192 -270.234918) (xy 388.630668 -270.2306) (xy 388.629398 -270.227298)
			(xy 388.618984 -270.21917) (xy 388.613726 -270.215329) (xy 388.601766 -270.210189) (xy 388.595362 -270.20901)
			(xy 388.594092 -270.208756) (xy 388.507478 -270.197326) (xy 388.500741 -270.196748) (xy 388.487362 -270.19868)
			(xy 388.481062 -270.201136) (xy 388.46887 -270.206216) (xy 388.465314 -270.210788) (xy 388.460234 -270.217646)
			(xy 388.445732 -270.236478) (xy 388.411879 -270.26984) (xy 388.373267 -270.297556) (xy 388.330828 -270.318958)
			(xy 388.285587 -270.333528) (xy 388.238635 -270.340916) (xy 388.21487 -270.341344) (xy 388.189613 -270.34082)
			(xy 388.13979 -270.332501) (xy 388.092014 -270.316096) (xy 388.047591 -270.292051) (xy 388.00773 -270.261023)
			(xy 387.97352 -270.223857) (xy 387.945893 -270.181568) (xy 387.925604 -270.135309) (xy 387.913204 -270.086341)
			(xy 387.909033 -270.036) (xy 387.913204 -269.985659) (xy 387.925604 -269.936691) (xy 387.945893 -269.890432)
			(xy 387.97352 -269.848143) (xy 388.00773 -269.810977) (xy 388.047591 -269.779949) (xy 388.092014 -269.755904)
			(xy 388.13979 -269.739499) (xy 388.189613 -269.73118) (xy 388.21487 -269.730728) (xy 388.215124 -269.730728)
			(xy 388.23889 -269.731176) (xy 388.285849 -269.738537) (xy 388.331098 -269.753091) (xy 388.373543 -269.774487)
			(xy 388.412155 -269.802207) (xy 388.446001 -269.835581) (xy 388.460488 -269.854426) (xy 388.464552 -269.860014)
			(xy 388.475474 -269.86865) (xy 388.481062 -269.870936) (xy 388.487114 -269.873325) (xy 388.499976 -269.875258)
			(xy 388.506462 -269.874746) (xy 388.530846 -269.871698) (xy 388.531354 -269.871698) (xy 388.594092 -269.863316)
			(xy 388.595362 -269.863062) (xy 388.60177 -269.861895) (xy 388.613732 -269.856754) (xy 388.618984 -269.852902)
			(xy 388.629398 -269.844774) (xy 388.630668 -269.841218) (xy 388.632192 -269.837154) (xy 388.634224 -269.832074)
			(xy 388.64491 -269.805822) (xy 388.670868 -269.755431) (xy 388.68604 -269.73149) (xy 388.69789 -269.713609)
			(xy 388.723953 -269.679534) (xy 388.73811 -269.663418) (xy 388.738364 -269.663164) (xy 388.740142 -269.661132)
			(xy 388.744968 -269.655544) (xy 388.74827 -269.646908) (xy 388.749032 -269.64513) (xy 388.750264 -269.641181)
			(xy 388.751541 -269.63301) (xy 388.751572 -269.628874) (xy 388.751572 -269.602204) (xy 388.751087 -269.592634)
			(xy 388.743896 -269.574888) (xy 388.737602 -269.56766) (xy 388.718806 -269.54988) (xy 388.70763 -269.542768)
			(xy 388.691882 -269.536164) (xy 388.690866 -269.535656) (xy 388.680452 -269.531592) (xy 388.673594 -269.531084)
			(xy 388.671308 -269.531084) (xy 388.651496 -269.52956) (xy 388.626238 -269.526276) (xy 388.577231 -269.512411)
			(xy 388.531197 -269.490623) (xy 388.510018 -269.476474) (xy 388.489856 -269.461802) (xy 388.454143 -269.427006)
			(xy 388.424557 -269.386871) (xy 388.401882 -269.342463) (xy 388.386722 -269.294962) (xy 388.379479 -269.245629)
			(xy 388.380346 -269.195775) (xy 388.389298 -269.146724) (xy 388.406099 -269.099778) (xy 388.430303 -269.056185)
			(xy 388.461265 -269.017102) (xy 388.498165 -268.983568) (xy 388.540022 -268.956472) (xy 388.585724 -268.936535)
			(xy 388.634058 -268.924286) (xy 388.658862 -268.921738) (xy 388.669276 -268.920976) (xy 388.67715 -268.917166)
			(xy 388.680468 -268.915415) (xy 388.686591 -268.91108) (xy 388.689342 -268.90853) (xy 388.711186 -268.885416)
			(xy 388.711186 -268.884908) (xy 388.738364 -268.855952) (xy 388.74433 -268.8488) (xy 388.751108 -268.831471)
			(xy 388.751572 -268.82217) (xy 388.751572 -268.009878) (xy 388.751197 -268.000558) (xy 388.744406 -267.983202)
			(xy 388.738364 -267.976096) (xy 388.692136 -267.926058) (xy 388.688918 -267.922749) (xy 388.681506 -267.917252)
			(xy 388.677404 -267.915136) (xy 388.669276 -267.911072) (xy 388.65937 -267.91031) (xy 388.634251 -267.907695)
			(xy 388.585302 -267.89528) (xy 388.539064 -267.874978) (xy 388.496798 -267.847342) (xy 388.459657 -267.813128)
			(xy 388.428653 -267.773267) (xy 388.404632 -267.728847) (xy 388.388249 -267.68108) (xy 388.379952 -267.631267)
			(xy 388.379462 -267.606018) (xy 388.380008 -267.580105) (xy 388.388754 -267.529023) (xy 388.405998 -267.480151)
			(xy 388.431245 -267.434891) (xy 388.46377 -267.394542) (xy 388.502639 -267.360264) (xy 388.546738 -267.333039)
			(xy 388.5948 -267.31365) (xy 388.645445 -267.302652) (xy 388.671308 -267.300964) (xy 388.673594 -267.300964)
			(xy 388.680452 -267.300456) (xy 388.690866 -267.296392) (xy 388.691882 -267.295884) (xy 388.70763 -267.28928)
			(xy 388.718806 -267.282168) (xy 388.737602 -267.264388) (xy 388.743954 -267.257198) (xy 388.751138 -267.239428)
			(xy 388.751572 -267.229844) (xy 388.751572 -267.214858) (xy 388.671308 -267.076936) (xy 388.660764 -267.058335)
			(xy 388.642201 -267.019812) (xy 388.634224 -266.999974) (xy 388.632192 -266.994894) (xy 388.630668 -266.990576)
			(xy 388.629398 -266.987274) (xy 388.618984 -266.979146) (xy 388.613725 -266.975306) (xy 388.601765 -266.970169)
			(xy 388.595362 -266.968986) (xy 388.594092 -266.968732) (xy 388.507478 -266.957302) (xy 388.500741 -266.956724)
			(xy 388.487362 -266.958655) (xy 388.481062 -266.961112) (xy 388.46887 -266.966192) (xy 388.465314 -266.970764)
			(xy 388.460234 -266.977622) (xy 388.445733 -266.996456) (xy 388.41188 -267.02982) (xy 388.373269 -267.057538)
			(xy 388.33083 -267.078942) (xy 388.285588 -267.093513) (xy 388.238635 -267.100901) (xy 388.21487 -267.10132)
			(xy 388.189615 -267.100796) (xy 388.139795 -267.092478) (xy 388.092024 -267.076074) (xy 388.047604 -267.052031)
			(xy 388.007747 -267.021005) (xy 387.973539 -266.983843) (xy 387.945915 -266.941557) (xy 387.925626 -266.895301)
			(xy 387.913228 -266.846337) (xy 387.909057 -266.796) (xy 387.913228 -266.745663) (xy 387.925626 -266.696699)
			(xy 387.945915 -266.650443) (xy 387.973539 -266.608157) (xy 388.007747 -266.570995) (xy 388.047604 -266.539969)
			(xy 388.092024 -266.515926) (xy 388.139795 -266.499522) (xy 388.189615 -266.491204) (xy 388.21487 -266.490704)
			(xy 388.215124 -266.490704) (xy 388.238891 -266.491152) (xy 388.28585 -266.498512) (xy 388.3311 -266.513066)
			(xy 388.373546 -266.534461) (xy 388.412159 -266.56218) (xy 388.446007 -266.595551) (xy 388.460488 -266.614402)
			(xy 388.464552 -266.61999) (xy 388.475474 -266.628626) (xy 388.481062 -266.630912) (xy 388.487114 -266.633302)
			(xy 388.499976 -266.635236) (xy 388.506462 -266.634722) (xy 388.530846 -266.631674) (xy 388.531354 -266.631674)
			(xy 388.594092 -266.623292) (xy 388.595362 -266.623038) (xy 388.601771 -266.621873) (xy 388.613738 -266.616738)
			(xy 388.618984 -266.612878) (xy 388.629398 -266.60475) (xy 388.630668 -266.601194) (xy 388.632192 -266.59713)
			(xy 388.634224 -266.59205) (xy 388.644911 -266.565798) (xy 388.670871 -266.515409) (xy 388.68604 -266.491466)
			(xy 388.697891 -266.473586) (xy 388.723954 -266.439511) (xy 388.73811 -266.423394) (xy 388.738364 -266.42314)
			(xy 388.740142 -266.421108) (xy 388.744968 -266.41552) (xy 388.74827 -266.406884) (xy 388.749032 -266.405106)
			(xy 388.750262 -266.401157) (xy 388.751535 -266.392986) (xy 388.751572 -266.38885) (xy 388.751572 -266.36218)
			(xy 388.7511 -266.352604) (xy 388.743929 -266.334839) (xy 388.737602 -266.327636) (xy 388.718806 -266.309856)
			(xy 388.70763 -266.302744) (xy 388.691882 -266.29614) (xy 388.690866 -266.295632) (xy 388.680452 -266.291568)
			(xy 388.673594 -266.29106) (xy 388.671308 -266.29106) (xy 388.646805 -266.289486) (xy 388.598736 -266.279496)
			(xy 388.552884 -266.261945) (xy 388.510432 -266.237282) (xy 388.472472 -266.206145) (xy 388.439984 -266.169336)
			(xy 388.413803 -266.127802) (xy 388.394606 -266.082615) (xy 388.382886 -266.034938) (xy 388.378945 -265.986)
			(xy 388.382886 -265.937062) (xy 388.394606 -265.889385) (xy 388.413803 -265.844198) (xy 388.439983 -265.802664)
			(xy 388.472472 -265.765855) (xy 388.510431 -265.734718) (xy 388.552884 -265.710056) (xy 388.598736 -265.692504)
			(xy 388.646805 -265.682514) (xy 388.671308 -265.680952) (xy 388.673594 -265.680952) (xy 388.680452 -265.680444)
			(xy 388.690866 -265.67638) (xy 388.691882 -265.675872) (xy 388.70763 -265.669268) (xy 388.718806 -265.662156)
			(xy 388.737602 -265.644376) (xy 388.743952 -265.637185) (xy 388.751132 -265.619415) (xy 388.751572 -265.609832)
			(xy 388.751572 -265.594846) (xy 388.671308 -265.456924) (xy 388.660765 -265.438322) (xy 388.642202 -265.3998)
			(xy 388.634224 -265.379962) (xy 388.632192 -265.374882) (xy 388.630668 -265.370564) (xy 388.629398 -265.367262)
			(xy 388.618984 -265.359134) (xy 388.613725 -265.355295) (xy 388.601765 -265.350159) (xy 388.595362 -265.348974)
			(xy 388.594092 -265.34872) (xy 388.507478 -265.33729) (xy 388.500741 -265.336712) (xy 388.487362 -265.338643)
			(xy 388.481062 -265.3411) (xy 388.46887 -265.34618) (xy 388.465314 -265.350752) (xy 388.460234 -265.35761)
			(xy 388.44573 -265.376439) (xy 388.411874 -265.409794) (xy 388.373261 -265.437505) (xy 388.330822 -265.458901)
			(xy 388.285583 -265.473468) (xy 388.238633 -265.480854) (xy 388.21487 -265.481308) (xy 388.189616 -265.480784)
			(xy 388.139798 -265.472466) (xy 388.092029 -265.456063) (xy 388.04761 -265.432021) (xy 388.007755 -265.400996)
			(xy 387.973549 -265.363835) (xy 387.945925 -265.321551) (xy 387.925638 -265.275297) (xy 387.91324 -265.226335)
			(xy 387.909069 -265.176) (xy 387.91324 -265.125665) (xy 387.925638 -265.076703) (xy 387.945925 -265.030449)
			(xy 387.973549 -264.988165) (xy 388.007755 -264.951004) (xy 388.04761 -264.919979) (xy 388.092029 -264.895937)
			(xy 388.139798 -264.879534) (xy 388.189616 -264.871216) (xy 388.21487 -264.870692) (xy 388.215124 -264.870692)
			(xy 388.238891 -264.87114) (xy 388.28585 -264.8785) (xy 388.331101 -264.893053) (xy 388.373547 -264.914448)
			(xy 388.412162 -264.942166) (xy 388.446011 -264.975537) (xy 388.460488 -264.99439) (xy 388.464552 -264.999978)
			(xy 388.475474 -265.008614) (xy 388.481062 -265.0109) (xy 388.487114 -265.01329) (xy 388.499976 -265.015225)
			(xy 388.506462 -265.01471) (xy 388.530846 -265.011662) (xy 388.531354 -265.011662) (xy 388.594092 -265.00328)
			(xy 388.595362 -265.003026) (xy 388.601771 -265.001861) (xy 388.613737 -264.996725) (xy 388.618984 -264.992866)
			(xy 388.629398 -264.984738) (xy 388.630668 -264.981182) (xy 388.632192 -264.977118) (xy 388.634224 -264.972038)
			(xy 388.644912 -264.945787) (xy 388.670872 -264.895398) (xy 388.68604 -264.871454) (xy 388.697891 -264.853574)
			(xy 388.723955 -264.8195) (xy 388.73811 -264.803382) (xy 388.738364 -264.803128) (xy 388.740142 -264.801096)
			(xy 388.744968 -264.795508) (xy 388.74827 -264.786872) (xy 388.749032 -264.785094) (xy 388.750261 -264.781145)
			(xy 388.751532 -264.772974) (xy 388.751572 -264.768838) (xy 388.751572 -264.742168) (xy 388.751098 -264.732593)
			(xy 388.743923 -264.714831) (xy 388.737602 -264.707624) (xy 388.718806 -264.689844) (xy 388.70763 -264.682732)
			(xy 388.691882 -264.676128) (xy 388.690866 -264.67562) (xy 388.680452 -264.671556) (xy 388.673594 -264.671048)
			(xy 388.671308 -264.671048) (xy 388.645442 -264.669363) (xy 388.59479 -264.658378) (xy 388.546721 -264.638995)
			(xy 388.502616 -264.611773) (xy 388.463742 -264.577494) (xy 388.431215 -264.537142) (xy 388.40597 -264.491876)
			(xy 388.388732 -264.442997) (xy 388.379997 -264.391909) (xy 388.379462 -264.365994) (xy 388.379684 -264.349479)
			(xy 388.383249 -264.316641) (xy 388.386574 -264.300462) (xy 388.388098 -264.293604) (xy 388.389114 -264.289286)
			(xy 388.386574 -264.278364) (xy 388.385088 -264.272974) (xy 388.380083 -264.262979) (xy 388.376668 -264.258552)
			(xy 388.357872 -264.235184) (xy 388.3279 -264.197846) (xy 388.32044 -264.189353) (xy 388.300077 -264.179586)
			(xy 388.288784 -264.17905) (xy 388.140702 -264.17905) (xy 388.12943 -264.179671) (xy 388.109105 -264.189427)
			(xy 388.101586 -264.197846) (xy 388.071614 -264.235184) (xy 388.052818 -264.258552) (xy 388.04941 -264.262983)
			(xy 388.044417 -264.272981) (xy 388.042912 -264.278364) (xy 388.040372 -264.289286) (xy 388.041388 -264.293604)
			(xy 388.042912 -264.300462) (xy 388.046235 -264.316641) (xy 388.049795 -264.349479) (xy 388.050024 -264.365994)
			(xy 388.049502 -264.391249) (xy 388.041189 -264.441071) (xy 388.024788 -264.488845) (xy 388.000747 -264.533268)
			(xy 387.969723 -264.573128) (xy 387.932561 -264.607338) (xy 387.890275 -264.634964) (xy 387.844019 -264.655254)
			(xy 387.795054 -264.667654) (xy 387.744716 -264.671825) (xy 387.694378 -264.667654) (xy 387.645413 -264.655254)
			(xy 387.599157 -264.634964) (xy 387.556871 -264.607338) (xy 387.519709 -264.573128) (xy 387.488685 -264.533268)
			(xy 387.464644 -264.488845) (xy 387.448243 -264.441071) (xy 387.43993 -264.391249) (xy 387.439408 -264.365994)
			(xy 387.43963 -264.349479) (xy 387.443196 -264.316641) (xy 387.44652 -264.300462) (xy 387.448044 -264.293604)
			(xy 387.44906 -264.289286) (xy 387.44652 -264.278364) (xy 387.445035 -264.272973) (xy 387.440034 -264.262976)
			(xy 387.436614 -264.258552) (xy 387.417818 -264.235184) (xy 387.387846 -264.197846) (xy 387.380389 -264.189345)
			(xy 387.360027 -264.17956) (xy 387.34873 -264.17905) (xy 387.200902 -264.17905) (xy 387.18963 -264.179671)
			(xy 387.169305 -264.189427) (xy 387.161786 -264.197846) (xy 387.131814 -264.235184) (xy 387.113018 -264.258552)
			(xy 387.10961 -264.262983) (xy 387.104617 -264.272981) (xy 387.103112 -264.278364) (xy 387.100572 -264.289286)
			(xy 387.101588 -264.293604) (xy 387.103112 -264.300462) (xy 387.106435 -264.316641) (xy 387.109995 -264.349479)
			(xy 387.110224 -264.365994) (xy 387.109702 -264.391249) (xy 387.101389 -264.441071) (xy 387.084988 -264.488845)
			(xy 387.060947 -264.533268) (xy 387.029923 -264.573128) (xy 386.992761 -264.607338) (xy 386.950475 -264.634964)
			(xy 386.904219 -264.655254) (xy 386.855254 -264.667654) (xy 386.804916 -264.671825) (xy 386.754578 -264.667654)
			(xy 386.705613 -264.655254) (xy 386.659357 -264.634964) (xy 386.617071 -264.607338) (xy 386.579909 -264.573128)
			(xy 386.548885 -264.533268) (xy 386.524844 -264.488845) (xy 386.508443 -264.441071) (xy 386.50013 -264.391249)
			(xy 386.499608 -264.365994) (xy 386.49983 -264.349479) (xy 386.503396 -264.316641) (xy 386.50672 -264.300462)
			(xy 386.508244 -264.293604) (xy 386.50926 -264.289286) (xy 386.50672 -264.278364) (xy 386.505235 -264.272973)
			(xy 386.500234 -264.262976) (xy 386.496814 -264.258552) (xy 386.478018 -264.235184) (xy 386.448046 -264.197846)
			(xy 386.440589 -264.189345) (xy 386.420227 -264.17956) (xy 386.40893 -264.17905) (xy 386.260848 -264.17905)
			(xy 386.249581 -264.179682) (xy 386.229275 -264.189451) (xy 386.221732 -264.197846) (xy 386.19176 -264.235184)
			(xy 386.172964 -264.258552) (xy 386.169559 -264.262984) (xy 386.164571 -264.272983) (xy 386.163058 -264.278364)
			(xy 386.160518 -264.289286) (xy 386.161534 -264.293604) (xy 386.163058 -264.300462) (xy 386.166382 -264.316641)
			(xy 386.169942 -264.349479) (xy 386.17017 -264.365994) (xy 386.169648 -264.391249) (xy 386.161335 -264.441071)
			(xy 386.144934 -264.488845) (xy 386.120893 -264.533268) (xy 386.089869 -264.573128) (xy 386.052707 -264.607338)
			(xy 386.010421 -264.634964) (xy 385.964165 -264.655254) (xy 385.9152 -264.667654) (xy 385.864862 -264.671825)
			(xy 385.814524 -264.667654) (xy 385.765559 -264.655254) (xy 385.719303 -264.634964) (xy 385.677017 -264.607338)
			(xy 385.639855 -264.573128) (xy 385.608831 -264.533268) (xy 385.58479 -264.488845) (xy 385.568389 -264.441071)
			(xy 385.560076 -264.391249) (xy 385.559554 -264.365994) (xy 385.559776 -264.349479) (xy 385.563341 -264.316641)
			(xy 385.566666 -264.300462) (xy 385.56819 -264.293604) (xy 385.569206 -264.289286) (xy 385.566666 -264.278364)
			(xy 385.565179 -264.272974) (xy 385.560174 -264.26298) (xy 385.55676 -264.258552) (xy 385.537964 -264.235184)
			(xy 385.507992 -264.197846) (xy 385.500532 -264.189354) (xy 385.480169 -264.17959) (xy 385.468876 -264.17905)
			(xy 385.320794 -264.17905) (xy 385.309523 -264.179673) (xy 385.289201 -264.18943) (xy 385.281678 -264.197846)
			(xy 385.251706 -264.235184) (xy 385.23291 -264.258552) (xy 385.229503 -264.262983) (xy 385.22451 -264.272981)
			(xy 385.223004 -264.278364) (xy 385.220464 -264.289286) (xy 385.22148 -264.293604) (xy 385.223004 -264.300462)
			(xy 385.226327 -264.316641) (xy 385.229887 -264.349479) (xy 385.230116 -264.365994) (xy 385.229594 -264.391249)
			(xy 385.221281 -264.441071) (xy 385.20488 -264.488845) (xy 385.180839 -264.533268) (xy 385.149815 -264.573128)
			(xy 385.112653 -264.607338) (xy 385.070367 -264.634964) (xy 385.024111 -264.655254) (xy 384.975146 -264.667654)
			(xy 384.924808 -264.671825) (xy 384.87447 -264.667654) (xy 384.825505 -264.655254) (xy 384.779249 -264.634964)
			(xy 384.736963 -264.607338) (xy 384.699801 -264.573128) (xy 384.668777 -264.533268) (xy 384.644736 -264.488845)
			(xy 384.628335 -264.441071) (xy 384.620022 -264.391249) (xy 384.6195 -264.365994) (xy 384.619722 -264.349479)
			(xy 384.623288 -264.316641) (xy 384.626612 -264.300462) (xy 384.628136 -264.293604) (xy 384.629152 -264.289286)
			(xy 384.626612 -264.278364) (xy 384.625127 -264.272974) (xy 384.620125 -264.262976) (xy 384.616706 -264.258552)
			(xy 384.59791 -264.235184) (xy 384.567938 -264.197846) (xy 384.560481 -264.189346) (xy 384.540118 -264.179564)
			(xy 384.528822 -264.17905) (xy 384.38074 -264.17905) (xy 384.369474 -264.179684) (xy 384.34917 -264.189455)
			(xy 384.341624 -264.197846) (xy 384.311652 -264.235184) (xy 384.292856 -264.258552) (xy 384.289452 -264.262984)
			(xy 384.284464 -264.272984) (xy 384.28295 -264.278364) (xy 384.28041 -264.289286) (xy 384.281426 -264.293604)
			(xy 384.28295 -264.300462) (xy 384.286274 -264.316641) (xy 384.289835 -264.349479) (xy 384.290062 -264.365994)
			(xy 384.28954 -264.391249) (xy 384.281227 -264.441071) (xy 384.264826 -264.488845) (xy 384.240785 -264.533268)
			(xy 384.209761 -264.573128) (xy 384.172599 -264.607338) (xy 384.130313 -264.634964) (xy 384.084057 -264.655254)
			(xy 384.035092 -264.667654) (xy 383.984754 -264.671825) (xy 383.934416 -264.667654) (xy 383.885451 -264.655254)
			(xy 383.839195 -264.634964) (xy 383.796909 -264.607338) (xy 383.759747 -264.573128) (xy 383.728723 -264.533268)
			(xy 383.704682 -264.488845) (xy 383.688281 -264.441071) (xy 383.679968 -264.391249) (xy 383.679446 -264.365994)
			(xy 383.679668 -264.349479) (xy 383.683233 -264.316641) (xy 383.686558 -264.300462) (xy 383.688082 -264.293604)
			(xy 383.689098 -264.289286) (xy 383.686558 -264.278364) (xy 383.685071 -264.272975) (xy 383.680065 -264.26298)
			(xy 383.676652 -264.258552) (xy 383.657856 -264.235184) (xy 383.627884 -264.197846) (xy 383.62043 -264.189339)
			(xy 383.600067 -264.179538) (xy 383.588768 -264.17905) (xy 383.440686 -264.17905) (xy 383.429415 -264.179674)
			(xy 383.409096 -264.189434) (xy 383.40157 -264.197846) (xy 383.371598 -264.235184) (xy 383.352802 -264.258552)
			(xy 383.349395 -264.262983) (xy 383.344403 -264.272981) (xy 383.342896 -264.278364) (xy 383.340356 -264.289286)
			(xy 383.341372 -264.293604) (xy 383.342896 -264.300462) (xy 383.346219 -264.316641) (xy 383.34978 -264.349479)
			(xy 383.350008 -264.365994) (xy 383.349486 -264.391249) (xy 383.341173 -264.441071) (xy 383.324772 -264.488845)
			(xy 383.300731 -264.533268) (xy 383.269707 -264.573128) (xy 383.232545 -264.607338) (xy 383.190259 -264.634964)
			(xy 383.144003 -264.655254) (xy 383.095038 -264.667654) (xy 383.0447 -264.671825) (xy 382.994362 -264.667654)
			(xy 382.945397 -264.655254) (xy 382.899141 -264.634964) (xy 382.856855 -264.607338) (xy 382.819693 -264.573128)
			(xy 382.788669 -264.533268) (xy 382.764628 -264.488845) (xy 382.748227 -264.441071) (xy 382.739914 -264.391249)
			(xy 382.739392 -264.365994) (xy 382.739614 -264.349479) (xy 382.74318 -264.316641) (xy 382.746504 -264.300462)
			(xy 382.748028 -264.293604) (xy 382.749044 -264.289286) (xy 382.746504 -264.278364) (xy 382.745018 -264.272974)
			(xy 382.740016 -264.262977) (xy 382.736598 -264.258552) (xy 382.717802 -264.235184) (xy 382.68783 -264.197846)
			(xy 382.680372 -264.189347) (xy 382.660009 -264.179568) (xy 382.648714 -264.17905) (xy 382.500886 -264.17905)
			(xy 382.489615 -264.179674) (xy 382.469296 -264.189434) (xy 382.46177 -264.197846) (xy 382.431798 -264.235184)
			(xy 382.413002 -264.258552) (xy 382.409595 -264.262983) (xy 382.404603 -264.272981) (xy 382.403096 -264.278364)
			(xy 382.400556 -264.289286) (xy 382.401572 -264.293604) (xy 382.403096 -264.300462) (xy 382.406419 -264.316641)
			(xy 382.40998 -264.349479) (xy 382.410208 -264.365994) (xy 382.409686 -264.391249) (xy 382.401373 -264.441071)
			(xy 382.384972 -264.488845) (xy 382.360931 -264.533268) (xy 382.329907 -264.573128) (xy 382.292745 -264.607338)
			(xy 382.250459 -264.634964) (xy 382.204203 -264.655254) (xy 382.155238 -264.667654) (xy 382.1049 -264.671825)
			(xy 382.054562 -264.667654) (xy 382.005597 -264.655254) (xy 381.959341 -264.634964) (xy 381.917055 -264.607338)
			(xy 381.879893 -264.573128) (xy 381.848869 -264.533268) (xy 381.824828 -264.488845) (xy 381.808427 -264.441071)
			(xy 381.800114 -264.391249) (xy 381.799592 -264.365994) (xy 381.799814 -264.349479) (xy 381.80338 -264.316641)
			(xy 381.806704 -264.300462) (xy 381.808228 -264.293604) (xy 381.809244 -264.289286) (xy 381.806704 -264.278364)
			(xy 381.805218 -264.272974) (xy 381.800216 -264.262977) (xy 381.796798 -264.258552) (xy 381.778002 -264.235184)
			(xy 381.74803 -264.197846) (xy 381.740572 -264.189347) (xy 381.720209 -264.179568) (xy 381.708914 -264.17905)
			(xy 381.560832 -264.17905) (xy 381.549567 -264.179685) (xy 381.529265 -264.189458) (xy 381.521716 -264.197846)
			(xy 381.480568 -264.249154) (xy 381.471932 -264.259822) (xy 381.466344 -264.26922) (xy 381.471678 -264.291572)
			(xy 381.471678 -264.29208) (xy 381.475809 -264.31028) (xy 381.480262 -264.347334) (xy 381.480568 -264.365994)
			(xy 381.480081 -264.390804) (xy 381.472319 -264.439812) (xy 381.456986 -264.487002) (xy 381.434459 -264.531213)
			(xy 381.405294 -264.571356) (xy 381.370208 -264.606442) (xy 381.330065 -264.635607) (xy 381.285854 -264.658134)
			(xy 381.238664 -264.673467) (xy 381.189656 -264.681229) (xy 381.140036 -264.681229) (xy 381.091028 -264.673467)
			(xy 381.043838 -264.658134) (xy 380.999627 -264.635607) (xy 380.959484 -264.606442) (xy 380.924398 -264.571356)
			(xy 380.895233 -264.531213) (xy 380.872706 -264.487002) (xy 380.857373 -264.439812) (xy 380.849611 -264.390804)
			(xy 380.849124 -264.365994) (xy 380.849419 -264.347271) (xy 380.853878 -264.310089) (xy 380.858014 -264.291826)
			(xy 380.858014 -264.291572) (xy 380.860209 -264.28017) (xy 380.85519 -264.257527) (xy 380.848362 -264.248138)
			(xy 380.807976 -264.197846) (xy 380.800521 -264.18934) (xy 380.780159 -264.179542) (xy 380.76886 -264.17905)
			(xy 380.620778 -264.17905) (xy 380.609508 -264.179676) (xy 380.589192 -264.189438) (xy 380.581662 -264.197846)
			(xy 380.55169 -264.235184) (xy 380.532894 -264.258552) (xy 380.529488 -264.262983) (xy 380.524496 -264.272982)
			(xy 380.522988 -264.278364) (xy 380.520448 -264.289286) (xy 380.521464 -264.293604) (xy 380.522988 -264.300462)
			(xy 380.526311 -264.316641) (xy 380.529872 -264.349479) (xy 380.5301 -264.365994) (xy 380.529654 -264.389987)
			(xy 380.522148 -264.437383) (xy 380.50732 -264.483021) (xy 380.485535 -264.525777) (xy 380.457329 -264.564599)
			(xy 380.423398 -264.598531) (xy 380.384576 -264.626736) (xy 380.341819 -264.648521) (xy 380.296181 -264.663349)
			(xy 380.248785 -264.670854) (xy 380.224792 -264.671302) (xy 380.212029 -264.671165) (xy 380.186595 -264.669005)
			(xy 380.173992 -264.666984) (xy 380.173992 -264.667238) (xy 380.15102 -264.662919) (xy 380.106648 -264.648224)
			(xy 380.065035 -264.626939) (xy 380.02715 -264.599561) (xy 379.993881 -264.56673) (xy 379.966003 -264.529213)
			(xy 379.944167 -264.487885) (xy 379.928885 -264.443713) (xy 379.920513 -264.397727) (xy 379.919484 -264.374376)
			(xy 379.919484 -264.365994) (xy 379.920048 -264.339295) (xy 379.929282 -264.286701) (xy 379.947504 -264.236508)
			(xy 379.974161 -264.19024) (xy 379.990858 -264.169398) (xy 379.991112 -264.169398) (xy 379.991366 -264.16889)
			(xy 379.99416 -264.165588) (xy 379.994414 -264.165334) (xy 379.997208 -264.161778) (xy 380.001526 -264.150856)
			(xy 380.002034 -264.14984) (xy 380.006352 -264.138156) (xy 380.007869 -264.133867) (xy 380.009524 -264.124923)
			(xy 380.009654 -264.120376) (xy 380.009908 -264.099294) (xy 380.009429 -264.089479) (xy 380.001976 -264.071318)
			(xy 379.99543 -264.063988) (xy 379.807216 -263.875774) (xy 379.799088 -263.86917) (xy 379.777498 -263.870694)
			(xy 379.754892 -263.871456) (xy 379.730101 -263.870994) (xy 379.68113 -263.863237) (xy 379.633976 -263.847914)
			(xy 379.589799 -263.825403) (xy 379.549687 -263.796258) (xy 379.514629 -263.761198) (xy 379.485487 -263.721084)
			(xy 379.462978 -263.676906) (xy 379.447659 -263.62975) (xy 379.439904 -263.580779) (xy 379.439424 -263.555988)
			(xy 379.440186 -263.533382) (xy 379.440186 -263.533128) (xy 379.440391 -263.522291) (xy 379.432749 -263.50203)
			(xy 379.425454 -263.494012) (xy 379.28423 -263.352788) (xy 379.276984 -263.346229) (xy 379.25894 -263.338772)
			(xy 379.249178 -263.33831) (xy 378.262642 -263.33831) (xy 378.250898 -263.338923) (xy 378.22994 -263.349518)
			(xy 378.22251 -263.35863) (xy 378.187458 -263.405874) (xy 378.18695 -263.406382) (xy 378.17425 -263.423908)
			(xy 378.171456 -263.42848) (xy 378.167646 -263.436354) (xy 378.175012 -263.458706) (xy 378.182142 -263.482392)
			(xy 378.189803 -263.531257) (xy 378.190252 -263.555988) (xy 378.189766 -263.580778) (xy 378.18201 -263.629746)
			(xy 378.166689 -263.676899) (xy 378.14418 -263.721074) (xy 378.115038 -263.761185) (xy 378.079981 -263.796242)
			(xy 378.03987 -263.825384) (xy 377.995695 -263.847893) (xy 377.948542 -263.863214) (xy 377.899574 -263.87097)
			(xy 377.849994 -263.87097) (xy 377.801026 -263.863214) (xy 377.753873 -263.847893) (xy 377.709698 -263.825384)
			(xy 377.669587 -263.796242) (xy 377.63453 -263.761185) (xy 377.605388 -263.721074) (xy 377.582879 -263.676899)
			(xy 377.567558 -263.629746) (xy 377.559802 -263.580778) (xy 377.559316 -263.555988) (xy 377.559732 -263.531254)
			(xy 377.56739 -263.482383) (xy 377.574556 -263.458706) (xy 377.582176 -263.435084) (xy 377.581922 -263.432798)
			(xy 377.527058 -263.35863) (xy 377.519574 -263.349579) (xy 377.49865 -263.338976) (xy 377.486926 -263.33831)
			(xy 377.322588 -263.33831) (xy 377.310851 -263.338935) (xy 377.289912 -263.349542) (xy 377.282456 -263.35863)
			(xy 377.25858 -263.390888) (xy 377.233688 -263.424416) (xy 377.230711 -263.428997) (xy 377.226612 -263.439121)
			(xy 377.22556 -263.444482) (xy 377.223528 -263.455912) (xy 377.223782 -263.457436) (xy 377.227084 -263.46785)
			(xy 377.23319 -263.489564) (xy 377.239701 -263.534197) (xy 377.240038 -263.55675) (xy 377.240038 -263.560306)
			(xy 377.239181 -263.585327) (xy 377.230317 -263.634598) (xy 377.213534 -263.681763) (xy 377.189283 -263.725559)
			(xy 377.158212 -263.764812) (xy 377.121153 -263.79847) (xy 377.079101 -263.825633) (xy 377.033181 -263.845572)
			(xy 376.984624 -263.857753) (xy 376.93473 -263.86185) (xy 376.884836 -263.857753) (xy 376.836279 -263.845572)
			(xy 376.790359 -263.825633) (xy 376.748307 -263.79847) (xy 376.711248 -263.764812) (xy 376.680177 -263.725559)
			(xy 376.655926 -263.681763) (xy 376.639143 -263.634598) (xy 376.630279 -263.585327) (xy 376.629422 -263.560306)
			(xy 376.629422 -263.55675) (xy 376.629748 -263.534195) (xy 376.636249 -263.489559) (xy 376.642376 -263.46785)
			(xy 376.645678 -263.457436) (xy 376.645932 -263.455912) (xy 376.6439 -263.444482) (xy 376.642831 -263.439126)
			(xy 376.638735 -263.429004) (xy 376.635772 -263.424416) (xy 376.61088 -263.390888) (xy 376.587004 -263.35863)
			(xy 376.579516 -263.349589) (xy 376.558592 -263.339007) (xy 376.546872 -263.33831) (xy 376.382788 -263.33831)
			(xy 376.371051 -263.338935) (xy 376.350112 -263.349542) (xy 376.342656 -263.35863) (xy 376.307604 -263.405874)
			(xy 376.307096 -263.406382) (xy 376.294396 -263.423908) (xy 376.291602 -263.42848) (xy 376.287792 -263.436354)
			(xy 376.295158 -263.458706) (xy 376.302388 -263.482374) (xy 376.31017 -263.531245) (xy 376.310652 -263.555988)
			(xy 376.310165 -263.580798) (xy 376.302403 -263.629806) (xy 376.28707 -263.676996) (xy 376.264543 -263.721207)
			(xy 376.235378 -263.76135) (xy 376.200292 -263.796436) (xy 376.160149 -263.825601) (xy 376.115938 -263.848128)
			(xy 376.068748 -263.863461) (xy 376.01974 -263.871223) (xy 375.97012 -263.871223) (xy 375.921112 -263.863461)
			(xy 375.873922 -263.848128) (xy 375.829711 -263.825601) (xy 375.789568 -263.796436) (xy 375.754482 -263.76135)
			(xy 375.725317 -263.721207) (xy 375.70279 -263.676996) (xy 375.687457 -263.629806) (xy 375.679695 -263.580798)
			(xy 375.679208 -263.555988) (xy 375.679732 -263.531249) (xy 375.687516 -263.482385) (xy 375.694702 -263.458706)
			(xy 375.702322 -263.435084) (xy 375.702068 -263.432798) (xy 375.647204 -263.35863) (xy 375.639716 -263.349589)
			(xy 375.618792 -263.339007) (xy 375.607072 -263.33831) (xy 375.442734 -263.33831) (xy 375.430991 -263.338925)
			(xy 375.410036 -263.349521) (xy 375.402602 -263.35863) (xy 375.378726 -263.390888) (xy 375.353834 -263.424416)
			(xy 375.350869 -263.429003) (xy 375.346776 -263.439126) (xy 375.345706 -263.444482) (xy 375.343674 -263.455912)
			(xy 375.343928 -263.457436) (xy 375.34723 -263.46785) (xy 375.353335 -263.489564) (xy 375.359845 -263.534197)
			(xy 375.360184 -263.55675) (xy 375.360184 -263.560306) (xy 375.359327 -263.585327) (xy 375.350463 -263.634598)
			(xy 375.33368 -263.681763) (xy 375.309429 -263.725559) (xy 375.278358 -263.764812) (xy 375.241299 -263.79847)
			(xy 375.199247 -263.825633) (xy 375.153327 -263.845572) (xy 375.10477 -263.857753) (xy 375.054876 -263.86185)
			(xy 375.004982 -263.857753) (xy 374.956425 -263.845572) (xy 374.910505 -263.825633) (xy 374.868453 -263.79847)
			(xy 374.831394 -263.764812) (xy 374.800323 -263.725559) (xy 374.776072 -263.681763) (xy 374.759289 -263.634598)
			(xy 374.750425 -263.585327) (xy 374.749568 -263.560306) (xy 374.749568 -263.55675) (xy 374.749894 -263.534195)
			(xy 374.756394 -263.489559) (xy 374.762522 -263.46785) (xy 374.765824 -263.457436) (xy 374.766078 -263.455912)
			(xy 374.764046 -263.444482) (xy 374.762978 -263.439126) (xy 374.758885 -263.429001) (xy 374.755918 -263.424416)
			(xy 374.731026 -263.390888) (xy 374.70715 -263.35863) (xy 374.699665 -263.349581) (xy 374.678742 -263.338981)
			(xy 374.667018 -263.33831) (xy 373.562626 -263.33831) (xy 373.550884 -263.338927) (xy 373.529932 -263.349525)
			(xy 373.522494 -263.35863) (xy 373.498618 -263.390888) (xy 373.473726 -263.424416) (xy 373.470762 -263.429003)
			(xy 373.466669 -263.439126) (xy 373.465598 -263.444482) (xy 373.463566 -263.455912) (xy 373.46382 -263.457436)
			(xy 373.467122 -263.46785) (xy 373.473227 -263.489564) (xy 373.479737 -263.534197) (xy 373.480076 -263.55675)
			(xy 373.480076 -263.560306) (xy 373.479219 -263.585327) (xy 373.470355 -263.634598) (xy 373.453572 -263.681763)
			(xy 373.429321 -263.725559) (xy 373.39825 -263.764812) (xy 373.361191 -263.79847) (xy 373.319139 -263.825633)
			(xy 373.273219 -263.845572) (xy 373.224662 -263.857753) (xy 373.174768 -263.86185) (xy 373.124874 -263.857753)
			(xy 373.076317 -263.845572) (xy 373.030397 -263.825633) (xy 372.988345 -263.79847) (xy 372.951286 -263.764812)
			(xy 372.920215 -263.725559) (xy 372.895964 -263.681763) (xy 372.879181 -263.634598) (xy 372.870317 -263.585327)
			(xy 372.86946 -263.560306) (xy 372.86946 -263.55675) (xy 372.869786 -263.534195) (xy 372.876285 -263.489559)
			(xy 372.882414 -263.46785) (xy 372.885716 -263.457436) (xy 372.88597 -263.455912) (xy 372.883938 -263.444482)
			(xy 372.88287 -263.439126) (xy 372.878776 -263.429002) (xy 372.87581 -263.424416) (xy 372.850918 -263.390888)
			(xy 372.827042 -263.35863) (xy 372.819557 -263.349582) (xy 372.798633 -263.338985) (xy 372.78691 -263.33831)
			(xy 372.025926 -263.33831) (xy 372.016089 -263.337774) (xy 371.997927 -263.330187) (xy 371.99062 -263.323578)
			(xy 371.724936 -263.057894) (xy 371.722258 -263.055287) (xy 371.716261 -263.050827) (xy 371.712998 -263.049004)
			(xy 371.70741 -263.045956) (xy 371.700044 -263.044432) (xy 371.67576 -263.038655) (xy 371.629352 -263.020279)
			(xy 371.58655 -262.9946) (xy 371.548494 -262.962303) (xy 371.516197 -262.924246) (xy 371.490519 -262.881444)
			(xy 371.472144 -262.835036) (xy 371.466364 -262.810752) (xy 371.46484 -262.803386) (xy 371.461792 -262.797798)
			(xy 371.459956 -262.794544) (xy 371.455495 -262.78855) (xy 371.452902 -262.78586) (xy 371.13083 -262.463788)
			(xy 371.123584 -262.457229) (xy 371.10554 -262.449772) (xy 371.095778 -262.44931) (xy 371.080538 -262.44931)
			(xy 371.069028 -262.449876) (xy 371.048371 -262.460031) (xy 371.034327 -262.478268) (xy 371.031516 -262.489442)
			(xy 371.031516 -262.501634) (xy 371.031651 -262.506525) (xy 371.033567 -262.516119) (xy 371.035326 -262.520684)
			(xy 371.037866 -262.527034) (xy 371.04193 -262.531352) (xy 371.045486 -262.535162) (xy 371.061263 -262.552297)
			(xy 371.087961 -262.59046) (xy 371.108548 -262.632239) (xy 371.122545 -262.676661) (xy 371.129627 -262.722694)
			(xy 371.130068 -262.745982) (xy 371.129623 -262.769975) (xy 371.122118 -262.81737) (xy 371.107291 -262.863008)
			(xy 371.085506 -262.905763) (xy 371.0573 -262.944584) (xy 371.023368 -262.978514) (xy 370.984545 -263.006717)
			(xy 370.941787 -263.028499) (xy 370.896149 -263.043324) (xy 370.848753 -263.050825) (xy 370.82476 -263.05129)
			(xy 370.80106 -263.050839) (xy 370.75423 -263.04351) (xy 370.709096 -263.029033) (xy 370.66674 -263.007756)
			(xy 370.628179 -262.98019) (xy 370.594341 -262.946998) (xy 370.566038 -262.908976) (xy 370.543949 -262.867038)
			(xy 370.528605 -262.82219) (xy 370.520375 -262.77551) (xy 370.519452 -262.751824) (xy 370.519452 -262.745982)
			(xy 370.519982 -262.720347) (xy 370.528545 -262.669797) (xy 370.545411 -262.621381) (xy 370.557298 -262.598662)
			(xy 370.557552 -262.598154) (xy 370.559076 -262.59536) (xy 370.561412 -262.590008) (xy 370.563859 -262.578593)
			(xy 370.563902 -262.572754) (xy 370.563902 -262.5598) (xy 370.56314 -262.55853) (xy 370.557298 -262.548624)
			(xy 370.513356 -262.473948) (xy 370.508661 -262.466666) (xy 370.495358 -262.455586) (xy 370.479086 -262.449673)
			(xy 370.47043 -262.44931) (xy 370.239036 -262.44931) (xy 370.230384 -262.449712) (xy 370.214117 -262.455621)
			(xy 370.200786 -262.46666) (xy 370.19611 -262.473948) (xy 370.152168 -262.548624) (xy 370.14912 -262.553958)
			(xy 370.145564 -262.566658) (xy 370.145564 -262.572754) (xy 370.145609 -262.578594) (xy 370.148048 -262.590011)
			(xy 370.15039 -262.59536) (xy 370.151914 -262.598154) (xy 370.163887 -262.620936) (xy 370.180874 -262.669515)
			(xy 370.189499 -262.720251) (xy 370.190014 -262.745982) (xy 370.190014 -262.751824) (xy 370.189041 -262.776763)
			(xy 370.179985 -262.82584) (xy 370.16307 -262.872792) (xy 370.138744 -262.916369) (xy 370.107657 -262.95541)
			(xy 370.070635 -262.988876) (xy 370.028664 -263.015877) (xy 369.982861 -263.035693) (xy 369.934446 -263.047798)
			(xy 369.884706 -263.051869) (xy 369.834966 -263.047798) (xy 369.786551 -263.035693) (xy 369.740748 -263.015877)
			(xy 369.698777 -262.988876) (xy 369.661755 -262.95541) (xy 369.630668 -262.916369) (xy 369.606342 -262.872792)
			(xy 369.589427 -262.82584) (xy 369.580371 -262.776763) (xy 369.579398 -262.751824) (xy 369.579398 -262.745982)
			(xy 369.579929 -262.720347) (xy 369.588493 -262.669798) (xy 369.605361 -262.621383) (xy 369.617244 -262.598662)
			(xy 369.617498 -262.598154) (xy 369.619022 -262.59536) (xy 369.62136 -262.590009) (xy 369.623809 -262.578593)
			(xy 369.623848 -262.572754) (xy 369.623848 -262.5598) (xy 369.623086 -262.55853) (xy 369.617244 -262.548624)
			(xy 369.573302 -262.473948) (xy 369.568605 -262.466672) (xy 369.555299 -262.455607) (xy 369.539028 -262.449711)
			(xy 369.530376 -262.44931) (xy 367.580926 -262.44931) (xy 367.571089 -262.448774) (xy 367.552927 -262.441187)
			(xy 367.54562 -262.434578) (xy 366.93983 -261.828788) (xy 366.932584 -261.822229) (xy 366.91454 -261.814772)
			(xy 366.904778 -261.81431) (xy 365.79937 -261.81431) (xy 365.789518 -261.813824) (xy 365.771319 -261.806273)
			(xy 365.757395 -261.792332) (xy 365.749865 -261.774124) (xy 365.749332 -261.764272) (xy 365.749332 -261.582916)
			(xy 365.748914 -261.57402) (xy 365.742645 -261.557364) (xy 365.731012 -261.543895) (xy 365.723424 -261.539228)
			(xy 365.638842 -261.497318) (xy 365.632899 -261.495023) (xy 365.620309 -261.493107) (xy 365.61395 -261.493508)
			(xy 365.600234 -261.494778) (xy 365.58855 -261.503668) (xy 365.565986 -261.520092) (xy 365.516653 -261.54618)
			(xy 365.463756 -261.563961) (xy 365.408681 -261.572968) (xy 365.380778 -261.573518) (xy 365.355079 -261.573036)
			(xy 365.304257 -261.565373) (xy 365.255144 -261.550221) (xy 365.208838 -261.527918) (xy 365.166372 -261.498964)
			(xy 365.128697 -261.464003) (xy 365.096652 -261.423819) (xy 365.070955 -261.379307) (xy 365.052178 -261.331462)
			(xy 365.040741 -261.281353) (xy 365.0369 -261.2301) (xy 365.040741 -261.178847) (xy 365.052178 -261.128738)
			(xy 365.070955 -261.080893) (xy 365.096652 -261.036381) (xy 365.128697 -260.996197) (xy 365.166372 -260.961236)
			(xy 365.208838 -260.932282) (xy 365.255144 -260.909979) (xy 365.304257 -260.894827) (xy 365.355079 -260.887164)
			(xy 365.380778 -260.886702) (xy 365.408682 -260.887242) (xy 365.463759 -260.896248) (xy 365.516661 -260.914026)
			(xy 365.565998 -260.940111) (xy 365.58855 -260.956552) (xy 365.590836 -260.95833) (xy 365.596195 -260.961768)
			(xy 365.608145 -260.966148) (xy 365.614458 -260.966966) (xy 365.621062 -260.967474) (xy 365.62792 -260.966204)
			(xy 365.631413 -260.96548) (xy 365.638167 -260.963179) (xy 365.641382 -260.961632) (xy 365.721646 -260.922008)
			(xy 365.72973 -260.917489) (xy 365.742182 -260.903804) (xy 365.748877 -260.886555) (xy 365.749332 -260.877304)
			(xy 365.749332 -260.632956) (xy 365.748921 -260.624057) (xy 365.74266 -260.60739) (xy 365.731029 -260.593909)
			(xy 365.723424 -260.589268) (xy 365.638842 -260.547358) (xy 365.632899 -260.545062) (xy 365.620309 -260.543145)
			(xy 365.61395 -260.543548) (xy 365.600234 -260.544818) (xy 365.58855 -260.553708) (xy 365.565987 -260.570134)
			(xy 365.516655 -260.596227) (xy 365.463757 -260.614011) (xy 365.408682 -260.62302) (xy 365.380778 -260.623558)
			(xy 365.355076 -260.623076) (xy 365.304248 -260.615412) (xy 365.255129 -260.600258) (xy 365.208818 -260.577953)
			(xy 365.166347 -260.548995) (xy 365.128667 -260.514031) (xy 365.096619 -260.473841) (xy 365.070918 -260.429324)
			(xy 365.05214 -260.381474) (xy 365.040702 -260.331359) (xy 365.03686 -260.2801) (xy 365.040702 -260.228841)
			(xy 365.05214 -260.178726) (xy 365.070918 -260.130876) (xy 365.096619 -260.086359) (xy 365.128667 -260.046169)
			(xy 365.166347 -260.011205) (xy 365.208818 -259.982247) (xy 365.255129 -259.959942) (xy 365.304248 -259.944788)
			(xy 365.355076 -259.937124) (xy 365.380778 -259.936742) (xy 365.408682 -259.937283) (xy 365.463759 -259.946289)
			(xy 365.516659 -259.964069) (xy 365.565994 -259.990156) (xy 365.58855 -260.006592) (xy 365.590836 -260.00837)
			(xy 365.596196 -260.011806) (xy 365.608146 -260.016182) (xy 365.614458 -260.017006) (xy 365.621062 -260.017514)
			(xy 365.62792 -260.016244) (xy 365.631414 -260.01552) (xy 365.638168 -260.013222) (xy 365.641382 -260.011672)
			(xy 365.721646 -259.972048) (xy 365.729734 -259.967531) (xy 365.742198 -259.953848) (xy 365.748905 -259.936597)
			(xy 365.749332 -259.927344) (xy 365.749332 -259.650484) (xy 365.748825 -259.64073) (xy 365.741387 -259.62269)
			(xy 365.734854 -259.615432) (xy 365.693452 -259.57403) (xy 365.687356 -259.56895) (xy 365.680812 -259.564488)
			(xy 365.665803 -259.559454) (xy 365.657892 -259.559044) (xy 365.648494 -259.559044) (xy 365.63935 -259.562854)
			(xy 365.634787 -259.564862) (xy 365.626473 -259.570362) (xy 365.62284 -259.573776) (xy 365.622332 -259.574284)
			(xy 365.602916 -259.592772) (xy 365.559411 -259.624101) (xy 365.511566 -259.648288) (xy 365.460544 -259.664745)
			(xy 365.407584 -259.673074) (xy 365.380778 -259.673598) (xy 365.354682 -259.673117) (xy 365.30309 -259.665229)
			(xy 365.253287 -259.649622) (xy 365.20642 -259.626656) (xy 365.163569 -259.596861) (xy 365.125722 -259.560922)
			(xy 365.093751 -259.519669) (xy 365.068393 -259.474052) (xy 365.050232 -259.425122) (xy 365.039687 -259.374007)
			(xy 365.037878 -259.34797) (xy 365.037878 -259.345684) (xy 365.036629 -259.336506) (xy 365.028547 -259.319854)
			(xy 365.02213 -259.313172) (xy 365.015526 -259.306822) (xy 365.006382 -259.303266) (xy 365.00193 -259.301595)
			(xy 364.992594 -259.299796) (xy 364.98784 -259.29971) (xy 363.356906 -259.29971) (xy 363.347071 -259.300251)
			(xy 363.328917 -259.307845) (xy 363.3216 -259.314442) (xy 363.300264 -259.335778) (xy 363.293026 -259.342491)
			(xy 363.274821 -259.350082) (xy 363.264958 -259.35051) (xy 359.699306 -259.35051) (xy 359.68947 -259.34997)
			(xy 359.671314 -259.342378) (xy 359.664 -259.335778) (xy 359.453434 -259.125212) (xy 359.450431 -259.122329)
			(xy 359.443666 -259.117479) (xy 359.439972 -259.11556) (xy 359.427526 -259.111242) (xy 359.420922 -259.109972)
			(xy 359.406444 -259.111242) (xy 359.399078 -259.11429) (xy 359.368854 -259.125479) (xy 359.305567 -259.137625)
			(xy 359.273348 -259.13842) (xy 359.266998 -259.13842) (xy 359.240551 -259.137524) (xy 359.188393 -259.128602)
			(xy 359.138221 -259.111786) (xy 359.091222 -259.087474) (xy 359.048507 -259.056241) (xy 359.011088 -259.018827)
			(xy 358.97985 -258.976116) (xy 358.955532 -258.92912) (xy 358.938709 -258.87895) (xy 358.92978 -258.826794)
			(xy 358.928924 -258.800346) (xy 358.928924 -258.794504) (xy 358.929692 -258.762158) (xy 358.941839 -258.698615)
			(xy 358.953054 -258.668266) (xy 358.954578 -258.664456) (xy 358.956337 -258.658194) (xy 358.956977 -258.645208)
			(xy 358.955848 -258.638802) (xy 358.954578 -258.632198) (xy 358.951276 -258.626102) (xy 358.94944 -258.622848)
			(xy 358.944978 -258.616855) (xy 358.942386 -258.614164) (xy 358.72801 -258.399788) (xy 358.720763 -258.393233)
			(xy 358.702719 -258.385783) (xy 358.692958 -258.38531) (xy 357.089456 -258.38531) (xy 357.079682 -258.385771)
			(xy 357.061603 -258.393205) (xy 357.047727 -258.406972) (xy 357.043482 -258.41579) (xy 357.020622 -258.470146)
			(xy 357.007668 -258.500372) (xy 357.005382 -258.50723) (xy 357.004087 -258.512791) (xy 357.003706 -258.5242)
			(xy 357.00462 -258.529836) (xy 357.00589 -258.536694) (xy 357.012748 -258.549648) (xy 357.018336 -258.55549)
			(xy 357.030528 -258.568698) (xy 357.031036 -258.569206) (xy 357.037386 -258.576826) (xy 357.041704 -258.58216)
			(xy 357.05905 -258.605052) (xy 357.086658 -258.655413) (xy 357.105502 -258.709665) (xy 357.115056 -258.766296)
			(xy 357.115618 -258.795012) (xy 357.115106 -258.822113) (xy 357.10659 -258.875642) (xy 357.089771 -258.927169)
			(xy 357.065066 -258.975414) (xy 357.03309 -259.019179) (xy 356.994636 -259.057378) (xy 356.950659 -259.089062)
			(xy 356.90225 -259.113444) (xy 356.850613 -259.12992) (xy 356.797028 -259.138079) (xy 356.769924 -259.13842)
			(xy 356.739661 -259.137579) (xy 356.680128 -259.126597) (xy 356.65156 -259.116576) (xy 356.651052 -259.116322)
			(xy 356.645235 -259.114349) (xy 356.633036 -259.112932) (xy 356.626922 -259.113528) (xy 356.615238 -259.115052)
			(xy 356.536244 -259.169662) (xy 356.531164 -259.173472) (xy 356.524165 -259.180368) (xy 356.515544 -259.198004)
			(xy 356.5144 -259.207762) (xy 356.514146 -259.211318) (xy 356.514146 -259.428742) (xy 356.5144 -259.432298)
			(xy 356.515529 -259.442061) (xy 356.524153 -259.4597) (xy 356.531164 -259.466588) (xy 356.536244 -259.470398)
			(xy 356.605078 -259.517896) (xy 356.61015 -259.521209) (xy 356.621448 -259.525575) (xy 356.62743 -259.526532)
			(xy 356.639368 -259.528056) (xy 356.65156 -259.523484) (xy 356.680604 -259.513275) (xy 356.741176 -259.502292)
			(xy 356.771956 -259.50164) (xy 356.77602 -259.50164) (xy 356.802807 -259.502452) (xy 356.85565 -259.511366)
			(xy 356.906467 -259.52838) (xy 356.954024 -259.553083) (xy 356.997165 -259.584873) (xy 357.034845 -259.622979)
			(xy 357.066147 -259.666476) (xy 357.090312 -259.714308) (xy 357.106753 -259.765313) (xy 357.115071 -259.818253)
			(xy 357.115618 -259.845048) (xy 358.928419 -259.845048) (xy 358.932449 -259.79255) (xy 358.944446 -259.741282)
			(xy 358.964129 -259.692447) (xy 358.991035 -259.647188) (xy 359.024535 -259.606567) (xy 359.063843 -259.571536)
			(xy 359.108038 -259.542916) (xy 359.156083 -259.521377) (xy 359.206854 -259.507425) (xy 359.259159 -259.501387)
			(xy 359.311773 -259.503404) (xy 359.363463 -259.513428) (xy 359.413016 -259.531226) (xy 359.459272 -259.556379)
			(xy 359.501146 -259.588298) (xy 359.537658 -259.626236) (xy 359.56795 -259.669302) (xy 359.591313 -259.716487)
			(xy 359.607199 -259.766686) (xy 359.615236 -259.818722) (xy 359.61574 -259.845048) (xy 361.178351 -259.845048)
			(xy 361.182381 -259.79255) (xy 361.194378 -259.741282) (xy 361.214061 -259.692447) (xy 361.240967 -259.647188)
			(xy 361.274467 -259.606567) (xy 361.313775 -259.571536) (xy 361.35797 -259.542916) (xy 361.406015 -259.521377)
			(xy 361.456786 -259.507425) (xy 361.509091 -259.501387) (xy 361.561705 -259.503404) (xy 361.613395 -259.513428)
			(xy 361.662948 -259.531226) (xy 361.709204 -259.556379) (xy 361.751078 -259.588298) (xy 361.78759 -259.626236)
			(xy 361.817882 -259.669302) (xy 361.841245 -259.716487) (xy 361.857131 -259.766686) (xy 361.865168 -259.818722)
			(xy 361.865672 -259.845048) (xy 363.778295 -259.845048) (xy 363.782325 -259.79255) (xy 363.794322 -259.741282)
			(xy 363.814005 -259.692447) (xy 363.840911 -259.647188) (xy 363.874411 -259.606567) (xy 363.913719 -259.571536)
			(xy 363.957914 -259.542916) (xy 364.005959 -259.521377) (xy 364.05673 -259.507425) (xy 364.109035 -259.501387)
			(xy 364.161649 -259.503404) (xy 364.213339 -259.513428) (xy 364.262892 -259.531226) (xy 364.309148 -259.556379)
			(xy 364.351022 -259.588298) (xy 364.387534 -259.626236) (xy 364.417826 -259.669302) (xy 364.441189 -259.716487)
			(xy 364.457075 -259.766686) (xy 364.465112 -259.818722) (xy 364.465616 -259.845048) (xy 364.465112 -259.871374)
			(xy 364.457075 -259.92341) (xy 364.441189 -259.973609) (xy 364.417826 -260.020794) (xy 364.387534 -260.06386)
			(xy 364.351022 -260.101798) (xy 364.309148 -260.133717) (xy 364.262892 -260.15887) (xy 364.213339 -260.176668)
			(xy 364.161649 -260.186692) (xy 364.109035 -260.188709) (xy 364.05673 -260.182671) (xy 364.005959 -260.168719)
			(xy 363.957914 -260.14718) (xy 363.913719 -260.11856) (xy 363.874411 -260.083529) (xy 363.840911 -260.042908)
			(xy 363.814005 -259.997649) (xy 363.794322 -259.948814) (xy 363.782325 -259.897546) (xy 363.778295 -259.845048)
			(xy 361.865672 -259.845048) (xy 361.865168 -259.871374) (xy 361.857131 -259.92341) (xy 361.841245 -259.973609)
			(xy 361.817882 -260.020794) (xy 361.78759 -260.06386) (xy 361.751078 -260.101798) (xy 361.709204 -260.133717)
			(xy 361.662948 -260.15887) (xy 361.613395 -260.176668) (xy 361.561705 -260.186692) (xy 361.509091 -260.188709)
			(xy 361.456786 -260.182671) (xy 361.406015 -260.168719) (xy 361.35797 -260.14718) (xy 361.313775 -260.11856)
			(xy 361.274467 -260.083529) (xy 361.240967 -260.042908) (xy 361.214061 -259.997649) (xy 361.194378 -259.948814)
			(xy 361.182381 -259.897546) (xy 361.178351 -259.845048) (xy 359.61574 -259.845048) (xy 359.615236 -259.871374)
			(xy 359.607199 -259.92341) (xy 359.591313 -259.973609) (xy 359.56795 -260.020794) (xy 359.537658 -260.06386)
			(xy 359.501146 -260.101798) (xy 359.459272 -260.133717) (xy 359.413016 -260.15887) (xy 359.363463 -260.176668)
			(xy 359.311773 -260.186692) (xy 359.259159 -260.188709) (xy 359.206854 -260.182671) (xy 359.156083 -260.168719)
			(xy 359.108038 -260.14718) (xy 359.063843 -260.11856) (xy 359.024535 -260.083529) (xy 358.991035 -260.042908)
			(xy 358.964129 -259.997649) (xy 358.944446 -259.948814) (xy 358.932449 -259.897546) (xy 358.928419 -259.845048)
			(xy 357.115618 -259.845048) (xy 357.115096 -259.871891) (xy 357.106734 -259.924923) (xy 357.090222 -259.976008)
			(xy 357.065961 -260.023901) (xy 357.034543 -260.067435) (xy 356.996733 -260.105549) (xy 356.953452 -260.137316)
			(xy 356.905756 -260.16196) (xy 356.854805 -260.178882) (xy 356.801842 -260.187669) (xy 356.775004 -260.188456)
			(xy 356.774496 -260.188456) (xy 356.77221 -260.18871) (xy 356.745828 -260.188233) (xy 356.693686 -260.180166)
			(xy 356.643396 -260.164204) (xy 356.619556 -260.152896) (xy 356.614476 -260.150356) (xy 356.591362 -260.144768)
			(xy 356.584923 -260.144958) (xy 356.572452 -260.148171) (xy 356.566724 -260.151118) (xy 356.540308 -260.16585)
			(xy 356.53261 -260.17053) (xy 356.520865 -260.184175) (xy 356.514575 -260.201045) (xy 356.514146 -260.210046)
			(xy 356.514146 -260.217412) (xy 356.510336 -260.226556) (xy 356.508327 -260.231119) (xy 356.502826 -260.239431)
			(xy 356.499414 -260.243066) (xy 356.110286 -260.632194) (xy 356.102887 -260.639039) (xy 356.084289 -260.646769)
			(xy 356.074218 -260.64718) (xy 355.004878 -260.64718) (xy 354.998867 -260.647344) (xy 354.987182 -260.650161)
			(xy 354.981764 -260.652768) (xy 354.97829 -260.654608) (xy 354.97191 -260.659201) (xy 354.969064 -260.661912)
			(xy 354.644198 -260.986778) (xy 354.63847 -260.99306) (xy 354.631078 -261.008358) (xy 354.62972 -261.01675)
			(xy 354.627688 -261.034022) (xy 354.632514 -261.041896) (xy 354.645769 -261.062953) (xy 354.666732 -261.108076)
			(xy 354.680972 -261.15575) (xy 354.688192 -261.204979) (xy 354.688648 -261.229856) (xy 354.688648 -261.23011)
			(xy 354.688145 -261.256421) (xy 354.680116 -261.308428) (xy 354.675564 -261.32282) (xy 355.244149 -261.32282)
			(xy 355.248179 -261.270322) (xy 355.260176 -261.219054) (xy 355.279859 -261.170219) (xy 355.306765 -261.12496)
			(xy 355.340265 -261.084339) (xy 355.379573 -261.049308) (xy 355.423768 -261.020688) (xy 355.471813 -260.999149)
			(xy 355.522584 -260.985197) (xy 355.574889 -260.979159) (xy 355.627503 -260.981176) (xy 355.679193 -260.9912)
			(xy 355.728746 -261.008998) (xy 355.775002 -261.034151) (xy 355.816876 -261.06607) (xy 355.853388 -261.104008)
			(xy 355.88368 -261.147074) (xy 355.907043 -261.194259) (xy 355.922929 -261.244458) (xy 355.930966 -261.296494)
			(xy 355.93147 -261.32282) (xy 356.194109 -261.32282) (xy 356.198139 -261.270322) (xy 356.210136 -261.219054)
			(xy 356.229819 -261.170219) (xy 356.256725 -261.12496) (xy 356.290225 -261.084339) (xy 356.329533 -261.049308)
			(xy 356.373728 -261.020688) (xy 356.421773 -260.999149) (xy 356.472544 -260.985197) (xy 356.524849 -260.979159)
			(xy 356.577463 -260.981176) (xy 356.629153 -260.9912) (xy 356.678706 -261.008998) (xy 356.724962 -261.034151)
			(xy 356.766836 -261.06607) (xy 356.803348 -261.104008) (xy 356.83364 -261.147074) (xy 356.857003 -261.194259)
			(xy 356.872889 -261.244458) (xy 356.880926 -261.296494) (xy 356.88143 -261.32282) (xy 357.144069 -261.32282)
			(xy 357.148099 -261.270322) (xy 357.160096 -261.219054) (xy 357.179779 -261.170219) (xy 357.206685 -261.12496)
			(xy 357.240185 -261.084339) (xy 357.279493 -261.049308) (xy 357.323688 -261.020688) (xy 357.371733 -260.999149)
			(xy 357.422504 -260.985197) (xy 357.474809 -260.979159) (xy 357.527423 -260.981176) (xy 357.579113 -260.9912)
			(xy 357.628666 -261.008998) (xy 357.674922 -261.034151) (xy 357.716796 -261.06607) (xy 357.753308 -261.104008)
			(xy 357.7836 -261.147074) (xy 357.806963 -261.194259) (xy 357.822849 -261.244458) (xy 357.830886 -261.296494)
			(xy 357.83139 -261.32282) (xy 358.094029 -261.32282) (xy 358.098059 -261.270322) (xy 358.110056 -261.219054)
			(xy 358.129739 -261.170219) (xy 358.156645 -261.12496) (xy 358.190145 -261.084339) (xy 358.229453 -261.049308)
			(xy 358.273648 -261.020688) (xy 358.321693 -260.999149) (xy 358.372464 -260.985197) (xy 358.424769 -260.979159)
			(xy 358.477383 -260.981176) (xy 358.529073 -260.9912) (xy 358.578626 -261.008998) (xy 358.624882 -261.034151)
			(xy 358.666756 -261.06607) (xy 358.703268 -261.104008) (xy 358.73356 -261.147074) (xy 358.756923 -261.194259)
			(xy 358.772809 -261.244458) (xy 358.780846 -261.296494) (xy 358.78135 -261.32282) (xy 359.043989 -261.32282)
			(xy 359.048019 -261.270322) (xy 359.060016 -261.219054) (xy 359.079699 -261.170219) (xy 359.106605 -261.12496)
			(xy 359.140105 -261.084339) (xy 359.179413 -261.049308) (xy 359.223608 -261.020688) (xy 359.271653 -260.999149)
			(xy 359.322424 -260.985197) (xy 359.374729 -260.979159) (xy 359.427343 -260.981176) (xy 359.479033 -260.9912)
			(xy 359.528586 -261.008998) (xy 359.574842 -261.034151) (xy 359.616716 -261.06607) (xy 359.653228 -261.104008)
			(xy 359.68352 -261.147074) (xy 359.706883 -261.194259) (xy 359.722769 -261.244458) (xy 359.730806 -261.296494)
			(xy 359.73131 -261.32282) (xy 359.993949 -261.32282) (xy 359.997979 -261.270322) (xy 360.009976 -261.219054)
			(xy 360.029659 -261.170219) (xy 360.056565 -261.12496) (xy 360.090065 -261.084339) (xy 360.129373 -261.049308)
			(xy 360.173568 -261.020688) (xy 360.221613 -260.999149) (xy 360.272384 -260.985197) (xy 360.324689 -260.979159)
			(xy 360.377303 -260.981176) (xy 360.428993 -260.9912) (xy 360.478546 -261.008998) (xy 360.524802 -261.034151)
			(xy 360.566676 -261.06607) (xy 360.603188 -261.104008) (xy 360.63348 -261.147074) (xy 360.656843 -261.194259)
			(xy 360.672729 -261.244458) (xy 360.680766 -261.296494) (xy 360.68127 -261.32282) (xy 360.944163 -261.32282)
			(xy 360.948193 -261.270322) (xy 360.96019 -261.219054) (xy 360.979873 -261.170219) (xy 361.006779 -261.12496)
			(xy 361.040279 -261.084339) (xy 361.079587 -261.049308) (xy 361.123782 -261.020688) (xy 361.171827 -260.999149)
			(xy 361.222598 -260.985197) (xy 361.274903 -260.979159) (xy 361.327517 -260.981176) (xy 361.379207 -260.9912)
			(xy 361.42876 -261.008998) (xy 361.475016 -261.034151) (xy 361.51689 -261.06607) (xy 361.553402 -261.104008)
			(xy 361.583694 -261.147074) (xy 361.607057 -261.194259) (xy 361.622943 -261.244458) (xy 361.63098 -261.296494)
			(xy 361.631484 -261.32282) (xy 361.894123 -261.32282) (xy 361.898153 -261.270322) (xy 361.91015 -261.219054)
			(xy 361.929833 -261.170219) (xy 361.956739 -261.12496) (xy 361.990239 -261.084339) (xy 362.029547 -261.049308)
			(xy 362.073742 -261.020688) (xy 362.121787 -260.999149) (xy 362.172558 -260.985197) (xy 362.224863 -260.979159)
			(xy 362.277477 -260.981176) (xy 362.329167 -260.9912) (xy 362.37872 -261.008998) (xy 362.424976 -261.034151)
			(xy 362.46685 -261.06607) (xy 362.503362 -261.104008) (xy 362.533654 -261.147074) (xy 362.557017 -261.194259)
			(xy 362.572903 -261.244458) (xy 362.58094 -261.296494) (xy 362.581444 -261.32282) (xy 362.844083 -261.32282)
			(xy 362.848113 -261.270322) (xy 362.86011 -261.219054) (xy 362.879793 -261.170219) (xy 362.906699 -261.12496)
			(xy 362.940199 -261.084339) (xy 362.979507 -261.049308) (xy 363.023702 -261.020688) (xy 363.071747 -260.999149)
			(xy 363.122518 -260.985197) (xy 363.174823 -260.979159) (xy 363.227437 -260.981176) (xy 363.279127 -260.9912)
			(xy 363.32868 -261.008998) (xy 363.374936 -261.034151) (xy 363.41681 -261.06607) (xy 363.453322 -261.104008)
			(xy 363.483614 -261.147074) (xy 363.506977 -261.194259) (xy 363.522863 -261.244458) (xy 363.5309 -261.296494)
			(xy 363.531404 -261.32282) (xy 363.794043 -261.32282) (xy 363.798073 -261.270322) (xy 363.81007 -261.219054)
			(xy 363.829753 -261.170219) (xy 363.856659 -261.12496) (xy 363.890159 -261.084339) (xy 363.929467 -261.049308)
			(xy 363.973662 -261.020688) (xy 364.021707 -260.999149) (xy 364.072478 -260.985197) (xy 364.124783 -260.979159)
			(xy 364.177397 -260.981176) (xy 364.229087 -260.9912) (xy 364.27864 -261.008998) (xy 364.324896 -261.034151)
			(xy 364.36677 -261.06607) (xy 364.403282 -261.104008) (xy 364.433574 -261.147074) (xy 364.456937 -261.194259)
			(xy 364.472823 -261.244458) (xy 364.48086 -261.296494) (xy 364.481364 -261.32282) (xy 364.48086 -261.349146)
			(xy 364.472823 -261.401182) (xy 364.456937 -261.451381) (xy 364.433574 -261.498566) (xy 364.403282 -261.541632)
			(xy 364.36677 -261.57957) (xy 364.324896 -261.611489) (xy 364.27864 -261.636642) (xy 364.229087 -261.65444)
			(xy 364.177397 -261.664464) (xy 364.124783 -261.666481) (xy 364.072478 -261.660443) (xy 364.021707 -261.646491)
			(xy 363.973662 -261.624952) (xy 363.929467 -261.596332) (xy 363.890159 -261.561301) (xy 363.856659 -261.52068)
			(xy 363.829753 -261.475421) (xy 363.81007 -261.426586) (xy 363.798073 -261.375318) (xy 363.794043 -261.32282)
			(xy 363.531404 -261.32282) (xy 363.5309 -261.349146) (xy 363.522863 -261.401182) (xy 363.506977 -261.451381)
			(xy 363.483614 -261.498566) (xy 363.453322 -261.541632) (xy 363.41681 -261.57957) (xy 363.374936 -261.611489)
			(xy 363.32868 -261.636642) (xy 363.279127 -261.65444) (xy 363.227437 -261.664464) (xy 363.174823 -261.666481)
			(xy 363.122518 -261.660443) (xy 363.071747 -261.646491) (xy 363.023702 -261.624952) (xy 362.979507 -261.596332)
			(xy 362.940199 -261.561301) (xy 362.906699 -261.52068) (xy 362.879793 -261.475421) (xy 362.86011 -261.426586)
			(xy 362.848113 -261.375318) (xy 362.844083 -261.32282) (xy 362.581444 -261.32282) (xy 362.58094 -261.349146)
			(xy 362.572903 -261.401182) (xy 362.557017 -261.451381) (xy 362.533654 -261.498566) (xy 362.503362 -261.541632)
			(xy 362.46685 -261.57957) (xy 362.424976 -261.611489) (xy 362.37872 -261.636642) (xy 362.329167 -261.65444)
			(xy 362.277477 -261.664464) (xy 362.224863 -261.666481) (xy 362.172558 -261.660443) (xy 362.121787 -261.646491)
			(xy 362.073742 -261.624952) (xy 362.029547 -261.596332) (xy 361.990239 -261.561301) (xy 361.956739 -261.52068)
			(xy 361.929833 -261.475421) (xy 361.91015 -261.426586) (xy 361.898153 -261.375318) (xy 361.894123 -261.32282)
			(xy 361.631484 -261.32282) (xy 361.63098 -261.349146) (xy 361.622943 -261.401182) (xy 361.607057 -261.451381)
			(xy 361.583694 -261.498566) (xy 361.553402 -261.541632) (xy 361.51689 -261.57957) (xy 361.475016 -261.611489)
			(xy 361.42876 -261.636642) (xy 361.379207 -261.65444) (xy 361.327517 -261.664464) (xy 361.274903 -261.666481)
			(xy 361.222598 -261.660443) (xy 361.171827 -261.646491) (xy 361.123782 -261.624952) (xy 361.079587 -261.596332)
			(xy 361.040279 -261.561301) (xy 361.006779 -261.52068) (xy 360.979873 -261.475421) (xy 360.96019 -261.426586)
			(xy 360.948193 -261.375318) (xy 360.944163 -261.32282) (xy 360.68127 -261.32282) (xy 360.680766 -261.349146)
			(xy 360.672729 -261.401182) (xy 360.656843 -261.451381) (xy 360.63348 -261.498566) (xy 360.603188 -261.541632)
			(xy 360.566676 -261.57957) (xy 360.524802 -261.611489) (xy 360.478546 -261.636642) (xy 360.428993 -261.65444)
			(xy 360.377303 -261.664464) (xy 360.324689 -261.666481) (xy 360.272384 -261.660443) (xy 360.221613 -261.646491)
			(xy 360.173568 -261.624952) (xy 360.129373 -261.596332) (xy 360.090065 -261.561301) (xy 360.056565 -261.52068)
			(xy 360.029659 -261.475421) (xy 360.009976 -261.426586) (xy 359.997979 -261.375318) (xy 359.993949 -261.32282)
			(xy 359.73131 -261.32282) (xy 359.730806 -261.349146) (xy 359.722769 -261.401182) (xy 359.706883 -261.451381)
			(xy 359.68352 -261.498566) (xy 359.653228 -261.541632) (xy 359.616716 -261.57957) (xy 359.574842 -261.611489)
			(xy 359.528586 -261.636642) (xy 359.479033 -261.65444) (xy 359.427343 -261.664464) (xy 359.374729 -261.666481)
			(xy 359.322424 -261.660443) (xy 359.271653 -261.646491) (xy 359.223608 -261.624952) (xy 359.179413 -261.596332)
			(xy 359.140105 -261.561301) (xy 359.106605 -261.52068) (xy 359.079699 -261.475421) (xy 359.060016 -261.426586)
			(xy 359.048019 -261.375318) (xy 359.043989 -261.32282) (xy 358.78135 -261.32282) (xy 358.780846 -261.349146)
			(xy 358.772809 -261.401182) (xy 358.756923 -261.451381) (xy 358.73356 -261.498566) (xy 358.703268 -261.541632)
			(xy 358.666756 -261.57957) (xy 358.624882 -261.611489) (xy 358.578626 -261.636642) (xy 358.529073 -261.65444)
			(xy 358.477383 -261.664464) (xy 358.424769 -261.666481) (xy 358.372464 -261.660443) (xy 358.321693 -261.646491)
			(xy 358.273648 -261.624952) (xy 358.229453 -261.596332) (xy 358.190145 -261.561301) (xy 358.156645 -261.52068)
			(xy 358.129739 -261.475421) (xy 358.110056 -261.426586) (xy 358.098059 -261.375318) (xy 358.094029 -261.32282)
			(xy 357.83139 -261.32282) (xy 357.830886 -261.349146) (xy 357.822849 -261.401182) (xy 357.806963 -261.451381)
			(xy 357.7836 -261.498566) (xy 357.753308 -261.541632) (xy 357.716796 -261.57957) (xy 357.674922 -261.611489)
			(xy 357.628666 -261.636642) (xy 357.579113 -261.65444) (xy 357.527423 -261.664464) (xy 357.474809 -261.666481)
			(xy 357.422504 -261.660443) (xy 357.371733 -261.646491) (xy 357.323688 -261.624952) (xy 357.279493 -261.596332)
			(xy 357.240185 -261.561301) (xy 357.206685 -261.52068) (xy 357.179779 -261.475421) (xy 357.160096 -261.426586)
			(xy 357.148099 -261.375318) (xy 357.144069 -261.32282) (xy 356.88143 -261.32282) (xy 356.880926 -261.349146)
			(xy 356.872889 -261.401182) (xy 356.857003 -261.451381) (xy 356.83364 -261.498566) (xy 356.803348 -261.541632)
			(xy 356.766836 -261.57957) (xy 356.724962 -261.611489) (xy 356.678706 -261.636642) (xy 356.629153 -261.65444)
			(xy 356.577463 -261.664464) (xy 356.524849 -261.666481) (xy 356.472544 -261.660443) (xy 356.421773 -261.646491)
			(xy 356.373728 -261.624952) (xy 356.329533 -261.596332) (xy 356.290225 -261.561301) (xy 356.256725 -261.52068)
			(xy 356.229819 -261.475421) (xy 356.210136 -261.426586) (xy 356.198139 -261.375318) (xy 356.194109 -261.32282)
			(xy 355.93147 -261.32282) (xy 355.930966 -261.349146) (xy 355.922929 -261.401182) (xy 355.907043 -261.451381)
			(xy 355.88368 -261.498566) (xy 355.853388 -261.541632) (xy 355.816876 -261.57957) (xy 355.775002 -261.611489)
			(xy 355.728746 -261.636642) (xy 355.679193 -261.65444) (xy 355.627503 -261.664464) (xy 355.574889 -261.666481)
			(xy 355.522584 -261.660443) (xy 355.471813 -261.646491) (xy 355.423768 -261.624952) (xy 355.379573 -261.596332)
			(xy 355.340265 -261.561301) (xy 355.306765 -261.52068) (xy 355.279859 -261.475421) (xy 355.260176 -261.426586)
			(xy 355.248179 -261.375318) (xy 355.244149 -261.32282) (xy 354.675564 -261.32282) (xy 354.664247 -261.358602)
			(xy 354.640911 -261.405767) (xy 354.610653 -261.448821) (xy 354.574181 -261.486755) (xy 354.532349 -261.518681)
			(xy 354.486137 -261.543853) (xy 354.436625 -261.56168) (xy 354.384974 -261.571746) (xy 354.358702 -261.573264)
			(xy 354.358448 -261.573264) (xy 354.348542 -261.573772) (xy 354.340414 -261.577328) (xy 354.336053 -261.579309)
			(xy 354.328123 -261.58468) (xy 354.324666 -261.587996) (xy 354.229162 -261.6835) (xy 354.224844 -261.688072)
			(xy 354.217478 -261.695184) (xy 353.788218 -262.124444) (xy 353.784557 -262.128318) (xy 353.7788 -262.137288)
			(xy 353.776788 -262.142224) (xy 353.773232 -262.151368) (xy 353.773232 -262.151622) (xy 353.773486 -262.154924)
			(xy 353.77374 -262.16229) (xy 353.774248 -262.18007) (xy 365.036865 -262.18007) (xy 365.040895 -262.127572)
			(xy 365.052892 -262.076304) (xy 365.072575 -262.027469) (xy 365.099481 -261.98221) (xy 365.132981 -261.941589)
			(xy 365.172289 -261.906558) (xy 365.216484 -261.877938) (xy 365.264529 -261.856399) (xy 365.3153 -261.842447)
			(xy 365.367605 -261.836409) (xy 365.420219 -261.838426) (xy 365.471909 -261.84845) (xy 365.521462 -261.866248)
			(xy 365.567718 -261.891401) (xy 365.609592 -261.92332) (xy 365.646104 -261.961258) (xy 365.676396 -262.004324)
			(xy 365.699759 -262.051509) (xy 365.715645 -262.101708) (xy 365.723682 -262.153744) (xy 365.724186 -262.18007)
			(xy 365.723682 -262.206396) (xy 365.715645 -262.258432) (xy 365.699759 -262.308631) (xy 365.676396 -262.355816)
			(xy 365.646104 -262.398882) (xy 365.609592 -262.43682) (xy 365.567718 -262.468739) (xy 365.521462 -262.493892)
			(xy 365.471909 -262.51169) (xy 365.420219 -262.521714) (xy 365.367605 -262.523731) (xy 365.3153 -262.517693)
			(xy 365.264529 -262.503741) (xy 365.216484 -262.482202) (xy 365.172289 -262.453582) (xy 365.132981 -262.418551)
			(xy 365.099481 -262.37793) (xy 365.072575 -262.332671) (xy 365.052892 -262.283836) (xy 365.040895 -262.232568)
			(xy 365.036865 -262.18007) (xy 353.774248 -262.18007) (xy 353.773721 -262.207058) (xy 353.765282 -262.26037)
			(xy 353.748608 -262.311705) (xy 353.724108 -262.3598) (xy 353.692386 -262.40347) (xy 353.654224 -262.441641)
			(xy 353.61056 -262.473371) (xy 353.56247 -262.497881) (xy 353.511138 -262.514566) (xy 353.457828 -262.523016)
			(xy 353.43084 -262.523478) (xy 353.404061 -262.522968) (xy 353.351151 -262.514658) (xy 353.300172 -262.498235)
			(xy 353.252362 -262.474095) (xy 353.20888 -262.442826) (xy 353.170779 -262.405184) (xy 353.138986 -262.362083)
			(xy 353.114269 -262.314568) (xy 353.09723 -262.263793) (xy 353.092258 -262.237474) (xy 353.092004 -262.236458)
			(xy 353.090116 -262.227899) (xy 353.081414 -262.212699) (xy 353.074986 -262.20674) (xy 353.068382 -262.201406)
			(xy 353.060508 -262.198358) (xy 353.056208 -262.196906) (xy 353.047266 -262.195364) (xy 353.042728 -262.19531)
			(xy 351.017332 -262.19531) (xy 351.011323 -262.195479) (xy 350.999643 -262.198307) (xy 350.994218 -262.200898)
			(xy 350.990742 -262.202736) (xy 350.98436 -262.207326) (xy 350.981518 -262.210042) (xy 350.471486 -262.720074)
			(xy 350.464921 -262.727197) (xy 350.457228 -262.744958) (xy 350.456998 -262.748014) (xy 350.78214 -262.748014)
			(xy 350.7861 -262.69896) (xy 350.797877 -262.651176) (xy 350.817168 -262.6059) (xy 350.843471 -262.564304)
			(xy 350.876106 -262.527467) (xy 350.914227 -262.496342) (xy 350.956848 -262.471735) (xy 351.002864 -262.454283)
			(xy 351.051083 -262.444439) (xy 351.100258 -262.442458) (xy 351.149113 -262.44839) (xy 351.196384 -262.462082)
			(xy 351.240846 -262.48318) (xy 351.281349 -262.511136) (xy 351.316842 -262.545228) (xy 351.346407 -262.584572)
			(xy 351.369278 -262.628149) (xy 351.384862 -262.67483) (xy 351.392757 -262.723407) (xy 351.393252 -262.748014)
			(xy 351.722194 -262.748014) (xy 351.726154 -262.69896) (xy 351.737931 -262.651176) (xy 351.757222 -262.6059)
			(xy 351.783525 -262.564304) (xy 351.81616 -262.527467) (xy 351.854281 -262.496342) (xy 351.896902 -262.471735)
			(xy 351.942918 -262.454283) (xy 351.991137 -262.444439) (xy 352.040312 -262.442458) (xy 352.089167 -262.44839)
			(xy 352.136438 -262.462082) (xy 352.1809 -262.48318) (xy 352.221403 -262.511136) (xy 352.256896 -262.545228)
			(xy 352.286461 -262.584572) (xy 352.309332 -262.628149) (xy 352.324916 -262.67483) (xy 352.332811 -262.723407)
			(xy 352.333306 -262.748014) (xy 352.332811 -262.772621) (xy 352.324916 -262.821198) (xy 352.309332 -262.867879)
			(xy 352.286461 -262.911456) (xy 352.256896 -262.9508) (xy 352.221403 -262.984892) (xy 352.1809 -263.012848)
			(xy 352.136438 -263.033946) (xy 352.089167 -263.047638) (xy 352.040312 -263.05357) (xy 351.991137 -263.051589)
			(xy 351.942918 -263.041745) (xy 351.896902 -263.024293) (xy 351.854281 -262.999686) (xy 351.81616 -262.968561)
			(xy 351.783525 -262.931724) (xy 351.757222 -262.890128) (xy 351.737931 -262.844852) (xy 351.726154 -262.797068)
			(xy 351.722194 -262.748014) (xy 351.393252 -262.748014) (xy 351.392757 -262.772621) (xy 351.384862 -262.821198)
			(xy 351.369278 -262.867879) (xy 351.346407 -262.911456) (xy 351.316842 -262.9508) (xy 351.281349 -262.984892)
			(xy 351.240846 -263.012848) (xy 351.196384 -263.033946) (xy 351.149113 -263.047638) (xy 351.100258 -263.05357)
			(xy 351.051083 -263.051589) (xy 351.002864 -263.041745) (xy 350.956848 -263.024293) (xy 350.914227 -262.999686)
			(xy 350.876106 -262.968561) (xy 350.843471 -262.931724) (xy 350.817168 -262.890128) (xy 350.797877 -262.844852)
			(xy 350.7861 -262.797068) (xy 350.78214 -262.748014) (xy 350.456998 -262.748014) (xy 350.4565 -262.754618)
			(xy 350.4565 -262.755126) (xy 350.455484 -262.770874) (xy 350.455484 -262.771382) (xy 350.45293 -262.796222)
			(xy 350.440774 -262.844652) (xy 350.420902 -262.89046) (xy 350.393843 -262.932425) (xy 350.360319 -262.969429)
			(xy 350.321221 -263.000488) (xy 350.277593 -263.024774) (xy 350.230595 -263.041639) (xy 350.18148 -263.050635)
			(xy 350.156526 -263.051544) (xy 350.14786 -263.052742) (xy 350.132027 -263.060154) (xy 350.125538 -263.066022)
			(xy 349.923862 -263.267698) (xy 349.917355 -263.274842) (xy 349.909775 -263.292601) (xy 349.90913 -263.302242)
			(xy 349.908368 -263.332468) (xy 349.908485 -263.341403) (xy 349.91421 -263.358319) (xy 349.919544 -263.365488)
			(xy 349.935188 -263.385928) (xy 349.960119 -263.430955) (xy 349.977159 -263.479521) (xy 349.985827 -263.530254)
			(xy 349.986346 -263.555988) (xy 350.315288 -263.555988) (xy 350.319248 -263.506934) (xy 350.331025 -263.45915)
			(xy 350.350316 -263.413874) (xy 350.376619 -263.372278) (xy 350.409254 -263.335441) (xy 350.447375 -263.304316)
			(xy 350.489996 -263.279709) (xy 350.536012 -263.262257) (xy 350.584231 -263.252413) (xy 350.633406 -263.250432)
			(xy 350.682261 -263.256364) (xy 350.729532 -263.270056) (xy 350.773994 -263.291154) (xy 350.814497 -263.31911)
			(xy 350.84999 -263.353202) (xy 350.879555 -263.392546) (xy 350.902426 -263.436123) (xy 350.91801 -263.482804)
			(xy 350.925905 -263.531381) (xy 350.9264 -263.555988) (xy 350.925905 -263.580595) (xy 350.91801 -263.629172)
			(xy 350.902426 -263.675853) (xy 350.879555 -263.71943) (xy 350.84999 -263.758774) (xy 350.814497 -263.792866)
			(xy 350.773994 -263.820822) (xy 350.729532 -263.84192) (xy 350.714376 -263.84631) (xy 359.174291 -263.84631)
			(xy 359.178321 -263.793812) (xy 359.190318 -263.742544) (xy 359.210001 -263.693709) (xy 359.236907 -263.64845)
			(xy 359.270407 -263.607829) (xy 359.309715 -263.572798) (xy 359.35391 -263.544178) (xy 359.401955 -263.522639)
			(xy 359.452726 -263.508687) (xy 359.505031 -263.502649) (xy 359.557645 -263.504666) (xy 359.609335 -263.51469)
			(xy 359.658888 -263.532488) (xy 359.702104 -263.555988) (xy 369.109002 -263.555988) (xy 369.112962 -263.506934)
			(xy 369.124739 -263.45915) (xy 369.14403 -263.413874) (xy 369.170333 -263.372278) (xy 369.202968 -263.335441)
			(xy 369.241089 -263.304316) (xy 369.28371 -263.279709) (xy 369.329726 -263.262257) (xy 369.377945 -263.252413)
			(xy 369.42712 -263.250432) (xy 369.475975 -263.256364) (xy 369.523246 -263.270056) (xy 369.567708 -263.291154)
			(xy 369.608211 -263.31911) (xy 369.643704 -263.353202) (xy 369.673269 -263.392546) (xy 369.69614 -263.436123)
			(xy 369.711724 -263.482804) (xy 369.719619 -263.531381) (xy 369.720114 -263.555988) (xy 370.98911 -263.555988)
			(xy 370.99307 -263.506934) (xy 371.004847 -263.45915) (xy 371.024138 -263.413874) (xy 371.050441 -263.372278)
			(xy 371.083076 -263.335441) (xy 371.121197 -263.304316) (xy 371.163818 -263.279709) (xy 371.209834 -263.262257)
			(xy 371.258053 -263.252413) (xy 371.307228 -263.250432) (xy 371.356083 -263.256364) (xy 371.403354 -263.270056)
			(xy 371.447816 -263.291154) (xy 371.488319 -263.31911) (xy 371.523812 -263.353202) (xy 371.553377 -263.392546)
			(xy 371.576248 -263.436123) (xy 371.591832 -263.482804) (xy 371.599727 -263.531381) (xy 371.600222 -263.555988)
			(xy 371.599727 -263.580595) (xy 371.591832 -263.629172) (xy 371.576248 -263.675853) (xy 371.553377 -263.71943)
			(xy 371.523812 -263.758774) (xy 371.488319 -263.792866) (xy 371.447816 -263.820822) (xy 371.403354 -263.84192)
			(xy 371.356083 -263.855612) (xy 371.307228 -263.861544) (xy 371.258053 -263.859563) (xy 371.209834 -263.849719)
			(xy 371.163818 -263.832267) (xy 371.121197 -263.80766) (xy 371.083076 -263.776535) (xy 371.050441 -263.739698)
			(xy 371.024138 -263.698102) (xy 371.004847 -263.652826) (xy 370.99307 -263.605042) (xy 370.98911 -263.555988)
			(xy 369.720114 -263.555988) (xy 369.719619 -263.580595) (xy 369.711724 -263.629172) (xy 369.69614 -263.675853)
			(xy 369.673269 -263.71943) (xy 369.643704 -263.758774) (xy 369.608211 -263.792866) (xy 369.567708 -263.820822)
			(xy 369.523246 -263.84192) (xy 369.475975 -263.855612) (xy 369.42712 -263.861544) (xy 369.377945 -263.859563)
			(xy 369.329726 -263.849719) (xy 369.28371 -263.832267) (xy 369.241089 -263.80766) (xy 369.202968 -263.776535)
			(xy 369.170333 -263.739698) (xy 369.14403 -263.698102) (xy 369.124739 -263.652826) (xy 369.112962 -263.605042)
			(xy 369.109002 -263.555988) (xy 359.702104 -263.555988) (xy 359.705144 -263.557641) (xy 359.747018 -263.58956)
			(xy 359.78353 -263.627498) (xy 359.813822 -263.670564) (xy 359.837185 -263.717749) (xy 359.853071 -263.767948)
			(xy 359.861108 -263.819984) (xy 359.861612 -263.84631) (xy 359.861108 -263.872636) (xy 359.853071 -263.924672)
			(xy 359.837185 -263.974871) (xy 359.813822 -264.022056) (xy 359.78353 -264.065122) (xy 359.747018 -264.10306)
			(xy 359.705144 -264.134979) (xy 359.658888 -264.160132) (xy 359.609335 -264.17793) (xy 359.557645 -264.187954)
			(xy 359.505031 -264.189971) (xy 359.452726 -264.183933) (xy 359.401955 -264.169981) (xy 359.35391 -264.148442)
			(xy 359.309715 -264.119822) (xy 359.270407 -264.084791) (xy 359.236907 -264.04417) (xy 359.210001 -263.998911)
			(xy 359.190318 -263.950076) (xy 359.178321 -263.898808) (xy 359.174291 -263.84631) (xy 350.714376 -263.84631)
			(xy 350.682261 -263.855612) (xy 350.633406 -263.861544) (xy 350.584231 -263.859563) (xy 350.536012 -263.849719)
			(xy 350.489996 -263.832267) (xy 350.447375 -263.80766) (xy 350.409254 -263.776535) (xy 350.376619 -263.739698)
			(xy 350.350316 -263.698102) (xy 350.331025 -263.652826) (xy 350.319248 -263.605042) (xy 350.315288 -263.555988)
			(xy 349.986346 -263.555988) (xy 349.985876 -263.579981) (xy 349.978372 -263.627376) (xy 349.963546 -263.673014)
			(xy 349.941764 -263.715771) (xy 349.913561 -263.754595) (xy 349.879633 -263.788529) (xy 349.840814 -263.816738)
			(xy 349.798061 -263.838527) (xy 349.752425 -263.85336) (xy 349.705031 -263.860872) (xy 349.681038 -263.861296)
			(xy 349.65623 -263.860814) (xy 349.607266 -263.852791) (xy 349.560246 -263.836952) (xy 349.516409 -263.813712)
			(xy 349.49638 -263.799066) (xy 349.49003 -263.79424) (xy 349.467424 -263.786366) (xy 349.463119 -263.784962)
			(xy 349.454173 -263.783564) (xy 349.449644 -263.783572) (xy 349.426276 -263.78408) (xy 349.419535 -263.784594)
			(xy 349.406663 -263.788713) (xy 349.400876 -263.792208) (xy 349.392748 -263.798812) (xy 349.008192 -264.183368)
			(xy 349.005486 -264.186219) (xy 349.000893 -264.192598) (xy 348.999048 -264.196068) (xy 348.996465 -264.201495)
			(xy 348.993645 -264.213175) (xy 348.99346 -264.219182) (xy 348.99346 -264.365994) (xy 349.845388 -264.365994)
			(xy 349.849348 -264.31694) (xy 349.861125 -264.269156) (xy 349.880416 -264.22388) (xy 349.906719 -264.182284)
			(xy 349.939354 -264.145447) (xy 349.977475 -264.114322) (xy 350.020096 -264.089715) (xy 350.066112 -264.072263)
			(xy 350.114331 -264.062419) (xy 350.163506 -264.060438) (xy 350.212361 -264.06637) (xy 350.259632 -264.080062)
			(xy 350.304094 -264.10116) (xy 350.344597 -264.129116) (xy 350.38009 -264.163208) (xy 350.409655 -264.202552)
			(xy 350.432526 -264.246129) (xy 350.44811 -264.29281) (xy 350.456005 -264.341387) (xy 350.4565 -264.365994)
			(xy 350.456459 -264.368026) (xy 351.722194 -264.368026) (xy 351.726154 -264.318972) (xy 351.737931 -264.271188)
			(xy 351.757222 -264.225912) (xy 351.783525 -264.184316) (xy 351.81616 -264.147479) (xy 351.854281 -264.116354)
			(xy 351.896902 -264.091747) (xy 351.942918 -264.074295) (xy 351.991137 -264.064451) (xy 352.040312 -264.06247)
			(xy 352.089167 -264.068402) (xy 352.136438 -264.082094) (xy 352.1809 -264.103192) (xy 352.221403 -264.131148)
			(xy 352.256896 -264.16524) (xy 352.286461 -264.204584) (xy 352.309332 -264.248161) (xy 352.324916 -264.294842)
			(xy 352.332811 -264.343419) (xy 352.333306 -264.368026) (xy 353.602302 -264.368026) (xy 353.606262 -264.318972)
			(xy 353.618039 -264.271188) (xy 353.63733 -264.225912) (xy 353.663633 -264.184316) (xy 353.696268 -264.147479)
			(xy 353.734389 -264.116354) (xy 353.77701 -264.091747) (xy 353.823026 -264.074295) (xy 353.871245 -264.064451)
			(xy 353.92042 -264.06247) (xy 353.969275 -264.068402) (xy 354.016546 -264.082094) (xy 354.061008 -264.103192)
			(xy 354.101511 -264.131148) (xy 354.137004 -264.16524) (xy 354.166569 -264.204584) (xy 354.18944 -264.248161)
			(xy 354.205024 -264.294842) (xy 354.212919 -264.343419) (xy 354.213414 -264.368026) (xy 355.482156 -264.368026)
			(xy 355.486116 -264.318972) (xy 355.497893 -264.271188) (xy 355.517184 -264.225912) (xy 355.543487 -264.184316)
			(xy 355.576122 -264.147479) (xy 355.614243 -264.116354) (xy 355.656864 -264.091747) (xy 355.70288 -264.074295)
			(xy 355.751099 -264.064451) (xy 355.800274 -264.06247) (xy 355.849129 -264.068402) (xy 355.8964 -264.082094)
			(xy 355.940862 -264.103192) (xy 355.981365 -264.131148) (xy 356.016858 -264.16524) (xy 356.046423 -264.204584)
			(xy 356.069294 -264.248161) (xy 356.084878 -264.294842) (xy 356.092773 -264.343419) (xy 356.093268 -264.368026)
			(xy 363.00208 -264.368026) (xy 363.00604 -264.318972) (xy 363.017817 -264.271188) (xy 363.037108 -264.225912)
			(xy 363.063411 -264.184316) (xy 363.096046 -264.147479) (xy 363.134167 -264.116354) (xy 363.176788 -264.091747)
			(xy 363.222804 -264.074295) (xy 363.271023 -264.064451) (xy 363.320198 -264.06247) (xy 363.369053 -264.068402)
			(xy 363.416324 -264.082094) (xy 363.460786 -264.103192) (xy 363.501289 -264.131148) (xy 363.536782 -264.16524)
			(xy 363.566347 -264.204584) (xy 363.589218 -264.248161) (xy 363.604802 -264.294842) (xy 363.612697 -264.343419)
			(xy 363.613192 -264.368026) (xy 364.882188 -264.368026) (xy 364.886148 -264.318972) (xy 364.897925 -264.271188)
			(xy 364.917216 -264.225912) (xy 364.943519 -264.184316) (xy 364.976154 -264.147479) (xy 365.014275 -264.116354)
			(xy 365.056896 -264.091747) (xy 365.102912 -264.074295) (xy 365.151131 -264.064451) (xy 365.200306 -264.06247)
			(xy 365.249161 -264.068402) (xy 365.296432 -264.082094) (xy 365.340894 -264.103192) (xy 365.381397 -264.131148)
			(xy 365.41689 -264.16524) (xy 365.446455 -264.204584) (xy 365.469326 -264.248161) (xy 365.48491 -264.294842)
			(xy 365.492805 -264.343419) (xy 365.4933 -264.368026) (xy 366.762042 -264.368026) (xy 366.766002 -264.318972)
			(xy 366.777779 -264.271188) (xy 366.79707 -264.225912) (xy 366.823373 -264.184316) (xy 366.856008 -264.147479)
			(xy 366.894129 -264.116354) (xy 366.93675 -264.091747) (xy 366.982766 -264.074295) (xy 367.030985 -264.064451)
			(xy 367.08016 -264.06247) (xy 367.129015 -264.068402) (xy 367.176286 -264.082094) (xy 367.220748 -264.103192)
			(xy 367.261251 -264.131148) (xy 367.296744 -264.16524) (xy 367.326309 -264.204584) (xy 367.34918 -264.248161)
			(xy 367.364764 -264.294842) (xy 367.372659 -264.343419) (xy 367.373154 -264.368026) (xy 368.639864 -264.368026)
			(xy 368.643824 -264.318972) (xy 368.655601 -264.271188) (xy 368.674892 -264.225912) (xy 368.701195 -264.184316)
			(xy 368.73383 -264.147479) (xy 368.771951 -264.116354) (xy 368.814572 -264.091747) (xy 368.860588 -264.074295)
			(xy 368.908807 -264.064451) (xy 368.957982 -264.06247) (xy 369.006837 -264.068402) (xy 369.054108 -264.082094)
			(xy 369.09857 -264.103192) (xy 369.139073 -264.131148) (xy 369.174566 -264.16524) (xy 369.204131 -264.204584)
			(xy 369.227002 -264.248161) (xy 369.242586 -264.294842) (xy 369.250481 -264.343419) (xy 369.250935 -264.365994)
			(xy 370.518956 -264.365994) (xy 370.522916 -264.31694) (xy 370.534693 -264.269156) (xy 370.553984 -264.22388)
			(xy 370.580287 -264.182284) (xy 370.612922 -264.145447) (xy 370.651043 -264.114322) (xy 370.693664 -264.089715)
			(xy 370.73968 -264.072263) (xy 370.787899 -264.062419) (xy 370.837074 -264.060438) (xy 370.885929 -264.06637)
			(xy 370.9332 -264.080062) (xy 370.977662 -264.10116) (xy 371.018165 -264.129116) (xy 371.053658 -264.163208)
			(xy 371.083223 -264.202552) (xy 371.106094 -264.246129) (xy 371.121678 -264.29281) (xy 371.129573 -264.341387)
			(xy 371.130068 -264.365994) (xy 372.399064 -264.365994) (xy 372.403024 -264.31694) (xy 372.414801 -264.269156)
			(xy 372.434092 -264.22388) (xy 372.460395 -264.182284) (xy 372.49303 -264.145447) (xy 372.531151 -264.114322)
			(xy 372.573772 -264.089715) (xy 372.619788 -264.072263) (xy 372.668007 -264.062419) (xy 372.717182 -264.060438)
			(xy 372.766037 -264.06637) (xy 372.813308 -264.080062) (xy 372.85777 -264.10116) (xy 372.898273 -264.129116)
			(xy 372.933766 -264.163208) (xy 372.963331 -264.202552) (xy 372.986202 -264.246129) (xy 373.001786 -264.29281)
			(xy 373.009681 -264.341387) (xy 373.010176 -264.365994) (xy 374.278918 -264.365994) (xy 374.282878 -264.31694)
			(xy 374.294655 -264.269156) (xy 374.313946 -264.22388) (xy 374.340249 -264.182284) (xy 374.372884 -264.145447)
			(xy 374.411005 -264.114322) (xy 374.453626 -264.089715) (xy 374.499642 -264.072263) (xy 374.547861 -264.062419)
			(xy 374.597036 -264.060438) (xy 374.645891 -264.06637) (xy 374.693162 -264.080062) (xy 374.737624 -264.10116)
			(xy 374.778127 -264.129116) (xy 374.81362 -264.163208) (xy 374.843185 -264.202552) (xy 374.866056 -264.246129)
			(xy 374.88164 -264.29281) (xy 374.889535 -264.341387) (xy 374.89003 -264.365994) (xy 376.148595 -264.365994)
			(xy 376.15269 -264.315266) (xy 376.164869 -264.265852) (xy 376.184817 -264.219032) (xy 376.212018 -264.176018)
			(xy 376.245766 -264.137924) (xy 376.285188 -264.105737) (xy 376.329262 -264.080291) (xy 376.376848 -264.062244)
			(xy 376.426712 -264.052064) (xy 376.477564 -264.050015) (xy 376.528085 -264.056149) (xy 376.576969 -264.070309)
			(xy 376.622948 -264.092126) (xy 376.664832 -264.121036) (xy 376.701536 -264.156291) (xy 376.732109 -264.196977)
			(xy 376.75576 -264.24204) (xy 376.771876 -264.290314) (xy 376.78004 -264.340548) (xy 376.780552 -264.365994)
			(xy 377.088649 -264.365994) (xy 377.092744 -264.315266) (xy 377.104923 -264.265852) (xy 377.124871 -264.219032)
			(xy 377.152072 -264.176018) (xy 377.18582 -264.137924) (xy 377.225242 -264.105737) (xy 377.269316 -264.080291)
			(xy 377.316902 -264.062244) (xy 377.366766 -264.052064) (xy 377.417618 -264.050015) (xy 377.468139 -264.056149)
			(xy 377.517023 -264.070309) (xy 377.563002 -264.092126) (xy 377.604886 -264.121036) (xy 377.64159 -264.156291)
			(xy 377.672163 -264.196977) (xy 377.695814 -264.24204) (xy 377.71193 -264.290314) (xy 377.720094 -264.340548)
			(xy 377.720606 -264.365994) (xy 378.039134 -264.365994) (xy 378.043094 -264.31694) (xy 378.054871 -264.269156)
			(xy 378.074162 -264.22388) (xy 378.100465 -264.182284) (xy 378.1331 -264.145447) (xy 378.171221 -264.114322)
			(xy 378.213842 -264.089715) (xy 378.259858 -264.072263) (xy 378.308077 -264.062419) (xy 378.357252 -264.060438)
			(xy 378.406107 -264.06637) (xy 378.453378 -264.080062) (xy 378.49784 -264.10116) (xy 378.538343 -264.129116)
			(xy 378.573836 -264.163208) (xy 378.603401 -264.202552) (xy 378.626272 -264.246129) (xy 378.641856 -264.29281)
			(xy 378.649751 -264.341387) (xy 378.650246 -264.365994) (xy 378.968503 -264.365994) (xy 378.972598 -264.315266)
			(xy 378.984777 -264.265852) (xy 379.004725 -264.219032) (xy 379.031926 -264.176018) (xy 379.065674 -264.137924)
			(xy 379.105096 -264.105737) (xy 379.14917 -264.080291) (xy 379.196756 -264.062244) (xy 379.24662 -264.052064)
			(xy 379.297472 -264.050015) (xy 379.347993 -264.056149) (xy 379.396877 -264.070309) (xy 379.442856 -264.092126)
			(xy 379.48474 -264.121036) (xy 379.521444 -264.156291) (xy 379.552017 -264.196977) (xy 379.575668 -264.24204)
			(xy 379.591784 -264.290314) (xy 379.599948 -264.340548) (xy 379.60046 -264.365994) (xy 379.599948 -264.39144)
			(xy 379.591784 -264.441674) (xy 379.575668 -264.489948) (xy 379.552017 -264.535011) (xy 379.521444 -264.575697)
			(xy 379.48474 -264.610952) (xy 379.442856 -264.639862) (xy 379.396877 -264.661679) (xy 379.347993 -264.675839)
			(xy 379.297472 -264.681973) (xy 379.24662 -264.679924) (xy 379.196756 -264.669744) (xy 379.14917 -264.651697)
			(xy 379.105096 -264.626251) (xy 379.065674 -264.594064) (xy 379.031926 -264.55597) (xy 379.004725 -264.512956)
			(xy 378.984777 -264.466136) (xy 378.972598 -264.416722) (xy 378.968503 -264.365994) (xy 378.650246 -264.365994)
			(xy 378.649751 -264.390601) (xy 378.641856 -264.439178) (xy 378.626272 -264.485859) (xy 378.603401 -264.529436)
			(xy 378.573836 -264.56878) (xy 378.538343 -264.602872) (xy 378.49784 -264.630828) (xy 378.453378 -264.651926)
			(xy 378.406107 -264.665618) (xy 378.357252 -264.67155) (xy 378.308077 -264.669569) (xy 378.259858 -264.659725)
			(xy 378.213842 -264.642273) (xy 378.171221 -264.617666) (xy 378.1331 -264.586541) (xy 378.100465 -264.549704)
			(xy 378.074162 -264.508108) (xy 378.054871 -264.462832) (xy 378.043094 -264.415048) (xy 378.039134 -264.365994)
			(xy 377.720606 -264.365994) (xy 377.720094 -264.39144) (xy 377.71193 -264.441674) (xy 377.695814 -264.489948)
			(xy 377.672163 -264.535011) (xy 377.64159 -264.575697) (xy 377.604886 -264.610952) (xy 377.563002 -264.639862)
			(xy 377.517023 -264.661679) (xy 377.468139 -264.675839) (xy 377.417618 -264.681973) (xy 377.366766 -264.679924)
			(xy 377.316902 -264.669744) (xy 377.269316 -264.651697) (xy 377.225242 -264.626251) (xy 377.18582 -264.594064)
			(xy 377.152072 -264.55597) (xy 377.124871 -264.512956) (xy 377.104923 -264.466136) (xy 377.092744 -264.416722)
			(xy 377.088649 -264.365994) (xy 376.780552 -264.365994) (xy 376.78004 -264.39144) (xy 376.771876 -264.441674)
			(xy 376.75576 -264.489948) (xy 376.732109 -264.535011) (xy 376.701536 -264.575697) (xy 376.664832 -264.610952)
			(xy 376.622948 -264.639862) (xy 376.576969 -264.661679) (xy 376.528085 -264.675839) (xy 376.477564 -264.681973)
			(xy 376.426712 -264.679924) (xy 376.376848 -264.669744) (xy 376.329262 -264.651697) (xy 376.285188 -264.626251)
			(xy 376.245766 -264.594064) (xy 376.212018 -264.55597) (xy 376.184817 -264.512956) (xy 376.164869 -264.466136)
			(xy 376.15269 -264.416722) (xy 376.148595 -264.365994) (xy 374.89003 -264.365994) (xy 374.889535 -264.390601)
			(xy 374.88164 -264.439178) (xy 374.866056 -264.485859) (xy 374.843185 -264.529436) (xy 374.81362 -264.56878)
			(xy 374.778127 -264.602872) (xy 374.737624 -264.630828) (xy 374.693162 -264.651926) (xy 374.645891 -264.665618)
			(xy 374.597036 -264.67155) (xy 374.547861 -264.669569) (xy 374.499642 -264.659725) (xy 374.453626 -264.642273)
			(xy 374.411005 -264.617666) (xy 374.372884 -264.586541) (xy 374.340249 -264.549704) (xy 374.313946 -264.508108)
			(xy 374.294655 -264.462832) (xy 374.282878 -264.415048) (xy 374.278918 -264.365994) (xy 373.010176 -264.365994)
			(xy 373.009681 -264.390601) (xy 373.001786 -264.439178) (xy 372.986202 -264.485859) (xy 372.963331 -264.529436)
			(xy 372.933766 -264.56878) (xy 372.898273 -264.602872) (xy 372.85777 -264.630828) (xy 372.813308 -264.651926)
			(xy 372.766037 -264.665618) (xy 372.717182 -264.67155) (xy 372.668007 -264.669569) (xy 372.619788 -264.659725)
			(xy 372.573772 -264.642273) (xy 372.531151 -264.617666) (xy 372.49303 -264.586541) (xy 372.460395 -264.549704)
			(xy 372.434092 -264.508108) (xy 372.414801 -264.462832) (xy 372.403024 -264.415048) (xy 372.399064 -264.365994)
			(xy 371.130068 -264.365994) (xy 371.129573 -264.390601) (xy 371.121678 -264.439178) (xy 371.106094 -264.485859)
			(xy 371.083223 -264.529436) (xy 371.053658 -264.56878) (xy 371.018165 -264.602872) (xy 370.977662 -264.630828)
			(xy 370.9332 -264.651926) (xy 370.885929 -264.665618) (xy 370.837074 -264.67155) (xy 370.787899 -264.669569)
			(xy 370.73968 -264.659725) (xy 370.693664 -264.642273) (xy 370.651043 -264.617666) (xy 370.612922 -264.586541)
			(xy 370.580287 -264.549704) (xy 370.553984 -264.508108) (xy 370.534693 -264.462832) (xy 370.522916 -264.415048)
			(xy 370.518956 -264.365994) (xy 369.250935 -264.365994) (xy 369.250976 -264.368026) (xy 369.250481 -264.392633)
			(xy 369.242586 -264.44121) (xy 369.227002 -264.487891) (xy 369.204131 -264.531468) (xy 369.174566 -264.570812)
			(xy 369.139073 -264.604904) (xy 369.09857 -264.63286) (xy 369.054108 -264.653958) (xy 369.006837 -264.66765)
			(xy 368.957982 -264.673582) (xy 368.908807 -264.671601) (xy 368.860588 -264.661757) (xy 368.814572 -264.644305)
			(xy 368.771951 -264.619698) (xy 368.73383 -264.588573) (xy 368.701195 -264.551736) (xy 368.674892 -264.51014)
			(xy 368.655601 -264.464864) (xy 368.643824 -264.41708) (xy 368.639864 -264.368026) (xy 367.373154 -264.368026)
			(xy 367.372659 -264.392633) (xy 367.364764 -264.44121) (xy 367.34918 -264.487891) (xy 367.326309 -264.531468)
			(xy 367.296744 -264.570812) (xy 367.261251 -264.604904) (xy 367.220748 -264.63286) (xy 367.176286 -264.653958)
			(xy 367.129015 -264.66765) (xy 367.08016 -264.673582) (xy 367.030985 -264.671601) (xy 366.982766 -264.661757)
			(xy 366.93675 -264.644305) (xy 366.894129 -264.619698) (xy 366.856008 -264.588573) (xy 366.823373 -264.551736)
			(xy 366.79707 -264.51014) (xy 366.777779 -264.464864) (xy 366.766002 -264.41708) (xy 366.762042 -264.368026)
			(xy 365.4933 -264.368026) (xy 365.492805 -264.392633) (xy 365.48491 -264.44121) (xy 365.469326 -264.487891)
			(xy 365.446455 -264.531468) (xy 365.41689 -264.570812) (xy 365.381397 -264.604904) (xy 365.340894 -264.63286)
			(xy 365.296432 -264.653958) (xy 365.249161 -264.66765) (xy 365.200306 -264.673582) (xy 365.151131 -264.671601)
			(xy 365.102912 -264.661757) (xy 365.056896 -264.644305) (xy 365.014275 -264.619698) (xy 364.976154 -264.588573)
			(xy 364.943519 -264.551736) (xy 364.917216 -264.51014) (xy 364.897925 -264.464864) (xy 364.886148 -264.41708)
			(xy 364.882188 -264.368026) (xy 363.613192 -264.368026) (xy 363.612697 -264.392633) (xy 363.604802 -264.44121)
			(xy 363.589218 -264.487891) (xy 363.566347 -264.531468) (xy 363.536782 -264.570812) (xy 363.501289 -264.604904)
			(xy 363.460786 -264.63286) (xy 363.416324 -264.653958) (xy 363.369053 -264.66765) (xy 363.320198 -264.673582)
			(xy 363.271023 -264.671601) (xy 363.222804 -264.661757) (xy 363.176788 -264.644305) (xy 363.134167 -264.619698)
			(xy 363.096046 -264.588573) (xy 363.063411 -264.551736) (xy 363.037108 -264.51014) (xy 363.017817 -264.464864)
			(xy 363.00604 -264.41708) (xy 363.00208 -264.368026) (xy 356.093268 -264.368026) (xy 356.092773 -264.392633)
			(xy 356.084878 -264.44121) (xy 356.069294 -264.487891) (xy 356.046423 -264.531468) (xy 356.016858 -264.570812)
			(xy 355.981365 -264.604904) (xy 355.940862 -264.63286) (xy 355.8964 -264.653958) (xy 355.849129 -264.66765)
			(xy 355.800274 -264.673582) (xy 355.751099 -264.671601) (xy 355.70288 -264.661757) (xy 355.656864 -264.644305)
			(xy 355.614243 -264.619698) (xy 355.576122 -264.588573) (xy 355.543487 -264.551736) (xy 355.517184 -264.51014)
			(xy 355.497893 -264.464864) (xy 355.486116 -264.41708) (xy 355.482156 -264.368026) (xy 354.213414 -264.368026)
			(xy 354.212919 -264.392633) (xy 354.205024 -264.44121) (xy 354.18944 -264.487891) (xy 354.166569 -264.531468)
			(xy 354.137004 -264.570812) (xy 354.101511 -264.604904) (xy 354.061008 -264.63286) (xy 354.016546 -264.653958)
			(xy 353.969275 -264.66765) (xy 353.92042 -264.673582) (xy 353.871245 -264.671601) (xy 353.823026 -264.661757)
			(xy 353.77701 -264.644305) (xy 353.734389 -264.619698) (xy 353.696268 -264.588573) (xy 353.663633 -264.551736)
			(xy 353.63733 -264.51014) (xy 353.618039 -264.464864) (xy 353.606262 -264.41708) (xy 353.602302 -264.368026)
			(xy 352.333306 -264.368026) (xy 352.332811 -264.392633) (xy 352.324916 -264.44121) (xy 352.309332 -264.487891)
			(xy 352.286461 -264.531468) (xy 352.256896 -264.570812) (xy 352.221403 -264.604904) (xy 352.1809 -264.63286)
			(xy 352.136438 -264.653958) (xy 352.089167 -264.66765) (xy 352.040312 -264.673582) (xy 351.991137 -264.671601)
			(xy 351.942918 -264.661757) (xy 351.896902 -264.644305) (xy 351.854281 -264.619698) (xy 351.81616 -264.588573)
			(xy 351.783525 -264.551736) (xy 351.757222 -264.51014) (xy 351.737931 -264.464864) (xy 351.726154 -264.41708)
			(xy 351.722194 -264.368026) (xy 350.456459 -264.368026) (xy 350.456005 -264.390601) (xy 350.44811 -264.439178)
			(xy 350.432526 -264.485859) (xy 350.409655 -264.529436) (xy 350.38009 -264.56878) (xy 350.344597 -264.602872)
			(xy 350.304094 -264.630828) (xy 350.259632 -264.651926) (xy 350.212361 -264.665618) (xy 350.163506 -264.67155)
			(xy 350.114331 -264.669569) (xy 350.066112 -264.659725) (xy 350.020096 -264.642273) (xy 349.977475 -264.617666)
			(xy 349.939354 -264.586541) (xy 349.906719 -264.549704) (xy 349.880416 -264.508108) (xy 349.861125 -264.462832)
			(xy 349.849348 -264.415048) (xy 349.845388 -264.365994) (xy 348.99346 -264.365994) (xy 348.99346 -264.502138)
			(xy 348.994476 -264.51179) (xy 348.99611 -264.51903) (xy 349.002963 -264.532188) (xy 349.007938 -264.537698)
			(xy 349.33255 -264.86231) (xy 359.174291 -264.86231) (xy 359.178321 -264.809812) (xy 359.190318 -264.758544)
			(xy 359.210001 -264.709709) (xy 359.236907 -264.66445) (xy 359.270407 -264.623829) (xy 359.309715 -264.588798)
			(xy 359.35391 -264.560178) (xy 359.401955 -264.538639) (xy 359.452726 -264.524687) (xy 359.505031 -264.518649)
			(xy 359.557645 -264.520666) (xy 359.609335 -264.53069) (xy 359.658888 -264.548488) (xy 359.705144 -264.573641)
			(xy 359.747018 -264.60556) (xy 359.78353 -264.643498) (xy 359.813822 -264.686564) (xy 359.837185 -264.733749)
			(xy 359.853071 -264.783948) (xy 359.861108 -264.835984) (xy 359.861612 -264.86231) (xy 359.861108 -264.888636)
			(xy 359.853071 -264.940672) (xy 359.837185 -264.990871) (xy 359.813822 -265.038056) (xy 359.78353 -265.081122)
			(xy 359.747018 -265.11906) (xy 359.705144 -265.150979) (xy 359.659131 -265.176) (xy 369.109002 -265.176)
			(xy 369.112962 -265.126946) (xy 369.124739 -265.079162) (xy 369.14403 -265.033886) (xy 369.170333 -264.99229)
			(xy 369.202968 -264.955453) (xy 369.241089 -264.924328) (xy 369.28371 -264.899721) (xy 369.329726 -264.882269)
			(xy 369.377945 -264.872425) (xy 369.42712 -264.870444) (xy 369.475975 -264.876376) (xy 369.523246 -264.890068)
			(xy 369.567708 -264.911166) (xy 369.608211 -264.939122) (xy 369.643704 -264.973214) (xy 369.673269 -265.012558)
			(xy 369.69614 -265.056135) (xy 369.711724 -265.102816) (xy 369.719619 -265.151393) (xy 369.720114 -265.176)
			(xy 370.98911 -265.176) (xy 370.99307 -265.126946) (xy 371.004847 -265.079162) (xy 371.024138 -265.033886)
			(xy 371.050441 -264.99229) (xy 371.083076 -264.955453) (xy 371.121197 -264.924328) (xy 371.163818 -264.899721)
			(xy 371.209834 -264.882269) (xy 371.258053 -264.872425) (xy 371.307228 -264.870444) (xy 371.356083 -264.876376)
			(xy 371.403354 -264.890068) (xy 371.447816 -264.911166) (xy 371.488319 -264.939122) (xy 371.523812 -264.973214)
			(xy 371.553377 -265.012558) (xy 371.576248 -265.056135) (xy 371.591832 -265.102816) (xy 371.599727 -265.151393)
			(xy 371.600222 -265.176) (xy 372.868964 -265.176) (xy 372.872924 -265.126946) (xy 372.884701 -265.079162)
			(xy 372.903992 -265.033886) (xy 372.930295 -264.99229) (xy 372.96293 -264.955453) (xy 373.001051 -264.924328)
			(xy 373.043672 -264.899721) (xy 373.089688 -264.882269) (xy 373.137907 -264.872425) (xy 373.187082 -264.870444)
			(xy 373.235937 -264.876376) (xy 373.283208 -264.890068) (xy 373.32767 -264.911166) (xy 373.368173 -264.939122)
			(xy 373.403666 -264.973214) (xy 373.433231 -265.012558) (xy 373.456102 -265.056135) (xy 373.471686 -265.102816)
			(xy 373.479581 -265.151393) (xy 373.480076 -265.176) (xy 374.749072 -265.176) (xy 374.753032 -265.126946)
			(xy 374.764809 -265.079162) (xy 374.7841 -265.033886) (xy 374.810403 -264.99229) (xy 374.843038 -264.955453)
			(xy 374.881159 -264.924328) (xy 374.92378 -264.899721) (xy 374.969796 -264.882269) (xy 375.018015 -264.872425)
			(xy 375.06719 -264.870444) (xy 375.116045 -264.876376) (xy 375.163316 -264.890068) (xy 375.207778 -264.911166)
			(xy 375.248281 -264.939122) (xy 375.283774 -264.973214) (xy 375.313339 -265.012558) (xy 375.33621 -265.056135)
			(xy 375.351794 -265.102816) (xy 375.359689 -265.151393) (xy 375.360184 -265.176) (xy 375.678695 -265.176)
			(xy 375.68279 -265.125272) (xy 375.694969 -265.075858) (xy 375.714917 -265.029038) (xy 375.742118 -264.986024)
			(xy 375.775866 -264.94793) (xy 375.815288 -264.915743) (xy 375.859362 -264.890297) (xy 375.906948 -264.87225)
			(xy 375.956812 -264.86207) (xy 376.007664 -264.860021) (xy 376.058185 -264.866155) (xy 376.107069 -264.880315)
			(xy 376.153048 -264.902132) (xy 376.194932 -264.931042) (xy 376.231636 -264.966297) (xy 376.262209 -265.006983)
			(xy 376.28586 -265.052046) (xy 376.301976 -265.10032) (xy 376.31014 -265.150554) (xy 376.310652 -265.176)
			(xy 376.628926 -265.176) (xy 376.632886 -265.126946) (xy 376.644663 -265.079162) (xy 376.663954 -265.033886)
			(xy 376.690257 -264.99229) (xy 376.722892 -264.955453) (xy 376.761013 -264.924328) (xy 376.803634 -264.899721)
			(xy 376.84965 -264.882269) (xy 376.897869 -264.872425) (xy 376.947044 -264.870444) (xy 376.995899 -264.876376)
			(xy 377.04317 -264.890068) (xy 377.087632 -264.911166) (xy 377.128135 -264.939122) (xy 377.163628 -264.973214)
			(xy 377.193193 -265.012558) (xy 377.216064 -265.056135) (xy 377.231648 -265.102816) (xy 377.239543 -265.151393)
			(xy 377.240038 -265.176) (xy 377.56898 -265.176) (xy 377.57294 -265.126946) (xy 377.584717 -265.079162)
			(xy 377.604008 -265.033886) (xy 377.630311 -264.99229) (xy 377.662946 -264.955453) (xy 377.701067 -264.924328)
			(xy 377.743688 -264.899721) (xy 377.789704 -264.882269) (xy 377.837923 -264.872425) (xy 377.887098 -264.870444)
			(xy 377.935953 -264.876376) (xy 377.983224 -264.890068) (xy 378.027686 -264.911166) (xy 378.068189 -264.939122)
			(xy 378.103682 -264.973214) (xy 378.133247 -265.012558) (xy 378.156118 -265.056135) (xy 378.171702 -265.102816)
			(xy 378.179597 -265.151393) (xy 378.180092 -265.176) (xy 378.509034 -265.176) (xy 378.512994 -265.126946)
			(xy 378.524771 -265.079162) (xy 378.544062 -265.033886) (xy 378.570365 -264.99229) (xy 378.603 -264.955453)
			(xy 378.641121 -264.924328) (xy 378.683742 -264.899721) (xy 378.729758 -264.882269) (xy 378.777977 -264.872425)
			(xy 378.827152 -264.870444) (xy 378.876007 -264.876376) (xy 378.923278 -264.890068) (xy 378.96774 -264.911166)
			(xy 379.008243 -264.939122) (xy 379.043736 -264.973214) (xy 379.073301 -265.012558) (xy 379.096172 -265.056135)
			(xy 379.111756 -265.102816) (xy 379.119651 -265.151393) (xy 379.120146 -265.176) (xy 379.438657 -265.176)
			(xy 379.442752 -265.125272) (xy 379.454931 -265.075858) (xy 379.474879 -265.029038) (xy 379.50208 -264.986024)
			(xy 379.535828 -264.94793) (xy 379.57525 -264.915743) (xy 379.619324 -264.890297) (xy 379.66691 -264.87225)
			(xy 379.716774 -264.86207) (xy 379.767626 -264.860021) (xy 379.818147 -264.866155) (xy 379.867031 -264.880315)
			(xy 379.91301 -264.902132) (xy 379.954894 -264.931042) (xy 379.991598 -264.966297) (xy 380.022171 -265.006983)
			(xy 380.045822 -265.052046) (xy 380.061938 -265.10032) (xy 380.070102 -265.150554) (xy 380.070614 -265.176)
			(xy 380.388888 -265.176) (xy 380.392848 -265.126946) (xy 380.404625 -265.079162) (xy 380.423916 -265.033886)
			(xy 380.450219 -264.99229) (xy 380.482854 -264.955453) (xy 380.520975 -264.924328) (xy 380.563596 -264.899721)
			(xy 380.609612 -264.882269) (xy 380.657831 -264.872425) (xy 380.707006 -264.870444) (xy 380.755861 -264.876376)
			(xy 380.803132 -264.890068) (xy 380.847594 -264.911166) (xy 380.888097 -264.939122) (xy 380.92359 -264.973214)
			(xy 380.953155 -265.012558) (xy 380.976026 -265.056135) (xy 380.99161 -265.102816) (xy 380.999505 -265.151393)
			(xy 381 -265.176) (xy 381.328942 -265.176) (xy 381.332902 -265.126946) (xy 381.344679 -265.079162)
			(xy 381.36397 -265.033886) (xy 381.390273 -264.99229) (xy 381.422908 -264.955453) (xy 381.461029 -264.924328)
			(xy 381.50365 -264.899721) (xy 381.549666 -264.882269) (xy 381.597885 -264.872425) (xy 381.64706 -264.870444)
			(xy 381.695915 -264.876376) (xy 381.743186 -264.890068) (xy 381.787648 -264.911166) (xy 381.828151 -264.939122)
			(xy 381.863644 -264.973214) (xy 381.893209 -265.012558) (xy 381.91608 -265.056135) (xy 381.931664 -265.102816)
			(xy 381.939559 -265.151393) (xy 381.940054 -265.176) (xy 382.268996 -265.176) (xy 382.272956 -265.126946)
			(xy 382.284733 -265.079162) (xy 382.304024 -265.033886) (xy 382.330327 -264.99229) (xy 382.362962 -264.955453)
			(xy 382.401083 -264.924328) (xy 382.443704 -264.899721) (xy 382.48972 -264.882269) (xy 382.537939 -264.872425)
			(xy 382.587114 -264.870444) (xy 382.635969 -264.876376) (xy 382.68324 -264.890068) (xy 382.727702 -264.911166)
			(xy 382.768205 -264.939122) (xy 382.803698 -264.973214) (xy 382.833263 -265.012558) (xy 382.856134 -265.056135)
			(xy 382.871718 -265.102816) (xy 382.879613 -265.151393) (xy 382.880108 -265.176) (xy 383.20905 -265.176)
			(xy 383.21301 -265.126946) (xy 383.224787 -265.079162) (xy 383.244078 -265.033886) (xy 383.270381 -264.99229)
			(xy 383.303016 -264.955453) (xy 383.341137 -264.924328) (xy 383.383758 -264.899721) (xy 383.429774 -264.882269)
			(xy 383.477993 -264.872425) (xy 383.527168 -264.870444) (xy 383.576023 -264.876376) (xy 383.623294 -264.890068)
			(xy 383.667756 -264.911166) (xy 383.708259 -264.939122) (xy 383.743752 -264.973214) (xy 383.773317 -265.012558)
			(xy 383.796188 -265.056135) (xy 383.811772 -265.102816) (xy 383.819667 -265.151393) (xy 383.820162 -265.176)
			(xy 384.149104 -265.176) (xy 384.153064 -265.126946) (xy 384.164841 -265.079162) (xy 384.184132 -265.033886)
			(xy 384.210435 -264.99229) (xy 384.24307 -264.955453) (xy 384.281191 -264.924328) (xy 384.323812 -264.899721)
			(xy 384.369828 -264.882269) (xy 384.418047 -264.872425) (xy 384.467222 -264.870444) (xy 384.516077 -264.876376)
			(xy 384.563348 -264.890068) (xy 384.60781 -264.911166) (xy 384.648313 -264.939122) (xy 384.683806 -264.973214)
			(xy 384.713371 -265.012558) (xy 384.736242 -265.056135) (xy 384.751826 -265.102816) (xy 384.759721 -265.151393)
			(xy 384.760216 -265.176) (xy 385.088904 -265.176) (xy 385.092864 -265.126946) (xy 385.104641 -265.079162)
			(xy 385.123932 -265.033886) (xy 385.150235 -264.99229) (xy 385.18287 -264.955453) (xy 385.220991 -264.924328)
			(xy 385.263612 -264.899721) (xy 385.309628 -264.882269) (xy 385.357847 -264.872425) (xy 385.407022 -264.870444)
			(xy 385.455877 -264.876376) (xy 385.503148 -264.890068) (xy 385.54761 -264.911166) (xy 385.588113 -264.939122)
			(xy 385.623606 -264.973214) (xy 385.653171 -265.012558) (xy 385.676042 -265.056135) (xy 385.691626 -265.102816)
			(xy 385.699521 -265.151393) (xy 385.700016 -265.176) (xy 386.028958 -265.176) (xy 386.032918 -265.126946)
			(xy 386.044695 -265.079162) (xy 386.063986 -265.033886) (xy 386.090289 -264.99229) (xy 386.122924 -264.955453)
			(xy 386.161045 -264.924328) (xy 386.203666 -264.899721) (xy 386.249682 -264.882269) (xy 386.297901 -264.872425)
			(xy 386.347076 -264.870444) (xy 386.395931 -264.876376) (xy 386.443202 -264.890068) (xy 386.487664 -264.911166)
			(xy 386.528167 -264.939122) (xy 386.56366 -264.973214) (xy 386.593225 -265.012558) (xy 386.616096 -265.056135)
			(xy 386.63168 -265.102816) (xy 386.639575 -265.151393) (xy 386.64007 -265.176) (xy 386.969012 -265.176)
			(xy 386.972972 -265.126946) (xy 386.984749 -265.079162) (xy 387.00404 -265.033886) (xy 387.030343 -264.99229)
			(xy 387.062978 -264.955453) (xy 387.101099 -264.924328) (xy 387.14372 -264.899721) (xy 387.189736 -264.882269)
			(xy 387.237955 -264.872425) (xy 387.28713 -264.870444) (xy 387.335985 -264.876376) (xy 387.383256 -264.890068)
			(xy 387.427718 -264.911166) (xy 387.468221 -264.939122) (xy 387.503714 -264.973214) (xy 387.533279 -265.012558)
			(xy 387.55615 -265.056135) (xy 387.571734 -265.102816) (xy 387.579629 -265.151393) (xy 387.580124 -265.176)
			(xy 387.579629 -265.200607) (xy 387.571734 -265.249184) (xy 387.55615 -265.295865) (xy 387.533279 -265.339442)
			(xy 387.503714 -265.378786) (xy 387.468221 -265.412878) (xy 387.427718 -265.440834) (xy 387.383256 -265.461932)
			(xy 387.335985 -265.475624) (xy 387.28713 -265.481556) (xy 387.237955 -265.479575) (xy 387.189736 -265.469731)
			(xy 387.14372 -265.452279) (xy 387.101099 -265.427672) (xy 387.062978 -265.396547) (xy 387.030343 -265.35971)
			(xy 387.00404 -265.318114) (xy 386.984749 -265.272838) (xy 386.972972 -265.225054) (xy 386.969012 -265.176)
			(xy 386.64007 -265.176) (xy 386.639575 -265.200607) (xy 386.63168 -265.249184) (xy 386.616096 -265.295865)
			(xy 386.593225 -265.339442) (xy 386.56366 -265.378786) (xy 386.528167 -265.412878) (xy 386.487664 -265.440834)
			(xy 386.443202 -265.461932) (xy 386.395931 -265.475624) (xy 386.347076 -265.481556) (xy 386.297901 -265.479575)
			(xy 386.249682 -265.469731) (xy 386.203666 -265.452279) (xy 386.161045 -265.427672) (xy 386.122924 -265.396547)
			(xy 386.090289 -265.35971) (xy 386.063986 -265.318114) (xy 386.044695 -265.272838) (xy 386.032918 -265.225054)
			(xy 386.028958 -265.176) (xy 385.700016 -265.176) (xy 385.699521 -265.200607) (xy 385.691626 -265.249184)
			(xy 385.676042 -265.295865) (xy 385.653171 -265.339442) (xy 385.623606 -265.378786) (xy 385.588113 -265.412878)
			(xy 385.54761 -265.440834) (xy 385.503148 -265.461932) (xy 385.455877 -265.475624) (xy 385.407022 -265.481556)
			(xy 385.357847 -265.479575) (xy 385.309628 -265.469731) (xy 385.263612 -265.452279) (xy 385.220991 -265.427672)
			(xy 385.18287 -265.396547) (xy 385.150235 -265.35971) (xy 385.123932 -265.318114) (xy 385.104641 -265.272838)
			(xy 385.092864 -265.225054) (xy 385.088904 -265.176) (xy 384.760216 -265.176) (xy 384.759721 -265.200607)
			(xy 384.751826 -265.249184) (xy 384.736242 -265.295865) (xy 384.713371 -265.339442) (xy 384.683806 -265.378786)
			(xy 384.648313 -265.412878) (xy 384.60781 -265.440834) (xy 384.563348 -265.461932) (xy 384.516077 -265.475624)
			(xy 384.467222 -265.481556) (xy 384.418047 -265.479575) (xy 384.369828 -265.469731) (xy 384.323812 -265.452279)
			(xy 384.281191 -265.427672) (xy 384.24307 -265.396547) (xy 384.210435 -265.35971) (xy 384.184132 -265.318114)
			(xy 384.164841 -265.272838) (xy 384.153064 -265.225054) (xy 384.149104 -265.176) (xy 383.820162 -265.176)
			(xy 383.819667 -265.200607) (xy 383.811772 -265.249184) (xy 383.796188 -265.295865) (xy 383.773317 -265.339442)
			(xy 383.743752 -265.378786) (xy 383.708259 -265.412878) (xy 383.667756 -265.440834) (xy 383.623294 -265.461932)
			(xy 383.576023 -265.475624) (xy 383.527168 -265.481556) (xy 383.477993 -265.479575) (xy 383.429774 -265.469731)
			(xy 383.383758 -265.452279) (xy 383.341137 -265.427672) (xy 383.303016 -265.396547) (xy 383.270381 -265.35971)
			(xy 383.244078 -265.318114) (xy 383.224787 -265.272838) (xy 383.21301 -265.225054) (xy 383.20905 -265.176)
			(xy 382.880108 -265.176) (xy 382.879613 -265.200607) (xy 382.871718 -265.249184) (xy 382.856134 -265.295865)
			(xy 382.833263 -265.339442) (xy 382.803698 -265.378786) (xy 382.768205 -265.412878) (xy 382.727702 -265.440834)
			(xy 382.68324 -265.461932) (xy 382.635969 -265.475624) (xy 382.587114 -265.481556) (xy 382.537939 -265.479575)
			(xy 382.48972 -265.469731) (xy 382.443704 -265.452279) (xy 382.401083 -265.427672) (xy 382.362962 -265.396547)
			(xy 382.330327 -265.35971) (xy 382.304024 -265.318114) (xy 382.284733 -265.272838) (xy 382.272956 -265.225054)
			(xy 382.268996 -265.176) (xy 381.940054 -265.176) (xy 381.939559 -265.200607) (xy 381.931664 -265.249184)
			(xy 381.91608 -265.295865) (xy 381.893209 -265.339442) (xy 381.863644 -265.378786) (xy 381.828151 -265.412878)
			(xy 381.787648 -265.440834) (xy 381.743186 -265.461932) (xy 381.695915 -265.475624) (xy 381.64706 -265.481556)
			(xy 381.597885 -265.479575) (xy 381.549666 -265.469731) (xy 381.50365 -265.452279) (xy 381.461029 -265.427672)
			(xy 381.422908 -265.396547) (xy 381.390273 -265.35971) (xy 381.36397 -265.318114) (xy 381.344679 -265.272838)
			(xy 381.332902 -265.225054) (xy 381.328942 -265.176) (xy 381 -265.176) (xy 380.999505 -265.200607)
			(xy 380.99161 -265.249184) (xy 380.976026 -265.295865) (xy 380.953155 -265.339442) (xy 380.92359 -265.378786)
			(xy 380.888097 -265.412878) (xy 380.847594 -265.440834) (xy 380.803132 -265.461932) (xy 380.755861 -265.475624)
			(xy 380.707006 -265.481556) (xy 380.657831 -265.479575) (xy 380.609612 -265.469731) (xy 380.563596 -265.452279)
			(xy 380.520975 -265.427672) (xy 380.482854 -265.396547) (xy 380.450219 -265.35971) (xy 380.423916 -265.318114)
			(xy 380.404625 -265.272838) (xy 380.392848 -265.225054) (xy 380.388888 -265.176) (xy 380.070614 -265.176)
			(xy 380.070102 -265.201446) (xy 380.061938 -265.25168) (xy 380.045822 -265.299954) (xy 380.022171 -265.345017)
			(xy 379.991598 -265.385703) (xy 379.954894 -265.420958) (xy 379.91301 -265.449868) (xy 379.867031 -265.471685)
			(xy 379.818147 -265.485845) (xy 379.767626 -265.491979) (xy 379.716774 -265.48993) (xy 379.66691 -265.47975)
			(xy 379.619324 -265.461703) (xy 379.57525 -265.436257) (xy 379.535828 -265.40407) (xy 379.50208 -265.365976)
			(xy 379.474879 -265.322962) (xy 379.454931 -265.276142) (xy 379.442752 -265.226728) (xy 379.438657 -265.176)
			(xy 379.120146 -265.176) (xy 379.119651 -265.200607) (xy 379.111756 -265.249184) (xy 379.096172 -265.295865)
			(xy 379.073301 -265.339442) (xy 379.043736 -265.378786) (xy 379.008243 -265.412878) (xy 378.96774 -265.440834)
			(xy 378.923278 -265.461932) (xy 378.876007 -265.475624) (xy 378.827152 -265.481556) (xy 378.777977 -265.479575)
			(xy 378.729758 -265.469731) (xy 378.683742 -265.452279) (xy 378.641121 -265.427672) (xy 378.603 -265.396547)
			(xy 378.570365 -265.35971) (xy 378.544062 -265.318114) (xy 378.524771 -265.272838) (xy 378.512994 -265.225054)
			(xy 378.509034 -265.176) (xy 378.180092 -265.176) (xy 378.179597 -265.200607) (xy 378.171702 -265.249184)
			(xy 378.156118 -265.295865) (xy 378.133247 -265.339442) (xy 378.103682 -265.378786) (xy 378.068189 -265.412878)
			(xy 378.027686 -265.440834) (xy 377.983224 -265.461932) (xy 377.935953 -265.475624) (xy 377.887098 -265.481556)
			(xy 377.837923 -265.479575) (xy 377.789704 -265.469731) (xy 377.743688 -265.452279) (xy 377.701067 -265.427672)
			(xy 377.662946 -265.396547) (xy 377.630311 -265.35971) (xy 377.604008 -265.318114) (xy 377.584717 -265.272838)
			(xy 377.57294 -265.225054) (xy 377.56898 -265.176) (xy 377.240038 -265.176) (xy 377.239543 -265.200607)
			(xy 377.231648 -265.249184) (xy 377.216064 -265.295865) (xy 377.193193 -265.339442) (xy 377.163628 -265.378786)
			(xy 377.128135 -265.412878) (xy 377.087632 -265.440834) (xy 377.04317 -265.461932) (xy 376.995899 -265.475624)
			(xy 376.947044 -265.481556) (xy 376.897869 -265.479575) (xy 376.84965 -265.469731) (xy 376.803634 -265.452279)
			(xy 376.761013 -265.427672) (xy 376.722892 -265.396547) (xy 376.690257 -265.35971) (xy 376.663954 -265.318114)
			(xy 376.644663 -265.272838) (xy 376.632886 -265.225054) (xy 376.628926 -265.176) (xy 376.310652 -265.176)
			(xy 376.31014 -265.201446) (xy 376.301976 -265.25168) (xy 376.28586 -265.299954) (xy 376.262209 -265.345017)
			(xy 376.231636 -265.385703) (xy 376.194932 -265.420958) (xy 376.153048 -265.449868) (xy 376.107069 -265.471685)
			(xy 376.058185 -265.485845) (xy 376.007664 -265.491979) (xy 375.956812 -265.48993) (xy 375.906948 -265.47975)
			(xy 375.859362 -265.461703) (xy 375.815288 -265.436257) (xy 375.775866 -265.40407) (xy 375.742118 -265.365976)
			(xy 375.714917 -265.322962) (xy 375.694969 -265.276142) (xy 375.68279 -265.226728) (xy 375.678695 -265.176)
			(xy 375.360184 -265.176) (xy 375.359689 -265.200607) (xy 375.351794 -265.249184) (xy 375.33621 -265.295865)
			(xy 375.313339 -265.339442) (xy 375.283774 -265.378786) (xy 375.248281 -265.412878) (xy 375.207778 -265.440834)
			(xy 375.163316 -265.461932) (xy 375.116045 -265.475624) (xy 375.06719 -265.481556) (xy 375.018015 -265.479575)
			(xy 374.969796 -265.469731) (xy 374.92378 -265.452279) (xy 374.881159 -265.427672) (xy 374.843038 -265.396547)
			(xy 374.810403 -265.35971) (xy 374.7841 -265.318114) (xy 374.764809 -265.272838) (xy 374.753032 -265.225054)
			(xy 374.749072 -265.176) (xy 373.480076 -265.176) (xy 373.479581 -265.200607) (xy 373.471686 -265.249184)
			(xy 373.456102 -265.295865) (xy 373.433231 -265.339442) (xy 373.403666 -265.378786) (xy 373.368173 -265.412878)
			(xy 373.32767 -265.440834) (xy 373.283208 -265.461932) (xy 373.235937 -265.475624) (xy 373.187082 -265.481556)
			(xy 373.137907 -265.479575) (xy 373.089688 -265.469731) (xy 373.043672 -265.452279) (xy 373.001051 -265.427672)
			(xy 372.96293 -265.396547) (xy 372.930295 -265.35971) (xy 372.903992 -265.318114) (xy 372.884701 -265.272838)
			(xy 372.872924 -265.225054) (xy 372.868964 -265.176) (xy 371.600222 -265.176) (xy 371.599727 -265.200607)
			(xy 371.591832 -265.249184) (xy 371.576248 -265.295865) (xy 371.553377 -265.339442) (xy 371.523812 -265.378786)
			(xy 371.488319 -265.412878) (xy 371.447816 -265.440834) (xy 371.403354 -265.461932) (xy 371.356083 -265.475624)
			(xy 371.307228 -265.481556) (xy 371.258053 -265.479575) (xy 371.209834 -265.469731) (xy 371.163818 -265.452279)
			(xy 371.121197 -265.427672) (xy 371.083076 -265.396547) (xy 371.050441 -265.35971) (xy 371.024138 -265.318114)
			(xy 371.004847 -265.272838) (xy 370.99307 -265.225054) (xy 370.98911 -265.176) (xy 369.720114 -265.176)
			(xy 369.719619 -265.200607) (xy 369.711724 -265.249184) (xy 369.69614 -265.295865) (xy 369.673269 -265.339442)
			(xy 369.643704 -265.378786) (xy 369.608211 -265.412878) (xy 369.567708 -265.440834) (xy 369.523246 -265.461932)
			(xy 369.475975 -265.475624) (xy 369.42712 -265.481556) (xy 369.377945 -265.479575) (xy 369.329726 -265.469731)
			(xy 369.28371 -265.452279) (xy 369.241089 -265.427672) (xy 369.202968 -265.396547) (xy 369.170333 -265.35971)
			(xy 369.14403 -265.318114) (xy 369.124739 -265.272838) (xy 369.112962 -265.225054) (xy 369.109002 -265.176)
			(xy 359.659131 -265.176) (xy 359.658888 -265.176132) (xy 359.609335 -265.19393) (xy 359.557645 -265.203954)
			(xy 359.505031 -265.205971) (xy 359.452726 -265.199933) (xy 359.401955 -265.185981) (xy 359.35391 -265.164442)
			(xy 359.309715 -265.135822) (xy 359.270407 -265.100791) (xy 359.236907 -265.06017) (xy 359.210001 -265.014911)
			(xy 359.190318 -264.966076) (xy 359.178321 -264.914808) (xy 359.174291 -264.86231) (xy 349.33255 -264.86231)
			(xy 349.400622 -264.930382) (xy 349.406838 -264.935483) (xy 349.421598 -264.941845) (xy 349.429578 -264.942828)
			(xy 349.455232 -264.943844) (xy 349.45975 -264.943904) (xy 349.468693 -264.94263) (xy 349.473012 -264.941304)
			(xy 349.494856 -264.933938) (xy 349.498412 -264.931398) (xy 349.518318 -264.917128) (xy 349.561728 -264.894455)
			(xy 349.608204 -264.879009) (xy 349.65655 -264.871189) (xy 349.681038 -264.870692) (xy 349.705027 -264.871165)
			(xy 349.752414 -264.878676) (xy 349.798043 -264.893507) (xy 349.840791 -264.915293) (xy 349.879604 -264.943497)
			(xy 349.913528 -264.977425) (xy 349.941727 -265.016242) (xy 349.963508 -265.058992) (xy 349.978333 -265.104623)
			(xy 349.985838 -265.152011) (xy 349.986346 -265.176) (xy 349.986209 -265.188763) (xy 349.98405 -265.214198)
			(xy 349.982028 -265.2268) (xy 349.982282 -265.2268) (xy 349.977811 -265.25061) (xy 349.962333 -265.296514)
			(xy 349.939792 -265.339393) (xy 349.910754 -265.378169) (xy 349.87595 -265.411865) (xy 349.836256 -265.439633)
			(xy 349.814642 -265.450574) (xy 349.790854 -265.461544) (xy 349.740536 -265.476098) (xy 349.714566 -265.47953)
			(xy 349.697903 -265.481127) (xy 349.664427 -265.481127) (xy 349.647764 -265.47953) (xy 349.638477 -265.478443)
			(xy 349.620049 -265.475266) (xy 349.610934 -265.47318) (xy 349.595094 -265.469236) (xy 349.564295 -265.458414)
			(xy 349.549466 -265.45159) (xy 349.548958 -265.451082) (xy 349.547688 -265.450574) (xy 349.542354 -265.448034)
			(xy 349.517138 -265.434495) (xy 349.471848 -265.399515) (xy 349.433876 -265.356702) (xy 349.418656 -265.332464)
			(xy 349.416116 -265.328146) (xy 349.413318 -265.324539) (xy 349.406672 -265.318283) (xy 349.402908 -265.3157)
			(xy 349.398336 -265.312906) (xy 349.387668 -265.308842) (xy 349.3516 -265.30427) (xy 349.303594 -265.298428)
			(xy 349.292145 -265.297523) (xy 349.270432 -265.304925) (xy 349.261938 -265.312652) (xy 348.72041 -265.85418)
			(xy 348.71369 -265.861415) (xy 348.70608 -265.87962) (xy 348.705678 -265.889486) (xy 348.705678 -266.074398)
			(xy 348.7062 -266.084145) (xy 348.713659 -266.102163) (xy 348.720156 -266.10945) (xy 348.90202 -266.291314)
			(xy 348.909264 -266.29788) (xy 348.927307 -266.305355) (xy 348.937072 -266.305792) (xy 349.810578 -266.305792)
			(xy 349.819554 -266.305421) (xy 349.836365 -266.299128) (xy 349.849898 -266.287335) (xy 349.85452 -266.27963)
			(xy 349.860362 -266.268962) (xy 349.896684 -266.20216) (xy 349.898716 -266.197842) (xy 349.90079 -266.192631)
			(xy 349.902833 -266.181607) (xy 349.90278 -266.175998) (xy 349.902272 -266.163298) (xy 349.894398 -266.151106)
			(xy 349.882929 -266.132546) (xy 349.864798 -266.092862) (xy 349.852497 -266.051003) (xy 349.846275 -266.00782)
			(xy 349.845884 -265.986006) (xy 349.846406 -265.960751) (xy 349.854719 -265.910929) (xy 349.87112 -265.863155)
			(xy 349.895161 -265.818732) (xy 349.926185 -265.778872) (xy 349.963347 -265.744662) (xy 350.005633 -265.717036)
			(xy 350.051889 -265.696746) (xy 350.100854 -265.684346) (xy 350.151192 -265.680175) (xy 350.20153 -265.684346)
			(xy 350.250495 -265.696746) (xy 350.296751 -265.717036) (xy 350.339037 -265.744662) (xy 350.376199 -265.778872)
			(xy 350.407223 -265.818732) (xy 350.431264 -265.863155) (xy 350.447665 -265.910929) (xy 350.455978 -265.960751)
			(xy 350.4565 -265.986006) (xy 350.455853 -266.014358) (xy 350.445347 -266.070081) (xy 350.424754 -266.122914)
			(xy 350.410272 -266.147296) (xy 350.407986 -266.151614) (xy 350.402652 -266.162028) (xy 350.401372 -266.165716)
			(xy 350.399838 -266.173371) (xy 350.399604 -266.177268) (xy 350.399096 -266.189968) (xy 350.442022 -266.268962)
			(xy 350.447864 -266.27963) (xy 350.452475 -266.287341) (xy 350.46602 -266.299125) (xy 350.48283 -266.305432)
			(xy 350.491806 -266.305792) (xy 351.690432 -266.305792) (xy 351.699412 -266.305429) (xy 351.716236 -266.299146)
			(xy 351.729782 -266.287355) (xy 351.734374 -266.27963) (xy 351.740216 -266.268962) (xy 351.776538 -266.20216)
			(xy 351.77857 -266.197842) (xy 351.780642 -266.192631) (xy 351.782683 -266.181606) (xy 351.782634 -266.175998)
			(xy 351.782126 -266.163298) (xy 351.774252 -266.151106) (xy 351.762784 -266.132545) (xy 351.744656 -266.092861)
			(xy 351.732357 -266.051003) (xy 351.726136 -266.00782) (xy 351.725738 -265.986006) (xy 351.72626 -265.960751)
			(xy 351.734573 -265.910929) (xy 351.750974 -265.863155) (xy 351.775015 -265.818732) (xy 351.806039 -265.778872)
			(xy 351.843201 -265.744662) (xy 351.885487 -265.717036) (xy 351.931743 -265.696746) (xy 351.980708 -265.684346)
			(xy 352.031046 -265.680175) (xy 352.081384 -265.684346) (xy 352.130349 -265.696746) (xy 352.176605 -265.717036)
			(xy 352.218891 -265.744662) (xy 352.256053 -265.778872) (xy 352.287077 -265.818732) (xy 352.311118 -265.863155)
			(xy 352.327519 -265.910929) (xy 352.335832 -265.960751) (xy 352.336354 -265.986006) (xy 352.335706 -266.014357)
			(xy 352.325199 -266.07008) (xy 352.304603 -266.122911) (xy 352.290126 -266.147296) (xy 352.28784 -266.151614)
			(xy 352.282506 -266.162028) (xy 352.281227 -266.165716) (xy 352.279694 -266.173371) (xy 352.279458 -266.177268)
			(xy 352.27895 -266.189968) (xy 352.321876 -266.268962) (xy 352.327718 -266.27963) (xy 352.332331 -266.287335)
			(xy 352.345879 -266.299104) (xy 352.362687 -266.305393) (xy 352.37166 -266.305792) (xy 353.57054 -266.305792)
			(xy 353.579519 -266.305427) (xy 353.596341 -266.299143) (xy 353.609885 -266.287352) (xy 353.614482 -266.27963)
			(xy 353.620324 -266.268962) (xy 353.656646 -266.20216) (xy 353.658678 -266.197842) (xy 353.66075 -266.192631)
			(xy 353.66279 -266.181606) (xy 353.662742 -266.175998) (xy 353.662234 -266.163298) (xy 353.65436 -266.151106)
			(xy 353.642892 -266.132545) (xy 353.624763 -266.092862) (xy 353.612464 -266.051003) (xy 353.606243 -266.00782)
			(xy 353.605846 -265.986006) (xy 353.606368 -265.960751) (xy 353.614681 -265.910929) (xy 353.631082 -265.863155)
			(xy 353.655123 -265.818732) (xy 353.686147 -265.778872) (xy 353.723309 -265.744662) (xy 353.765595 -265.717036)
			(xy 353.811851 -265.696746) (xy 353.860816 -265.684346) (xy 353.911154 -265.680175) (xy 353.961492 -265.684346)
			(xy 354.010457 -265.696746) (xy 354.056713 -265.717036) (xy 354.098999 -265.744662) (xy 354.136161 -265.778872)
			(xy 354.167185 -265.818732) (xy 354.191226 -265.863155) (xy 354.207627 -265.910929) (xy 354.21594 -265.960751)
			(xy 354.216462 -265.986006) (xy 354.215814 -266.014357) (xy 354.205308 -266.07008) (xy 354.184712 -266.122912)
			(xy 354.170234 -266.147296) (xy 354.167948 -266.151614) (xy 354.162614 -266.162028) (xy 354.161335 -266.165717)
			(xy 354.159802 -266.173371) (xy 354.159566 -266.177268) (xy 354.159058 -266.189968) (xy 354.201984 -266.268962)
			(xy 354.207826 -266.27963) (xy 354.21244 -266.287334) (xy 354.225988 -266.299101) (xy 354.242796 -266.305388)
			(xy 354.251768 -266.305792) (xy 355.450394 -266.305792) (xy 355.459368 -266.305418) (xy 355.476175 -266.299122)
			(xy 355.489704 -266.287328) (xy 355.494336 -266.27963) (xy 355.500178 -266.268962) (xy 355.5365 -266.20216)
			(xy 355.538532 -266.197842) (xy 355.540606 -266.192631) (xy 355.542648 -266.181607) (xy 355.542596 -266.175998)
			(xy 355.542088 -266.163298) (xy 355.534214 -266.151106) (xy 355.522745 -266.132546) (xy 355.504613 -266.092863)
			(xy 355.492311 -266.051004) (xy 355.486089 -266.00782) (xy 355.4857 -265.986006) (xy 355.486222 -265.960751)
			(xy 355.494535 -265.910929) (xy 355.510936 -265.863155) (xy 355.534977 -265.818732) (xy 355.566001 -265.778872)
			(xy 355.603163 -265.744662) (xy 355.645449 -265.717036) (xy 355.691705 -265.696746) (xy 355.74067 -265.684346)
			(xy 355.791008 -265.680175) (xy 355.841346 -265.684346) (xy 355.890311 -265.696746) (xy 355.936567 -265.717036)
			(xy 355.978853 -265.744662) (xy 356.016015 -265.778872) (xy 356.047039 -265.818732) (xy 356.07108 -265.863155)
			(xy 356.087481 -265.910929) (xy 356.095794 -265.960751) (xy 356.096316 -265.986006) (xy 356.095669 -266.014358)
			(xy 356.085164 -266.070081) (xy 356.064571 -266.122915) (xy 356.050088 -266.147296) (xy 356.047802 -266.151614)
			(xy 356.042468 -266.162028) (xy 356.041188 -266.165716) (xy 356.039653 -266.173371) (xy 356.03942 -266.177268)
			(xy 356.038912 -266.189968) (xy 356.081838 -266.268962) (xy 356.08768 -266.27963) (xy 356.092291 -266.287339)
			(xy 356.105838 -266.299119) (xy 356.122647 -266.30542) (xy 356.131622 -266.305792) (xy 357.330502 -266.305792)
			(xy 357.339475 -266.305417) (xy 357.35628 -266.299119) (xy 357.369807 -266.287324) (xy 357.374444 -266.27963)
			(xy 357.380286 -266.268962) (xy 357.416608 -266.20216) (xy 357.41864 -266.197842) (xy 357.420713 -266.192631)
			(xy 357.422755 -266.181606) (xy 357.422704 -266.175998) (xy 357.422196 -266.163298) (xy 357.414322 -266.151106)
			(xy 357.402852 -266.132546) (xy 357.38472 -266.092863) (xy 357.372418 -266.051004) (xy 357.366196 -266.007821)
			(xy 357.365808 -265.986006) (xy 357.36633 -265.960751) (xy 357.374643 -265.910929) (xy 357.391044 -265.863155)
			(xy 357.415085 -265.818732) (xy 357.446109 -265.778872) (xy 357.483271 -265.744662) (xy 357.525557 -265.717036)
			(xy 357.571813 -265.696746) (xy 357.620778 -265.684346) (xy 357.671116 -265.680175) (xy 357.721454 -265.684346)
			(xy 357.770419 -265.696746) (xy 357.816675 -265.717036) (xy 357.858961 -265.744662) (xy 357.896123 -265.778872)
			(xy 357.927147 -265.818732) (xy 357.951188 -265.863155) (xy 357.967589 -265.910929) (xy 357.975902 -265.960751)
			(xy 357.976424 -265.986006) (xy 357.975776 -266.014357) (xy 357.965268 -266.070079) (xy 357.94467 -266.12291)
			(xy 357.930196 -266.147296) (xy 357.92791 -266.151614) (xy 357.922576 -266.162028) (xy 357.921295 -266.165716)
			(xy 357.919761 -266.173371) (xy 357.919528 -266.177268) (xy 357.91902 -266.189968) (xy 357.961946 -266.268962)
			(xy 357.967788 -266.27963) (xy 357.9724 -266.287339) (xy 357.985946 -266.299116) (xy 358.002755 -266.305415)
			(xy 358.01173 -266.305792) (xy 361.084114 -266.305792) (xy 361.093086 -266.305415) (xy 361.109888 -266.299114)
			(xy 361.123411 -266.287319) (xy 361.128056 -266.27963) (xy 361.133898 -266.268962) (xy 361.17022 -266.20216)
			(xy 361.172252 -266.197842) (xy 361.174325 -266.192631) (xy 361.176366 -266.181606) (xy 361.176316 -266.175998)
			(xy 361.175808 -266.163298) (xy 361.167934 -266.151106) (xy 361.156467 -266.132545) (xy 361.13834 -266.092861)
			(xy 361.126041 -266.051002) (xy 361.119821 -266.00782) (xy 361.11942 -265.986006) (xy 361.119942 -265.960751)
			(xy 361.128255 -265.910929) (xy 361.144656 -265.863155) (xy 361.168697 -265.818732) (xy 361.199721 -265.778872)
			(xy 361.236883 -265.744662) (xy 361.279169 -265.717036) (xy 361.325425 -265.696746) (xy 361.37439 -265.684346)
			(xy 361.424728 -265.680175) (xy 361.475066 -265.684346) (xy 361.524031 -265.696746) (xy 361.570287 -265.717036)
			(xy 361.612573 -265.744662) (xy 361.649735 -265.778872) (xy 361.680759 -265.818732) (xy 361.7048 -265.863155)
			(xy 361.721201 -265.910929) (xy 361.729514 -265.960751) (xy 361.730036 -265.986006) (xy 361.729388 -266.014357)
			(xy 361.718881 -266.070079) (xy 361.698283 -266.12291) (xy 361.683808 -266.147296) (xy 361.681522 -266.151614)
			(xy 361.676188 -266.162028) (xy 361.674907 -266.165716) (xy 361.673372 -266.173371) (xy 361.67314 -266.177268)
			(xy 361.672632 -266.189968) (xy 361.715558 -266.268962) (xy 361.7214 -266.27963) (xy 361.726012 -266.287337)
			(xy 361.739559 -266.299112) (xy 361.756368 -266.305406) (xy 361.765342 -266.305792) (xy 362.964222 -266.305792)
			(xy 362.973193 -266.305414) (xy 362.989993 -266.299111) (xy 363.003514 -266.287315) (xy 363.008164 -266.27963)
			(xy 363.014006 -266.268962) (xy 363.050328 -266.20216) (xy 363.05236 -266.197842) (xy 363.054433 -266.192631)
			(xy 363.056474 -266.181606) (xy 363.056424 -266.175998) (xy 363.055916 -266.163298) (xy 363.048042 -266.151106)
			(xy 363.036575 -266.132545) (xy 363.018447 -266.092861) (xy 363.006148 -266.051002) (xy 362.999928 -266.00782)
			(xy 362.999528 -265.986006) (xy 363.00005 -265.960751) (xy 363.008363 -265.910929) (xy 363.024764 -265.863155)
			(xy 363.048805 -265.818732) (xy 363.079829 -265.778872) (xy 363.116991 -265.744662) (xy 363.159277 -265.717036)
			(xy 363.205533 -265.696746) (xy 363.254498 -265.684346) (xy 363.304836 -265.680175) (xy 363.355174 -265.684346)
			(xy 363.404139 -265.696746) (xy 363.450395 -265.717036) (xy 363.492681 -265.744662) (xy 363.529843 -265.778872)
			(xy 363.560867 -265.818732) (xy 363.584908 -265.863155) (xy 363.601309 -265.910929) (xy 363.609622 -265.960751)
			(xy 363.610144 -265.986006) (xy 363.609496 -266.014357) (xy 363.598989 -266.07008) (xy 363.578392 -266.122911)
			(xy 363.563916 -266.147296) (xy 363.56163 -266.151614) (xy 363.556296 -266.162028) (xy 363.555015 -266.165716)
			(xy 363.55348 -266.173371) (xy 363.553248 -266.177268) (xy 363.55274 -266.189968) (xy 363.595666 -266.268962)
			(xy 363.601508 -266.27963) (xy 363.606121 -266.287336) (xy 363.619668 -266.299108) (xy 363.636477 -266.3054)
			(xy 363.64545 -266.305792) (xy 364.844076 -266.305792) (xy 364.853052 -266.305421) (xy 364.869864 -266.299129)
			(xy 364.883398 -266.287336) (xy 364.888018 -266.27963) (xy 364.89386 -266.268962) (xy 364.930182 -266.20216)
			(xy 364.932214 -266.197842) (xy 364.934288 -266.192631) (xy 364.936331 -266.181607) (xy 364.936278 -266.175998)
			(xy 364.93577 -266.163298) (xy 364.927896 -266.151106) (xy 364.916427 -266.132546) (xy 364.898296 -266.092862)
			(xy 364.885995 -266.051003) (xy 364.879774 -266.00782) (xy 364.879382 -265.986006) (xy 364.879904 -265.960751)
			(xy 364.888217 -265.910929) (xy 364.904618 -265.863155) (xy 364.928659 -265.818732) (xy 364.959683 -265.778872)
			(xy 364.996845 -265.744662) (xy 365.039131 -265.717036) (xy 365.085387 -265.696746) (xy 365.134352 -265.684346)
			(xy 365.18469 -265.680175) (xy 365.235028 -265.684346) (xy 365.283993 -265.696746) (xy 365.330249 -265.717036)
			(xy 365.372535 -265.744662) (xy 365.409697 -265.778872) (xy 365.440721 -265.818732) (xy 365.464762 -265.863155)
			(xy 365.481163 -265.910929) (xy 365.489476 -265.960751) (xy 365.489998 -265.986006) (xy 365.48935 -266.014358)
			(xy 365.478845 -266.070081) (xy 365.458252 -266.122914) (xy 365.44377 -266.147296) (xy 365.441484 -266.151614)
			(xy 365.43615 -266.162028) (xy 365.43487 -266.165716) (xy 365.433336 -266.173371) (xy 365.433102 -266.177268)
			(xy 365.432594 -266.189968) (xy 365.47552 -266.268962) (xy 365.481362 -266.27963) (xy 365.485973 -266.287341)
			(xy 365.499518 -266.299126) (xy 365.516328 -266.305433) (xy 365.525304 -266.305792) (xy 366.724184 -266.305792)
			(xy 366.733159 -266.30542) (xy 366.749969 -266.299126) (xy 366.763501 -266.287332) (xy 366.768126 -266.27963)
			(xy 366.773968 -266.268962) (xy 366.81029 -266.20216) (xy 366.812322 -266.197842) (xy 366.814396 -266.192631)
			(xy 366.816439 -266.181607) (xy 366.816386 -266.175998) (xy 366.815878 -266.163298) (xy 366.808004 -266.151106)
			(xy 366.796535 -266.132546) (xy 366.778404 -266.092862) (xy 366.766102 -266.051004) (xy 366.75988 -266.00782)
			(xy 366.75949 -265.986006) (xy 366.760012 -265.960751) (xy 366.768325 -265.910929) (xy 366.784726 -265.863155)
			(xy 366.808767 -265.818732) (xy 366.839791 -265.778872) (xy 366.876953 -265.744662) (xy 366.919239 -265.717036)
			(xy 366.965495 -265.696746) (xy 367.01446 -265.684346) (xy 367.064798 -265.680175) (xy 367.115136 -265.684346)
			(xy 367.164101 -265.696746) (xy 367.210357 -265.717036) (xy 367.252643 -265.744662) (xy 367.289805 -265.778872)
			(xy 367.320829 -265.818732) (xy 367.34487 -265.863155) (xy 367.361271 -265.910929) (xy 367.369584 -265.960751)
			(xy 367.370106 -265.986006) (xy 367.369459 -266.014358) (xy 367.358954 -266.070081) (xy 367.33836 -266.122914)
			(xy 367.323878 -266.147296) (xy 367.321592 -266.151614) (xy 367.316258 -266.162028) (xy 367.314978 -266.165716)
			(xy 367.313444 -266.173371) (xy 367.31321 -266.177268) (xy 367.312702 -266.189968) (xy 367.355628 -266.268962)
			(xy 367.36147 -266.27963) (xy 367.366081 -266.28734) (xy 367.379627 -266.299123) (xy 367.396436 -266.305427)
			(xy 367.405412 -266.305792) (xy 368.604292 -266.305792) (xy 368.613266 -266.305419) (xy 368.630074 -266.299123)
			(xy 368.643603 -266.287328) (xy 368.648234 -266.27963) (xy 368.654076 -266.268962) (xy 368.690398 -266.20216)
			(xy 368.69243 -266.197842) (xy 368.694504 -266.192631) (xy 368.696546 -266.181607) (xy 368.696494 -266.175998)
			(xy 368.695986 -266.163298) (xy 368.688112 -266.151106) (xy 368.676643 -266.132546) (xy 368.658511 -266.092863)
			(xy 368.646209 -266.051004) (xy 368.639987 -266.00782) (xy 368.639598 -265.986006) (xy 368.64012 -265.960751)
			(xy 368.648433 -265.910929) (xy 368.664834 -265.863155) (xy 368.688875 -265.818732) (xy 368.719899 -265.778872)
			(xy 368.757061 -265.744662) (xy 368.799347 -265.717036) (xy 368.845603 -265.696746) (xy 368.894568 -265.684346)
			(xy 368.944906 -265.680175) (xy 368.995244 -265.684346) (xy 369.044209 -265.696746) (xy 369.090465 -265.717036)
			(xy 369.132751 -265.744662) (xy 369.169913 -265.778872) (xy 369.200937 -265.818732) (xy 369.224978 -265.863155)
			(xy 369.241379 -265.910929) (xy 369.249692 -265.960751) (xy 369.250214 -265.986006) (xy 369.249567 -266.014358)
			(xy 369.239062 -266.070081) (xy 369.218469 -266.122915) (xy 369.203986 -266.147296) (xy 369.2017 -266.151614)
			(xy 369.196366 -266.162028) (xy 369.195086 -266.165716) (xy 369.193552 -266.173371) (xy 369.193318 -266.177268)
			(xy 369.19281 -266.189968) (xy 369.235736 -266.268962) (xy 369.241578 -266.27963) (xy 369.246189 -266.28734)
			(xy 369.259735 -266.29912) (xy 369.276545 -266.305422) (xy 369.28552 -266.305792) (xy 370.484146 -266.305792)
			(xy 370.493125 -266.305426) (xy 370.509945 -266.29914) (xy 370.523487 -266.287349) (xy 370.528088 -266.27963)
			(xy 370.53393 -266.268962) (xy 370.570252 -266.20216) (xy 370.572284 -266.197842) (xy 370.574356 -266.192631)
			(xy 370.576396 -266.181606) (xy 370.576348 -266.175998) (xy 370.57584 -266.163298) (xy 370.567966 -266.151106)
			(xy 370.556498 -266.132545) (xy 370.538369 -266.092862) (xy 370.526069 -266.051003) (xy 370.519848 -266.00782)
			(xy 370.519452 -265.986006) (xy 370.519974 -265.960751) (xy 370.528287 -265.910929) (xy 370.544688 -265.863155)
			(xy 370.568729 -265.818732) (xy 370.599753 -265.778872) (xy 370.636915 -265.744662) (xy 370.679201 -265.717036)
			(xy 370.725457 -265.696746) (xy 370.774422 -265.684346) (xy 370.82476 -265.680175) (xy 370.875098 -265.684346)
			(xy 370.924063 -265.696746) (xy 370.970319 -265.717036) (xy 371.012605 -265.744662) (xy 371.049767 -265.778872)
			(xy 371.080791 -265.818732) (xy 371.104832 -265.863155) (xy 371.121233 -265.910929) (xy 371.129546 -265.960751)
			(xy 371.130068 -265.986006) (xy 371.12942 -266.014358) (xy 371.118914 -266.07008) (xy 371.098318 -266.122912)
			(xy 371.08384 -266.147296) (xy 371.081554 -266.151614) (xy 371.07622 -266.162028) (xy 371.074941 -266.165716)
			(xy 371.073408 -266.173371) (xy 371.073172 -266.177268) (xy 371.072664 -266.189968) (xy 371.11559 -266.268962)
			(xy 371.121432 -266.27963) (xy 371.126046 -266.287334) (xy 371.139594 -266.299099) (xy 371.156402 -266.305384)
			(xy 371.165374 -266.305792) (xy 372.364254 -266.305792) (xy 372.373232 -266.305425) (xy 372.39005 -266.299137)
			(xy 372.40359 -266.287345) (xy 372.408196 -266.27963) (xy 372.414038 -266.268962) (xy 372.45036 -266.20216)
			(xy 372.452392 -266.197842) (xy 372.454467 -266.192632) (xy 372.456511 -266.181607) (xy 372.456456 -266.175998)
			(xy 372.455948 -266.163298) (xy 372.448074 -266.151106) (xy 372.436606 -266.132545) (xy 372.418476 -266.092862)
			(xy 372.406176 -266.051003) (xy 372.399955 -266.00782) (xy 372.39956 -265.986006) (xy 372.400082 -265.960751)
			(xy 372.408395 -265.910929) (xy 372.424796 -265.863155) (xy 372.448837 -265.818732) (xy 372.479861 -265.778872)
			(xy 372.517023 -265.744662) (xy 372.559309 -265.717036) (xy 372.605565 -265.696746) (xy 372.65453 -265.684346)
			(xy 372.704868 -265.680175) (xy 372.755206 -265.684346) (xy 372.804171 -265.696746) (xy 372.850427 -265.717036)
			(xy 372.892713 -265.744662) (xy 372.929875 -265.778872) (xy 372.960899 -265.818732) (xy 372.98494 -265.863155)
			(xy 373.001341 -265.910929) (xy 373.009654 -265.960751) (xy 373.010176 -265.986006) (xy 374.278918 -265.986006)
			(xy 374.282878 -265.936952) (xy 374.294655 -265.889168) (xy 374.313946 -265.843892) (xy 374.340249 -265.802296)
			(xy 374.372884 -265.765459) (xy 374.411005 -265.734334) (xy 374.453626 -265.709727) (xy 374.499642 -265.692275)
			(xy 374.547861 -265.682431) (xy 374.597036 -265.68045) (xy 374.645891 -265.686382) (xy 374.693162 -265.700074)
			(xy 374.737624 -265.721172) (xy 374.778127 -265.749128) (xy 374.81362 -265.78322) (xy 374.843185 -265.822564)
			(xy 374.866056 -265.866141) (xy 374.88164 -265.912822) (xy 374.889535 -265.961399) (xy 374.89003 -265.986006)
			(xy 376.148595 -265.986006) (xy 376.15269 -265.935278) (xy 376.164869 -265.885864) (xy 376.184817 -265.839044)
			(xy 376.212018 -265.79603) (xy 376.245766 -265.757936) (xy 376.285188 -265.725749) (xy 376.329262 -265.700303)
			(xy 376.376848 -265.682256) (xy 376.426712 -265.672076) (xy 376.477564 -265.670027) (xy 376.528085 -265.676161)
			(xy 376.576969 -265.690321) (xy 376.622948 -265.712138) (xy 376.664832 -265.741048) (xy 376.701536 -265.776303)
			(xy 376.732109 -265.816989) (xy 376.75576 -265.862052) (xy 376.771876 -265.910326) (xy 376.78004 -265.96056)
			(xy 376.780552 -265.986006) (xy 377.09908 -265.986006) (xy 377.10304 -265.936952) (xy 377.114817 -265.889168)
			(xy 377.134108 -265.843892) (xy 377.160411 -265.802296) (xy 377.193046 -265.765459) (xy 377.231167 -265.734334)
			(xy 377.273788 -265.709727) (xy 377.319804 -265.692275) (xy 377.368023 -265.682431) (xy 377.417198 -265.68045)
			(xy 377.466053 -265.686382) (xy 377.513324 -265.700074) (xy 377.557786 -265.721172) (xy 377.598289 -265.749128)
			(xy 377.633782 -265.78322) (xy 377.663347 -265.822564) (xy 377.686218 -265.866141) (xy 377.701802 -265.912822)
			(xy 377.709697 -265.961399) (xy 377.710192 -265.986006) (xy 378.968503 -265.986006) (xy 378.972598 -265.935278)
			(xy 378.984777 -265.885864) (xy 379.004725 -265.839044) (xy 379.031926 -265.79603) (xy 379.065674 -265.757936)
			(xy 379.105096 -265.725749) (xy 379.14917 -265.700303) (xy 379.196756 -265.682256) (xy 379.24662 -265.672076)
			(xy 379.297472 -265.670027) (xy 379.347993 -265.676161) (xy 379.396877 -265.690321) (xy 379.442856 -265.712138)
			(xy 379.48474 -265.741048) (xy 379.521444 -265.776303) (xy 379.552017 -265.816989) (xy 379.575668 -265.862052)
			(xy 379.591784 -265.910326) (xy 379.599948 -265.96056) (xy 379.60046 -265.986006) (xy 379.918988 -265.986006)
			(xy 379.922948 -265.936952) (xy 379.934725 -265.889168) (xy 379.954016 -265.843892) (xy 379.980319 -265.802296)
			(xy 380.012954 -265.765459) (xy 380.051075 -265.734334) (xy 380.093696 -265.709727) (xy 380.139712 -265.692275)
			(xy 380.187931 -265.682431) (xy 380.237106 -265.68045) (xy 380.285961 -265.686382) (xy 380.333232 -265.700074)
			(xy 380.377694 -265.721172) (xy 380.418197 -265.749128) (xy 380.45369 -265.78322) (xy 380.483255 -265.822564)
			(xy 380.506126 -265.866141) (xy 380.52171 -265.912822) (xy 380.529605 -265.961399) (xy 380.5301 -265.986006)
			(xy 380.859042 -265.986006) (xy 380.863002 -265.936952) (xy 380.874779 -265.889168) (xy 380.89407 -265.843892)
			(xy 380.920373 -265.802296) (xy 380.953008 -265.765459) (xy 380.991129 -265.734334) (xy 381.03375 -265.709727)
			(xy 381.079766 -265.692275) (xy 381.127985 -265.682431) (xy 381.17716 -265.68045) (xy 381.226015 -265.686382)
			(xy 381.273286 -265.700074) (xy 381.317748 -265.721172) (xy 381.358251 -265.749128) (xy 381.393744 -265.78322)
			(xy 381.423309 -265.822564) (xy 381.44618 -265.866141) (xy 381.461764 -265.912822) (xy 381.469659 -265.961399)
			(xy 381.470154 -265.986006) (xy 381.799096 -265.986006) (xy 381.803056 -265.936952) (xy 381.814833 -265.889168)
			(xy 381.834124 -265.843892) (xy 381.860427 -265.802296) (xy 381.893062 -265.765459) (xy 381.931183 -265.734334)
			(xy 381.973804 -265.709727) (xy 382.01982 -265.692275) (xy 382.068039 -265.682431) (xy 382.117214 -265.68045)
			(xy 382.166069 -265.686382) (xy 382.21334 -265.700074) (xy 382.257802 -265.721172) (xy 382.298305 -265.749128)
			(xy 382.333798 -265.78322) (xy 382.363363 -265.822564) (xy 382.386234 -265.866141) (xy 382.401818 -265.912822)
			(xy 382.409713 -265.961399) (xy 382.410208 -265.986006) (xy 382.738896 -265.986006) (xy 382.742856 -265.936952)
			(xy 382.754633 -265.889168) (xy 382.773924 -265.843892) (xy 382.800227 -265.802296) (xy 382.832862 -265.765459)
			(xy 382.870983 -265.734334) (xy 382.913604 -265.709727) (xy 382.95962 -265.692275) (xy 383.007839 -265.682431)
			(xy 383.057014 -265.68045) (xy 383.105869 -265.686382) (xy 383.15314 -265.700074) (xy 383.197602 -265.721172)
			(xy 383.238105 -265.749128) (xy 383.273598 -265.78322) (xy 383.303163 -265.822564) (xy 383.326034 -265.866141)
			(xy 383.341618 -265.912822) (xy 383.349513 -265.961399) (xy 383.350008 -265.986006) (xy 383.67895 -265.986006)
			(xy 383.68291 -265.936952) (xy 383.694687 -265.889168) (xy 383.713978 -265.843892) (xy 383.740281 -265.802296)
			(xy 383.772916 -265.765459) (xy 383.811037 -265.734334) (xy 383.853658 -265.709727) (xy 383.899674 -265.692275)
			(xy 383.947893 -265.682431) (xy 383.997068 -265.68045) (xy 384.045923 -265.686382) (xy 384.093194 -265.700074)
			(xy 384.137656 -265.721172) (xy 384.178159 -265.749128) (xy 384.213652 -265.78322) (xy 384.243217 -265.822564)
			(xy 384.266088 -265.866141) (xy 384.281672 -265.912822) (xy 384.289567 -265.961399) (xy 384.290062 -265.986006)
			(xy 385.559058 -265.986006) (xy 385.563018 -265.936952) (xy 385.574795 -265.889168) (xy 385.594086 -265.843892)
			(xy 385.620389 -265.802296) (xy 385.653024 -265.765459) (xy 385.691145 -265.734334) (xy 385.733766 -265.709727)
			(xy 385.779782 -265.692275) (xy 385.828001 -265.682431) (xy 385.877176 -265.68045) (xy 385.926031 -265.686382)
			(xy 385.973302 -265.700074) (xy 386.017764 -265.721172) (xy 386.058267 -265.749128) (xy 386.09376 -265.78322)
			(xy 386.123325 -265.822564) (xy 386.146196 -265.866141) (xy 386.16178 -265.912822) (xy 386.169675 -265.961399)
			(xy 386.17017 -265.986006) (xy 386.499112 -265.986006) (xy 386.503072 -265.936952) (xy 386.514849 -265.889168)
			(xy 386.53414 -265.843892) (xy 386.560443 -265.802296) (xy 386.593078 -265.765459) (xy 386.631199 -265.734334)
			(xy 386.67382 -265.709727) (xy 386.719836 -265.692275) (xy 386.768055 -265.682431) (xy 386.81723 -265.68045)
			(xy 386.866085 -265.686382) (xy 386.913356 -265.700074) (xy 386.957818 -265.721172) (xy 386.998321 -265.749128)
			(xy 387.033814 -265.78322) (xy 387.063379 -265.822564) (xy 387.08625 -265.866141) (xy 387.101834 -265.912822)
			(xy 387.109729 -265.961399) (xy 387.110224 -265.986006) (xy 387.438912 -265.986006) (xy 387.442872 -265.936952)
			(xy 387.454649 -265.889168) (xy 387.47394 -265.843892) (xy 387.500243 -265.802296) (xy 387.532878 -265.765459)
			(xy 387.570999 -265.734334) (xy 387.61362 -265.709727) (xy 387.659636 -265.692275) (xy 387.707855 -265.682431)
			(xy 387.75703 -265.68045) (xy 387.805885 -265.686382) (xy 387.853156 -265.700074) (xy 387.897618 -265.721172)
			(xy 387.938121 -265.749128) (xy 387.973614 -265.78322) (xy 388.003179 -265.822564) (xy 388.02605 -265.866141)
			(xy 388.041634 -265.912822) (xy 388.049529 -265.961399) (xy 388.050024 -265.986006) (xy 388.049529 -266.010613)
			(xy 388.041634 -266.05919) (xy 388.02605 -266.105871) (xy 388.003179 -266.149448) (xy 387.973614 -266.188792)
			(xy 387.938121 -266.222884) (xy 387.897618 -266.25084) (xy 387.853156 -266.271938) (xy 387.805885 -266.28563)
			(xy 387.75703 -266.291562) (xy 387.707855 -266.289581) (xy 387.659636 -266.279737) (xy 387.61362 -266.262285)
			(xy 387.570999 -266.237678) (xy 387.532878 -266.206553) (xy 387.500243 -266.169716) (xy 387.47394 -266.12812)
			(xy 387.454649 -266.082844) (xy 387.442872 -266.03506) (xy 387.438912 -265.986006) (xy 387.110224 -265.986006)
			(xy 387.109729 -266.010613) (xy 387.101834 -266.05919) (xy 387.08625 -266.105871) (xy 387.063379 -266.149448)
			(xy 387.033814 -266.188792) (xy 386.998321 -266.222884) (xy 386.957818 -266.25084) (xy 386.913356 -266.271938)
			(xy 386.866085 -266.28563) (xy 386.81723 -266.291562) (xy 386.768055 -266.289581) (xy 386.719836 -266.279737)
			(xy 386.67382 -266.262285) (xy 386.631199 -266.237678) (xy 386.593078 -266.206553) (xy 386.560443 -266.169716)
			(xy 386.53414 -266.12812) (xy 386.514849 -266.082844) (xy 386.503072 -266.03506) (xy 386.499112 -265.986006)
			(xy 386.17017 -265.986006) (xy 386.169675 -266.010613) (xy 386.16178 -266.05919) (xy 386.146196 -266.105871)
			(xy 386.123325 -266.149448) (xy 386.09376 -266.188792) (xy 386.058267 -266.222884) (xy 386.017764 -266.25084)
			(xy 385.973302 -266.271938) (xy 385.926031 -266.28563) (xy 385.877176 -266.291562) (xy 385.828001 -266.289581)
			(xy 385.779782 -266.279737) (xy 385.733766 -266.262285) (xy 385.691145 -266.237678) (xy 385.653024 -266.206553)
			(xy 385.620389 -266.169716) (xy 385.594086 -266.12812) (xy 385.574795 -266.082844) (xy 385.563018 -266.03506)
			(xy 385.559058 -265.986006) (xy 384.290062 -265.986006) (xy 384.289567 -266.010613) (xy 384.281672 -266.05919)
			(xy 384.266088 -266.105871) (xy 384.243217 -266.149448) (xy 384.213652 -266.188792) (xy 384.178159 -266.222884)
			(xy 384.137656 -266.25084) (xy 384.093194 -266.271938) (xy 384.045923 -266.28563) (xy 383.997068 -266.291562)
			(xy 383.947893 -266.289581) (xy 383.899674 -266.279737) (xy 383.853658 -266.262285) (xy 383.811037 -266.237678)
			(xy 383.772916 -266.206553) (xy 383.740281 -266.169716) (xy 383.713978 -266.12812) (xy 383.694687 -266.082844)
			(xy 383.68291 -266.03506) (xy 383.67895 -265.986006) (xy 383.350008 -265.986006) (xy 383.349513 -266.010613)
			(xy 383.341618 -266.05919) (xy 383.326034 -266.105871) (xy 383.303163 -266.149448) (xy 383.273598 -266.188792)
			(xy 383.238105 -266.222884) (xy 383.197602 -266.25084) (xy 383.15314 -266.271938) (xy 383.105869 -266.28563)
			(xy 383.057014 -266.291562) (xy 383.007839 -266.289581) (xy 382.95962 -266.279737) (xy 382.913604 -266.262285)
			(xy 382.870983 -266.237678) (xy 382.832862 -266.206553) (xy 382.800227 -266.169716) (xy 382.773924 -266.12812)
			(xy 382.754633 -266.082844) (xy 382.742856 -266.03506) (xy 382.738896 -265.986006) (xy 382.410208 -265.986006)
			(xy 382.409713 -266.010613) (xy 382.401818 -266.05919) (xy 382.386234 -266.105871) (xy 382.363363 -266.149448)
			(xy 382.333798 -266.188792) (xy 382.298305 -266.222884) (xy 382.257802 -266.25084) (xy 382.21334 -266.271938)
			(xy 382.166069 -266.28563) (xy 382.117214 -266.291562) (xy 382.068039 -266.289581) (xy 382.01982 -266.279737)
			(xy 381.973804 -266.262285) (xy 381.931183 -266.237678) (xy 381.893062 -266.206553) (xy 381.860427 -266.169716)
			(xy 381.834124 -266.12812) (xy 381.814833 -266.082844) (xy 381.803056 -266.03506) (xy 381.799096 -265.986006)
			(xy 381.470154 -265.986006) (xy 381.469659 -266.010613) (xy 381.461764 -266.05919) (xy 381.44618 -266.105871)
			(xy 381.423309 -266.149448) (xy 381.393744 -266.188792) (xy 381.358251 -266.222884) (xy 381.317748 -266.25084)
			(xy 381.273286 -266.271938) (xy 381.226015 -266.28563) (xy 381.17716 -266.291562) (xy 381.127985 -266.289581)
			(xy 381.079766 -266.279737) (xy 381.03375 -266.262285) (xy 380.991129 -266.237678) (xy 380.953008 -266.206553)
			(xy 380.920373 -266.169716) (xy 380.89407 -266.12812) (xy 380.874779 -266.082844) (xy 380.863002 -266.03506)
			(xy 380.859042 -265.986006) (xy 380.5301 -265.986006) (xy 380.529605 -266.010613) (xy 380.52171 -266.05919)
			(xy 380.506126 -266.105871) (xy 380.483255 -266.149448) (xy 380.45369 -266.188792) (xy 380.418197 -266.222884)
			(xy 380.377694 -266.25084) (xy 380.333232 -266.271938) (xy 380.285961 -266.28563) (xy 380.237106 -266.291562)
			(xy 380.187931 -266.289581) (xy 380.139712 -266.279737) (xy 380.093696 -266.262285) (xy 380.051075 -266.237678)
			(xy 380.012954 -266.206553) (xy 379.980319 -266.169716) (xy 379.954016 -266.12812) (xy 379.934725 -266.082844)
			(xy 379.922948 -266.03506) (xy 379.918988 -265.986006) (xy 379.60046 -265.986006) (xy 379.599948 -266.011452)
			(xy 379.591784 -266.061686) (xy 379.575668 -266.10996) (xy 379.552017 -266.155023) (xy 379.521444 -266.195709)
			(xy 379.48474 -266.230964) (xy 379.442856 -266.259874) (xy 379.396877 -266.281691) (xy 379.347993 -266.295851)
			(xy 379.297472 -266.301985) (xy 379.24662 -266.299936) (xy 379.196756 -266.289756) (xy 379.14917 -266.271709)
			(xy 379.105096 -266.246263) (xy 379.065674 -266.214076) (xy 379.031926 -266.175982) (xy 379.004725 -266.132968)
			(xy 378.984777 -266.086148) (xy 378.972598 -266.036734) (xy 378.968503 -265.986006) (xy 377.710192 -265.986006)
			(xy 377.709697 -266.010613) (xy 377.701802 -266.05919) (xy 377.686218 -266.105871) (xy 377.663347 -266.149448)
			(xy 377.633782 -266.188792) (xy 377.598289 -266.222884) (xy 377.557786 -266.25084) (xy 377.513324 -266.271938)
			(xy 377.466053 -266.28563) (xy 377.417198 -266.291562) (xy 377.368023 -266.289581) (xy 377.319804 -266.279737)
			(xy 377.273788 -266.262285) (xy 377.231167 -266.237678) (xy 377.193046 -266.206553) (xy 377.160411 -266.169716)
			(xy 377.134108 -266.12812) (xy 377.114817 -266.082844) (xy 377.10304 -266.03506) (xy 377.09908 -265.986006)
			(xy 376.780552 -265.986006) (xy 376.78004 -266.011452) (xy 376.771876 -266.061686) (xy 376.75576 -266.10996)
			(xy 376.732109 -266.155023) (xy 376.701536 -266.195709) (xy 376.664832 -266.230964) (xy 376.622948 -266.259874)
			(xy 376.576969 -266.281691) (xy 376.528085 -266.295851) (xy 376.477564 -266.301985) (xy 376.426712 -266.299936)
			(xy 376.376848 -266.289756) (xy 376.329262 -266.271709) (xy 376.285188 -266.246263) (xy 376.245766 -266.214076)
			(xy 376.212018 -266.175982) (xy 376.184817 -266.132968) (xy 376.164869 -266.086148) (xy 376.15269 -266.036734)
			(xy 376.148595 -265.986006) (xy 374.89003 -265.986006) (xy 374.889535 -266.010613) (xy 374.88164 -266.05919)
			(xy 374.866056 -266.105871) (xy 374.843185 -266.149448) (xy 374.81362 -266.188792) (xy 374.778127 -266.222884)
			(xy 374.737624 -266.25084) (xy 374.693162 -266.271938) (xy 374.645891 -266.28563) (xy 374.597036 -266.291562)
			(xy 374.547861 -266.289581) (xy 374.499642 -266.279737) (xy 374.453626 -266.262285) (xy 374.411005 -266.237678)
			(xy 374.372884 -266.206553) (xy 374.340249 -266.169716) (xy 374.313946 -266.12812) (xy 374.294655 -266.082844)
			(xy 374.282878 -266.03506) (xy 374.278918 -265.986006) (xy 373.010176 -265.986006) (xy 373.009528 -266.014358)
			(xy 372.999022 -266.07008) (xy 372.978427 -266.122912) (xy 372.963948 -266.147296) (xy 372.961662 -266.151614)
			(xy 372.956328 -266.162028) (xy 372.955049 -266.165716) (xy 372.953516 -266.173371) (xy 372.95328 -266.177268)
			(xy 372.952772 -266.189968) (xy 372.995698 -266.268962) (xy 373.00154 -266.27963) (xy 373.00615 -266.287344)
			(xy 373.019694 -266.299134) (xy 373.036504 -266.305448) (xy 373.045482 -266.305792) (xy 373.396764 -266.305792)
			(xy 373.406602 -266.306326) (xy 373.424766 -266.313911) (xy 373.43207 -266.320524) (xy 373.726456 -266.61491)
			(xy 373.733985 -266.621745) (xy 373.752866 -266.629239) (xy 373.763032 -266.629388) (xy 373.838978 -266.62507)
			(xy 373.844464 -266.624669) (xy 373.855092 -266.621844) (xy 373.86006 -266.619482) (xy 373.86895 -266.614656)
			(xy 373.874538 -266.607798) (xy 373.875554 -266.606274) (xy 373.89013 -266.588583) (xy 373.923679 -266.557351)
			(xy 373.961517 -266.531479) (xy 374.002793 -266.511546) (xy 374.046582 -266.498) (xy 374.091904 -266.491145)
			(xy 374.114822 -266.490704) (xy 374.138812 -266.491176) (xy 374.1862 -266.498685) (xy 374.23183 -266.513515)
			(xy 374.274579 -266.5353) (xy 374.313394 -266.563504) (xy 374.347319 -266.597432) (xy 374.375518 -266.63625)
			(xy 374.397298 -266.679001) (xy 374.412123 -266.724633) (xy 374.419626 -266.772022) (xy 374.42013 -266.796012)
			(xy 374.749072 -266.796012) (xy 374.753032 -266.746958) (xy 374.764809 -266.699174) (xy 374.7841 -266.653898)
			(xy 374.810403 -266.612302) (xy 374.843038 -266.575465) (xy 374.881159 -266.54434) (xy 374.92378 -266.519733)
			(xy 374.969796 -266.502281) (xy 375.018015 -266.492437) (xy 375.06719 -266.490456) (xy 375.116045 -266.496388)
			(xy 375.163316 -266.51008) (xy 375.207778 -266.531178) (xy 375.248281 -266.559134) (xy 375.283774 -266.593226)
			(xy 375.313339 -266.63257) (xy 375.33621 -266.676147) (xy 375.351794 -266.722828) (xy 375.359689 -266.771405)
			(xy 375.360184 -266.796012) (xy 375.678695 -266.796012) (xy 375.68279 -266.745284) (xy 375.694969 -266.69587)
			(xy 375.714917 -266.64905) (xy 375.742118 -266.606036) (xy 375.775866 -266.567942) (xy 375.815288 -266.535755)
			(xy 375.859362 -266.510309) (xy 375.906948 -266.492262) (xy 375.956812 -266.482082) (xy 376.007664 -266.480033)
			(xy 376.058185 -266.486167) (xy 376.107069 -266.500327) (xy 376.153048 -266.522144) (xy 376.194932 -266.551054)
			(xy 376.231636 -266.586309) (xy 376.262209 -266.626995) (xy 376.28586 -266.672058) (xy 376.301976 -266.720332)
			(xy 376.31014 -266.770566) (xy 376.310652 -266.796012) (xy 376.628926 -266.796012) (xy 376.632886 -266.746958)
			(xy 376.644663 -266.699174) (xy 376.663954 -266.653898) (xy 376.690257 -266.612302) (xy 376.722892 -266.575465)
			(xy 376.761013 -266.54434) (xy 376.803634 -266.519733) (xy 376.84965 -266.502281) (xy 376.897869 -266.492437)
			(xy 376.947044 -266.490456) (xy 376.995899 -266.496388) (xy 377.04317 -266.51008) (xy 377.087632 -266.531178)
			(xy 377.128135 -266.559134) (xy 377.163628 -266.593226) (xy 377.193193 -266.63257) (xy 377.216064 -266.676147)
			(xy 377.231648 -266.722828) (xy 377.239543 -266.771405) (xy 377.240038 -266.796012) (xy 377.558549 -266.796012)
			(xy 377.562644 -266.745284) (xy 377.574823 -266.69587) (xy 377.594771 -266.64905) (xy 377.621972 -266.606036)
			(xy 377.65572 -266.567942) (xy 377.695142 -266.535755) (xy 377.739216 -266.510309) (xy 377.786802 -266.492262)
			(xy 377.836666 -266.482082) (xy 377.887518 -266.480033) (xy 377.938039 -266.486167) (xy 377.986923 -266.500327)
			(xy 378.032902 -266.522144) (xy 378.074786 -266.551054) (xy 378.11149 -266.586309) (xy 378.142063 -266.626995)
			(xy 378.165714 -266.672058) (xy 378.18183 -266.720332) (xy 378.189994 -266.770566) (xy 378.190506 -266.796012)
			(xy 378.509034 -266.796012) (xy 378.512994 -266.746958) (xy 378.524771 -266.699174) (xy 378.544062 -266.653898)
			(xy 378.570365 -266.612302) (xy 378.603 -266.575465) (xy 378.641121 -266.54434) (xy 378.683742 -266.519733)
			(xy 378.729758 -266.502281) (xy 378.777977 -266.492437) (xy 378.827152 -266.490456) (xy 378.876007 -266.496388)
			(xy 378.923278 -266.51008) (xy 378.96774 -266.531178) (xy 379.008243 -266.559134) (xy 379.043736 -266.593226)
			(xy 379.073301 -266.63257) (xy 379.096172 -266.676147) (xy 379.111756 -266.722828) (xy 379.119651 -266.771405)
			(xy 379.120146 -266.796012) (xy 379.438657 -266.796012) (xy 379.442752 -266.745284) (xy 379.454931 -266.69587)
			(xy 379.474879 -266.64905) (xy 379.50208 -266.606036) (xy 379.535828 -266.567942) (xy 379.57525 -266.535755)
			(xy 379.619324 -266.510309) (xy 379.66691 -266.492262) (xy 379.716774 -266.482082) (xy 379.767626 -266.480033)
			(xy 379.818147 -266.486167) (xy 379.867031 -266.500327) (xy 379.91301 -266.522144) (xy 379.954894 -266.551054)
			(xy 379.991598 -266.586309) (xy 380.022171 -266.626995) (xy 380.045822 -266.672058) (xy 380.061938 -266.720332)
			(xy 380.070102 -266.770566) (xy 380.070614 -266.796012) (xy 380.378711 -266.796012) (xy 380.382806 -266.745284)
			(xy 380.394985 -266.69587) (xy 380.414933 -266.64905) (xy 380.442134 -266.606036) (xy 380.475882 -266.567942)
			(xy 380.515304 -266.535755) (xy 380.559378 -266.510309) (xy 380.606964 -266.492262) (xy 380.656828 -266.482082)
			(xy 380.70768 -266.480033) (xy 380.758201 -266.486167) (xy 380.807085 -266.500327) (xy 380.853064 -266.522144)
			(xy 380.894948 -266.551054) (xy 380.931652 -266.586309) (xy 380.962225 -266.626995) (xy 380.985876 -266.672058)
			(xy 381.001992 -266.720332) (xy 381.010156 -266.770566) (xy 381.010668 -266.796012) (xy 381.328942 -266.796012)
			(xy 381.332902 -266.746958) (xy 381.344679 -266.699174) (xy 381.36397 -266.653898) (xy 381.390273 -266.612302)
			(xy 381.422908 -266.575465) (xy 381.461029 -266.54434) (xy 381.50365 -266.519733) (xy 381.549666 -266.502281)
			(xy 381.597885 -266.492437) (xy 381.64706 -266.490456) (xy 381.695915 -266.496388) (xy 381.743186 -266.51008)
			(xy 381.787648 -266.531178) (xy 381.828151 -266.559134) (xy 381.863644 -266.593226) (xy 381.893209 -266.63257)
			(xy 381.91608 -266.676147) (xy 381.931664 -266.722828) (xy 381.939559 -266.771405) (xy 381.940054 -266.796012)
			(xy 382.268996 -266.796012) (xy 382.272956 -266.746958) (xy 382.284733 -266.699174) (xy 382.304024 -266.653898)
			(xy 382.330327 -266.612302) (xy 382.362962 -266.575465) (xy 382.401083 -266.54434) (xy 382.443704 -266.519733)
			(xy 382.48972 -266.502281) (xy 382.537939 -266.492437) (xy 382.587114 -266.490456) (xy 382.635969 -266.496388)
			(xy 382.68324 -266.51008) (xy 382.727702 -266.531178) (xy 382.768205 -266.559134) (xy 382.803698 -266.593226)
			(xy 382.833263 -266.63257) (xy 382.856134 -266.676147) (xy 382.871718 -266.722828) (xy 382.879613 -266.771405)
			(xy 382.880108 -266.796012) (xy 383.20905 -266.796012) (xy 383.21301 -266.746958) (xy 383.224787 -266.699174)
			(xy 383.244078 -266.653898) (xy 383.270381 -266.612302) (xy 383.303016 -266.575465) (xy 383.341137 -266.54434)
			(xy 383.383758 -266.519733) (xy 383.429774 -266.502281) (xy 383.477993 -266.492437) (xy 383.527168 -266.490456)
			(xy 383.576023 -266.496388) (xy 383.623294 -266.51008) (xy 383.667756 -266.531178) (xy 383.708259 -266.559134)
			(xy 383.743752 -266.593226) (xy 383.773317 -266.63257) (xy 383.796188 -266.676147) (xy 383.811772 -266.722828)
			(xy 383.819667 -266.771405) (xy 383.820162 -266.796012) (xy 384.149104 -266.796012) (xy 384.153064 -266.746958)
			(xy 384.164841 -266.699174) (xy 384.184132 -266.653898) (xy 384.210435 -266.612302) (xy 384.24307 -266.575465)
			(xy 384.281191 -266.54434) (xy 384.323812 -266.519733) (xy 384.369828 -266.502281) (xy 384.418047 -266.492437)
			(xy 384.467222 -266.490456) (xy 384.516077 -266.496388) (xy 384.563348 -266.51008) (xy 384.60781 -266.531178)
			(xy 384.648313 -266.559134) (xy 384.683806 -266.593226) (xy 384.713371 -266.63257) (xy 384.736242 -266.676147)
			(xy 384.751826 -266.722828) (xy 384.759721 -266.771405) (xy 384.760216 -266.796012) (xy 385.088904 -266.796012)
			(xy 385.092864 -266.746958) (xy 385.104641 -266.699174) (xy 385.123932 -266.653898) (xy 385.150235 -266.612302)
			(xy 385.18287 -266.575465) (xy 385.220991 -266.54434) (xy 385.263612 -266.519733) (xy 385.309628 -266.502281)
			(xy 385.357847 -266.492437) (xy 385.407022 -266.490456) (xy 385.455877 -266.496388) (xy 385.503148 -266.51008)
			(xy 385.54761 -266.531178) (xy 385.588113 -266.559134) (xy 385.623606 -266.593226) (xy 385.653171 -266.63257)
			(xy 385.676042 -266.676147) (xy 385.691626 -266.722828) (xy 385.699521 -266.771405) (xy 385.700016 -266.796012)
			(xy 386.028958 -266.796012) (xy 386.032918 -266.746958) (xy 386.044695 -266.699174) (xy 386.063986 -266.653898)
			(xy 386.090289 -266.612302) (xy 386.122924 -266.575465) (xy 386.161045 -266.54434) (xy 386.203666 -266.519733)
			(xy 386.249682 -266.502281) (xy 386.297901 -266.492437) (xy 386.347076 -266.490456) (xy 386.395931 -266.496388)
			(xy 386.443202 -266.51008) (xy 386.487664 -266.531178) (xy 386.528167 -266.559134) (xy 386.56366 -266.593226)
			(xy 386.593225 -266.63257) (xy 386.616096 -266.676147) (xy 386.63168 -266.722828) (xy 386.639575 -266.771405)
			(xy 386.64007 -266.796012) (xy 386.969012 -266.796012) (xy 386.972972 -266.746958) (xy 386.984749 -266.699174)
			(xy 387.00404 -266.653898) (xy 387.030343 -266.612302) (xy 387.062978 -266.575465) (xy 387.101099 -266.54434)
			(xy 387.14372 -266.519733) (xy 387.189736 -266.502281) (xy 387.237955 -266.492437) (xy 387.28713 -266.490456)
			(xy 387.335985 -266.496388) (xy 387.383256 -266.51008) (xy 387.427718 -266.531178) (xy 387.468221 -266.559134)
			(xy 387.503714 -266.593226) (xy 387.533279 -266.63257) (xy 387.55615 -266.676147) (xy 387.571734 -266.722828)
			(xy 387.579629 -266.771405) (xy 387.580124 -266.796012) (xy 387.579629 -266.820619) (xy 387.571734 -266.869196)
			(xy 387.55615 -266.915877) (xy 387.533279 -266.959454) (xy 387.503714 -266.998798) (xy 387.468221 -267.03289)
			(xy 387.427718 -267.060846) (xy 387.383256 -267.081944) (xy 387.335985 -267.095636) (xy 387.28713 -267.101568)
			(xy 387.237955 -267.099587) (xy 387.189736 -267.089743) (xy 387.14372 -267.072291) (xy 387.101099 -267.047684)
			(xy 387.062978 -267.016559) (xy 387.030343 -266.979722) (xy 387.00404 -266.938126) (xy 386.984749 -266.89285)
			(xy 386.972972 -266.845066) (xy 386.969012 -266.796012) (xy 386.64007 -266.796012) (xy 386.639575 -266.820619)
			(xy 386.63168 -266.869196) (xy 386.616096 -266.915877) (xy 386.593225 -266.959454) (xy 386.56366 -266.998798)
			(xy 386.528167 -267.03289) (xy 386.487664 -267.060846) (xy 386.443202 -267.081944) (xy 386.395931 -267.095636)
			(xy 386.347076 -267.101568) (xy 386.297901 -267.099587) (xy 386.249682 -267.089743) (xy 386.203666 -267.072291)
			(xy 386.161045 -267.047684) (xy 386.122924 -267.016559) (xy 386.090289 -266.979722) (xy 386.063986 -266.938126)
			(xy 386.044695 -266.89285) (xy 386.032918 -266.845066) (xy 386.028958 -266.796012) (xy 385.700016 -266.796012)
			(xy 385.699521 -266.820619) (xy 385.691626 -266.869196) (xy 385.676042 -266.915877) (xy 385.653171 -266.959454)
			(xy 385.623606 -266.998798) (xy 385.588113 -267.03289) (xy 385.54761 -267.060846) (xy 385.503148 -267.081944)
			(xy 385.455877 -267.095636) (xy 385.407022 -267.101568) (xy 385.357847 -267.099587) (xy 385.309628 -267.089743)
			(xy 385.263612 -267.072291) (xy 385.220991 -267.047684) (xy 385.18287 -267.016559) (xy 385.150235 -266.979722)
			(xy 385.123932 -266.938126) (xy 385.104641 -266.89285) (xy 385.092864 -266.845066) (xy 385.088904 -266.796012)
			(xy 384.760216 -266.796012) (xy 384.759721 -266.820619) (xy 384.751826 -266.869196) (xy 384.736242 -266.915877)
			(xy 384.713371 -266.959454) (xy 384.683806 -266.998798) (xy 384.648313 -267.03289) (xy 384.60781 -267.060846)
			(xy 384.563348 -267.081944) (xy 384.516077 -267.095636) (xy 384.467222 -267.101568) (xy 384.418047 -267.099587)
			(xy 384.369828 -267.089743) (xy 384.323812 -267.072291) (xy 384.281191 -267.047684) (xy 384.24307 -267.016559)
			(xy 384.210435 -266.979722) (xy 384.184132 -266.938126) (xy 384.164841 -266.89285) (xy 384.153064 -266.845066)
			(xy 384.149104 -266.796012) (xy 383.820162 -266.796012) (xy 383.819667 -266.820619) (xy 383.811772 -266.869196)
			(xy 383.796188 -266.915877) (xy 383.773317 -266.959454) (xy 383.743752 -266.998798) (xy 383.708259 -267.03289)
			(xy 383.667756 -267.060846) (xy 383.623294 -267.081944) (xy 383.576023 -267.095636) (xy 383.527168 -267.101568)
			(xy 383.477993 -267.099587) (xy 383.429774 -267.089743) (xy 383.383758 -267.072291) (xy 383.341137 -267.047684)
			(xy 383.303016 -267.016559) (xy 383.270381 -266.979722) (xy 383.244078 -266.938126) (xy 383.224787 -266.89285)
			(xy 383.21301 -266.845066) (xy 383.20905 -266.796012) (xy 382.880108 -266.796012) (xy 382.879613 -266.820619)
			(xy 382.871718 -266.869196) (xy 382.856134 -266.915877) (xy 382.833263 -266.959454) (xy 382.803698 -266.998798)
			(xy 382.768205 -267.03289) (xy 382.727702 -267.060846) (xy 382.68324 -267.081944) (xy 382.635969 -267.095636)
			(xy 382.587114 -267.101568) (xy 382.537939 -267.099587) (xy 382.48972 -267.089743) (xy 382.443704 -267.072291)
			(xy 382.401083 -267.047684) (xy 382.362962 -267.016559) (xy 382.330327 -266.979722) (xy 382.304024 -266.938126)
			(xy 382.284733 -266.89285) (xy 382.272956 -266.845066) (xy 382.268996 -266.796012) (xy 381.940054 -266.796012)
			(xy 381.939559 -266.820619) (xy 381.931664 -266.869196) (xy 381.91608 -266.915877) (xy 381.893209 -266.959454)
			(xy 381.863644 -266.998798) (xy 381.828151 -267.03289) (xy 381.787648 -267.060846) (xy 381.743186 -267.081944)
			(xy 381.695915 -267.095636) (xy 381.64706 -267.101568) (xy 381.597885 -267.099587) (xy 381.549666 -267.089743)
			(xy 381.50365 -267.072291) (xy 381.461029 -267.047684) (xy 381.422908 -267.016559) (xy 381.390273 -266.979722)
			(xy 381.36397 -266.938126) (xy 381.344679 -266.89285) (xy 381.332902 -266.845066) (xy 381.328942 -266.796012)
			(xy 381.010668 -266.796012) (xy 381.010156 -266.821458) (xy 381.001992 -266.871692) (xy 380.985876 -266.919966)
			(xy 380.962225 -266.965029) (xy 380.931652 -267.005715) (xy 380.894948 -267.04097) (xy 380.853064 -267.06988)
			(xy 380.807085 -267.091697) (xy 380.758201 -267.105857) (xy 380.70768 -267.111991) (xy 380.656828 -267.109942)
			(xy 380.606964 -267.099762) (xy 380.559378 -267.081715) (xy 380.515304 -267.056269) (xy 380.475882 -267.024082)
			(xy 380.442134 -266.985988) (xy 380.414933 -266.942974) (xy 380.394985 -266.896154) (xy 380.382806 -266.84674)
			(xy 380.378711 -266.796012) (xy 380.070614 -266.796012) (xy 380.070102 -266.821458) (xy 380.061938 -266.871692)
			(xy 380.045822 -266.919966) (xy 380.022171 -266.965029) (xy 379.991598 -267.005715) (xy 379.954894 -267.04097)
			(xy 379.91301 -267.06988) (xy 379.867031 -267.091697) (xy 379.818147 -267.105857) (xy 379.767626 -267.111991)
			(xy 379.716774 -267.109942) (xy 379.66691 -267.099762) (xy 379.619324 -267.081715) (xy 379.57525 -267.056269)
			(xy 379.535828 -267.024082) (xy 379.50208 -266.985988) (xy 379.474879 -266.942974) (xy 379.454931 -266.896154)
			(xy 379.442752 -266.84674) (xy 379.438657 -266.796012) (xy 379.120146 -266.796012) (xy 379.119651 -266.820619)
			(xy 379.111756 -266.869196) (xy 379.096172 -266.915877) (xy 379.073301 -266.959454) (xy 379.043736 -266.998798)
			(xy 379.008243 -267.03289) (xy 378.96774 -267.060846) (xy 378.923278 -267.081944) (xy 378.876007 -267.095636)
			(xy 378.827152 -267.101568) (xy 378.777977 -267.099587) (xy 378.729758 -267.089743) (xy 378.683742 -267.072291)
			(xy 378.641121 -267.047684) (xy 378.603 -267.016559) (xy 378.570365 -266.979722) (xy 378.544062 -266.938126)
			(xy 378.524771 -266.89285) (xy 378.512994 -266.845066) (xy 378.509034 -266.796012) (xy 378.190506 -266.796012)
			(xy 378.189994 -266.821458) (xy 378.18183 -266.871692) (xy 378.165714 -266.919966) (xy 378.142063 -266.965029)
			(xy 378.11149 -267.005715) (xy 378.074786 -267.04097) (xy 378.032902 -267.06988) (xy 377.986923 -267.091697)
			(xy 377.938039 -267.105857) (xy 377.887518 -267.111991) (xy 377.836666 -267.109942) (xy 377.786802 -267.099762)
			(xy 377.739216 -267.081715) (xy 377.695142 -267.056269) (xy 377.65572 -267.024082) (xy 377.621972 -266.985988)
			(xy 377.594771 -266.942974) (xy 377.574823 -266.896154) (xy 377.562644 -266.84674) (xy 377.558549 -266.796012)
			(xy 377.240038 -266.796012) (xy 377.239543 -266.820619) (xy 377.231648 -266.869196) (xy 377.216064 -266.915877)
			(xy 377.193193 -266.959454) (xy 377.163628 -266.998798) (xy 377.128135 -267.03289) (xy 377.087632 -267.060846)
			(xy 377.04317 -267.081944) (xy 376.995899 -267.095636) (xy 376.947044 -267.101568) (xy 376.897869 -267.099587)
			(xy 376.84965 -267.089743) (xy 376.803634 -267.072291) (xy 376.761013 -267.047684) (xy 376.722892 -267.016559)
			(xy 376.690257 -266.979722) (xy 376.663954 -266.938126) (xy 376.644663 -266.89285) (xy 376.632886 -266.845066)
			(xy 376.628926 -266.796012) (xy 376.310652 -266.796012) (xy 376.31014 -266.821458) (xy 376.301976 -266.871692)
			(xy 376.28586 -266.919966) (xy 376.262209 -266.965029) (xy 376.231636 -267.005715) (xy 376.194932 -267.04097)
			(xy 376.153048 -267.06988) (xy 376.107069 -267.091697) (xy 376.058185 -267.105857) (xy 376.007664 -267.111991)
			(xy 375.956812 -267.109942) (xy 375.906948 -267.099762) (xy 375.859362 -267.081715) (xy 375.815288 -267.056269)
			(xy 375.775866 -267.024082) (xy 375.742118 -266.985988) (xy 375.714917 -266.942974) (xy 375.694969 -266.896154)
			(xy 375.68279 -266.84674) (xy 375.678695 -266.796012) (xy 375.360184 -266.796012) (xy 375.359689 -266.820619)
			(xy 375.351794 -266.869196) (xy 375.33621 -266.915877) (xy 375.313339 -266.959454) (xy 375.283774 -266.998798)
			(xy 375.248281 -267.03289) (xy 375.207778 -267.060846) (xy 375.163316 -267.081944) (xy 375.116045 -267.095636)
			(xy 375.06719 -267.101568) (xy 375.018015 -267.099587) (xy 374.969796 -267.089743) (xy 374.92378 -267.072291)
			(xy 374.881159 -267.047684) (xy 374.843038 -267.016559) (xy 374.810403 -266.979722) (xy 374.7841 -266.938126)
			(xy 374.764809 -266.89285) (xy 374.753032 -266.845066) (xy 374.749072 -266.796012) (xy 374.42013 -266.796012)
			(xy 374.419726 -266.818935) (xy 374.412887 -266.864268) (xy 374.399349 -266.90807) (xy 374.379417 -266.949356)
			(xy 374.353538 -266.987199) (xy 374.322293 -267.02075) (xy 374.30456 -267.03528) (xy 374.303036 -267.036296)
			(xy 374.296178 -267.041884) (xy 374.291352 -267.050774) (xy 374.288945 -267.055725) (xy 374.286127 -267.066363)
			(xy 374.285764 -267.071856) (xy 374.281446 -267.147802) (xy 374.281663 -267.157956) (xy 374.289139 -267.17682)
			(xy 374.295924 -267.184378) (xy 374.4214 -267.309854) (xy 374.42677 -267.314855) (xy 374.43967 -267.321839)
			(xy 374.4468 -267.32357) (xy 374.46077 -267.326618) (xy 374.465596 -267.32484) (xy 374.475248 -267.32103)
			(xy 374.501623 -267.31157) (xy 374.556709 -267.301351) (xy 374.584722 -267.30071) (xy 374.608712 -267.301182)
			(xy 374.6561 -267.308691) (xy 374.701729 -267.323521) (xy 374.744478 -267.345306) (xy 374.783292 -267.37351)
			(xy 374.817216 -267.407439) (xy 374.845415 -267.446256) (xy 374.867195 -267.489008) (xy 374.882018 -267.534639)
			(xy 374.889521 -267.582028) (xy 374.89003 -267.606018) (xy 376.159026 -267.606018) (xy 376.162986 -267.556964)
			(xy 376.174763 -267.50918) (xy 376.194054 -267.463904) (xy 376.220357 -267.422308) (xy 376.252992 -267.385471)
			(xy 376.291113 -267.354346) (xy 376.333734 -267.329739) (xy 376.37975 -267.312287) (xy 376.427969 -267.302443)
			(xy 376.477144 -267.300462) (xy 376.525999 -267.306394) (xy 376.57327 -267.320086) (xy 376.617732 -267.341184)
			(xy 376.658235 -267.36914) (xy 376.693728 -267.403232) (xy 376.723293 -267.442576) (xy 376.746164 -267.486153)
			(xy 376.761748 -267.532834) (xy 376.769643 -267.581411) (xy 376.770138 -267.606018) (xy 377.088649 -267.606018)
			(xy 377.092744 -267.55529) (xy 377.104923 -267.505876) (xy 377.124871 -267.459056) (xy 377.152072 -267.416042)
			(xy 377.18582 -267.377948) (xy 377.225242 -267.345761) (xy 377.269316 -267.320315) (xy 377.316902 -267.302268)
			(xy 377.366766 -267.292088) (xy 377.417618 -267.290039) (xy 377.468139 -267.296173) (xy 377.517023 -267.310333)
			(xy 377.563002 -267.33215) (xy 377.604886 -267.36106) (xy 377.64159 -267.396315) (xy 377.672163 -267.437001)
			(xy 377.695814 -267.482064) (xy 377.71193 -267.530338) (xy 377.720094 -267.580572) (xy 377.720606 -267.606018)
			(xy 378.039134 -267.606018) (xy 378.043094 -267.556964) (xy 378.054871 -267.50918) (xy 378.074162 -267.463904)
			(xy 378.100465 -267.422308) (xy 378.1331 -267.385471) (xy 378.171221 -267.354346) (xy 378.213842 -267.329739)
			(xy 378.259858 -267.312287) (xy 378.308077 -267.302443) (xy 378.357252 -267.300462) (xy 378.406107 -267.306394)
			(xy 378.453378 -267.320086) (xy 378.49784 -267.341184) (xy 378.538343 -267.36914) (xy 378.573836 -267.403232)
			(xy 378.603401 -267.442576) (xy 378.626272 -267.486153) (xy 378.641856 -267.532834) (xy 378.649751 -267.581411)
			(xy 378.650246 -267.606018) (xy 378.978934 -267.606018) (xy 378.982894 -267.556964) (xy 378.994671 -267.50918)
			(xy 379.013962 -267.463904) (xy 379.040265 -267.422308) (xy 379.0729 -267.385471) (xy 379.111021 -267.354346)
			(xy 379.153642 -267.329739) (xy 379.199658 -267.312287) (xy 379.247877 -267.302443) (xy 379.297052 -267.300462)
			(xy 379.345907 -267.306394) (xy 379.393178 -267.320086) (xy 379.43764 -267.341184) (xy 379.478143 -267.36914)
			(xy 379.513636 -267.403232) (xy 379.543201 -267.442576) (xy 379.566072 -267.486153) (xy 379.581656 -267.532834)
			(xy 379.589551 -267.581411) (xy 379.590046 -267.606018) (xy 379.918988 -267.606018) (xy 379.922948 -267.556964)
			(xy 379.934725 -267.50918) (xy 379.954016 -267.463904) (xy 379.980319 -267.422308) (xy 380.012954 -267.385471)
			(xy 380.051075 -267.354346) (xy 380.093696 -267.329739) (xy 380.139712 -267.312287) (xy 380.187931 -267.302443)
			(xy 380.237106 -267.300462) (xy 380.285961 -267.306394) (xy 380.333232 -267.320086) (xy 380.377694 -267.341184)
			(xy 380.418197 -267.36914) (xy 380.45369 -267.403232) (xy 380.483255 -267.442576) (xy 380.506126 -267.486153)
			(xy 380.52171 -267.532834) (xy 380.529605 -267.581411) (xy 380.5301 -267.606018) (xy 380.848611 -267.606018)
			(xy 380.852706 -267.55529) (xy 380.864885 -267.505876) (xy 380.884833 -267.459056) (xy 380.912034 -267.416042)
			(xy 380.945782 -267.377948) (xy 380.985204 -267.345761) (xy 381.029278 -267.320315) (xy 381.076864 -267.302268)
			(xy 381.126728 -267.292088) (xy 381.17758 -267.290039) (xy 381.228101 -267.296173) (xy 381.276985 -267.310333)
			(xy 381.322964 -267.33215) (xy 381.364848 -267.36106) (xy 381.401552 -267.396315) (xy 381.432125 -267.437001)
			(xy 381.455776 -267.482064) (xy 381.471892 -267.530338) (xy 381.480056 -267.580572) (xy 381.480568 -267.606018)
			(xy 381.799096 -267.606018) (xy 381.803056 -267.556964) (xy 381.814833 -267.50918) (xy 381.834124 -267.463904)
			(xy 381.860427 -267.422308) (xy 381.893062 -267.385471) (xy 381.931183 -267.354346) (xy 381.973804 -267.329739)
			(xy 382.01982 -267.312287) (xy 382.068039 -267.302443) (xy 382.117214 -267.300462) (xy 382.166069 -267.306394)
			(xy 382.21334 -267.320086) (xy 382.257802 -267.341184) (xy 382.298305 -267.36914) (xy 382.333798 -267.403232)
			(xy 382.363363 -267.442576) (xy 382.386234 -267.486153) (xy 382.401818 -267.532834) (xy 382.409713 -267.581411)
			(xy 382.410208 -267.606018) (xy 382.738896 -267.606018) (xy 382.742856 -267.556964) (xy 382.754633 -267.50918)
			(xy 382.773924 -267.463904) (xy 382.800227 -267.422308) (xy 382.832862 -267.385471) (xy 382.870983 -267.354346)
			(xy 382.913604 -267.329739) (xy 382.95962 -267.312287) (xy 383.007839 -267.302443) (xy 383.057014 -267.300462)
			(xy 383.105869 -267.306394) (xy 383.15314 -267.320086) (xy 383.197602 -267.341184) (xy 383.238105 -267.36914)
			(xy 383.273598 -267.403232) (xy 383.303163 -267.442576) (xy 383.326034 -267.486153) (xy 383.341618 -267.532834)
			(xy 383.349513 -267.581411) (xy 383.350008 -267.606018) (xy 383.67895 -267.606018) (xy 383.68291 -267.556964)
			(xy 383.694687 -267.50918) (xy 383.713978 -267.463904) (xy 383.740281 -267.422308) (xy 383.772916 -267.385471)
			(xy 383.811037 -267.354346) (xy 383.853658 -267.329739) (xy 383.899674 -267.312287) (xy 383.947893 -267.302443)
			(xy 383.997068 -267.300462) (xy 384.045923 -267.306394) (xy 384.093194 -267.320086) (xy 384.137656 -267.341184)
			(xy 384.178159 -267.36914) (xy 384.213652 -267.403232) (xy 384.243217 -267.442576) (xy 384.266088 -267.486153)
			(xy 384.281672 -267.532834) (xy 384.289567 -267.581411) (xy 384.290062 -267.606018) (xy 384.619004 -267.606018)
			(xy 384.622964 -267.556964) (xy 384.634741 -267.50918) (xy 384.654032 -267.463904) (xy 384.680335 -267.422308)
			(xy 384.71297 -267.385471) (xy 384.751091 -267.354346) (xy 384.793712 -267.329739) (xy 384.839728 -267.312287)
			(xy 384.887947 -267.302443) (xy 384.937122 -267.300462) (xy 384.985977 -267.306394) (xy 385.033248 -267.320086)
			(xy 385.07771 -267.341184) (xy 385.118213 -267.36914) (xy 385.153706 -267.403232) (xy 385.183271 -267.442576)
			(xy 385.206142 -267.486153) (xy 385.221726 -267.532834) (xy 385.229621 -267.581411) (xy 385.230116 -267.606018)
			(xy 385.559058 -267.606018) (xy 385.563018 -267.556964) (xy 385.574795 -267.50918) (xy 385.594086 -267.463904)
			(xy 385.620389 -267.422308) (xy 385.653024 -267.385471) (xy 385.691145 -267.354346) (xy 385.733766 -267.329739)
			(xy 385.779782 -267.312287) (xy 385.828001 -267.302443) (xy 385.877176 -267.300462) (xy 385.926031 -267.306394)
			(xy 385.973302 -267.320086) (xy 386.017764 -267.341184) (xy 386.058267 -267.36914) (xy 386.09376 -267.403232)
			(xy 386.123325 -267.442576) (xy 386.146196 -267.486153) (xy 386.16178 -267.532834) (xy 386.169675 -267.581411)
			(xy 386.17017 -267.606018) (xy 386.499112 -267.606018) (xy 386.503072 -267.556964) (xy 386.514849 -267.50918)
			(xy 386.53414 -267.463904) (xy 386.560443 -267.422308) (xy 386.593078 -267.385471) (xy 386.631199 -267.354346)
			(xy 386.67382 -267.329739) (xy 386.719836 -267.312287) (xy 386.768055 -267.302443) (xy 386.81723 -267.300462)
			(xy 386.866085 -267.306394) (xy 386.913356 -267.320086) (xy 386.957818 -267.341184) (xy 386.998321 -267.36914)
			(xy 387.033814 -267.403232) (xy 387.063379 -267.442576) (xy 387.08625 -267.486153) (xy 387.101834 -267.532834)
			(xy 387.109729 -267.581411) (xy 387.110224 -267.606018) (xy 387.438912 -267.606018) (xy 387.442872 -267.556964)
			(xy 387.454649 -267.50918) (xy 387.47394 -267.463904) (xy 387.500243 -267.422308) (xy 387.532878 -267.385471)
			(xy 387.570999 -267.354346) (xy 387.61362 -267.329739) (xy 387.659636 -267.312287) (xy 387.707855 -267.302443)
			(xy 387.75703 -267.300462) (xy 387.805885 -267.306394) (xy 387.853156 -267.320086) (xy 387.897618 -267.341184)
			(xy 387.938121 -267.36914) (xy 387.973614 -267.403232) (xy 388.003179 -267.442576) (xy 388.02605 -267.486153)
			(xy 388.041634 -267.532834) (xy 388.049529 -267.581411) (xy 388.050024 -267.606018) (xy 388.049529 -267.630625)
			(xy 388.041634 -267.679202) (xy 388.02605 -267.725883) (xy 388.003179 -267.76946) (xy 387.973614 -267.808804)
			(xy 387.938121 -267.842896) (xy 387.897618 -267.870852) (xy 387.853156 -267.89195) (xy 387.805885 -267.905642)
			(xy 387.75703 -267.911574) (xy 387.707855 -267.909593) (xy 387.659636 -267.899749) (xy 387.61362 -267.882297)
			(xy 387.570999 -267.85769) (xy 387.532878 -267.826565) (xy 387.500243 -267.789728) (xy 387.47394 -267.748132)
			(xy 387.454649 -267.702856) (xy 387.442872 -267.655072) (xy 387.438912 -267.606018) (xy 387.110224 -267.606018)
			(xy 387.109729 -267.630625) (xy 387.101834 -267.679202) (xy 387.08625 -267.725883) (xy 387.063379 -267.76946)
			(xy 387.033814 -267.808804) (xy 386.998321 -267.842896) (xy 386.957818 -267.870852) (xy 386.913356 -267.89195)
			(xy 386.866085 -267.905642) (xy 386.81723 -267.911574) (xy 386.768055 -267.909593) (xy 386.719836 -267.899749)
			(xy 386.67382 -267.882297) (xy 386.631199 -267.85769) (xy 386.593078 -267.826565) (xy 386.560443 -267.789728)
			(xy 386.53414 -267.748132) (xy 386.514849 -267.702856) (xy 386.503072 -267.655072) (xy 386.499112 -267.606018)
			(xy 386.17017 -267.606018) (xy 386.169675 -267.630625) (xy 386.16178 -267.679202) (xy 386.146196 -267.725883)
			(xy 386.123325 -267.76946) (xy 386.09376 -267.808804) (xy 386.058267 -267.842896) (xy 386.017764 -267.870852)
			(xy 385.973302 -267.89195) (xy 385.926031 -267.905642) (xy 385.877176 -267.911574) (xy 385.828001 -267.909593)
			(xy 385.779782 -267.899749) (xy 385.733766 -267.882297) (xy 385.691145 -267.85769) (xy 385.653024 -267.826565)
			(xy 385.620389 -267.789728) (xy 385.594086 -267.748132) (xy 385.574795 -267.702856) (xy 385.563018 -267.655072)
			(xy 385.559058 -267.606018) (xy 385.230116 -267.606018) (xy 385.229621 -267.630625) (xy 385.221726 -267.679202)
			(xy 385.206142 -267.725883) (xy 385.183271 -267.76946) (xy 385.153706 -267.808804) (xy 385.118213 -267.842896)
			(xy 385.07771 -267.870852) (xy 385.033248 -267.89195) (xy 384.985977 -267.905642) (xy 384.937122 -267.911574)
			(xy 384.887947 -267.909593) (xy 384.839728 -267.899749) (xy 384.793712 -267.882297) (xy 384.751091 -267.85769)
			(xy 384.71297 -267.826565) (xy 384.680335 -267.789728) (xy 384.654032 -267.748132) (xy 384.634741 -267.702856)
			(xy 384.622964 -267.655072) (xy 384.619004 -267.606018) (xy 384.290062 -267.606018) (xy 384.289567 -267.630625)
			(xy 384.281672 -267.679202) (xy 384.266088 -267.725883) (xy 384.243217 -267.76946) (xy 384.213652 -267.808804)
			(xy 384.178159 -267.842896) (xy 384.137656 -267.870852) (xy 384.093194 -267.89195) (xy 384.045923 -267.905642)
			(xy 383.997068 -267.911574) (xy 383.947893 -267.909593) (xy 383.899674 -267.899749) (xy 383.853658 -267.882297)
			(xy 383.811037 -267.85769) (xy 383.772916 -267.826565) (xy 383.740281 -267.789728) (xy 383.713978 -267.748132)
			(xy 383.694687 -267.702856) (xy 383.68291 -267.655072) (xy 383.67895 -267.606018) (xy 383.350008 -267.606018)
			(xy 383.349513 -267.630625) (xy 383.341618 -267.679202) (xy 383.326034 -267.725883) (xy 383.303163 -267.76946)
			(xy 383.273598 -267.808804) (xy 383.238105 -267.842896) (xy 383.197602 -267.870852) (xy 383.15314 -267.89195)
			(xy 383.105869 -267.905642) (xy 383.057014 -267.911574) (xy 383.007839 -267.909593) (xy 382.95962 -267.899749)
			(xy 382.913604 -267.882297) (xy 382.870983 -267.85769) (xy 382.832862 -267.826565) (xy 382.800227 -267.789728)
			(xy 382.773924 -267.748132) (xy 382.754633 -267.702856) (xy 382.742856 -267.655072) (xy 382.738896 -267.606018)
			(xy 382.410208 -267.606018) (xy 382.409713 -267.630625) (xy 382.401818 -267.679202) (xy 382.386234 -267.725883)
			(xy 382.363363 -267.76946) (xy 382.333798 -267.808804) (xy 382.298305 -267.842896) (xy 382.257802 -267.870852)
			(xy 382.21334 -267.89195) (xy 382.166069 -267.905642) (xy 382.117214 -267.911574) (xy 382.068039 -267.909593)
			(xy 382.01982 -267.899749) (xy 381.973804 -267.882297) (xy 381.931183 -267.85769) (xy 381.893062 -267.826565)
			(xy 381.860427 -267.789728) (xy 381.834124 -267.748132) (xy 381.814833 -267.702856) (xy 381.803056 -267.655072)
			(xy 381.799096 -267.606018) (xy 381.480568 -267.606018) (xy 381.480056 -267.631464) (xy 381.471892 -267.681698)
			(xy 381.455776 -267.729972) (xy 381.432125 -267.775035) (xy 381.401552 -267.815721) (xy 381.364848 -267.850976)
			(xy 381.322964 -267.879886) (xy 381.276985 -267.901703) (xy 381.228101 -267.915863) (xy 381.17758 -267.921997)
			(xy 381.126728 -267.919948) (xy 381.076864 -267.909768) (xy 381.029278 -267.891721) (xy 380.985204 -267.866275)
			(xy 380.945782 -267.834088) (xy 380.912034 -267.795994) (xy 380.884833 -267.75298) (xy 380.864885 -267.70616)
			(xy 380.852706 -267.656746) (xy 380.848611 -267.606018) (xy 380.5301 -267.606018) (xy 380.529605 -267.630625)
			(xy 380.52171 -267.679202) (xy 380.506126 -267.725883) (xy 380.483255 -267.76946) (xy 380.45369 -267.808804)
			(xy 380.418197 -267.842896) (xy 380.377694 -267.870852) (xy 380.333232 -267.89195) (xy 380.285961 -267.905642)
			(xy 380.237106 -267.911574) (xy 380.187931 -267.909593) (xy 380.139712 -267.899749) (xy 380.093696 -267.882297)
			(xy 380.051075 -267.85769) (xy 380.012954 -267.826565) (xy 379.980319 -267.789728) (xy 379.954016 -267.748132)
			(xy 379.934725 -267.702856) (xy 379.922948 -267.655072) (xy 379.918988 -267.606018) (xy 379.590046 -267.606018)
			(xy 379.589551 -267.630625) (xy 379.581656 -267.679202) (xy 379.566072 -267.725883) (xy 379.543201 -267.76946)
			(xy 379.513636 -267.808804) (xy 379.478143 -267.842896) (xy 379.43764 -267.870852) (xy 379.393178 -267.89195)
			(xy 379.345907 -267.905642) (xy 379.297052 -267.911574) (xy 379.247877 -267.909593) (xy 379.199658 -267.899749)
			(xy 379.153642 -267.882297) (xy 379.111021 -267.85769) (xy 379.0729 -267.826565) (xy 379.040265 -267.789728)
			(xy 379.013962 -267.748132) (xy 378.994671 -267.702856) (xy 378.982894 -267.655072) (xy 378.978934 -267.606018)
			(xy 378.650246 -267.606018) (xy 378.649751 -267.630625) (xy 378.641856 -267.679202) (xy 378.626272 -267.725883)
			(xy 378.603401 -267.76946) (xy 378.573836 -267.808804) (xy 378.538343 -267.842896) (xy 378.49784 -267.870852)
			(xy 378.453378 -267.89195) (xy 378.406107 -267.905642) (xy 378.357252 -267.911574) (xy 378.308077 -267.909593)
			(xy 378.259858 -267.899749) (xy 378.213842 -267.882297) (xy 378.171221 -267.85769) (xy 378.1331 -267.826565)
			(xy 378.100465 -267.789728) (xy 378.074162 -267.748132) (xy 378.054871 -267.702856) (xy 378.043094 -267.655072)
			(xy 378.039134 -267.606018) (xy 377.720606 -267.606018) (xy 377.720094 -267.631464) (xy 377.71193 -267.681698)
			(xy 377.695814 -267.729972) (xy 377.672163 -267.775035) (xy 377.64159 -267.815721) (xy 377.604886 -267.850976)
			(xy 377.563002 -267.879886) (xy 377.517023 -267.901703) (xy 377.468139 -267.915863) (xy 377.417618 -267.921997)
			(xy 377.366766 -267.919948) (xy 377.316902 -267.909768) (xy 377.269316 -267.891721) (xy 377.225242 -267.866275)
			(xy 377.18582 -267.834088) (xy 377.152072 -267.795994) (xy 377.124871 -267.75298) (xy 377.104923 -267.70616)
			(xy 377.092744 -267.656746) (xy 377.088649 -267.606018) (xy 376.770138 -267.606018) (xy 376.769643 -267.630625)
			(xy 376.761748 -267.679202) (xy 376.746164 -267.725883) (xy 376.723293 -267.76946) (xy 376.693728 -267.808804)
			(xy 376.658235 -267.842896) (xy 376.617732 -267.870852) (xy 376.57327 -267.89195) (xy 376.525999 -267.905642)
			(xy 376.477144 -267.911574) (xy 376.427969 -267.909593) (xy 376.37975 -267.899749) (xy 376.333734 -267.882297)
			(xy 376.291113 -267.85769) (xy 376.252992 -267.826565) (xy 376.220357 -267.789728) (xy 376.194054 -267.748132)
			(xy 376.174763 -267.702856) (xy 376.162986 -267.655072) (xy 376.159026 -267.606018) (xy 374.89003 -267.606018)
			(xy 374.889396 -267.634031) (xy 374.879167 -267.689116) (xy 374.86971 -267.715492) (xy 374.8659 -267.725144)
			(xy 374.864122 -267.72997) (xy 374.86717 -267.74394) (xy 374.868901 -267.751073) (xy 374.875862 -267.763989)
			(xy 374.880886 -267.76934) (xy 375.221246 -268.1097) (xy 375.227003 -268.115886) (xy 375.234385 -268.131074)
			(xy 375.235724 -268.139418) (xy 375.235724 -268.140434) (xy 375.23674 -268.1478) (xy 375.239026 -268.152626)
			(xy 375.25325 -268.183868) (xy 375.260616 -268.190472) (xy 375.279038 -268.207958) (xy 375.310379 -268.247924)
			(xy 375.334674 -268.292525) (xy 375.351251 -268.340533) (xy 375.359654 -268.390622) (xy 375.359653 -268.416024)
			(xy 375.689126 -268.416024) (xy 375.693086 -268.36697) (xy 375.704863 -268.319186) (xy 375.724154 -268.27391)
			(xy 375.750457 -268.232314) (xy 375.783092 -268.195477) (xy 375.821213 -268.164352) (xy 375.863834 -268.139745)
			(xy 375.90985 -268.122293) (xy 375.958069 -268.112449) (xy 376.007244 -268.110468) (xy 376.056099 -268.1164)
			(xy 376.10337 -268.130092) (xy 376.147832 -268.15119) (xy 376.188335 -268.179146) (xy 376.223828 -268.213238)
			(xy 376.253393 -268.252582) (xy 376.276264 -268.296159) (xy 376.291848 -268.34284) (xy 376.299743 -268.391417)
			(xy 376.300238 -268.416024) (xy 376.628926 -268.416024) (xy 376.632886 -268.36697) (xy 376.644663 -268.319186)
			(xy 376.663954 -268.27391) (xy 376.690257 -268.232314) (xy 376.722892 -268.195477) (xy 376.761013 -268.164352)
			(xy 376.803634 -268.139745) (xy 376.84965 -268.122293) (xy 376.897869 -268.112449) (xy 376.947044 -268.110468)
			(xy 376.995899 -268.1164) (xy 377.04317 -268.130092) (xy 377.087632 -268.15119) (xy 377.128135 -268.179146)
			(xy 377.163628 -268.213238) (xy 377.193193 -268.252582) (xy 377.216064 -268.296159) (xy 377.231648 -268.34284)
			(xy 377.239543 -268.391417) (xy 377.240038 -268.416024) (xy 377.56898 -268.416024) (xy 377.57294 -268.36697)
			(xy 377.584717 -268.319186) (xy 377.604008 -268.27391) (xy 377.630311 -268.232314) (xy 377.662946 -268.195477)
			(xy 377.701067 -268.164352) (xy 377.743688 -268.139745) (xy 377.789704 -268.122293) (xy 377.837923 -268.112449)
			(xy 377.887098 -268.110468) (xy 377.935953 -268.1164) (xy 377.983224 -268.130092) (xy 378.027686 -268.15119)
			(xy 378.068189 -268.179146) (xy 378.103682 -268.213238) (xy 378.133247 -268.252582) (xy 378.156118 -268.296159)
			(xy 378.171702 -268.34284) (xy 378.179597 -268.391417) (xy 378.180092 -268.416024) (xy 379.449088 -268.416024)
			(xy 379.453048 -268.36697) (xy 379.464825 -268.319186) (xy 379.484116 -268.27391) (xy 379.510419 -268.232314)
			(xy 379.543054 -268.195477) (xy 379.581175 -268.164352) (xy 379.623796 -268.139745) (xy 379.669812 -268.122293)
			(xy 379.718031 -268.112449) (xy 379.767206 -268.110468) (xy 379.816061 -268.1164) (xy 379.863332 -268.130092)
			(xy 379.907794 -268.15119) (xy 379.948297 -268.179146) (xy 379.98379 -268.213238) (xy 380.013355 -268.252582)
			(xy 380.036226 -268.296159) (xy 380.05181 -268.34284) (xy 380.059705 -268.391417) (xy 380.0602 -268.416024)
			(xy 380.388888 -268.416024) (xy 380.392848 -268.36697) (xy 380.404625 -268.319186) (xy 380.423916 -268.27391)
			(xy 380.450219 -268.232314) (xy 380.482854 -268.195477) (xy 380.520975 -268.164352) (xy 380.563596 -268.139745)
			(xy 380.609612 -268.122293) (xy 380.657831 -268.112449) (xy 380.707006 -268.110468) (xy 380.755861 -268.1164)
			(xy 380.803132 -268.130092) (xy 380.847594 -268.15119) (xy 380.888097 -268.179146) (xy 380.92359 -268.213238)
			(xy 380.953155 -268.252582) (xy 380.976026 -268.296159) (xy 380.99161 -268.34284) (xy 380.999505 -268.391417)
			(xy 381 -268.416024) (xy 381.328942 -268.416024) (xy 381.332902 -268.36697) (xy 381.344679 -268.319186)
			(xy 381.36397 -268.27391) (xy 381.390273 -268.232314) (xy 381.422908 -268.195477) (xy 381.461029 -268.164352)
			(xy 381.50365 -268.139745) (xy 381.549666 -268.122293) (xy 381.597885 -268.112449) (xy 381.64706 -268.110468)
			(xy 381.695915 -268.1164) (xy 381.743186 -268.130092) (xy 381.787648 -268.15119) (xy 381.828151 -268.179146)
			(xy 381.863644 -268.213238) (xy 381.893209 -268.252582) (xy 381.91608 -268.296159) (xy 381.931664 -268.34284)
			(xy 381.939559 -268.391417) (xy 381.940054 -268.416024) (xy 382.268996 -268.416024) (xy 382.272956 -268.36697)
			(xy 382.284733 -268.319186) (xy 382.304024 -268.27391) (xy 382.330327 -268.232314) (xy 382.362962 -268.195477)
			(xy 382.401083 -268.164352) (xy 382.443704 -268.139745) (xy 382.48972 -268.122293) (xy 382.537939 -268.112449)
			(xy 382.587114 -268.110468) (xy 382.635969 -268.1164) (xy 382.68324 -268.130092) (xy 382.727702 -268.15119)
			(xy 382.768205 -268.179146) (xy 382.803698 -268.213238) (xy 382.833263 -268.252582) (xy 382.856134 -268.296159)
			(xy 382.871718 -268.34284) (xy 382.879613 -268.391417) (xy 382.880108 -268.416024) (xy 383.20905 -268.416024)
			(xy 383.21301 -268.36697) (xy 383.224787 -268.319186) (xy 383.244078 -268.27391) (xy 383.270381 -268.232314)
			(xy 383.303016 -268.195477) (xy 383.341137 -268.164352) (xy 383.383758 -268.139745) (xy 383.429774 -268.122293)
			(xy 383.477993 -268.112449) (xy 383.527168 -268.110468) (xy 383.576023 -268.1164) (xy 383.623294 -268.130092)
			(xy 383.667756 -268.15119) (xy 383.708259 -268.179146) (xy 383.743752 -268.213238) (xy 383.773317 -268.252582)
			(xy 383.796188 -268.296159) (xy 383.811772 -268.34284) (xy 383.819667 -268.391417) (xy 383.820162 -268.416024)
			(xy 384.149104 -268.416024) (xy 384.153064 -268.36697) (xy 384.164841 -268.319186) (xy 384.184132 -268.27391)
			(xy 384.210435 -268.232314) (xy 384.24307 -268.195477) (xy 384.281191 -268.164352) (xy 384.323812 -268.139745)
			(xy 384.369828 -268.122293) (xy 384.418047 -268.112449) (xy 384.467222 -268.110468) (xy 384.516077 -268.1164)
			(xy 384.563348 -268.130092) (xy 384.60781 -268.15119) (xy 384.648313 -268.179146) (xy 384.683806 -268.213238)
			(xy 384.713371 -268.252582) (xy 384.736242 -268.296159) (xy 384.751826 -268.34284) (xy 384.759721 -268.391417)
			(xy 384.760216 -268.416024) (xy 386.028958 -268.416024) (xy 386.032918 -268.36697) (xy 386.044695 -268.319186)
			(xy 386.063986 -268.27391) (xy 386.090289 -268.232314) (xy 386.122924 -268.195477) (xy 386.161045 -268.164352)
			(xy 386.203666 -268.139745) (xy 386.249682 -268.122293) (xy 386.297901 -268.112449) (xy 386.347076 -268.110468)
			(xy 386.395931 -268.1164) (xy 386.443202 -268.130092) (xy 386.487664 -268.15119) (xy 386.528167 -268.179146)
			(xy 386.56366 -268.213238) (xy 386.593225 -268.252582) (xy 386.616096 -268.296159) (xy 386.63168 -268.34284)
			(xy 386.639575 -268.391417) (xy 386.64007 -268.416024) (xy 386.969012 -268.416024) (xy 386.972972 -268.36697)
			(xy 386.984749 -268.319186) (xy 387.00404 -268.27391) (xy 387.030343 -268.232314) (xy 387.062978 -268.195477)
			(xy 387.101099 -268.164352) (xy 387.14372 -268.139745) (xy 387.189736 -268.122293) (xy 387.237955 -268.112449)
			(xy 387.28713 -268.110468) (xy 387.335985 -268.1164) (xy 387.383256 -268.130092) (xy 387.427718 -268.15119)
			(xy 387.468221 -268.179146) (xy 387.503714 -268.213238) (xy 387.533279 -268.252582) (xy 387.55615 -268.296159)
			(xy 387.571734 -268.34284) (xy 387.579629 -268.391417) (xy 387.580124 -268.416024) (xy 387.909066 -268.416024)
			(xy 387.913026 -268.36697) (xy 387.924803 -268.319186) (xy 387.944094 -268.27391) (xy 387.970397 -268.232314)
			(xy 388.003032 -268.195477) (xy 388.041153 -268.164352) (xy 388.083774 -268.139745) (xy 388.12979 -268.122293)
			(xy 388.178009 -268.112449) (xy 388.227184 -268.110468) (xy 388.276039 -268.1164) (xy 388.32331 -268.130092)
			(xy 388.367772 -268.15119) (xy 388.408275 -268.179146) (xy 388.443768 -268.213238) (xy 388.473333 -268.252582)
			(xy 388.496204 -268.296159) (xy 388.511788 -268.34284) (xy 388.519683 -268.391417) (xy 388.520178 -268.416024)
			(xy 388.519683 -268.440631) (xy 388.511788 -268.489208) (xy 388.496204 -268.535889) (xy 388.473333 -268.579466)
			(xy 388.443768 -268.61881) (xy 388.408275 -268.652902) (xy 388.367772 -268.680858) (xy 388.32331 -268.701956)
			(xy 388.276039 -268.715648) (xy 388.227184 -268.72158) (xy 388.178009 -268.719599) (xy 388.12979 -268.709755)
			(xy 388.083774 -268.692303) (xy 388.041153 -268.667696) (xy 388.003032 -268.636571) (xy 387.970397 -268.599734)
			(xy 387.944094 -268.558138) (xy 387.924803 -268.512862) (xy 387.913026 -268.465078) (xy 387.909066 -268.416024)
			(xy 387.580124 -268.416024) (xy 387.579629 -268.440631) (xy 387.571734 -268.489208) (xy 387.55615 -268.535889)
			(xy 387.533279 -268.579466) (xy 387.503714 -268.61881) (xy 387.468221 -268.652902) (xy 387.427718 -268.680858)
			(xy 387.383256 -268.701956) (xy 387.335985 -268.715648) (xy 387.28713 -268.72158) (xy 387.237955 -268.719599)
			(xy 387.189736 -268.709755) (xy 387.14372 -268.692303) (xy 387.101099 -268.667696) (xy 387.062978 -268.636571)
			(xy 387.030343 -268.599734) (xy 387.00404 -268.558138) (xy 386.984749 -268.512862) (xy 386.972972 -268.465078)
			(xy 386.969012 -268.416024) (xy 386.64007 -268.416024) (xy 386.639575 -268.440631) (xy 386.63168 -268.489208)
			(xy 386.616096 -268.535889) (xy 386.593225 -268.579466) (xy 386.56366 -268.61881) (xy 386.528167 -268.652902)
			(xy 386.487664 -268.680858) (xy 386.443202 -268.701956) (xy 386.395931 -268.715648) (xy 386.347076 -268.72158)
			(xy 386.297901 -268.719599) (xy 386.249682 -268.709755) (xy 386.203666 -268.692303) (xy 386.161045 -268.667696)
			(xy 386.122924 -268.636571) (xy 386.090289 -268.599734) (xy 386.063986 -268.558138) (xy 386.044695 -268.512862)
			(xy 386.032918 -268.465078) (xy 386.028958 -268.416024) (xy 384.760216 -268.416024) (xy 384.759721 -268.440631)
			(xy 384.751826 -268.489208) (xy 384.736242 -268.535889) (xy 384.713371 -268.579466) (xy 384.683806 -268.61881)
			(xy 384.648313 -268.652902) (xy 384.60781 -268.680858) (xy 384.563348 -268.701956) (xy 384.516077 -268.715648)
			(xy 384.467222 -268.72158) (xy 384.418047 -268.719599) (xy 384.369828 -268.709755) (xy 384.323812 -268.692303)
			(xy 384.281191 -268.667696) (xy 384.24307 -268.636571) (xy 384.210435 -268.599734) (xy 384.184132 -268.558138)
			(xy 384.164841 -268.512862) (xy 384.153064 -268.465078) (xy 384.149104 -268.416024) (xy 383.820162 -268.416024)
			(xy 383.819667 -268.440631) (xy 383.811772 -268.489208) (xy 383.796188 -268.535889) (xy 383.773317 -268.579466)
			(xy 383.743752 -268.61881) (xy 383.708259 -268.652902) (xy 383.667756 -268.680858) (xy 383.623294 -268.701956)
			(xy 383.576023 -268.715648) (xy 383.527168 -268.72158) (xy 383.477993 -268.719599) (xy 383.429774 -268.709755)
			(xy 383.383758 -268.692303) (xy 383.341137 -268.667696) (xy 383.303016 -268.636571) (xy 383.270381 -268.599734)
			(xy 383.244078 -268.558138) (xy 383.224787 -268.512862) (xy 383.21301 -268.465078) (xy 383.20905 -268.416024)
			(xy 382.880108 -268.416024) (xy 382.879613 -268.440631) (xy 382.871718 -268.489208) (xy 382.856134 -268.535889)
			(xy 382.833263 -268.579466) (xy 382.803698 -268.61881) (xy 382.768205 -268.652902) (xy 382.727702 -268.680858)
			(xy 382.68324 -268.701956) (xy 382.635969 -268.715648) (xy 382.587114 -268.72158) (xy 382.537939 -268.719599)
			(xy 382.48972 -268.709755) (xy 382.443704 -268.692303) (xy 382.401083 -268.667696) (xy 382.362962 -268.636571)
			(xy 382.330327 -268.599734) (xy 382.304024 -268.558138) (xy 382.284733 -268.512862) (xy 382.272956 -268.465078)
			(xy 382.268996 -268.416024) (xy 381.940054 -268.416024) (xy 381.939559 -268.440631) (xy 381.931664 -268.489208)
			(xy 381.91608 -268.535889) (xy 381.893209 -268.579466) (xy 381.863644 -268.61881) (xy 381.828151 -268.652902)
			(xy 381.787648 -268.680858) (xy 381.743186 -268.701956) (xy 381.695915 -268.715648) (xy 381.64706 -268.72158)
			(xy 381.597885 -268.719599) (xy 381.549666 -268.709755) (xy 381.50365 -268.692303) (xy 381.461029 -268.667696)
			(xy 381.422908 -268.636571) (xy 381.390273 -268.599734) (xy 381.36397 -268.558138) (xy 381.344679 -268.512862)
			(xy 381.332902 -268.465078) (xy 381.328942 -268.416024) (xy 381 -268.416024) (xy 380.999505 -268.440631)
			(xy 380.99161 -268.489208) (xy 380.976026 -268.535889) (xy 380.953155 -268.579466) (xy 380.92359 -268.61881)
			(xy 380.888097 -268.652902) (xy 380.847594 -268.680858) (xy 380.803132 -268.701956) (xy 380.755861 -268.715648)
			(xy 380.707006 -268.72158) (xy 380.657831 -268.719599) (xy 380.609612 -268.709755) (xy 380.563596 -268.692303)
			(xy 380.520975 -268.667696) (xy 380.482854 -268.636571) (xy 380.450219 -268.599734) (xy 380.423916 -268.558138)
			(xy 380.404625 -268.512862) (xy 380.392848 -268.465078) (xy 380.388888 -268.416024) (xy 380.0602 -268.416024)
			(xy 380.059705 -268.440631) (xy 380.05181 -268.489208) (xy 380.036226 -268.535889) (xy 380.013355 -268.579466)
			(xy 379.98379 -268.61881) (xy 379.948297 -268.652902) (xy 379.907794 -268.680858) (xy 379.863332 -268.701956)
			(xy 379.816061 -268.715648) (xy 379.767206 -268.72158) (xy 379.718031 -268.719599) (xy 379.669812 -268.709755)
			(xy 379.623796 -268.692303) (xy 379.581175 -268.667696) (xy 379.543054 -268.636571) (xy 379.510419 -268.599734)
			(xy 379.484116 -268.558138) (xy 379.464825 -268.512862) (xy 379.453048 -268.465078) (xy 379.449088 -268.416024)
			(xy 378.180092 -268.416024) (xy 378.179597 -268.440631) (xy 378.171702 -268.489208) (xy 378.156118 -268.535889)
			(xy 378.133247 -268.579466) (xy 378.103682 -268.61881) (xy 378.068189 -268.652902) (xy 378.027686 -268.680858)
			(xy 377.983224 -268.701956) (xy 377.935953 -268.715648) (xy 377.887098 -268.72158) (xy 377.837923 -268.719599)
			(xy 377.789704 -268.709755) (xy 377.743688 -268.692303) (xy 377.701067 -268.667696) (xy 377.662946 -268.636571)
			(xy 377.630311 -268.599734) (xy 377.604008 -268.558138) (xy 377.584717 -268.512862) (xy 377.57294 -268.465078)
			(xy 377.56898 -268.416024) (xy 377.240038 -268.416024) (xy 377.239543 -268.440631) (xy 377.231648 -268.489208)
			(xy 377.216064 -268.535889) (xy 377.193193 -268.579466) (xy 377.163628 -268.61881) (xy 377.128135 -268.652902)
			(xy 377.087632 -268.680858) (xy 377.04317 -268.701956) (xy 376.995899 -268.715648) (xy 376.947044 -268.72158)
			(xy 376.897869 -268.719599) (xy 376.84965 -268.709755) (xy 376.803634 -268.692303) (xy 376.761013 -268.667696)
			(xy 376.722892 -268.636571) (xy 376.690257 -268.599734) (xy 376.663954 -268.558138) (xy 376.644663 -268.512862)
			(xy 376.632886 -268.465078) (xy 376.628926 -268.416024) (xy 376.300238 -268.416024) (xy 376.299743 -268.440631)
			(xy 376.291848 -268.489208) (xy 376.276264 -268.535889) (xy 376.253393 -268.579466) (xy 376.223828 -268.61881)
			(xy 376.188335 -268.652902) (xy 376.147832 -268.680858) (xy 376.10337 -268.701956) (xy 376.056099 -268.715648)
			(xy 376.007244 -268.72158) (xy 375.958069 -268.719599) (xy 375.90985 -268.709755) (xy 375.863834 -268.692303)
			(xy 375.821213 -268.667696) (xy 375.783092 -268.636571) (xy 375.750457 -268.599734) (xy 375.724154 -268.558138)
			(xy 375.704863 -268.512862) (xy 375.693086 -268.465078) (xy 375.689126 -268.416024) (xy 375.359653 -268.416024)
			(xy 375.359652 -268.441411) (xy 375.351243 -268.491499) (xy 375.334661 -268.539504) (xy 375.310361 -268.584103)
			(xy 375.279016 -268.624066) (xy 375.260616 -268.641576) (xy 375.25325 -268.64818) (xy 375.240804 -268.675358)
			(xy 375.23674 -268.687804) (xy 375.235978 -268.69644) (xy 375.235978 -268.867382) (xy 375.236379 -268.875934)
			(xy 375.24218 -268.89203) (xy 375.252995 -268.905288) (xy 375.260108 -268.910054) (xy 375.315734 -268.943582)
			(xy 375.336054 -268.955774) (xy 375.34124 -268.958302) (xy 375.352394 -268.961239) (xy 375.358152 -268.961616)
			(xy 375.370852 -268.96187) (xy 375.382536 -268.955774) (xy 375.404529 -268.944776) (xy 375.451158 -268.929172)
			(xy 375.499683 -268.921232) (xy 375.524268 -268.920722) (xy 375.530364 -268.920722) (xy 375.555315 -268.921674)
			(xy 375.604423 -268.930694) (xy 375.651409 -268.947584) (xy 375.695021 -268.971894) (xy 375.734097 -269.002975)
			(xy 375.767595 -269.04) (xy 375.794622 -269.081981) (xy 375.814459 -269.127801) (xy 375.826576 -269.176238)
			(xy 375.830652 -269.226001) (xy 375.83065 -269.22603) (xy 376.159026 -269.22603) (xy 376.162986 -269.176976)
			(xy 376.174763 -269.129192) (xy 376.194054 -269.083916) (xy 376.220357 -269.04232) (xy 376.252992 -269.005483)
			(xy 376.291113 -268.974358) (xy 376.333734 -268.949751) (xy 376.37975 -268.932299) (xy 376.427969 -268.922455)
			(xy 376.477144 -268.920474) (xy 376.525999 -268.926406) (xy 376.57327 -268.940098) (xy 376.617732 -268.961196)
			(xy 376.658235 -268.989152) (xy 376.693728 -269.023244) (xy 376.723293 -269.062588) (xy 376.746164 -269.106165)
			(xy 376.761748 -269.152846) (xy 376.769643 -269.201423) (xy 376.770138 -269.22603) (xy 377.088649 -269.22603)
			(xy 377.092744 -269.175302) (xy 377.104923 -269.125888) (xy 377.124871 -269.079068) (xy 377.152072 -269.036054)
			(xy 377.18582 -268.99796) (xy 377.225242 -268.965773) (xy 377.269316 -268.940327) (xy 377.316902 -268.92228)
			(xy 377.366766 -268.9121) (xy 377.417618 -268.910051) (xy 377.468139 -268.916185) (xy 377.517023 -268.930345)
			(xy 377.563002 -268.952162) (xy 377.604886 -268.981072) (xy 377.64159 -269.016327) (xy 377.672163 -269.057013)
			(xy 377.695814 -269.102076) (xy 377.71193 -269.15035) (xy 377.720094 -269.200584) (xy 377.720606 -269.22603)
			(xy 378.039134 -269.22603) (xy 378.043094 -269.176976) (xy 378.054871 -269.129192) (xy 378.074162 -269.083916)
			(xy 378.100465 -269.04232) (xy 378.1331 -269.005483) (xy 378.171221 -268.974358) (xy 378.213842 -268.949751)
			(xy 378.259858 -268.932299) (xy 378.308077 -268.922455) (xy 378.357252 -268.920474) (xy 378.406107 -268.926406)
			(xy 378.453378 -268.940098) (xy 378.49784 -268.961196) (xy 378.538343 -268.989152) (xy 378.573836 -269.023244)
			(xy 378.603401 -269.062588) (xy 378.626272 -269.106165) (xy 378.641856 -269.152846) (xy 378.649751 -269.201423)
			(xy 378.650246 -269.22603) (xy 378.978934 -269.22603) (xy 378.982894 -269.176976) (xy 378.994671 -269.129192)
			(xy 379.013962 -269.083916) (xy 379.040265 -269.04232) (xy 379.0729 -269.005483) (xy 379.111021 -268.974358)
			(xy 379.153642 -268.949751) (xy 379.199658 -268.932299) (xy 379.247877 -268.922455) (xy 379.297052 -268.920474)
			(xy 379.345907 -268.926406) (xy 379.393178 -268.940098) (xy 379.43764 -268.961196) (xy 379.478143 -268.989152)
			(xy 379.513636 -269.023244) (xy 379.543201 -269.062588) (xy 379.566072 -269.106165) (xy 379.581656 -269.152846)
			(xy 379.589551 -269.201423) (xy 379.590046 -269.22603) (xy 379.918988 -269.22603) (xy 379.922948 -269.176976)
			(xy 379.934725 -269.129192) (xy 379.954016 -269.083916) (xy 379.980319 -269.04232) (xy 380.012954 -269.005483)
			(xy 380.051075 -268.974358) (xy 380.093696 -268.949751) (xy 380.139712 -268.932299) (xy 380.187931 -268.922455)
			(xy 380.237106 -268.920474) (xy 380.285961 -268.926406) (xy 380.333232 -268.940098) (xy 380.377694 -268.961196)
			(xy 380.418197 -268.989152) (xy 380.45369 -269.023244) (xy 380.483255 -269.062588) (xy 380.506126 -269.106165)
			(xy 380.52171 -269.152846) (xy 380.529605 -269.201423) (xy 380.5301 -269.22603) (xy 380.848611 -269.22603)
			(xy 380.852706 -269.175302) (xy 380.864885 -269.125888) (xy 380.884833 -269.079068) (xy 380.912034 -269.036054)
			(xy 380.945782 -268.99796) (xy 380.985204 -268.965773) (xy 381.029278 -268.940327) (xy 381.076864 -268.92228)
			(xy 381.126728 -268.9121) (xy 381.17758 -268.910051) (xy 381.228101 -268.916185) (xy 381.276985 -268.930345)
			(xy 381.322964 -268.952162) (xy 381.364848 -268.981072) (xy 381.401552 -269.016327) (xy 381.432125 -269.057013)
			(xy 381.455776 -269.102076) (xy 381.471892 -269.15035) (xy 381.480056 -269.200584) (xy 381.480568 -269.22603)
			(xy 381.799096 -269.22603) (xy 381.803056 -269.176976) (xy 381.814833 -269.129192) (xy 381.834124 -269.083916)
			(xy 381.860427 -269.04232) (xy 381.893062 -269.005483) (xy 381.931183 -268.974358) (xy 381.973804 -268.949751)
			(xy 382.01982 -268.932299) (xy 382.068039 -268.922455) (xy 382.117214 -268.920474) (xy 382.166069 -268.926406)
			(xy 382.21334 -268.940098) (xy 382.257802 -268.961196) (xy 382.298305 -268.989152) (xy 382.333798 -269.023244)
			(xy 382.363363 -269.062588) (xy 382.386234 -269.106165) (xy 382.401818 -269.152846) (xy 382.409713 -269.201423)
			(xy 382.410208 -269.22603) (xy 382.738896 -269.22603) (xy 382.742856 -269.176976) (xy 382.754633 -269.129192)
			(xy 382.773924 -269.083916) (xy 382.800227 -269.04232) (xy 382.832862 -269.005483) (xy 382.870983 -268.974358)
			(xy 382.913604 -268.949751) (xy 382.95962 -268.932299) (xy 383.007839 -268.922455) (xy 383.057014 -268.920474)
			(xy 383.105869 -268.926406) (xy 383.15314 -268.940098) (xy 383.197602 -268.961196) (xy 383.238105 -268.989152)
			(xy 383.273598 -269.023244) (xy 383.303163 -269.062588) (xy 383.326034 -269.106165) (xy 383.341618 -269.152846)
			(xy 383.349513 -269.201423) (xy 383.350008 -269.22603) (xy 383.67895 -269.22603) (xy 383.68291 -269.176976)
			(xy 383.694687 -269.129192) (xy 383.713978 -269.083916) (xy 383.740281 -269.04232) (xy 383.772916 -269.005483)
			(xy 383.811037 -268.974358) (xy 383.853658 -268.949751) (xy 383.899674 -268.932299) (xy 383.947893 -268.922455)
			(xy 383.997068 -268.920474) (xy 384.045923 -268.926406) (xy 384.093194 -268.940098) (xy 384.137656 -268.961196)
			(xy 384.178159 -268.989152) (xy 384.213652 -269.023244) (xy 384.243217 -269.062588) (xy 384.266088 -269.106165)
			(xy 384.281672 -269.152846) (xy 384.289567 -269.201423) (xy 384.290062 -269.22603) (xy 384.619004 -269.22603)
			(xy 384.622964 -269.176976) (xy 384.634741 -269.129192) (xy 384.654032 -269.083916) (xy 384.680335 -269.04232)
			(xy 384.71297 -269.005483) (xy 384.751091 -268.974358) (xy 384.793712 -268.949751) (xy 384.839728 -268.932299)
			(xy 384.887947 -268.922455) (xy 384.937122 -268.920474) (xy 384.985977 -268.926406) (xy 385.033248 -268.940098)
			(xy 385.07771 -268.961196) (xy 385.118213 -268.989152) (xy 385.153706 -269.023244) (xy 385.183271 -269.062588)
			(xy 385.206142 -269.106165) (xy 385.221726 -269.152846) (xy 385.229621 -269.201423) (xy 385.230116 -269.22603)
			(xy 385.559058 -269.22603) (xy 385.563018 -269.176976) (xy 385.574795 -269.129192) (xy 385.594086 -269.083916)
			(xy 385.620389 -269.04232) (xy 385.653024 -269.005483) (xy 385.691145 -268.974358) (xy 385.733766 -268.949751)
			(xy 385.779782 -268.932299) (xy 385.828001 -268.922455) (xy 385.877176 -268.920474) (xy 385.926031 -268.926406)
			(xy 385.973302 -268.940098) (xy 386.017764 -268.961196) (xy 386.058267 -268.989152) (xy 386.09376 -269.023244)
			(xy 386.123325 -269.062588) (xy 386.146196 -269.106165) (xy 386.16178 -269.152846) (xy 386.169675 -269.201423)
			(xy 386.17017 -269.22603) (xy 386.499112 -269.22603) (xy 386.503072 -269.176976) (xy 386.514849 -269.129192)
			(xy 386.53414 -269.083916) (xy 386.560443 -269.04232) (xy 386.593078 -269.005483) (xy 386.631199 -268.974358)
			(xy 386.67382 -268.949751) (xy 386.719836 -268.932299) (xy 386.768055 -268.922455) (xy 386.81723 -268.920474)
			(xy 386.866085 -268.926406) (xy 386.913356 -268.940098) (xy 386.957818 -268.961196) (xy 386.998321 -268.989152)
			(xy 387.033814 -269.023244) (xy 387.063379 -269.062588) (xy 387.08625 -269.106165) (xy 387.101834 -269.152846)
			(xy 387.109729 -269.201423) (xy 387.110224 -269.22603) (xy 387.438912 -269.22603) (xy 387.442872 -269.176976)
			(xy 387.454649 -269.129192) (xy 387.47394 -269.083916) (xy 387.500243 -269.04232) (xy 387.532878 -269.005483)
			(xy 387.570999 -268.974358) (xy 387.61362 -268.949751) (xy 387.659636 -268.932299) (xy 387.707855 -268.922455)
			(xy 387.75703 -268.920474) (xy 387.805885 -268.926406) (xy 387.853156 -268.940098) (xy 387.897618 -268.961196)
			(xy 387.938121 -268.989152) (xy 387.973614 -269.023244) (xy 388.003179 -269.062588) (xy 388.02605 -269.106165)
			(xy 388.041634 -269.152846) (xy 388.049529 -269.201423) (xy 388.050024 -269.22603) (xy 388.049529 -269.250637)
			(xy 388.041634 -269.299214) (xy 388.02605 -269.345895) (xy 388.003179 -269.389472) (xy 387.973614 -269.428816)
			(xy 387.938121 -269.462908) (xy 387.897618 -269.490864) (xy 387.853156 -269.511962) (xy 387.805885 -269.525654)
			(xy 387.75703 -269.531586) (xy 387.707855 -269.529605) (xy 387.659636 -269.519761) (xy 387.61362 -269.502309)
			(xy 387.570999 -269.477702) (xy 387.532878 -269.446577) (xy 387.500243 -269.40974) (xy 387.47394 -269.368144)
			(xy 387.454649 -269.322868) (xy 387.442872 -269.275084) (xy 387.438912 -269.22603) (xy 387.110224 -269.22603)
			(xy 387.109729 -269.250637) (xy 387.101834 -269.299214) (xy 387.08625 -269.345895) (xy 387.063379 -269.389472)
			(xy 387.033814 -269.428816) (xy 386.998321 -269.462908) (xy 386.957818 -269.490864) (xy 386.913356 -269.511962)
			(xy 386.866085 -269.525654) (xy 386.81723 -269.531586) (xy 386.768055 -269.529605) (xy 386.719836 -269.519761)
			(xy 386.67382 -269.502309) (xy 386.631199 -269.477702) (xy 386.593078 -269.446577) (xy 386.560443 -269.40974)
			(xy 386.53414 -269.368144) (xy 386.514849 -269.322868) (xy 386.503072 -269.275084) (xy 386.499112 -269.22603)
			(xy 386.17017 -269.22603) (xy 386.169675 -269.250637) (xy 386.16178 -269.299214) (xy 386.146196 -269.345895)
			(xy 386.123325 -269.389472) (xy 386.09376 -269.428816) (xy 386.058267 -269.462908) (xy 386.017764 -269.490864)
			(xy 385.973302 -269.511962) (xy 385.926031 -269.525654) (xy 385.877176 -269.531586) (xy 385.828001 -269.529605)
			(xy 385.779782 -269.519761) (xy 385.733766 -269.502309) (xy 385.691145 -269.477702) (xy 385.653024 -269.446577)
			(xy 385.620389 -269.40974) (xy 385.594086 -269.368144) (xy 385.574795 -269.322868) (xy 385.563018 -269.275084)
			(xy 385.559058 -269.22603) (xy 385.230116 -269.22603) (xy 385.229621 -269.250637) (xy 385.221726 -269.299214)
			(xy 385.206142 -269.345895) (xy 385.183271 -269.389472) (xy 385.153706 -269.428816) (xy 385.118213 -269.462908)
			(xy 385.07771 -269.490864) (xy 385.033248 -269.511962) (xy 384.985977 -269.525654) (xy 384.937122 -269.531586)
			(xy 384.887947 -269.529605) (xy 384.839728 -269.519761) (xy 384.793712 -269.502309) (xy 384.751091 -269.477702)
			(xy 384.71297 -269.446577) (xy 384.680335 -269.40974) (xy 384.654032 -269.368144) (xy 384.634741 -269.322868)
			(xy 384.622964 -269.275084) (xy 384.619004 -269.22603) (xy 384.290062 -269.22603) (xy 384.289567 -269.250637)
			(xy 384.281672 -269.299214) (xy 384.266088 -269.345895) (xy 384.243217 -269.389472) (xy 384.213652 -269.428816)
			(xy 384.178159 -269.462908) (xy 384.137656 -269.490864) (xy 384.093194 -269.511962) (xy 384.045923 -269.525654)
			(xy 383.997068 -269.531586) (xy 383.947893 -269.529605) (xy 383.899674 -269.519761) (xy 383.853658 -269.502309)
			(xy 383.811037 -269.477702) (xy 383.772916 -269.446577) (xy 383.740281 -269.40974) (xy 383.713978 -269.368144)
			(xy 383.694687 -269.322868) (xy 383.68291 -269.275084) (xy 383.67895 -269.22603) (xy 383.350008 -269.22603)
			(xy 383.349513 -269.250637) (xy 383.341618 -269.299214) (xy 383.326034 -269.345895) (xy 383.303163 -269.389472)
			(xy 383.273598 -269.428816) (xy 383.238105 -269.462908) (xy 383.197602 -269.490864) (xy 383.15314 -269.511962)
			(xy 383.105869 -269.525654) (xy 383.057014 -269.531586) (xy 383.007839 -269.529605) (xy 382.95962 -269.519761)
			(xy 382.913604 -269.502309) (xy 382.870983 -269.477702) (xy 382.832862 -269.446577) (xy 382.800227 -269.40974)
			(xy 382.773924 -269.368144) (xy 382.754633 -269.322868) (xy 382.742856 -269.275084) (xy 382.738896 -269.22603)
			(xy 382.410208 -269.22603) (xy 382.409713 -269.250637) (xy 382.401818 -269.299214) (xy 382.386234 -269.345895)
			(xy 382.363363 -269.389472) (xy 382.333798 -269.428816) (xy 382.298305 -269.462908) (xy 382.257802 -269.490864)
			(xy 382.21334 -269.511962) (xy 382.166069 -269.525654) (xy 382.117214 -269.531586) (xy 382.068039 -269.529605)
			(xy 382.01982 -269.519761) (xy 381.973804 -269.502309) (xy 381.931183 -269.477702) (xy 381.893062 -269.446577)
			(xy 381.860427 -269.40974) (xy 381.834124 -269.368144) (xy 381.814833 -269.322868) (xy 381.803056 -269.275084)
			(xy 381.799096 -269.22603) (xy 381.480568 -269.22603) (xy 381.480056 -269.251476) (xy 381.471892 -269.30171)
			(xy 381.455776 -269.349984) (xy 381.432125 -269.395047) (xy 381.401552 -269.435733) (xy 381.364848 -269.470988)
			(xy 381.322964 -269.499898) (xy 381.276985 -269.521715) (xy 381.228101 -269.535875) (xy 381.17758 -269.542009)
			(xy 381.126728 -269.53996) (xy 381.076864 -269.52978) (xy 381.029278 -269.511733) (xy 380.985204 -269.486287)
			(xy 380.945782 -269.4541) (xy 380.912034 -269.416006) (xy 380.884833 -269.372992) (xy 380.864885 -269.326172)
			(xy 380.852706 -269.276758) (xy 380.848611 -269.22603) (xy 380.5301 -269.22603) (xy 380.529605 -269.250637)
			(xy 380.52171 -269.299214) (xy 380.506126 -269.345895) (xy 380.483255 -269.389472) (xy 380.45369 -269.428816)
			(xy 380.418197 -269.462908) (xy 380.377694 -269.490864) (xy 380.333232 -269.511962) (xy 380.285961 -269.525654)
			(xy 380.237106 -269.531586) (xy 380.187931 -269.529605) (xy 380.139712 -269.519761) (xy 380.093696 -269.502309)
			(xy 380.051075 -269.477702) (xy 380.012954 -269.446577) (xy 379.980319 -269.40974) (xy 379.954016 -269.368144)
			(xy 379.934725 -269.322868) (xy 379.922948 -269.275084) (xy 379.918988 -269.22603) (xy 379.590046 -269.22603)
			(xy 379.589551 -269.250637) (xy 379.581656 -269.299214) (xy 379.566072 -269.345895) (xy 379.543201 -269.389472)
			(xy 379.513636 -269.428816) (xy 379.478143 -269.462908) (xy 379.43764 -269.490864) (xy 379.393178 -269.511962)
			(xy 379.345907 -269.525654) (xy 379.297052 -269.531586) (xy 379.247877 -269.529605) (xy 379.199658 -269.519761)
			(xy 379.153642 -269.502309) (xy 379.111021 -269.477702) (xy 379.0729 -269.446577) (xy 379.040265 -269.40974)
			(xy 379.013962 -269.368144) (xy 378.994671 -269.322868) (xy 378.982894 -269.275084) (xy 378.978934 -269.22603)
			(xy 378.650246 -269.22603) (xy 378.649751 -269.250637) (xy 378.641856 -269.299214) (xy 378.626272 -269.345895)
			(xy 378.603401 -269.389472) (xy 378.573836 -269.428816) (xy 378.538343 -269.462908) (xy 378.49784 -269.490864)
			(xy 378.453378 -269.511962) (xy 378.406107 -269.525654) (xy 378.357252 -269.531586) (xy 378.308077 -269.529605)
			(xy 378.259858 -269.519761) (xy 378.213842 -269.502309) (xy 378.171221 -269.477702) (xy 378.1331 -269.446577)
			(xy 378.100465 -269.40974) (xy 378.074162 -269.368144) (xy 378.054871 -269.322868) (xy 378.043094 -269.275084)
			(xy 378.039134 -269.22603) (xy 377.720606 -269.22603) (xy 377.720094 -269.251476) (xy 377.71193 -269.30171)
			(xy 377.695814 -269.349984) (xy 377.672163 -269.395047) (xy 377.64159 -269.435733) (xy 377.604886 -269.470988)
			(xy 377.563002 -269.499898) (xy 377.517023 -269.521715) (xy 377.468139 -269.535875) (xy 377.417618 -269.542009)
			(xy 377.366766 -269.53996) (xy 377.316902 -269.52978) (xy 377.269316 -269.511733) (xy 377.225242 -269.486287)
			(xy 377.18582 -269.4541) (xy 377.152072 -269.416006) (xy 377.124871 -269.372992) (xy 377.104923 -269.326172)
			(xy 377.092744 -269.276758) (xy 377.088649 -269.22603) (xy 376.770138 -269.22603) (xy 376.769643 -269.250637)
			(xy 376.761748 -269.299214) (xy 376.746164 -269.345895) (xy 376.723293 -269.389472) (xy 376.693728 -269.428816)
			(xy 376.658235 -269.462908) (xy 376.617732 -269.490864) (xy 376.57327 -269.511962) (xy 376.525999 -269.525654)
			(xy 376.477144 -269.531586) (xy 376.427969 -269.529605) (xy 376.37975 -269.519761) (xy 376.333734 -269.502309)
			(xy 376.291113 -269.477702) (xy 376.252992 -269.446577) (xy 376.220357 -269.40974) (xy 376.194054 -269.368144)
			(xy 376.174763 -269.322868) (xy 376.162986 -269.275084) (xy 376.159026 -269.22603) (xy 375.83065 -269.22603)
			(xy 375.826576 -269.275763) (xy 375.814458 -269.3242) (xy 375.794621 -269.37002) (xy 375.767594 -269.412001)
			(xy 375.734096 -269.449026) (xy 375.69502 -269.480107) (xy 375.651408 -269.504416) (xy 375.604422 -269.521306)
			(xy 375.555314 -269.530326) (xy 375.530364 -269.531338) (xy 375.524268 -269.531338) (xy 375.499681 -269.53085)
			(xy 375.451151 -269.52292) (xy 375.404522 -269.507303) (xy 375.382536 -269.496286) (xy 375.376694 -269.493238)
			(xy 375.364248 -269.490444) (xy 375.358152 -269.490444) (xy 375.352388 -269.490773) (xy 375.341231 -269.49373)
			(xy 375.336054 -269.496286) (xy 375.315734 -269.508478) (xy 375.260108 -269.542006) (xy 375.252938 -269.546716)
			(xy 375.242061 -269.559967) (xy 375.236281 -269.576107) (xy 375.235978 -269.584678) (xy 375.235978 -269.755366)
			(xy 375.236994 -269.765526) (xy 375.24055 -269.776448) (xy 375.25325 -269.80388) (xy 375.260616 -269.810484)
			(xy 375.279037 -269.82797) (xy 375.310376 -269.867935) (xy 375.334669 -269.912536) (xy 375.351244 -269.960543)
			(xy 375.359646 -270.01063) (xy 375.359644 -270.036036) (xy 375.678695 -270.036036) (xy 375.68279 -269.985308)
			(xy 375.694969 -269.935894) (xy 375.714917 -269.889074) (xy 375.742118 -269.84606) (xy 375.775866 -269.807966)
			(xy 375.815288 -269.775779) (xy 375.859362 -269.750333) (xy 375.906948 -269.732286) (xy 375.956812 -269.722106)
			(xy 376.007664 -269.720057) (xy 376.058185 -269.726191) (xy 376.107069 -269.740351) (xy 376.153048 -269.762168)
			(xy 376.194932 -269.791078) (xy 376.231636 -269.826333) (xy 376.262209 -269.867019) (xy 376.28586 -269.912082)
			(xy 376.301976 -269.960356) (xy 376.31014 -270.01059) (xy 376.310652 -270.036036) (xy 376.628926 -270.036036)
			(xy 376.632886 -269.986982) (xy 376.644663 -269.939198) (xy 376.663954 -269.893922) (xy 376.690257 -269.852326)
			(xy 376.722892 -269.815489) (xy 376.761013 -269.784364) (xy 376.803634 -269.759757) (xy 376.84965 -269.742305)
			(xy 376.897869 -269.732461) (xy 376.947044 -269.73048) (xy 376.995899 -269.736412) (xy 377.04317 -269.750104)
			(xy 377.087632 -269.771202) (xy 377.128135 -269.799158) (xy 377.163628 -269.83325) (xy 377.193193 -269.872594)
			(xy 377.216064 -269.916171) (xy 377.231648 -269.962852) (xy 377.239543 -270.011429) (xy 377.240038 -270.036036)
			(xy 377.558549 -270.036036) (xy 377.562644 -269.985308) (xy 377.574823 -269.935894) (xy 377.594771 -269.889074)
			(xy 377.621972 -269.84606) (xy 377.65572 -269.807966) (xy 377.695142 -269.775779) (xy 377.739216 -269.750333)
			(xy 377.786802 -269.732286) (xy 377.836666 -269.722106) (xy 377.887518 -269.720057) (xy 377.938039 -269.726191)
			(xy 377.986923 -269.740351) (xy 378.032902 -269.762168) (xy 378.074786 -269.791078) (xy 378.11149 -269.826333)
			(xy 378.142063 -269.867019) (xy 378.165714 -269.912082) (xy 378.18183 -269.960356) (xy 378.189994 -270.01059)
			(xy 378.190506 -270.036036) (xy 378.509034 -270.036036) (xy 378.512994 -269.986982) (xy 378.524771 -269.939198)
			(xy 378.544062 -269.893922) (xy 378.570365 -269.852326) (xy 378.603 -269.815489) (xy 378.641121 -269.784364)
			(xy 378.683742 -269.759757) (xy 378.729758 -269.742305) (xy 378.777977 -269.732461) (xy 378.827152 -269.73048)
			(xy 378.876007 -269.736412) (xy 378.923278 -269.750104) (xy 378.96774 -269.771202) (xy 379.008243 -269.799158)
			(xy 379.043736 -269.83325) (xy 379.073301 -269.872594) (xy 379.096172 -269.916171) (xy 379.111756 -269.962852)
			(xy 379.119651 -270.011429) (xy 379.120146 -270.036036) (xy 379.438657 -270.036036) (xy 379.442752 -269.985308)
			(xy 379.454931 -269.935894) (xy 379.474879 -269.889074) (xy 379.50208 -269.84606) (xy 379.535828 -269.807966)
			(xy 379.57525 -269.775779) (xy 379.619324 -269.750333) (xy 379.66691 -269.732286) (xy 379.716774 -269.722106)
			(xy 379.767626 -269.720057) (xy 379.818147 -269.726191) (xy 379.867031 -269.740351) (xy 379.91301 -269.762168)
			(xy 379.954894 -269.791078) (xy 379.991598 -269.826333) (xy 380.022171 -269.867019) (xy 380.045822 -269.912082)
			(xy 380.061938 -269.960356) (xy 380.070102 -270.01059) (xy 380.070614 -270.036036) (xy 380.378711 -270.036036)
			(xy 380.382806 -269.985308) (xy 380.394985 -269.935894) (xy 380.414933 -269.889074) (xy 380.442134 -269.84606)
			(xy 380.475882 -269.807966) (xy 380.515304 -269.775779) (xy 380.559378 -269.750333) (xy 380.606964 -269.732286)
			(xy 380.656828 -269.722106) (xy 380.70768 -269.720057) (xy 380.758201 -269.726191) (xy 380.807085 -269.740351)
			(xy 380.853064 -269.762168) (xy 380.894948 -269.791078) (xy 380.931652 -269.826333) (xy 380.962225 -269.867019)
			(xy 380.985876 -269.912082) (xy 381.001992 -269.960356) (xy 381.010156 -270.01059) (xy 381.010668 -270.036036)
			(xy 381.328942 -270.036036) (xy 381.332902 -269.986982) (xy 381.344679 -269.939198) (xy 381.36397 -269.893922)
			(xy 381.390273 -269.852326) (xy 381.422908 -269.815489) (xy 381.461029 -269.784364) (xy 381.50365 -269.759757)
			(xy 381.549666 -269.742305) (xy 381.597885 -269.732461) (xy 381.64706 -269.73048) (xy 381.695915 -269.736412)
			(xy 381.743186 -269.750104) (xy 381.787648 -269.771202) (xy 381.828151 -269.799158) (xy 381.863644 -269.83325)
			(xy 381.893209 -269.872594) (xy 381.91608 -269.916171) (xy 381.931664 -269.962852) (xy 381.939559 -270.011429)
			(xy 381.940054 -270.036036) (xy 382.268996 -270.036036) (xy 382.272956 -269.986982) (xy 382.284733 -269.939198)
			(xy 382.304024 -269.893922) (xy 382.330327 -269.852326) (xy 382.362962 -269.815489) (xy 382.401083 -269.784364)
			(xy 382.443704 -269.759757) (xy 382.48972 -269.742305) (xy 382.537939 -269.732461) (xy 382.587114 -269.73048)
			(xy 382.635969 -269.736412) (xy 382.68324 -269.750104) (xy 382.727702 -269.771202) (xy 382.768205 -269.799158)
			(xy 382.803698 -269.83325) (xy 382.833263 -269.872594) (xy 382.856134 -269.916171) (xy 382.871718 -269.962852)
			(xy 382.879613 -270.011429) (xy 382.880108 -270.036036) (xy 383.20905 -270.036036) (xy 383.21301 -269.986982)
			(xy 383.224787 -269.939198) (xy 383.244078 -269.893922) (xy 383.270381 -269.852326) (xy 383.303016 -269.815489)
			(xy 383.341137 -269.784364) (xy 383.383758 -269.759757) (xy 383.429774 -269.742305) (xy 383.477993 -269.732461)
			(xy 383.527168 -269.73048) (xy 383.576023 -269.736412) (xy 383.623294 -269.750104) (xy 383.667756 -269.771202)
			(xy 383.708259 -269.799158) (xy 383.743752 -269.83325) (xy 383.773317 -269.872594) (xy 383.796188 -269.916171)
			(xy 383.811772 -269.962852) (xy 383.819667 -270.011429) (xy 383.820162 -270.036036) (xy 384.149104 -270.036036)
			(xy 384.153064 -269.986982) (xy 384.164841 -269.939198) (xy 384.184132 -269.893922) (xy 384.210435 -269.852326)
			(xy 384.24307 -269.815489) (xy 384.281191 -269.784364) (xy 384.323812 -269.759757) (xy 384.369828 -269.742305)
			(xy 384.418047 -269.732461) (xy 384.467222 -269.73048) (xy 384.516077 -269.736412) (xy 384.563348 -269.750104)
			(xy 384.60781 -269.771202) (xy 384.648313 -269.799158) (xy 384.683806 -269.83325) (xy 384.713371 -269.872594)
			(xy 384.736242 -269.916171) (xy 384.751826 -269.962852) (xy 384.759721 -270.011429) (xy 384.760216 -270.036036)
			(xy 385.088904 -270.036036) (xy 385.092864 -269.986982) (xy 385.104641 -269.939198) (xy 385.123932 -269.893922)
			(xy 385.150235 -269.852326) (xy 385.18287 -269.815489) (xy 385.220991 -269.784364) (xy 385.263612 -269.759757)
			(xy 385.309628 -269.742305) (xy 385.357847 -269.732461) (xy 385.407022 -269.73048) (xy 385.455877 -269.736412)
			(xy 385.503148 -269.750104) (xy 385.54761 -269.771202) (xy 385.588113 -269.799158) (xy 385.623606 -269.83325)
			(xy 385.653171 -269.872594) (xy 385.676042 -269.916171) (xy 385.691626 -269.962852) (xy 385.699521 -270.011429)
			(xy 385.700016 -270.036036) (xy 386.028958 -270.036036) (xy 386.032918 -269.986982) (xy 386.044695 -269.939198)
			(xy 386.063986 -269.893922) (xy 386.090289 -269.852326) (xy 386.122924 -269.815489) (xy 386.161045 -269.784364)
			(xy 386.203666 -269.759757) (xy 386.249682 -269.742305) (xy 386.297901 -269.732461) (xy 386.347076 -269.73048)
			(xy 386.395931 -269.736412) (xy 386.443202 -269.750104) (xy 386.487664 -269.771202) (xy 386.528167 -269.799158)
			(xy 386.56366 -269.83325) (xy 386.593225 -269.872594) (xy 386.616096 -269.916171) (xy 386.63168 -269.962852)
			(xy 386.639575 -270.011429) (xy 386.64007 -270.036036) (xy 386.969012 -270.036036) (xy 386.972972 -269.986982)
			(xy 386.984749 -269.939198) (xy 387.00404 -269.893922) (xy 387.030343 -269.852326) (xy 387.062978 -269.815489)
			(xy 387.101099 -269.784364) (xy 387.14372 -269.759757) (xy 387.189736 -269.742305) (xy 387.237955 -269.732461)
			(xy 387.28713 -269.73048) (xy 387.335985 -269.736412) (xy 387.383256 -269.750104) (xy 387.427718 -269.771202)
			(xy 387.468221 -269.799158) (xy 387.503714 -269.83325) (xy 387.533279 -269.872594) (xy 387.55615 -269.916171)
			(xy 387.571734 -269.962852) (xy 387.579629 -270.011429) (xy 387.580124 -270.036036) (xy 387.579629 -270.060643)
			(xy 387.571734 -270.10922) (xy 387.55615 -270.155901) (xy 387.533279 -270.199478) (xy 387.503714 -270.238822)
			(xy 387.468221 -270.272914) (xy 387.427718 -270.30087) (xy 387.383256 -270.321968) (xy 387.335985 -270.33566)
			(xy 387.28713 -270.341592) (xy 387.237955 -270.339611) (xy 387.189736 -270.329767) (xy 387.14372 -270.312315)
			(xy 387.101099 -270.287708) (xy 387.062978 -270.256583) (xy 387.030343 -270.219746) (xy 387.00404 -270.17815)
			(xy 386.984749 -270.132874) (xy 386.972972 -270.08509) (xy 386.969012 -270.036036) (xy 386.64007 -270.036036)
			(xy 386.639575 -270.060643) (xy 386.63168 -270.10922) (xy 386.616096 -270.155901) (xy 386.593225 -270.199478)
			(xy 386.56366 -270.238822) (xy 386.528167 -270.272914) (xy 386.487664 -270.30087) (xy 386.443202 -270.321968)
			(xy 386.395931 -270.33566) (xy 386.347076 -270.341592) (xy 386.297901 -270.339611) (xy 386.249682 -270.329767)
			(xy 386.203666 -270.312315) (xy 386.161045 -270.287708) (xy 386.122924 -270.256583) (xy 386.090289 -270.219746)
			(xy 386.063986 -270.17815) (xy 386.044695 -270.132874) (xy 386.032918 -270.08509) (xy 386.028958 -270.036036)
			(xy 385.700016 -270.036036) (xy 385.699521 -270.060643) (xy 385.691626 -270.10922) (xy 385.676042 -270.155901)
			(xy 385.653171 -270.199478) (xy 385.623606 -270.238822) (xy 385.588113 -270.272914) (xy 385.54761 -270.30087)
			(xy 385.503148 -270.321968) (xy 385.455877 -270.33566) (xy 385.407022 -270.341592) (xy 385.357847 -270.339611)
			(xy 385.309628 -270.329767) (xy 385.263612 -270.312315) (xy 385.220991 -270.287708) (xy 385.18287 -270.256583)
			(xy 385.150235 -270.219746) (xy 385.123932 -270.17815) (xy 385.104641 -270.132874) (xy 385.092864 -270.08509)
			(xy 385.088904 -270.036036) (xy 384.760216 -270.036036) (xy 384.759721 -270.060643) (xy 384.751826 -270.10922)
			(xy 384.736242 -270.155901) (xy 384.713371 -270.199478) (xy 384.683806 -270.238822) (xy 384.648313 -270.272914)
			(xy 384.60781 -270.30087) (xy 384.563348 -270.321968) (xy 384.516077 -270.33566) (xy 384.467222 -270.341592)
			(xy 384.418047 -270.339611) (xy 384.369828 -270.329767) (xy 384.323812 -270.312315) (xy 384.281191 -270.287708)
			(xy 384.24307 -270.256583) (xy 384.210435 -270.219746) (xy 384.184132 -270.17815) (xy 384.164841 -270.132874)
			(xy 384.153064 -270.08509) (xy 384.149104 -270.036036) (xy 383.820162 -270.036036) (xy 383.819667 -270.060643)
			(xy 383.811772 -270.10922) (xy 383.796188 -270.155901) (xy 383.773317 -270.199478) (xy 383.743752 -270.238822)
			(xy 383.708259 -270.272914) (xy 383.667756 -270.30087) (xy 383.623294 -270.321968) (xy 383.576023 -270.33566)
			(xy 383.527168 -270.341592) (xy 383.477993 -270.339611) (xy 383.429774 -270.329767) (xy 383.383758 -270.312315)
			(xy 383.341137 -270.287708) (xy 383.303016 -270.256583) (xy 383.270381 -270.219746) (xy 383.244078 -270.17815)
			(xy 383.224787 -270.132874) (xy 383.21301 -270.08509) (xy 383.20905 -270.036036) (xy 382.880108 -270.036036)
			(xy 382.879613 -270.060643) (xy 382.871718 -270.10922) (xy 382.856134 -270.155901) (xy 382.833263 -270.199478)
			(xy 382.803698 -270.238822) (xy 382.768205 -270.272914) (xy 382.727702 -270.30087) (xy 382.68324 -270.321968)
			(xy 382.635969 -270.33566) (xy 382.587114 -270.341592) (xy 382.537939 -270.339611) (xy 382.48972 -270.329767)
			(xy 382.443704 -270.312315) (xy 382.401083 -270.287708) (xy 382.362962 -270.256583) (xy 382.330327 -270.219746)
			(xy 382.304024 -270.17815) (xy 382.284733 -270.132874) (xy 382.272956 -270.08509) (xy 382.268996 -270.036036)
			(xy 381.940054 -270.036036) (xy 381.939559 -270.060643) (xy 381.931664 -270.10922) (xy 381.91608 -270.155901)
			(xy 381.893209 -270.199478) (xy 381.863644 -270.238822) (xy 381.828151 -270.272914) (xy 381.787648 -270.30087)
			(xy 381.743186 -270.321968) (xy 381.695915 -270.33566) (xy 381.64706 -270.341592) (xy 381.597885 -270.339611)
			(xy 381.549666 -270.329767) (xy 381.50365 -270.312315) (xy 381.461029 -270.287708) (xy 381.422908 -270.256583)
			(xy 381.390273 -270.219746) (xy 381.36397 -270.17815) (xy 381.344679 -270.132874) (xy 381.332902 -270.08509)
			(xy 381.328942 -270.036036) (xy 381.010668 -270.036036) (xy 381.010156 -270.061482) (xy 381.001992 -270.111716)
			(xy 380.985876 -270.15999) (xy 380.962225 -270.205053) (xy 380.931652 -270.245739) (xy 380.894948 -270.280994)
			(xy 380.853064 -270.309904) (xy 380.807085 -270.331721) (xy 380.758201 -270.345881) (xy 380.70768 -270.352015)
			(xy 380.656828 -270.349966) (xy 380.606964 -270.339786) (xy 380.559378 -270.321739) (xy 380.515304 -270.296293)
			(xy 380.475882 -270.264106) (xy 380.442134 -270.226012) (xy 380.414933 -270.182998) (xy 380.394985 -270.136178)
			(xy 380.382806 -270.086764) (xy 380.378711 -270.036036) (xy 380.070614 -270.036036) (xy 380.070102 -270.061482)
			(xy 380.061938 -270.111716) (xy 380.045822 -270.15999) (xy 380.022171 -270.205053) (xy 379.991598 -270.245739)
			(xy 379.954894 -270.280994) (xy 379.91301 -270.309904) (xy 379.867031 -270.331721) (xy 379.818147 -270.345881)
			(xy 379.767626 -270.352015) (xy 379.716774 -270.349966) (xy 379.66691 -270.339786) (xy 379.619324 -270.321739)
			(xy 379.57525 -270.296293) (xy 379.535828 -270.264106) (xy 379.50208 -270.226012) (xy 379.474879 -270.182998)
			(xy 379.454931 -270.136178) (xy 379.442752 -270.086764) (xy 379.438657 -270.036036) (xy 379.120146 -270.036036)
			(xy 379.119651 -270.060643) (xy 379.111756 -270.10922) (xy 379.096172 -270.155901) (xy 379.073301 -270.199478)
			(xy 379.043736 -270.238822) (xy 379.008243 -270.272914) (xy 378.96774 -270.30087) (xy 378.923278 -270.321968)
			(xy 378.876007 -270.33566) (xy 378.827152 -270.341592) (xy 378.777977 -270.339611) (xy 378.729758 -270.329767)
			(xy 378.683742 -270.312315) (xy 378.641121 -270.287708) (xy 378.603 -270.256583) (xy 378.570365 -270.219746)
			(xy 378.544062 -270.17815) (xy 378.524771 -270.132874) (xy 378.512994 -270.08509) (xy 378.509034 -270.036036)
			(xy 378.190506 -270.036036) (xy 378.189994 -270.061482) (xy 378.18183 -270.111716) (xy 378.165714 -270.15999)
			(xy 378.142063 -270.205053) (xy 378.11149 -270.245739) (xy 378.074786 -270.280994) (xy 378.032902 -270.309904)
			(xy 377.986923 -270.331721) (xy 377.938039 -270.345881) (xy 377.887518 -270.352015) (xy 377.836666 -270.349966)
			(xy 377.786802 -270.339786) (xy 377.739216 -270.321739) (xy 377.695142 -270.296293) (xy 377.65572 -270.264106)
			(xy 377.621972 -270.226012) (xy 377.594771 -270.182998) (xy 377.574823 -270.136178) (xy 377.562644 -270.086764)
			(xy 377.558549 -270.036036) (xy 377.240038 -270.036036) (xy 377.239543 -270.060643) (xy 377.231648 -270.10922)
			(xy 377.216064 -270.155901) (xy 377.193193 -270.199478) (xy 377.163628 -270.238822) (xy 377.128135 -270.272914)
			(xy 377.087632 -270.30087) (xy 377.04317 -270.321968) (xy 376.995899 -270.33566) (xy 376.947044 -270.341592)
			(xy 376.897869 -270.339611) (xy 376.84965 -270.329767) (xy 376.803634 -270.312315) (xy 376.761013 -270.287708)
			(xy 376.722892 -270.256583) (xy 376.690257 -270.219746) (xy 376.663954 -270.17815) (xy 376.644663 -270.132874)
			(xy 376.632886 -270.08509) (xy 376.628926 -270.036036) (xy 376.310652 -270.036036) (xy 376.31014 -270.061482)
			(xy 376.301976 -270.111716) (xy 376.28586 -270.15999) (xy 376.262209 -270.205053) (xy 376.231636 -270.245739)
			(xy 376.194932 -270.280994) (xy 376.153048 -270.309904) (xy 376.107069 -270.331721) (xy 376.058185 -270.345881)
			(xy 376.007664 -270.352015) (xy 375.956812 -270.349966) (xy 375.906948 -270.339786) (xy 375.859362 -270.321739)
			(xy 375.815288 -270.296293) (xy 375.775866 -270.264106) (xy 375.742118 -270.226012) (xy 375.714917 -270.182998)
			(xy 375.694969 -270.136178) (xy 375.68279 -270.086764) (xy 375.678695 -270.036036) (xy 375.359644 -270.036036)
			(xy 375.359642 -270.061418) (xy 375.351232 -270.111504) (xy 375.334649 -270.159508) (xy 375.31035 -270.204105)
			(xy 375.279004 -270.244066) (xy 375.260616 -270.261588) (xy 375.25325 -270.268192) (xy 375.240804 -270.29537)
			(xy 375.23674 -270.307816) (xy 375.235978 -270.316452) (xy 375.235978 -270.846042) (xy 376.148595 -270.846042)
			(xy 376.15269 -270.795314) (xy 376.164869 -270.7459) (xy 376.184817 -270.69908) (xy 376.212018 -270.656066)
			(xy 376.245766 -270.617972) (xy 376.285188 -270.585785) (xy 376.329262 -270.560339) (xy 376.376848 -270.542292)
			(xy 376.426712 -270.532112) (xy 376.477564 -270.530063) (xy 376.528085 -270.536197) (xy 376.576969 -270.550357)
			(xy 376.622948 -270.572174) (xy 376.664832 -270.601084) (xy 376.701536 -270.636339) (xy 376.732109 -270.677025)
			(xy 376.75576 -270.722088) (xy 376.771876 -270.770362) (xy 376.78004 -270.820596) (xy 376.780552 -270.846042)
			(xy 377.088649 -270.846042) (xy 377.092744 -270.795314) (xy 377.104923 -270.7459) (xy 377.124871 -270.69908)
			(xy 377.152072 -270.656066) (xy 377.18582 -270.617972) (xy 377.225242 -270.585785) (xy 377.269316 -270.560339)
			(xy 377.316902 -270.542292) (xy 377.366766 -270.532112) (xy 377.417618 -270.530063) (xy 377.468139 -270.536197)
			(xy 377.517023 -270.550357) (xy 377.563002 -270.572174) (xy 377.604886 -270.601084) (xy 377.64159 -270.636339)
			(xy 377.672163 -270.677025) (xy 377.695814 -270.722088) (xy 377.71193 -270.770362) (xy 377.720094 -270.820596)
			(xy 377.720606 -270.846042) (xy 378.968503 -270.846042) (xy 378.972598 -270.795314) (xy 378.984777 -270.7459)
			(xy 379.004725 -270.69908) (xy 379.031926 -270.656066) (xy 379.065674 -270.617972) (xy 379.105096 -270.585785)
			(xy 379.14917 -270.560339) (xy 379.196756 -270.542292) (xy 379.24662 -270.532112) (xy 379.297472 -270.530063)
			(xy 379.347993 -270.536197) (xy 379.396877 -270.550357) (xy 379.442856 -270.572174) (xy 379.48474 -270.601084)
			(xy 379.521444 -270.636339) (xy 379.552017 -270.677025) (xy 379.575668 -270.722088) (xy 379.591784 -270.770362)
			(xy 379.599948 -270.820596) (xy 379.60046 -270.846042) (xy 379.918988 -270.846042) (xy 379.922948 -270.796988)
			(xy 379.934725 -270.749204) (xy 379.954016 -270.703928) (xy 379.980319 -270.662332) (xy 380.012954 -270.625495)
			(xy 380.051075 -270.59437) (xy 380.093696 -270.569763) (xy 380.139712 -270.552311) (xy 380.187931 -270.542467)
			(xy 380.237106 -270.540486) (xy 380.285961 -270.546418) (xy 380.333232 -270.56011) (xy 380.377694 -270.581208)
			(xy 380.418197 -270.609164) (xy 380.45369 -270.643256) (xy 380.483255 -270.6826) (xy 380.506126 -270.726177)
			(xy 380.52171 -270.772858) (xy 380.529605 -270.821435) (xy 380.5301 -270.846042) (xy 380.848611 -270.846042)
			(xy 380.852706 -270.795314) (xy 380.864885 -270.7459) (xy 380.884833 -270.69908) (xy 380.912034 -270.656066)
			(xy 380.945782 -270.617972) (xy 380.985204 -270.585785) (xy 381.029278 -270.560339) (xy 381.076864 -270.542292)
			(xy 381.126728 -270.532112) (xy 381.17758 -270.530063) (xy 381.228101 -270.536197) (xy 381.276985 -270.550357)
			(xy 381.322964 -270.572174) (xy 381.364848 -270.601084) (xy 381.401552 -270.636339) (xy 381.432125 -270.677025)
			(xy 381.455776 -270.722088) (xy 381.471892 -270.770362) (xy 381.480056 -270.820596) (xy 381.480568 -270.846042)
			(xy 381.799096 -270.846042) (xy 381.803056 -270.796988) (xy 381.814833 -270.749204) (xy 381.834124 -270.703928)
			(xy 381.860427 -270.662332) (xy 381.893062 -270.625495) (xy 381.931183 -270.59437) (xy 381.973804 -270.569763)
			(xy 382.01982 -270.552311) (xy 382.068039 -270.542467) (xy 382.117214 -270.540486) (xy 382.166069 -270.546418)
			(xy 382.21334 -270.56011) (xy 382.257802 -270.581208) (xy 382.298305 -270.609164) (xy 382.333798 -270.643256)
			(xy 382.363363 -270.6826) (xy 382.386234 -270.726177) (xy 382.401818 -270.772858) (xy 382.409713 -270.821435)
			(xy 382.410208 -270.846042) (xy 382.738896 -270.846042) (xy 382.742856 -270.796988) (xy 382.754633 -270.749204)
			(xy 382.773924 -270.703928) (xy 382.800227 -270.662332) (xy 382.832862 -270.625495) (xy 382.870983 -270.59437)
			(xy 382.913604 -270.569763) (xy 382.95962 -270.552311) (xy 383.007839 -270.542467) (xy 383.057014 -270.540486)
			(xy 383.105869 -270.546418) (xy 383.15314 -270.56011) (xy 383.197602 -270.581208) (xy 383.238105 -270.609164)
			(xy 383.273598 -270.643256) (xy 383.303163 -270.6826) (xy 383.326034 -270.726177) (xy 383.341618 -270.772858)
			(xy 383.349513 -270.821435) (xy 383.350008 -270.846042) (xy 383.67895 -270.846042) (xy 383.68291 -270.796988)
			(xy 383.694687 -270.749204) (xy 383.713978 -270.703928) (xy 383.740281 -270.662332) (xy 383.772916 -270.625495)
			(xy 383.811037 -270.59437) (xy 383.853658 -270.569763) (xy 383.899674 -270.552311) (xy 383.947893 -270.542467)
			(xy 383.997068 -270.540486) (xy 384.045923 -270.546418) (xy 384.093194 -270.56011) (xy 384.137656 -270.581208)
			(xy 384.178159 -270.609164) (xy 384.213652 -270.643256) (xy 384.243217 -270.6826) (xy 384.266088 -270.726177)
			(xy 384.281672 -270.772858) (xy 384.289567 -270.821435) (xy 384.290062 -270.846042) (xy 385.559058 -270.846042)
			(xy 385.563018 -270.796988) (xy 385.574795 -270.749204) (xy 385.594086 -270.703928) (xy 385.620389 -270.662332)
			(xy 385.653024 -270.625495) (xy 385.691145 -270.59437) (xy 385.733766 -270.569763) (xy 385.779782 -270.552311)
			(xy 385.828001 -270.542467) (xy 385.877176 -270.540486) (xy 385.926031 -270.546418) (xy 385.973302 -270.56011)
			(xy 386.017764 -270.581208) (xy 386.058267 -270.609164) (xy 386.09376 -270.643256) (xy 386.123325 -270.6826)
			(xy 386.146196 -270.726177) (xy 386.16178 -270.772858) (xy 386.169675 -270.821435) (xy 386.17017 -270.846042)
			(xy 386.499112 -270.846042) (xy 386.503072 -270.796988) (xy 386.514849 -270.749204) (xy 386.53414 -270.703928)
			(xy 386.560443 -270.662332) (xy 386.593078 -270.625495) (xy 386.631199 -270.59437) (xy 386.67382 -270.569763)
			(xy 386.719836 -270.552311) (xy 386.768055 -270.542467) (xy 386.81723 -270.540486) (xy 386.866085 -270.546418)
			(xy 386.913356 -270.56011) (xy 386.957818 -270.581208) (xy 386.998321 -270.609164) (xy 387.033814 -270.643256)
			(xy 387.063379 -270.6826) (xy 387.08625 -270.726177) (xy 387.101834 -270.772858) (xy 387.109729 -270.821435)
			(xy 387.110224 -270.846042) (xy 387.438912 -270.846042) (xy 387.442872 -270.796988) (xy 387.454649 -270.749204)
			(xy 387.47394 -270.703928) (xy 387.500243 -270.662332) (xy 387.532878 -270.625495) (xy 387.570999 -270.59437)
			(xy 387.61362 -270.569763) (xy 387.659636 -270.552311) (xy 387.707855 -270.542467) (xy 387.75703 -270.540486)
			(xy 387.805885 -270.546418) (xy 387.853156 -270.56011) (xy 387.897618 -270.581208) (xy 387.938121 -270.609164)
			(xy 387.973614 -270.643256) (xy 388.003179 -270.6826) (xy 388.02605 -270.726177) (xy 388.041634 -270.772858)
			(xy 388.049529 -270.821435) (xy 388.050024 -270.846042) (xy 388.049529 -270.870649) (xy 388.041634 -270.919226)
			(xy 388.02605 -270.965907) (xy 388.003179 -271.009484) (xy 387.973614 -271.048828) (xy 387.938121 -271.08292)
			(xy 387.897618 -271.110876) (xy 387.853156 -271.131974) (xy 387.805885 -271.145666) (xy 387.75703 -271.151598)
			(xy 387.707855 -271.149617) (xy 387.659636 -271.139773) (xy 387.61362 -271.122321) (xy 387.570999 -271.097714)
			(xy 387.532878 -271.066589) (xy 387.500243 -271.029752) (xy 387.47394 -270.988156) (xy 387.454649 -270.94288)
			(xy 387.442872 -270.895096) (xy 387.438912 -270.846042) (xy 387.110224 -270.846042) (xy 387.109729 -270.870649)
			(xy 387.101834 -270.919226) (xy 387.08625 -270.965907) (xy 387.063379 -271.009484) (xy 387.033814 -271.048828)
			(xy 386.998321 -271.08292) (xy 386.957818 -271.110876) (xy 386.913356 -271.131974) (xy 386.866085 -271.145666)
			(xy 386.81723 -271.151598) (xy 386.768055 -271.149617) (xy 386.719836 -271.139773) (xy 386.67382 -271.122321)
			(xy 386.631199 -271.097714) (xy 386.593078 -271.066589) (xy 386.560443 -271.029752) (xy 386.53414 -270.988156)
			(xy 386.514849 -270.94288) (xy 386.503072 -270.895096) (xy 386.499112 -270.846042) (xy 386.17017 -270.846042)
			(xy 386.169675 -270.870649) (xy 386.16178 -270.919226) (xy 386.146196 -270.965907) (xy 386.123325 -271.009484)
			(xy 386.09376 -271.048828) (xy 386.058267 -271.08292) (xy 386.017764 -271.110876) (xy 385.973302 -271.131974)
			(xy 385.926031 -271.145666) (xy 385.877176 -271.151598) (xy 385.828001 -271.149617) (xy 385.779782 -271.139773)
			(xy 385.733766 -271.122321) (xy 385.691145 -271.097714) (xy 385.653024 -271.066589) (xy 385.620389 -271.029752)
			(xy 385.594086 -270.988156) (xy 385.574795 -270.94288) (xy 385.563018 -270.895096) (xy 385.559058 -270.846042)
			(xy 384.290062 -270.846042) (xy 384.289567 -270.870649) (xy 384.281672 -270.919226) (xy 384.266088 -270.965907)
			(xy 384.243217 -271.009484) (xy 384.213652 -271.048828) (xy 384.178159 -271.08292) (xy 384.137656 -271.110876)
			(xy 384.093194 -271.131974) (xy 384.045923 -271.145666) (xy 383.997068 -271.151598) (xy 383.947893 -271.149617)
			(xy 383.899674 -271.139773) (xy 383.853658 -271.122321) (xy 383.811037 -271.097714) (xy 383.772916 -271.066589)
			(xy 383.740281 -271.029752) (xy 383.713978 -270.988156) (xy 383.694687 -270.94288) (xy 383.68291 -270.895096)
			(xy 383.67895 -270.846042) (xy 383.350008 -270.846042) (xy 383.349513 -270.870649) (xy 383.341618 -270.919226)
			(xy 383.326034 -270.965907) (xy 383.303163 -271.009484) (xy 383.273598 -271.048828) (xy 383.238105 -271.08292)
			(xy 383.197602 -271.110876) (xy 383.15314 -271.131974) (xy 383.105869 -271.145666) (xy 383.057014 -271.151598)
			(xy 383.007839 -271.149617) (xy 382.95962 -271.139773) (xy 382.913604 -271.122321) (xy 382.870983 -271.097714)
			(xy 382.832862 -271.066589) (xy 382.800227 -271.029752) (xy 382.773924 -270.988156) (xy 382.754633 -270.94288)
			(xy 382.742856 -270.895096) (xy 382.738896 -270.846042) (xy 382.410208 -270.846042) (xy 382.409713 -270.870649)
			(xy 382.401818 -270.919226) (xy 382.386234 -270.965907) (xy 382.363363 -271.009484) (xy 382.333798 -271.048828)
			(xy 382.298305 -271.08292) (xy 382.257802 -271.110876) (xy 382.21334 -271.131974) (xy 382.166069 -271.145666)
			(xy 382.117214 -271.151598) (xy 382.068039 -271.149617) (xy 382.01982 -271.139773) (xy 381.973804 -271.122321)
			(xy 381.931183 -271.097714) (xy 381.893062 -271.066589) (xy 381.860427 -271.029752) (xy 381.834124 -270.988156)
			(xy 381.814833 -270.94288) (xy 381.803056 -270.895096) (xy 381.799096 -270.846042) (xy 381.480568 -270.846042)
			(xy 381.480056 -270.871488) (xy 381.471892 -270.921722) (xy 381.455776 -270.969996) (xy 381.432125 -271.015059)
			(xy 381.401552 -271.055745) (xy 381.364848 -271.091) (xy 381.322964 -271.11991) (xy 381.276985 -271.141727)
			(xy 381.228101 -271.155887) (xy 381.17758 -271.162021) (xy 381.126728 -271.159972) (xy 381.076864 -271.149792)
			(xy 381.029278 -271.131745) (xy 380.985204 -271.106299) (xy 380.945782 -271.074112) (xy 380.912034 -271.036018)
			(xy 380.884833 -270.993004) (xy 380.864885 -270.946184) (xy 380.852706 -270.89677) (xy 380.848611 -270.846042)
			(xy 380.5301 -270.846042) (xy 380.529605 -270.870649) (xy 380.52171 -270.919226) (xy 380.506126 -270.965907)
			(xy 380.483255 -271.009484) (xy 380.45369 -271.048828) (xy 380.418197 -271.08292) (xy 380.377694 -271.110876)
			(xy 380.333232 -271.131974) (xy 380.285961 -271.145666) (xy 380.237106 -271.151598) (xy 380.187931 -271.149617)
			(xy 380.139712 -271.139773) (xy 380.093696 -271.122321) (xy 380.051075 -271.097714) (xy 380.012954 -271.066589)
			(xy 379.980319 -271.029752) (xy 379.954016 -270.988156) (xy 379.934725 -270.94288) (xy 379.922948 -270.895096)
			(xy 379.918988 -270.846042) (xy 379.60046 -270.846042) (xy 379.599948 -270.871488) (xy 379.591784 -270.921722)
			(xy 379.575668 -270.969996) (xy 379.552017 -271.015059) (xy 379.521444 -271.055745) (xy 379.48474 -271.091)
			(xy 379.442856 -271.11991) (xy 379.396877 -271.141727) (xy 379.347993 -271.155887) (xy 379.297472 -271.162021)
			(xy 379.24662 -271.159972) (xy 379.196756 -271.149792) (xy 379.14917 -271.131745) (xy 379.105096 -271.106299)
			(xy 379.065674 -271.074112) (xy 379.031926 -271.036018) (xy 379.004725 -270.993004) (xy 378.984777 -270.946184)
			(xy 378.972598 -270.89677) (xy 378.968503 -270.846042) (xy 377.720606 -270.846042) (xy 377.720094 -270.871488)
			(xy 377.71193 -270.921722) (xy 377.695814 -270.969996) (xy 377.672163 -271.015059) (xy 377.64159 -271.055745)
			(xy 377.604886 -271.091) (xy 377.563002 -271.11991) (xy 377.517023 -271.141727) (xy 377.468139 -271.155887)
			(xy 377.417618 -271.162021) (xy 377.366766 -271.159972) (xy 377.316902 -271.149792) (xy 377.269316 -271.131745)
			(xy 377.225242 -271.106299) (xy 377.18582 -271.074112) (xy 377.152072 -271.036018) (xy 377.124871 -270.993004)
			(xy 377.104923 -270.946184) (xy 377.092744 -270.89677) (xy 377.088649 -270.846042) (xy 376.780552 -270.846042)
			(xy 376.78004 -270.871488) (xy 376.771876 -270.921722) (xy 376.75576 -270.969996) (xy 376.732109 -271.015059)
			(xy 376.701536 -271.055745) (xy 376.664832 -271.091) (xy 376.622948 -271.11991) (xy 376.576969 -271.141727)
			(xy 376.528085 -271.155887) (xy 376.477564 -271.162021) (xy 376.426712 -271.159972) (xy 376.376848 -271.149792)
			(xy 376.329262 -271.131745) (xy 376.285188 -271.106299) (xy 376.245766 -271.074112) (xy 376.212018 -271.036018)
			(xy 376.184817 -270.993004) (xy 376.164869 -270.946184) (xy 376.15269 -270.89677) (xy 376.148595 -270.846042)
			(xy 375.235978 -270.846042) (xy 375.235978 -271.375378) (xy 375.236994 -271.385538) (xy 375.24055 -271.39646)
			(xy 375.25325 -271.423892) (xy 375.260616 -271.430496) (xy 375.279036 -271.447982) (xy 375.310373 -271.487947)
			(xy 375.334664 -271.532547) (xy 375.351238 -271.580553) (xy 375.359638 -271.630639) (xy 375.359635 -271.656048)
			(xy 375.678695 -271.656048) (xy 375.68279 -271.60532) (xy 375.694969 -271.555906) (xy 375.714917 -271.509086)
			(xy 375.742118 -271.466072) (xy 375.775866 -271.427978) (xy 375.815288 -271.395791) (xy 375.859362 -271.370345)
			(xy 375.906948 -271.352298) (xy 375.956812 -271.342118) (xy 376.007664 -271.340069) (xy 376.058185 -271.346203)
			(xy 376.107069 -271.360363) (xy 376.153048 -271.38218) (xy 376.194932 -271.41109) (xy 376.231636 -271.446345)
			(xy 376.262209 -271.487031) (xy 376.28586 -271.532094) (xy 376.301976 -271.580368) (xy 376.31014 -271.630602)
			(xy 376.310652 -271.656048) (xy 376.628926 -271.656048) (xy 376.632886 -271.606994) (xy 376.644663 -271.55921)
			(xy 376.663954 -271.513934) (xy 376.690257 -271.472338) (xy 376.722892 -271.435501) (xy 376.761013 -271.404376)
			(xy 376.803634 -271.379769) (xy 376.84965 -271.362317) (xy 376.897869 -271.352473) (xy 376.947044 -271.350492)
			(xy 376.995899 -271.356424) (xy 377.04317 -271.370116) (xy 377.087632 -271.391214) (xy 377.128135 -271.41917)
			(xy 377.163628 -271.453262) (xy 377.193193 -271.492606) (xy 377.216064 -271.536183) (xy 377.231648 -271.582864)
			(xy 377.239543 -271.631441) (xy 377.240038 -271.656048) (xy 377.558549 -271.656048) (xy 377.562644 -271.60532)
			(xy 377.574823 -271.555906) (xy 377.594771 -271.509086) (xy 377.621972 -271.466072) (xy 377.65572 -271.427978)
			(xy 377.695142 -271.395791) (xy 377.739216 -271.370345) (xy 377.786802 -271.352298) (xy 377.836666 -271.342118)
			(xy 377.887518 -271.340069) (xy 377.938039 -271.346203) (xy 377.986923 -271.360363) (xy 378.032902 -271.38218)
			(xy 378.074786 -271.41109) (xy 378.11149 -271.446345) (xy 378.142063 -271.487031) (xy 378.165714 -271.532094)
			(xy 378.18183 -271.580368) (xy 378.189994 -271.630602) (xy 378.190506 -271.656048) (xy 378.509034 -271.656048)
			(xy 378.512994 -271.606994) (xy 378.524771 -271.55921) (xy 378.544062 -271.513934) (xy 378.570365 -271.472338)
			(xy 378.603 -271.435501) (xy 378.641121 -271.404376) (xy 378.683742 -271.379769) (xy 378.729758 -271.362317)
			(xy 378.777977 -271.352473) (xy 378.827152 -271.350492) (xy 378.876007 -271.356424) (xy 378.923278 -271.370116)
			(xy 378.96774 -271.391214) (xy 379.008243 -271.41917) (xy 379.043736 -271.453262) (xy 379.073301 -271.492606)
			(xy 379.096172 -271.536183) (xy 379.111756 -271.582864) (xy 379.119651 -271.631441) (xy 379.120146 -271.656048)
			(xy 379.438657 -271.656048) (xy 379.442752 -271.60532) (xy 379.454931 -271.555906) (xy 379.474879 -271.509086)
			(xy 379.50208 -271.466072) (xy 379.535828 -271.427978) (xy 379.57525 -271.395791) (xy 379.619324 -271.370345)
			(xy 379.66691 -271.352298) (xy 379.716774 -271.342118) (xy 379.767626 -271.340069) (xy 379.818147 -271.346203)
			(xy 379.867031 -271.360363) (xy 379.91301 -271.38218) (xy 379.954894 -271.41109) (xy 379.991598 -271.446345)
			(xy 380.022171 -271.487031) (xy 380.045822 -271.532094) (xy 380.061938 -271.580368) (xy 380.070102 -271.630602)
			(xy 380.070614 -271.656048) (xy 380.378711 -271.656048) (xy 380.382806 -271.60532) (xy 380.394985 -271.555906)
			(xy 380.414933 -271.509086) (xy 380.442134 -271.466072) (xy 380.475882 -271.427978) (xy 380.515304 -271.395791)
			(xy 380.559378 -271.370345) (xy 380.606964 -271.352298) (xy 380.656828 -271.342118) (xy 380.70768 -271.340069)
			(xy 380.758201 -271.346203) (xy 380.807085 -271.360363) (xy 380.853064 -271.38218) (xy 380.894948 -271.41109)
			(xy 380.931652 -271.446345) (xy 380.962225 -271.487031) (xy 380.985876 -271.532094) (xy 381.001992 -271.580368)
			(xy 381.010156 -271.630602) (xy 381.010668 -271.656048) (xy 381.328942 -271.656048) (xy 381.332902 -271.606994)
			(xy 381.344679 -271.55921) (xy 381.36397 -271.513934) (xy 381.390273 -271.472338) (xy 381.422908 -271.435501)
			(xy 381.461029 -271.404376) (xy 381.50365 -271.379769) (xy 381.549666 -271.362317) (xy 381.597885 -271.352473)
			(xy 381.64706 -271.350492) (xy 381.695915 -271.356424) (xy 381.743186 -271.370116) (xy 381.787648 -271.391214)
			(xy 381.828151 -271.41917) (xy 381.863644 -271.453262) (xy 381.893209 -271.492606) (xy 381.91608 -271.536183)
			(xy 381.931664 -271.582864) (xy 381.939559 -271.631441) (xy 381.940054 -271.656048) (xy 382.268996 -271.656048)
			(xy 382.272956 -271.606994) (xy 382.284733 -271.55921) (xy 382.304024 -271.513934) (xy 382.330327 -271.472338)
			(xy 382.362962 -271.435501) (xy 382.401083 -271.404376) (xy 382.443704 -271.379769) (xy 382.48972 -271.362317)
			(xy 382.537939 -271.352473) (xy 382.587114 -271.350492) (xy 382.635969 -271.356424) (xy 382.68324 -271.370116)
			(xy 382.727702 -271.391214) (xy 382.768205 -271.41917) (xy 382.803698 -271.453262) (xy 382.833263 -271.492606)
			(xy 382.856134 -271.536183) (xy 382.871718 -271.582864) (xy 382.879613 -271.631441) (xy 382.880108 -271.656048)
			(xy 383.20905 -271.656048) (xy 383.21301 -271.606994) (xy 383.224787 -271.55921) (xy 383.244078 -271.513934)
			(xy 383.270381 -271.472338) (xy 383.303016 -271.435501) (xy 383.341137 -271.404376) (xy 383.383758 -271.379769)
			(xy 383.429774 -271.362317) (xy 383.477993 -271.352473) (xy 383.527168 -271.350492) (xy 383.576023 -271.356424)
			(xy 383.623294 -271.370116) (xy 383.667756 -271.391214) (xy 383.708259 -271.41917) (xy 383.743752 -271.453262)
			(xy 383.773317 -271.492606) (xy 383.796188 -271.536183) (xy 383.811772 -271.582864) (xy 383.819667 -271.631441)
			(xy 383.820162 -271.656048) (xy 384.149104 -271.656048) (xy 384.153064 -271.606994) (xy 384.164841 -271.55921)
			(xy 384.184132 -271.513934) (xy 384.210435 -271.472338) (xy 384.24307 -271.435501) (xy 384.281191 -271.404376)
			(xy 384.323812 -271.379769) (xy 384.369828 -271.362317) (xy 384.418047 -271.352473) (xy 384.467222 -271.350492)
			(xy 384.516077 -271.356424) (xy 384.563348 -271.370116) (xy 384.60781 -271.391214) (xy 384.648313 -271.41917)
			(xy 384.683806 -271.453262) (xy 384.713371 -271.492606) (xy 384.736242 -271.536183) (xy 384.751826 -271.582864)
			(xy 384.759721 -271.631441) (xy 384.760216 -271.656048) (xy 385.088904 -271.656048) (xy 385.092864 -271.606994)
			(xy 385.104641 -271.55921) (xy 385.123932 -271.513934) (xy 385.150235 -271.472338) (xy 385.18287 -271.435501)
			(xy 385.220991 -271.404376) (xy 385.263612 -271.379769) (xy 385.309628 -271.362317) (xy 385.357847 -271.352473)
			(xy 385.407022 -271.350492) (xy 385.455877 -271.356424) (xy 385.503148 -271.370116) (xy 385.54761 -271.391214)
			(xy 385.588113 -271.41917) (xy 385.623606 -271.453262) (xy 385.653171 -271.492606) (xy 385.676042 -271.536183)
			(xy 385.691626 -271.582864) (xy 385.699521 -271.631441) (xy 385.700016 -271.656048) (xy 386.028958 -271.656048)
			(xy 386.032918 -271.606994) (xy 386.044695 -271.55921) (xy 386.063986 -271.513934) (xy 386.090289 -271.472338)
			(xy 386.122924 -271.435501) (xy 386.161045 -271.404376) (xy 386.203666 -271.379769) (xy 386.249682 -271.362317)
			(xy 386.297901 -271.352473) (xy 386.347076 -271.350492) (xy 386.395931 -271.356424) (xy 386.443202 -271.370116)
			(xy 386.487664 -271.391214) (xy 386.528167 -271.41917) (xy 386.56366 -271.453262) (xy 386.593225 -271.492606)
			(xy 386.616096 -271.536183) (xy 386.63168 -271.582864) (xy 386.639575 -271.631441) (xy 386.64007 -271.656048)
			(xy 386.969012 -271.656048) (xy 386.972972 -271.606994) (xy 386.984749 -271.55921) (xy 387.00404 -271.513934)
			(xy 387.030343 -271.472338) (xy 387.062978 -271.435501) (xy 387.101099 -271.404376) (xy 387.14372 -271.379769)
			(xy 387.189736 -271.362317) (xy 387.237955 -271.352473) (xy 387.28713 -271.350492) (xy 387.335985 -271.356424)
			(xy 387.383256 -271.370116) (xy 387.427718 -271.391214) (xy 387.468221 -271.41917) (xy 387.503714 -271.453262)
			(xy 387.533279 -271.492606) (xy 387.55615 -271.536183) (xy 387.571734 -271.582864) (xy 387.579629 -271.631441)
			(xy 387.580124 -271.656048) (xy 387.579629 -271.680655) (xy 387.571734 -271.729232) (xy 387.55615 -271.775913)
			(xy 387.533279 -271.81949) (xy 387.503714 -271.858834) (xy 387.468221 -271.892926) (xy 387.427718 -271.920882)
			(xy 387.383256 -271.94198) (xy 387.335985 -271.955672) (xy 387.28713 -271.961604) (xy 387.237955 -271.959623)
			(xy 387.189736 -271.949779) (xy 387.14372 -271.932327) (xy 387.101099 -271.90772) (xy 387.062978 -271.876595)
			(xy 387.030343 -271.839758) (xy 387.00404 -271.798162) (xy 386.984749 -271.752886) (xy 386.972972 -271.705102)
			(xy 386.969012 -271.656048) (xy 386.64007 -271.656048) (xy 386.639575 -271.680655) (xy 386.63168 -271.729232)
			(xy 386.616096 -271.775913) (xy 386.593225 -271.81949) (xy 386.56366 -271.858834) (xy 386.528167 -271.892926)
			(xy 386.487664 -271.920882) (xy 386.443202 -271.94198) (xy 386.395931 -271.955672) (xy 386.347076 -271.961604)
			(xy 386.297901 -271.959623) (xy 386.249682 -271.949779) (xy 386.203666 -271.932327) (xy 386.161045 -271.90772)
			(xy 386.122924 -271.876595) (xy 386.090289 -271.839758) (xy 386.063986 -271.798162) (xy 386.044695 -271.752886)
			(xy 386.032918 -271.705102) (xy 386.028958 -271.656048) (xy 385.700016 -271.656048) (xy 385.699521 -271.680655)
			(xy 385.691626 -271.729232) (xy 385.676042 -271.775913) (xy 385.653171 -271.81949) (xy 385.623606 -271.858834)
			(xy 385.588113 -271.892926) (xy 385.54761 -271.920882) (xy 385.503148 -271.94198) (xy 385.455877 -271.955672)
			(xy 385.407022 -271.961604) (xy 385.357847 -271.959623) (xy 385.309628 -271.949779) (xy 385.263612 -271.932327)
			(xy 385.220991 -271.90772) (xy 385.18287 -271.876595) (xy 385.150235 -271.839758) (xy 385.123932 -271.798162)
			(xy 385.104641 -271.752886) (xy 385.092864 -271.705102) (xy 385.088904 -271.656048) (xy 384.760216 -271.656048)
			(xy 384.759721 -271.680655) (xy 384.751826 -271.729232) (xy 384.736242 -271.775913) (xy 384.713371 -271.81949)
			(xy 384.683806 -271.858834) (xy 384.648313 -271.892926) (xy 384.60781 -271.920882) (xy 384.563348 -271.94198)
			(xy 384.516077 -271.955672) (xy 384.467222 -271.961604) (xy 384.418047 -271.959623) (xy 384.369828 -271.949779)
			(xy 384.323812 -271.932327) (xy 384.281191 -271.90772) (xy 384.24307 -271.876595) (xy 384.210435 -271.839758)
			(xy 384.184132 -271.798162) (xy 384.164841 -271.752886) (xy 384.153064 -271.705102) (xy 384.149104 -271.656048)
			(xy 383.820162 -271.656048) (xy 383.819667 -271.680655) (xy 383.811772 -271.729232) (xy 383.796188 -271.775913)
			(xy 383.773317 -271.81949) (xy 383.743752 -271.858834) (xy 383.708259 -271.892926) (xy 383.667756 -271.920882)
			(xy 383.623294 -271.94198) (xy 383.576023 -271.955672) (xy 383.527168 -271.961604) (xy 383.477993 -271.959623)
			(xy 383.429774 -271.949779) (xy 383.383758 -271.932327) (xy 383.341137 -271.90772) (xy 383.303016 -271.876595)
			(xy 383.270381 -271.839758) (xy 383.244078 -271.798162) (xy 383.224787 -271.752886) (xy 383.21301 -271.705102)
			(xy 383.20905 -271.656048) (xy 382.880108 -271.656048) (xy 382.879613 -271.680655) (xy 382.871718 -271.729232)
			(xy 382.856134 -271.775913) (xy 382.833263 -271.81949) (xy 382.803698 -271.858834) (xy 382.768205 -271.892926)
			(xy 382.727702 -271.920882) (xy 382.68324 -271.94198) (xy 382.635969 -271.955672) (xy 382.587114 -271.961604)
			(xy 382.537939 -271.959623) (xy 382.48972 -271.949779) (xy 382.443704 -271.932327) (xy 382.401083 -271.90772)
			(xy 382.362962 -271.876595) (xy 382.330327 -271.839758) (xy 382.304024 -271.798162) (xy 382.284733 -271.752886)
			(xy 382.272956 -271.705102) (xy 382.268996 -271.656048) (xy 381.940054 -271.656048) (xy 381.939559 -271.680655)
			(xy 381.931664 -271.729232) (xy 381.91608 -271.775913) (xy 381.893209 -271.81949) (xy 381.863644 -271.858834)
			(xy 381.828151 -271.892926) (xy 381.787648 -271.920882) (xy 381.743186 -271.94198) (xy 381.695915 -271.955672)
			(xy 381.64706 -271.961604) (xy 381.597885 -271.959623) (xy 381.549666 -271.949779) (xy 381.50365 -271.932327)
			(xy 381.461029 -271.90772) (xy 381.422908 -271.876595) (xy 381.390273 -271.839758) (xy 381.36397 -271.798162)
			(xy 381.344679 -271.752886) (xy 381.332902 -271.705102) (xy 381.328942 -271.656048) (xy 381.010668 -271.656048)
			(xy 381.010156 -271.681494) (xy 381.001992 -271.731728) (xy 380.985876 -271.780002) (xy 380.962225 -271.825065)
			(xy 380.931652 -271.865751) (xy 380.894948 -271.901006) (xy 380.853064 -271.929916) (xy 380.807085 -271.951733)
			(xy 380.758201 -271.965893) (xy 380.70768 -271.972027) (xy 380.656828 -271.969978) (xy 380.606964 -271.959798)
			(xy 380.559378 -271.941751) (xy 380.515304 -271.916305) (xy 380.475882 -271.884118) (xy 380.442134 -271.846024)
			(xy 380.414933 -271.80301) (xy 380.394985 -271.75619) (xy 380.382806 -271.706776) (xy 380.378711 -271.656048)
			(xy 380.070614 -271.656048) (xy 380.070102 -271.681494) (xy 380.061938 -271.731728) (xy 380.045822 -271.780002)
			(xy 380.022171 -271.825065) (xy 379.991598 -271.865751) (xy 379.954894 -271.901006) (xy 379.91301 -271.929916)
			(xy 379.867031 -271.951733) (xy 379.818147 -271.965893) (xy 379.767626 -271.972027) (xy 379.716774 -271.969978)
			(xy 379.66691 -271.959798) (xy 379.619324 -271.941751) (xy 379.57525 -271.916305) (xy 379.535828 -271.884118)
			(xy 379.50208 -271.846024) (xy 379.474879 -271.80301) (xy 379.454931 -271.75619) (xy 379.442752 -271.706776)
			(xy 379.438657 -271.656048) (xy 379.120146 -271.656048) (xy 379.119651 -271.680655) (xy 379.111756 -271.729232)
			(xy 379.096172 -271.775913) (xy 379.073301 -271.81949) (xy 379.043736 -271.858834) (xy 379.008243 -271.892926)
			(xy 378.96774 -271.920882) (xy 378.923278 -271.94198) (xy 378.876007 -271.955672) (xy 378.827152 -271.961604)
			(xy 378.777977 -271.959623) (xy 378.729758 -271.949779) (xy 378.683742 -271.932327) (xy 378.641121 -271.90772)
			(xy 378.603 -271.876595) (xy 378.570365 -271.839758) (xy 378.544062 -271.798162) (xy 378.524771 -271.752886)
			(xy 378.512994 -271.705102) (xy 378.509034 -271.656048) (xy 378.190506 -271.656048) (xy 378.189994 -271.681494)
			(xy 378.18183 -271.731728) (xy 378.165714 -271.780002) (xy 378.142063 -271.825065) (xy 378.11149 -271.865751)
			(xy 378.074786 -271.901006) (xy 378.032902 -271.929916) (xy 377.986923 -271.951733) (xy 377.938039 -271.965893)
			(xy 377.887518 -271.972027) (xy 377.836666 -271.969978) (xy 377.786802 -271.959798) (xy 377.739216 -271.941751)
			(xy 377.695142 -271.916305) (xy 377.65572 -271.884118) (xy 377.621972 -271.846024) (xy 377.594771 -271.80301)
			(xy 377.574823 -271.75619) (xy 377.562644 -271.706776) (xy 377.558549 -271.656048) (xy 377.240038 -271.656048)
			(xy 377.239543 -271.680655) (xy 377.231648 -271.729232) (xy 377.216064 -271.775913) (xy 377.193193 -271.81949)
			(xy 377.163628 -271.858834) (xy 377.128135 -271.892926) (xy 377.087632 -271.920882) (xy 377.04317 -271.94198)
			(xy 376.995899 -271.955672) (xy 376.947044 -271.961604) (xy 376.897869 -271.959623) (xy 376.84965 -271.949779)
			(xy 376.803634 -271.932327) (xy 376.761013 -271.90772) (xy 376.722892 -271.876595) (xy 376.690257 -271.839758)
			(xy 376.663954 -271.798162) (xy 376.644663 -271.752886) (xy 376.632886 -271.705102) (xy 376.628926 -271.656048)
			(xy 376.310652 -271.656048) (xy 376.31014 -271.681494) (xy 376.301976 -271.731728) (xy 376.28586 -271.780002)
			(xy 376.262209 -271.825065) (xy 376.231636 -271.865751) (xy 376.194932 -271.901006) (xy 376.153048 -271.929916)
			(xy 376.107069 -271.951733) (xy 376.058185 -271.965893) (xy 376.007664 -271.972027) (xy 375.956812 -271.969978)
			(xy 375.906948 -271.959798) (xy 375.859362 -271.941751) (xy 375.815288 -271.916305) (xy 375.775866 -271.884118)
			(xy 375.742118 -271.846024) (xy 375.714917 -271.80301) (xy 375.694969 -271.75619) (xy 375.68279 -271.706776)
			(xy 375.678695 -271.656048) (xy 375.359635 -271.656048) (xy 375.359633 -271.681425) (xy 375.351222 -271.73151)
			(xy 375.334638 -271.779512) (xy 375.310338 -271.824107) (xy 375.278992 -271.864065) (xy 375.260616 -271.8816)
			(xy 375.25325 -271.888204) (xy 375.240804 -271.915382) (xy 375.23674 -271.927828) (xy 375.235978 -271.936464)
			(xy 375.235978 -272.107406) (xy 375.236383 -272.115956) (xy 375.242189 -272.132046) (xy 375.253005 -272.145298)
			(xy 375.260108 -272.150078) (xy 375.315734 -272.183606) (xy 375.336054 -272.195798) (xy 375.341239 -272.198329)
			(xy 375.352393 -272.201271) (xy 375.358152 -272.20164) (xy 375.370852 -272.201894) (xy 375.382536 -272.195798)
			(xy 375.40453 -272.184802) (xy 375.451159 -272.169201) (xy 375.499684 -272.161264) (xy 375.524268 -272.160746)
			(xy 375.530364 -272.160746) (xy 375.555322 -272.161698) (xy 375.604442 -272.17072) (xy 375.65144 -272.187614)
			(xy 375.695063 -272.211929) (xy 375.734148 -272.243018) (xy 375.767654 -272.280052) (xy 375.794689 -272.322044)
			(xy 375.814531 -272.367875) (xy 375.826652 -272.416324) (xy 375.830724 -272.466054) (xy 376.148595 -272.466054)
			(xy 376.15269 -272.415326) (xy 376.164869 -272.365912) (xy 376.184817 -272.319092) (xy 376.212018 -272.276078)
			(xy 376.245766 -272.237984) (xy 376.285188 -272.205797) (xy 376.329262 -272.180351) (xy 376.376848 -272.162304)
			(xy 376.426712 -272.152124) (xy 376.477564 -272.150075) (xy 376.528085 -272.156209) (xy 376.576969 -272.170369)
			(xy 376.622948 -272.192186) (xy 376.664832 -272.221096) (xy 376.701536 -272.256351) (xy 376.732109 -272.297037)
			(xy 376.75576 -272.3421) (xy 376.771876 -272.390374) (xy 376.78004 -272.440608) (xy 376.780552 -272.466054)
			(xy 377.088649 -272.466054) (xy 377.092744 -272.415326) (xy 377.104923 -272.365912) (xy 377.124871 -272.319092)
			(xy 377.152072 -272.276078) (xy 377.18582 -272.237984) (xy 377.225242 -272.205797) (xy 377.269316 -272.180351)
			(xy 377.316902 -272.162304) (xy 377.366766 -272.152124) (xy 377.417618 -272.150075) (xy 377.468139 -272.156209)
			(xy 377.517023 -272.170369) (xy 377.563002 -272.192186) (xy 377.604886 -272.221096) (xy 377.64159 -272.256351)
			(xy 377.672163 -272.297037) (xy 377.695814 -272.3421) (xy 377.71193 -272.390374) (xy 377.720094 -272.440608)
			(xy 377.720606 -272.466054) (xy 378.039134 -272.466054) (xy 378.043094 -272.417) (xy 378.054871 -272.369216)
			(xy 378.074162 -272.32394) (xy 378.100465 -272.282344) (xy 378.1331 -272.245507) (xy 378.171221 -272.214382)
			(xy 378.213842 -272.189775) (xy 378.259858 -272.172323) (xy 378.308077 -272.162479) (xy 378.357252 -272.160498)
			(xy 378.406107 -272.16643) (xy 378.453378 -272.180122) (xy 378.49784 -272.20122) (xy 378.538343 -272.229176)
			(xy 378.573836 -272.263268) (xy 378.603401 -272.302612) (xy 378.626272 -272.346189) (xy 378.641856 -272.39287)
			(xy 378.649751 -272.441447) (xy 378.650246 -272.466054) (xy 378.968503 -272.466054) (xy 378.972598 -272.415326)
			(xy 378.984777 -272.365912) (xy 379.004725 -272.319092) (xy 379.031926 -272.276078) (xy 379.065674 -272.237984)
			(xy 379.105096 -272.205797) (xy 379.14917 -272.180351) (xy 379.196756 -272.162304) (xy 379.24662 -272.152124)
			(xy 379.297472 -272.150075) (xy 379.347993 -272.156209) (xy 379.396877 -272.170369) (xy 379.442856 -272.192186)
			(xy 379.48474 -272.221096) (xy 379.521444 -272.256351) (xy 379.552017 -272.297037) (xy 379.575668 -272.3421)
			(xy 379.591784 -272.390374) (xy 379.599948 -272.440608) (xy 379.60046 -272.466054) (xy 379.918988 -272.466054)
			(xy 379.922948 -272.417) (xy 379.934725 -272.369216) (xy 379.954016 -272.32394) (xy 379.980319 -272.282344)
			(xy 380.012954 -272.245507) (xy 380.051075 -272.214382) (xy 380.093696 -272.189775) (xy 380.139712 -272.172323)
			(xy 380.187931 -272.162479) (xy 380.237106 -272.160498) (xy 380.285961 -272.16643) (xy 380.333232 -272.180122)
			(xy 380.377694 -272.20122) (xy 380.418197 -272.229176) (xy 380.45369 -272.263268) (xy 380.483255 -272.302612)
			(xy 380.506126 -272.346189) (xy 380.52171 -272.39287) (xy 380.529605 -272.441447) (xy 380.5301 -272.466054)
			(xy 380.848611 -272.466054) (xy 380.852706 -272.415326) (xy 380.864885 -272.365912) (xy 380.884833 -272.319092)
			(xy 380.912034 -272.276078) (xy 380.945782 -272.237984) (xy 380.985204 -272.205797) (xy 381.029278 -272.180351)
			(xy 381.076864 -272.162304) (xy 381.126728 -272.152124) (xy 381.17758 -272.150075) (xy 381.228101 -272.156209)
			(xy 381.276985 -272.170369) (xy 381.322964 -272.192186) (xy 381.364848 -272.221096) (xy 381.401552 -272.256351)
			(xy 381.432125 -272.297037) (xy 381.455776 -272.3421) (xy 381.471892 -272.390374) (xy 381.480056 -272.440608)
			(xy 381.480568 -272.466054) (xy 381.799096 -272.466054) (xy 381.803056 -272.417) (xy 381.814833 -272.369216)
			(xy 381.834124 -272.32394) (xy 381.860427 -272.282344) (xy 381.893062 -272.245507) (xy 381.931183 -272.214382)
			(xy 381.973804 -272.189775) (xy 382.01982 -272.172323) (xy 382.068039 -272.162479) (xy 382.117214 -272.160498)
			(xy 382.166069 -272.16643) (xy 382.21334 -272.180122) (xy 382.257802 -272.20122) (xy 382.298305 -272.229176)
			(xy 382.333798 -272.263268) (xy 382.363363 -272.302612) (xy 382.386234 -272.346189) (xy 382.401818 -272.39287)
			(xy 382.409713 -272.441447) (xy 382.410208 -272.466054) (xy 382.738896 -272.466054) (xy 382.742856 -272.417)
			(xy 382.754633 -272.369216) (xy 382.773924 -272.32394) (xy 382.800227 -272.282344) (xy 382.832862 -272.245507)
			(xy 382.870983 -272.214382) (xy 382.913604 -272.189775) (xy 382.95962 -272.172323) (xy 383.007839 -272.162479)
			(xy 383.057014 -272.160498) (xy 383.105869 -272.16643) (xy 383.15314 -272.180122) (xy 383.197602 -272.20122)
			(xy 383.238105 -272.229176) (xy 383.273598 -272.263268) (xy 383.303163 -272.302612) (xy 383.326034 -272.346189)
			(xy 383.341618 -272.39287) (xy 383.349513 -272.441447) (xy 383.350008 -272.466054) (xy 383.67895 -272.466054)
			(xy 383.68291 -272.417) (xy 383.694687 -272.369216) (xy 383.713978 -272.32394) (xy 383.740281 -272.282344)
			(xy 383.772916 -272.245507) (xy 383.811037 -272.214382) (xy 383.853658 -272.189775) (xy 383.899674 -272.172323)
			(xy 383.947893 -272.162479) (xy 383.997068 -272.160498) (xy 384.045923 -272.16643) (xy 384.093194 -272.180122)
			(xy 384.137656 -272.20122) (xy 384.178159 -272.229176) (xy 384.213652 -272.263268) (xy 384.243217 -272.302612)
			(xy 384.266088 -272.346189) (xy 384.281672 -272.39287) (xy 384.289567 -272.441447) (xy 384.290062 -272.466054)
			(xy 384.619004 -272.466054) (xy 384.622964 -272.417) (xy 384.634741 -272.369216) (xy 384.654032 -272.32394)
			(xy 384.680335 -272.282344) (xy 384.71297 -272.245507) (xy 384.751091 -272.214382) (xy 384.793712 -272.189775)
			(xy 384.839728 -272.172323) (xy 384.887947 -272.162479) (xy 384.937122 -272.160498) (xy 384.985977 -272.16643)
			(xy 385.033248 -272.180122) (xy 385.07771 -272.20122) (xy 385.118213 -272.229176) (xy 385.153706 -272.263268)
			(xy 385.183271 -272.302612) (xy 385.206142 -272.346189) (xy 385.221726 -272.39287) (xy 385.229621 -272.441447)
			(xy 385.230116 -272.466054) (xy 385.559058 -272.466054) (xy 385.563018 -272.417) (xy 385.574795 -272.369216)
			(xy 385.594086 -272.32394) (xy 385.620389 -272.282344) (xy 385.653024 -272.245507) (xy 385.691145 -272.214382)
			(xy 385.733766 -272.189775) (xy 385.779782 -272.172323) (xy 385.828001 -272.162479) (xy 385.877176 -272.160498)
			(xy 385.926031 -272.16643) (xy 385.973302 -272.180122) (xy 386.017764 -272.20122) (xy 386.058267 -272.229176)
			(xy 386.09376 -272.263268) (xy 386.123325 -272.302612) (xy 386.146196 -272.346189) (xy 386.16178 -272.39287)
			(xy 386.169675 -272.441447) (xy 386.17017 -272.466054) (xy 386.499112 -272.466054) (xy 386.503072 -272.417)
			(xy 386.514849 -272.369216) (xy 386.53414 -272.32394) (xy 386.560443 -272.282344) (xy 386.593078 -272.245507)
			(xy 386.631199 -272.214382) (xy 386.67382 -272.189775) (xy 386.719836 -272.172323) (xy 386.768055 -272.162479)
			(xy 386.81723 -272.160498) (xy 386.866085 -272.16643) (xy 386.913356 -272.180122) (xy 386.957818 -272.20122)
			(xy 386.998321 -272.229176) (xy 387.033814 -272.263268) (xy 387.063379 -272.302612) (xy 387.08625 -272.346189)
			(xy 387.101834 -272.39287) (xy 387.109729 -272.441447) (xy 387.110224 -272.466054) (xy 387.438912 -272.466054)
			(xy 387.442872 -272.417) (xy 387.454649 -272.369216) (xy 387.47394 -272.32394) (xy 387.500243 -272.282344)
			(xy 387.532878 -272.245507) (xy 387.570999 -272.214382) (xy 387.61362 -272.189775) (xy 387.659636 -272.172323)
			(xy 387.707855 -272.162479) (xy 387.75703 -272.160498) (xy 387.805885 -272.16643) (xy 387.853156 -272.180122)
			(xy 387.897618 -272.20122) (xy 387.938121 -272.229176) (xy 387.973614 -272.263268) (xy 388.003179 -272.302612)
			(xy 388.02605 -272.346189) (xy 388.041634 -272.39287) (xy 388.049529 -272.441447) (xy 388.050024 -272.466054)
			(xy 388.049529 -272.490661) (xy 388.041634 -272.539238) (xy 388.02605 -272.585919) (xy 388.003179 -272.629496)
			(xy 387.973614 -272.66884) (xy 387.938121 -272.702932) (xy 387.897618 -272.730888) (xy 387.853156 -272.751986)
			(xy 387.805885 -272.765678) (xy 387.75703 -272.77161) (xy 387.707855 -272.769629) (xy 387.659636 -272.759785)
			(xy 387.61362 -272.742333) (xy 387.570999 -272.717726) (xy 387.532878 -272.686601) (xy 387.500243 -272.649764)
			(xy 387.47394 -272.608168) (xy 387.454649 -272.562892) (xy 387.442872 -272.515108) (xy 387.438912 -272.466054)
			(xy 387.110224 -272.466054) (xy 387.109729 -272.490661) (xy 387.101834 -272.539238) (xy 387.08625 -272.585919)
			(xy 387.063379 -272.629496) (xy 387.033814 -272.66884) (xy 386.998321 -272.702932) (xy 386.957818 -272.730888)
			(xy 386.913356 -272.751986) (xy 386.866085 -272.765678) (xy 386.81723 -272.77161) (xy 386.768055 -272.769629)
			(xy 386.719836 -272.759785) (xy 386.67382 -272.742333) (xy 386.631199 -272.717726) (xy 386.593078 -272.686601)
			(xy 386.560443 -272.649764) (xy 386.53414 -272.608168) (xy 386.514849 -272.562892) (xy 386.503072 -272.515108)
			(xy 386.499112 -272.466054) (xy 386.17017 -272.466054) (xy 386.169675 -272.490661) (xy 386.16178 -272.539238)
			(xy 386.146196 -272.585919) (xy 386.123325 -272.629496) (xy 386.09376 -272.66884) (xy 386.058267 -272.702932)
			(xy 386.017764 -272.730888) (xy 385.973302 -272.751986) (xy 385.926031 -272.765678) (xy 385.877176 -272.77161)
			(xy 385.828001 -272.769629) (xy 385.779782 -272.759785) (xy 385.733766 -272.742333) (xy 385.691145 -272.717726)
			(xy 385.653024 -272.686601) (xy 385.620389 -272.649764) (xy 385.594086 -272.608168) (xy 385.574795 -272.562892)
			(xy 385.563018 -272.515108) (xy 385.559058 -272.466054) (xy 385.230116 -272.466054) (xy 385.229621 -272.490661)
			(xy 385.221726 -272.539238) (xy 385.206142 -272.585919) (xy 385.183271 -272.629496) (xy 385.153706 -272.66884)
			(xy 385.118213 -272.702932) (xy 385.07771 -272.730888) (xy 385.033248 -272.751986) (xy 384.985977 -272.765678)
			(xy 384.937122 -272.77161) (xy 384.887947 -272.769629) (xy 384.839728 -272.759785) (xy 384.793712 -272.742333)
			(xy 384.751091 -272.717726) (xy 384.71297 -272.686601) (xy 384.680335 -272.649764) (xy 384.654032 -272.608168)
			(xy 384.634741 -272.562892) (xy 384.622964 -272.515108) (xy 384.619004 -272.466054) (xy 384.290062 -272.466054)
			(xy 384.289567 -272.490661) (xy 384.281672 -272.539238) (xy 384.266088 -272.585919) (xy 384.243217 -272.629496)
			(xy 384.213652 -272.66884) (xy 384.178159 -272.702932) (xy 384.137656 -272.730888) (xy 384.093194 -272.751986)
			(xy 384.045923 -272.765678) (xy 383.997068 -272.77161) (xy 383.947893 -272.769629) (xy 383.899674 -272.759785)
			(xy 383.853658 -272.742333) (xy 383.811037 -272.717726) (xy 383.772916 -272.686601) (xy 383.740281 -272.649764)
			(xy 383.713978 -272.608168) (xy 383.694687 -272.562892) (xy 383.68291 -272.515108) (xy 383.67895 -272.466054)
			(xy 383.350008 -272.466054) (xy 383.349513 -272.490661) (xy 383.341618 -272.539238) (xy 383.326034 -272.585919)
			(xy 383.303163 -272.629496) (xy 383.273598 -272.66884) (xy 383.238105 -272.702932) (xy 383.197602 -272.730888)
			(xy 383.15314 -272.751986) (xy 383.105869 -272.765678) (xy 383.057014 -272.77161) (xy 383.007839 -272.769629)
			(xy 382.95962 -272.759785) (xy 382.913604 -272.742333) (xy 382.870983 -272.717726) (xy 382.832862 -272.686601)
			(xy 382.800227 -272.649764) (xy 382.773924 -272.608168) (xy 382.754633 -272.562892) (xy 382.742856 -272.515108)
			(xy 382.738896 -272.466054) (xy 382.410208 -272.466054) (xy 382.409713 -272.490661) (xy 382.401818 -272.539238)
			(xy 382.386234 -272.585919) (xy 382.363363 -272.629496) (xy 382.333798 -272.66884) (xy 382.298305 -272.702932)
			(xy 382.257802 -272.730888) (xy 382.21334 -272.751986) (xy 382.166069 -272.765678) (xy 382.117214 -272.77161)
			(xy 382.068039 -272.769629) (xy 382.01982 -272.759785) (xy 381.973804 -272.742333) (xy 381.931183 -272.717726)
			(xy 381.893062 -272.686601) (xy 381.860427 -272.649764) (xy 381.834124 -272.608168) (xy 381.814833 -272.562892)
			(xy 381.803056 -272.515108) (xy 381.799096 -272.466054) (xy 381.480568 -272.466054) (xy 381.480056 -272.4915)
			(xy 381.471892 -272.541734) (xy 381.455776 -272.590008) (xy 381.432125 -272.635071) (xy 381.401552 -272.675757)
			(xy 381.364848 -272.711012) (xy 381.322964 -272.739922) (xy 381.276985 -272.761739) (xy 381.228101 -272.775899)
			(xy 381.17758 -272.782033) (xy 381.126728 -272.779984) (xy 381.076864 -272.769804) (xy 381.029278 -272.751757)
			(xy 380.985204 -272.726311) (xy 380.945782 -272.694124) (xy 380.912034 -272.65603) (xy 380.884833 -272.613016)
			(xy 380.864885 -272.566196) (xy 380.852706 -272.516782) (xy 380.848611 -272.466054) (xy 380.5301 -272.466054)
			(xy 380.529605 -272.490661) (xy 380.52171 -272.539238) (xy 380.506126 -272.585919) (xy 380.483255 -272.629496)
			(xy 380.45369 -272.66884) (xy 380.418197 -272.702932) (xy 380.377694 -272.730888) (xy 380.333232 -272.751986)
			(xy 380.285961 -272.765678) (xy 380.237106 -272.77161) (xy 380.187931 -272.769629) (xy 380.139712 -272.759785)
			(xy 380.093696 -272.742333) (xy 380.051075 -272.717726) (xy 380.012954 -272.686601) (xy 379.980319 -272.649764)
			(xy 379.954016 -272.608168) (xy 379.934725 -272.562892) (xy 379.922948 -272.515108) (xy 379.918988 -272.466054)
			(xy 379.60046 -272.466054) (xy 379.599948 -272.4915) (xy 379.591784 -272.541734) (xy 379.575668 -272.590008)
			(xy 379.552017 -272.635071) (xy 379.521444 -272.675757) (xy 379.48474 -272.711012) (xy 379.442856 -272.739922)
			(xy 379.396877 -272.761739) (xy 379.347993 -272.775899) (xy 379.297472 -272.782033) (xy 379.24662 -272.779984)
			(xy 379.196756 -272.769804) (xy 379.14917 -272.751757) (xy 379.105096 -272.726311) (xy 379.065674 -272.694124)
			(xy 379.031926 -272.65603) (xy 379.004725 -272.613016) (xy 378.984777 -272.566196) (xy 378.972598 -272.516782)
			(xy 378.968503 -272.466054) (xy 378.650246 -272.466054) (xy 378.649751 -272.490661) (xy 378.641856 -272.539238)
			(xy 378.626272 -272.585919) (xy 378.603401 -272.629496) (xy 378.573836 -272.66884) (xy 378.538343 -272.702932)
			(xy 378.49784 -272.730888) (xy 378.453378 -272.751986) (xy 378.406107 -272.765678) (xy 378.357252 -272.77161)
			(xy 378.308077 -272.769629) (xy 378.259858 -272.759785) (xy 378.213842 -272.742333) (xy 378.171221 -272.717726)
			(xy 378.1331 -272.686601) (xy 378.100465 -272.649764) (xy 378.074162 -272.608168) (xy 378.054871 -272.562892)
			(xy 378.043094 -272.515108) (xy 378.039134 -272.466054) (xy 377.720606 -272.466054) (xy 377.720094 -272.4915)
			(xy 377.71193 -272.541734) (xy 377.695814 -272.590008) (xy 377.672163 -272.635071) (xy 377.64159 -272.675757)
			(xy 377.604886 -272.711012) (xy 377.563002 -272.739922) (xy 377.517023 -272.761739) (xy 377.468139 -272.775899)
			(xy 377.417618 -272.782033) (xy 377.366766 -272.779984) (xy 377.316902 -272.769804) (xy 377.269316 -272.751757)
			(xy 377.225242 -272.726311) (xy 377.18582 -272.694124) (xy 377.152072 -272.65603) (xy 377.124871 -272.613016)
			(xy 377.104923 -272.566196) (xy 377.092744 -272.516782) (xy 377.088649 -272.466054) (xy 376.780552 -272.466054)
			(xy 376.78004 -272.4915) (xy 376.771876 -272.541734) (xy 376.75576 -272.590008) (xy 376.732109 -272.635071)
			(xy 376.701536 -272.675757) (xy 376.664832 -272.711012) (xy 376.622948 -272.739922) (xy 376.576969 -272.761739)
			(xy 376.528085 -272.775899) (xy 376.477564 -272.782033) (xy 376.426712 -272.779984) (xy 376.376848 -272.769804)
			(xy 376.329262 -272.751757) (xy 376.285188 -272.726311) (xy 376.245766 -272.694124) (xy 376.212018 -272.65603)
			(xy 376.184817 -272.613016) (xy 376.164869 -272.566196) (xy 376.15269 -272.516782) (xy 376.148595 -272.466054)
			(xy 375.830724 -272.466054) (xy 375.830728 -272.466099) (xy 375.826652 -272.515874) (xy 375.814531 -272.564323)
			(xy 375.79469 -272.610154) (xy 375.767655 -272.652147) (xy 375.734149 -272.689181) (xy 375.695064 -272.72027)
			(xy 375.651441 -272.744585) (xy 375.604444 -272.761479) (xy 375.555323 -272.770502) (xy 375.530364 -272.771362)
			(xy 375.524268 -272.771362) (xy 375.499681 -272.770874) (xy 375.45115 -272.762945) (xy 375.404521 -272.747329)
			(xy 375.382536 -272.73631) (xy 375.376694 -272.733262) (xy 375.364248 -272.730468) (xy 375.358152 -272.730468)
			(xy 375.352388 -272.730796) (xy 375.341229 -272.73375) (xy 375.336054 -272.73631) (xy 375.315734 -272.748502)
			(xy 375.260108 -272.78203) (xy 375.25294 -272.786741) (xy 375.24207 -272.799993) (xy 375.236297 -272.816132)
			(xy 375.235978 -272.824702) (xy 375.235978 -272.99539) (xy 375.236994 -273.00555) (xy 375.24055 -273.016472)
			(xy 375.25325 -273.043904) (xy 375.260616 -273.050508) (xy 375.279043 -273.067994) (xy 375.310395 -273.107962)
			(xy 375.334699 -273.152567) (xy 375.351286 -273.200579) (xy 375.359698 -273.250675) (xy 375.3597 -273.27606)
			(xy 375.678695 -273.27606) (xy 375.68279 -273.225332) (xy 375.694969 -273.175918) (xy 375.714917 -273.129098)
			(xy 375.742118 -273.086084) (xy 375.775866 -273.04799) (xy 375.815288 -273.015803) (xy 375.859362 -272.990357)
			(xy 375.906948 -272.97231) (xy 375.956812 -272.96213) (xy 376.007664 -272.960081) (xy 376.058185 -272.966215)
			(xy 376.107069 -272.980375) (xy 376.153048 -273.002192) (xy 376.194932 -273.031102) (xy 376.231636 -273.066357)
			(xy 376.262209 -273.107043) (xy 376.28586 -273.152106) (xy 376.301976 -273.20038) (xy 376.31014 -273.250614)
			(xy 376.310652 -273.27606) (xy 376.628926 -273.27606) (xy 376.632886 -273.227006) (xy 376.644663 -273.179222)
			(xy 376.663954 -273.133946) (xy 376.690257 -273.09235) (xy 376.722892 -273.055513) (xy 376.761013 -273.024388)
			(xy 376.803634 -272.999781) (xy 376.84965 -272.982329) (xy 376.897869 -272.972485) (xy 376.947044 -272.970504)
			(xy 376.995899 -272.976436) (xy 377.04317 -272.990128) (xy 377.087632 -273.011226) (xy 377.128135 -273.039182)
			(xy 377.163628 -273.073274) (xy 377.193193 -273.112618) (xy 377.216064 -273.156195) (xy 377.231648 -273.202876)
			(xy 377.239543 -273.251453) (xy 377.240038 -273.27606) (xy 377.558549 -273.27606) (xy 377.562644 -273.225332)
			(xy 377.574823 -273.175918) (xy 377.594771 -273.129098) (xy 377.621972 -273.086084) (xy 377.65572 -273.04799)
			(xy 377.695142 -273.015803) (xy 377.739216 -272.990357) (xy 377.786802 -272.97231) (xy 377.836666 -272.96213)
			(xy 377.887518 -272.960081) (xy 377.938039 -272.966215) (xy 377.986923 -272.980375) (xy 378.032902 -273.002192)
			(xy 378.074786 -273.031102) (xy 378.11149 -273.066357) (xy 378.142063 -273.107043) (xy 378.165714 -273.152106)
			(xy 378.18183 -273.20038) (xy 378.189994 -273.250614) (xy 378.190506 -273.27606) (xy 379.438657 -273.27606)
			(xy 379.442752 -273.225332) (xy 379.454931 -273.175918) (xy 379.474879 -273.129098) (xy 379.50208 -273.086084)
			(xy 379.535828 -273.04799) (xy 379.57525 -273.015803) (xy 379.619324 -272.990357) (xy 379.66691 -272.97231)
			(xy 379.716774 -272.96213) (xy 379.767626 -272.960081) (xy 379.818147 -272.966215) (xy 379.867031 -272.980375)
			(xy 379.91301 -273.002192) (xy 379.954894 -273.031102) (xy 379.991598 -273.066357) (xy 380.022171 -273.107043)
			(xy 380.045822 -273.152106) (xy 380.061938 -273.20038) (xy 380.070102 -273.250614) (xy 380.070614 -273.27606)
			(xy 380.378711 -273.27606) (xy 380.382806 -273.225332) (xy 380.394985 -273.175918) (xy 380.414933 -273.129098)
			(xy 380.442134 -273.086084) (xy 380.475882 -273.04799) (xy 380.515304 -273.015803) (xy 380.559378 -272.990357)
			(xy 380.606964 -272.97231) (xy 380.656828 -272.96213) (xy 380.70768 -272.960081) (xy 380.758201 -272.966215)
			(xy 380.807085 -272.980375) (xy 380.853064 -273.002192) (xy 380.894948 -273.031102) (xy 380.931652 -273.066357)
			(xy 380.962225 -273.107043) (xy 380.985876 -273.152106) (xy 381.001992 -273.20038) (xy 381.010156 -273.250614)
			(xy 381.010668 -273.27606) (xy 381.328942 -273.27606) (xy 381.332902 -273.227006) (xy 381.344679 -273.179222)
			(xy 381.36397 -273.133946) (xy 381.390273 -273.09235) (xy 381.422908 -273.055513) (xy 381.461029 -273.024388)
			(xy 381.50365 -272.999781) (xy 381.549666 -272.982329) (xy 381.597885 -272.972485) (xy 381.64706 -272.970504)
			(xy 381.695915 -272.976436) (xy 381.743186 -272.990128) (xy 381.787648 -273.011226) (xy 381.828151 -273.039182)
			(xy 381.863644 -273.073274) (xy 381.893209 -273.112618) (xy 381.91608 -273.156195) (xy 381.931664 -273.202876)
			(xy 381.939559 -273.251453) (xy 381.940054 -273.27606) (xy 382.268996 -273.27606) (xy 382.272956 -273.227006)
			(xy 382.284733 -273.179222) (xy 382.304024 -273.133946) (xy 382.330327 -273.09235) (xy 382.362962 -273.055513)
			(xy 382.401083 -273.024388) (xy 382.443704 -272.999781) (xy 382.48972 -272.982329) (xy 382.537939 -272.972485)
			(xy 382.587114 -272.970504) (xy 382.635969 -272.976436) (xy 382.68324 -272.990128) (xy 382.727702 -273.011226)
			(xy 382.768205 -273.039182) (xy 382.803698 -273.073274) (xy 382.833263 -273.112618) (xy 382.856134 -273.156195)
			(xy 382.871718 -273.202876) (xy 382.879613 -273.251453) (xy 382.880108 -273.27606) (xy 383.20905 -273.27606)
			(xy 383.21301 -273.227006) (xy 383.224787 -273.179222) (xy 383.244078 -273.133946) (xy 383.270381 -273.09235)
			(xy 383.303016 -273.055513) (xy 383.341137 -273.024388) (xy 383.383758 -272.999781) (xy 383.429774 -272.982329)
			(xy 383.477993 -272.972485) (xy 383.527168 -272.970504) (xy 383.576023 -272.976436) (xy 383.623294 -272.990128)
			(xy 383.667756 -273.011226) (xy 383.708259 -273.039182) (xy 383.743752 -273.073274) (xy 383.773317 -273.112618)
			(xy 383.796188 -273.156195) (xy 383.811772 -273.202876) (xy 383.819667 -273.251453) (xy 383.820162 -273.27606)
			(xy 384.149104 -273.27606) (xy 384.153064 -273.227006) (xy 384.164841 -273.179222) (xy 384.184132 -273.133946)
			(xy 384.210435 -273.09235) (xy 384.24307 -273.055513) (xy 384.281191 -273.024388) (xy 384.323812 -272.999781)
			(xy 384.369828 -272.982329) (xy 384.418047 -272.972485) (xy 384.467222 -272.970504) (xy 384.516077 -272.976436)
			(xy 384.563348 -272.990128) (xy 384.60781 -273.011226) (xy 384.648313 -273.039182) (xy 384.683806 -273.073274)
			(xy 384.713371 -273.112618) (xy 384.736242 -273.156195) (xy 384.751826 -273.202876) (xy 384.759721 -273.251453)
			(xy 384.760216 -273.27606) (xy 386.028958 -273.27606) (xy 386.032918 -273.227006) (xy 386.044695 -273.179222)
			(xy 386.063986 -273.133946) (xy 386.090289 -273.09235) (xy 386.122924 -273.055513) (xy 386.161045 -273.024388)
			(xy 386.203666 -272.999781) (xy 386.249682 -272.982329) (xy 386.297901 -272.972485) (xy 386.347076 -272.970504)
			(xy 386.395931 -272.976436) (xy 386.443202 -272.990128) (xy 386.487664 -273.011226) (xy 386.528167 -273.039182)
			(xy 386.56366 -273.073274) (xy 386.593225 -273.112618) (xy 386.616096 -273.156195) (xy 386.63168 -273.202876)
			(xy 386.639575 -273.251453) (xy 386.64007 -273.27606) (xy 386.969012 -273.27606) (xy 386.972972 -273.227006)
			(xy 386.984749 -273.179222) (xy 387.00404 -273.133946) (xy 387.030343 -273.09235) (xy 387.062978 -273.055513)
			(xy 387.101099 -273.024388) (xy 387.14372 -272.999781) (xy 387.189736 -272.982329) (xy 387.237955 -272.972485)
			(xy 387.28713 -272.970504) (xy 387.335985 -272.976436) (xy 387.383256 -272.990128) (xy 387.427718 -273.011226)
			(xy 387.468221 -273.039182) (xy 387.503714 -273.073274) (xy 387.533279 -273.112618) (xy 387.55615 -273.156195)
			(xy 387.571734 -273.202876) (xy 387.579629 -273.251453) (xy 387.580124 -273.27606) (xy 387.579629 -273.300667)
			(xy 387.571734 -273.349244) (xy 387.55615 -273.395925) (xy 387.533279 -273.439502) (xy 387.503714 -273.478846)
			(xy 387.468221 -273.512938) (xy 387.427718 -273.540894) (xy 387.383256 -273.561992) (xy 387.335985 -273.575684)
			(xy 387.28713 -273.581616) (xy 387.237955 -273.579635) (xy 387.189736 -273.569791) (xy 387.14372 -273.552339)
			(xy 387.101099 -273.527732) (xy 387.062978 -273.496607) (xy 387.030343 -273.45977) (xy 387.00404 -273.418174)
			(xy 386.984749 -273.372898) (xy 386.972972 -273.325114) (xy 386.969012 -273.27606) (xy 386.64007 -273.27606)
			(xy 386.639575 -273.300667) (xy 386.63168 -273.349244) (xy 386.616096 -273.395925) (xy 386.593225 -273.439502)
			(xy 386.56366 -273.478846) (xy 386.528167 -273.512938) (xy 386.487664 -273.540894) (xy 386.443202 -273.561992)
			(xy 386.395931 -273.575684) (xy 386.347076 -273.581616) (xy 386.297901 -273.579635) (xy 386.249682 -273.569791)
			(xy 386.203666 -273.552339) (xy 386.161045 -273.527732) (xy 386.122924 -273.496607) (xy 386.090289 -273.45977)
			(xy 386.063986 -273.418174) (xy 386.044695 -273.372898) (xy 386.032918 -273.325114) (xy 386.028958 -273.27606)
			(xy 384.760216 -273.27606) (xy 384.759721 -273.300667) (xy 384.751826 -273.349244) (xy 384.736242 -273.395925)
			(xy 384.713371 -273.439502) (xy 384.683806 -273.478846) (xy 384.648313 -273.512938) (xy 384.60781 -273.540894)
			(xy 384.563348 -273.561992) (xy 384.516077 -273.575684) (xy 384.467222 -273.581616) (xy 384.418047 -273.579635)
			(xy 384.369828 -273.569791) (xy 384.323812 -273.552339) (xy 384.281191 -273.527732) (xy 384.24307 -273.496607)
			(xy 384.210435 -273.45977) (xy 384.184132 -273.418174) (xy 384.164841 -273.372898) (xy 384.153064 -273.325114)
			(xy 384.149104 -273.27606) (xy 383.820162 -273.27606) (xy 383.819667 -273.300667) (xy 383.811772 -273.349244)
			(xy 383.796188 -273.395925) (xy 383.773317 -273.439502) (xy 383.743752 -273.478846) (xy 383.708259 -273.512938)
			(xy 383.667756 -273.540894) (xy 383.623294 -273.561992) (xy 383.576023 -273.575684) (xy 383.527168 -273.581616)
			(xy 383.477993 -273.579635) (xy 383.429774 -273.569791) (xy 383.383758 -273.552339) (xy 383.341137 -273.527732)
			(xy 383.303016 -273.496607) (xy 383.270381 -273.45977) (xy 383.244078 -273.418174) (xy 383.224787 -273.372898)
			(xy 383.21301 -273.325114) (xy 383.20905 -273.27606) (xy 382.880108 -273.27606) (xy 382.879613 -273.300667)
			(xy 382.871718 -273.349244) (xy 382.856134 -273.395925) (xy 382.833263 -273.439502) (xy 382.803698 -273.478846)
			(xy 382.768205 -273.512938) (xy 382.727702 -273.540894) (xy 382.68324 -273.561992) (xy 382.635969 -273.575684)
			(xy 382.587114 -273.581616) (xy 382.537939 -273.579635) (xy 382.48972 -273.569791) (xy 382.443704 -273.552339)
			(xy 382.401083 -273.527732) (xy 382.362962 -273.496607) (xy 382.330327 -273.45977) (xy 382.304024 -273.418174)
			(xy 382.284733 -273.372898) (xy 382.272956 -273.325114) (xy 382.268996 -273.27606) (xy 381.940054 -273.27606)
			(xy 381.939559 -273.300667) (xy 381.931664 -273.349244) (xy 381.91608 -273.395925) (xy 381.893209 -273.439502)
			(xy 381.863644 -273.478846) (xy 381.828151 -273.512938) (xy 381.787648 -273.540894) (xy 381.743186 -273.561992)
			(xy 381.695915 -273.575684) (xy 381.64706 -273.581616) (xy 381.597885 -273.579635) (xy 381.549666 -273.569791)
			(xy 381.50365 -273.552339) (xy 381.461029 -273.527732) (xy 381.422908 -273.496607) (xy 381.390273 -273.45977)
			(xy 381.36397 -273.418174) (xy 381.344679 -273.372898) (xy 381.332902 -273.325114) (xy 381.328942 -273.27606)
			(xy 381.010668 -273.27606) (xy 381.010156 -273.301506) (xy 381.001992 -273.35174) (xy 380.985876 -273.400014)
			(xy 380.962225 -273.445077) (xy 380.931652 -273.485763) (xy 380.894948 -273.521018) (xy 380.853064 -273.549928)
			(xy 380.807085 -273.571745) (xy 380.758201 -273.585905) (xy 380.70768 -273.592039) (xy 380.656828 -273.58999)
			(xy 380.606964 -273.57981) (xy 380.559378 -273.561763) (xy 380.515304 -273.536317) (xy 380.475882 -273.50413)
			(xy 380.442134 -273.466036) (xy 380.414933 -273.423022) (xy 380.394985 -273.376202) (xy 380.382806 -273.326788)
			(xy 380.378711 -273.27606) (xy 380.070614 -273.27606) (xy 380.070102 -273.301506) (xy 380.061938 -273.35174)
			(xy 380.045822 -273.400014) (xy 380.022171 -273.445077) (xy 379.991598 -273.485763) (xy 379.954894 -273.521018)
			(xy 379.91301 -273.549928) (xy 379.867031 -273.571745) (xy 379.818147 -273.585905) (xy 379.767626 -273.592039)
			(xy 379.716774 -273.58999) (xy 379.66691 -273.57981) (xy 379.619324 -273.561763) (xy 379.57525 -273.536317)
			(xy 379.535828 -273.50413) (xy 379.50208 -273.466036) (xy 379.474879 -273.423022) (xy 379.454931 -273.376202)
			(xy 379.442752 -273.326788) (xy 379.438657 -273.27606) (xy 378.190506 -273.27606) (xy 378.189994 -273.301506)
			(xy 378.18183 -273.35174) (xy 378.165714 -273.400014) (xy 378.142063 -273.445077) (xy 378.11149 -273.485763)
			(xy 378.074786 -273.521018) (xy 378.032902 -273.549928) (xy 377.986923 -273.571745) (xy 377.938039 -273.585905)
			(xy 377.887518 -273.592039) (xy 377.836666 -273.58999) (xy 377.786802 -273.57981) (xy 377.739216 -273.561763)
			(xy 377.695142 -273.536317) (xy 377.65572 -273.50413) (xy 377.621972 -273.466036) (xy 377.594771 -273.423022)
			(xy 377.574823 -273.376202) (xy 377.562644 -273.326788) (xy 377.558549 -273.27606) (xy 377.240038 -273.27606)
			(xy 377.239543 -273.300667) (xy 377.231648 -273.349244) (xy 377.216064 -273.395925) (xy 377.193193 -273.439502)
			(xy 377.163628 -273.478846) (xy 377.128135 -273.512938) (xy 377.087632 -273.540894) (xy 377.04317 -273.561992)
			(xy 376.995899 -273.575684) (xy 376.947044 -273.581616) (xy 376.897869 -273.579635) (xy 376.84965 -273.569791)
			(xy 376.803634 -273.552339) (xy 376.761013 -273.527732) (xy 376.722892 -273.496607) (xy 376.690257 -273.45977)
			(xy 376.663954 -273.418174) (xy 376.644663 -273.372898) (xy 376.632886 -273.325114) (xy 376.628926 -273.27606)
			(xy 376.310652 -273.27606) (xy 376.31014 -273.301506) (xy 376.301976 -273.35174) (xy 376.28586 -273.400014)
			(xy 376.262209 -273.445077) (xy 376.231636 -273.485763) (xy 376.194932 -273.521018) (xy 376.153048 -273.549928)
			(xy 376.107069 -273.571745) (xy 376.058185 -273.585905) (xy 376.007664 -273.592039) (xy 375.956812 -273.58999)
			(xy 375.906948 -273.57981) (xy 375.859362 -273.561763) (xy 375.815288 -273.536317) (xy 375.775866 -273.50413)
			(xy 375.742118 -273.466036) (xy 375.714917 -273.423022) (xy 375.694969 -273.376202) (xy 375.68279 -273.326788)
			(xy 375.678695 -273.27606) (xy 375.3597 -273.27606) (xy 375.359702 -273.301472) (xy 375.3513 -273.351569)
			(xy 375.334721 -273.399584) (xy 375.310425 -273.444193) (xy 375.27908 -273.484166) (xy 375.260616 -273.501612)
			(xy 375.25325 -273.508216) (xy 375.240804 -273.535394) (xy 375.23674 -273.54784) (xy 375.235978 -273.556476)
			(xy 375.235978 -274.086066) (xy 376.148595 -274.086066) (xy 376.15269 -274.035338) (xy 376.164869 -273.985924)
			(xy 376.184817 -273.939104) (xy 376.212018 -273.89609) (xy 376.245766 -273.857996) (xy 376.285188 -273.825809)
			(xy 376.329262 -273.800363) (xy 376.376848 -273.782316) (xy 376.426712 -273.772136) (xy 376.477564 -273.770087)
			(xy 376.528085 -273.776221) (xy 376.576969 -273.790381) (xy 376.622948 -273.812198) (xy 376.664832 -273.841108)
			(xy 376.701536 -273.876363) (xy 376.732109 -273.917049) (xy 376.75576 -273.962112) (xy 376.771876 -274.010386)
			(xy 376.78004 -274.06062) (xy 376.780552 -274.086066) (xy 377.088649 -274.086066) (xy 377.092744 -274.035338)
			(xy 377.104923 -273.985924) (xy 377.124871 -273.939104) (xy 377.152072 -273.89609) (xy 377.18582 -273.857996)
			(xy 377.225242 -273.825809) (xy 377.269316 -273.800363) (xy 377.316902 -273.782316) (xy 377.366766 -273.772136)
			(xy 377.417618 -273.770087) (xy 377.468139 -273.776221) (xy 377.517023 -273.790381) (xy 377.563002 -273.812198)
			(xy 377.604886 -273.841108) (xy 377.64159 -273.876363) (xy 377.672163 -273.917049) (xy 377.695814 -273.962112)
			(xy 377.71193 -274.010386) (xy 377.720094 -274.06062) (xy 377.720606 -274.086066) (xy 378.039134 -274.086066)
			(xy 378.043094 -274.037012) (xy 378.054871 -273.989228) (xy 378.074162 -273.943952) (xy 378.100465 -273.902356)
			(xy 378.1331 -273.865519) (xy 378.171221 -273.834394) (xy 378.213842 -273.809787) (xy 378.259858 -273.792335)
			(xy 378.308077 -273.782491) (xy 378.357252 -273.78051) (xy 378.406107 -273.786442) (xy 378.453378 -273.800134)
			(xy 378.49784 -273.821232) (xy 378.538343 -273.849188) (xy 378.573836 -273.88328) (xy 378.603401 -273.922624)
			(xy 378.626272 -273.966201) (xy 378.641856 -274.012882) (xy 378.649751 -274.061459) (xy 378.650246 -274.086066)
			(xy 378.968503 -274.086066) (xy 378.972598 -274.035338) (xy 378.984777 -273.985924) (xy 379.004725 -273.939104)
			(xy 379.031926 -273.89609) (xy 379.065674 -273.857996) (xy 379.105096 -273.825809) (xy 379.14917 -273.800363)
			(xy 379.196756 -273.782316) (xy 379.24662 -273.772136) (xy 379.297472 -273.770087) (xy 379.347993 -273.776221)
			(xy 379.396877 -273.790381) (xy 379.442856 -273.812198) (xy 379.48474 -273.841108) (xy 379.521444 -273.876363)
			(xy 379.552017 -273.917049) (xy 379.575668 -273.962112) (xy 379.591784 -274.010386) (xy 379.599948 -274.06062)
			(xy 379.60046 -274.086066) (xy 379.918988 -274.086066) (xy 379.922948 -274.037012) (xy 379.934725 -273.989228)
			(xy 379.954016 -273.943952) (xy 379.980319 -273.902356) (xy 380.012954 -273.865519) (xy 380.051075 -273.834394)
			(xy 380.093696 -273.809787) (xy 380.139712 -273.792335) (xy 380.187931 -273.782491) (xy 380.237106 -273.78051)
			(xy 380.285961 -273.786442) (xy 380.333232 -273.800134) (xy 380.377694 -273.821232) (xy 380.418197 -273.849188)
			(xy 380.45369 -273.88328) (xy 380.483255 -273.922624) (xy 380.506126 -273.966201) (xy 380.52171 -274.012882)
			(xy 380.529605 -274.061459) (xy 380.5301 -274.086066) (xy 380.848611 -274.086066) (xy 380.852706 -274.035338)
			(xy 380.864885 -273.985924) (xy 380.884833 -273.939104) (xy 380.912034 -273.89609) (xy 380.945782 -273.857996)
			(xy 380.985204 -273.825809) (xy 381.029278 -273.800363) (xy 381.076864 -273.782316) (xy 381.126728 -273.772136)
			(xy 381.17758 -273.770087) (xy 381.228101 -273.776221) (xy 381.276985 -273.790381) (xy 381.322964 -273.812198)
			(xy 381.364848 -273.841108) (xy 381.401552 -273.876363) (xy 381.432125 -273.917049) (xy 381.455776 -273.962112)
			(xy 381.471892 -274.010386) (xy 381.480056 -274.06062) (xy 381.480568 -274.086066) (xy 381.799096 -274.086066)
			(xy 381.803056 -274.037012) (xy 381.814833 -273.989228) (xy 381.834124 -273.943952) (xy 381.860427 -273.902356)
			(xy 381.893062 -273.865519) (xy 381.931183 -273.834394) (xy 381.973804 -273.809787) (xy 382.01982 -273.792335)
			(xy 382.068039 -273.782491) (xy 382.117214 -273.78051) (xy 382.166069 -273.786442) (xy 382.21334 -273.800134)
			(xy 382.257802 -273.821232) (xy 382.298305 -273.849188) (xy 382.333798 -273.88328) (xy 382.363363 -273.922624)
			(xy 382.386234 -273.966201) (xy 382.401818 -274.012882) (xy 382.409713 -274.061459) (xy 382.410208 -274.086066)
			(xy 382.738896 -274.086066) (xy 382.742856 -274.037012) (xy 382.754633 -273.989228) (xy 382.773924 -273.943952)
			(xy 382.800227 -273.902356) (xy 382.832862 -273.865519) (xy 382.870983 -273.834394) (xy 382.913604 -273.809787)
			(xy 382.95962 -273.792335) (xy 383.007839 -273.782491) (xy 383.057014 -273.78051) (xy 383.105869 -273.786442)
			(xy 383.15314 -273.800134) (xy 383.197602 -273.821232) (xy 383.238105 -273.849188) (xy 383.273598 -273.88328)
			(xy 383.303163 -273.922624) (xy 383.326034 -273.966201) (xy 383.341618 -274.012882) (xy 383.349513 -274.061459)
			(xy 383.350008 -274.086066) (xy 383.67895 -274.086066) (xy 383.68291 -274.037012) (xy 383.694687 -273.989228)
			(xy 383.713978 -273.943952) (xy 383.740281 -273.902356) (xy 383.772916 -273.865519) (xy 383.811037 -273.834394)
			(xy 383.853658 -273.809787) (xy 383.899674 -273.792335) (xy 383.947893 -273.782491) (xy 383.997068 -273.78051)
			(xy 384.045923 -273.786442) (xy 384.093194 -273.800134) (xy 384.137656 -273.821232) (xy 384.178159 -273.849188)
			(xy 384.213652 -273.88328) (xy 384.243217 -273.922624) (xy 384.266088 -273.966201) (xy 384.281672 -274.012882)
			(xy 384.289567 -274.061459) (xy 384.290062 -274.086066) (xy 384.619004 -274.086066) (xy 384.622964 -274.037012)
			(xy 384.634741 -273.989228) (xy 384.654032 -273.943952) (xy 384.680335 -273.902356) (xy 384.71297 -273.865519)
			(xy 384.751091 -273.834394) (xy 384.793712 -273.809787) (xy 384.839728 -273.792335) (xy 384.887947 -273.782491)
			(xy 384.937122 -273.78051) (xy 384.985977 -273.786442) (xy 385.033248 -273.800134) (xy 385.07771 -273.821232)
			(xy 385.118213 -273.849188) (xy 385.153706 -273.88328) (xy 385.183271 -273.922624) (xy 385.206142 -273.966201)
			(xy 385.221726 -274.012882) (xy 385.229621 -274.061459) (xy 385.230116 -274.086066) (xy 385.559058 -274.086066)
			(xy 385.563018 -274.037012) (xy 385.574795 -273.989228) (xy 385.594086 -273.943952) (xy 385.620389 -273.902356)
			(xy 385.653024 -273.865519) (xy 385.691145 -273.834394) (xy 385.733766 -273.809787) (xy 385.779782 -273.792335)
			(xy 385.828001 -273.782491) (xy 385.877176 -273.78051) (xy 385.926031 -273.786442) (xy 385.973302 -273.800134)
			(xy 386.017764 -273.821232) (xy 386.058267 -273.849188) (xy 386.09376 -273.88328) (xy 386.123325 -273.922624)
			(xy 386.146196 -273.966201) (xy 386.16178 -274.012882) (xy 386.169675 -274.061459) (xy 386.17017 -274.086066)
			(xy 386.499112 -274.086066) (xy 386.503072 -274.037012) (xy 386.514849 -273.989228) (xy 386.53414 -273.943952)
			(xy 386.560443 -273.902356) (xy 386.593078 -273.865519) (xy 386.631199 -273.834394) (xy 386.67382 -273.809787)
			(xy 386.719836 -273.792335) (xy 386.768055 -273.782491) (xy 386.81723 -273.78051) (xy 386.866085 -273.786442)
			(xy 386.913356 -273.800134) (xy 386.957818 -273.821232) (xy 386.998321 -273.849188) (xy 387.033814 -273.88328)
			(xy 387.063379 -273.922624) (xy 387.08625 -273.966201) (xy 387.101834 -274.012882) (xy 387.109729 -274.061459)
			(xy 387.110224 -274.086066) (xy 387.438912 -274.086066) (xy 387.442872 -274.037012) (xy 387.454649 -273.989228)
			(xy 387.47394 -273.943952) (xy 387.500243 -273.902356) (xy 387.532878 -273.865519) (xy 387.570999 -273.834394)
			(xy 387.61362 -273.809787) (xy 387.659636 -273.792335) (xy 387.707855 -273.782491) (xy 387.75703 -273.78051)
			(xy 387.805885 -273.786442) (xy 387.853156 -273.800134) (xy 387.897618 -273.821232) (xy 387.938121 -273.849188)
			(xy 387.973614 -273.88328) (xy 388.003179 -273.922624) (xy 388.02605 -273.966201) (xy 388.041634 -274.012882)
			(xy 388.049529 -274.061459) (xy 388.050024 -274.086066) (xy 388.049529 -274.110673) (xy 388.041634 -274.15925)
			(xy 388.02605 -274.205931) (xy 388.003179 -274.249508) (xy 387.973614 -274.288852) (xy 387.938121 -274.322944)
			(xy 387.897618 -274.3509) (xy 387.853156 -274.371998) (xy 387.805885 -274.38569) (xy 387.75703 -274.391622)
			(xy 387.707855 -274.389641) (xy 387.659636 -274.379797) (xy 387.61362 -274.362345) (xy 387.570999 -274.337738)
			(xy 387.532878 -274.306613) (xy 387.500243 -274.269776) (xy 387.47394 -274.22818) (xy 387.454649 -274.182904)
			(xy 387.442872 -274.13512) (xy 387.438912 -274.086066) (xy 387.110224 -274.086066) (xy 387.109729 -274.110673)
			(xy 387.101834 -274.15925) (xy 387.08625 -274.205931) (xy 387.063379 -274.249508) (xy 387.033814 -274.288852)
			(xy 386.998321 -274.322944) (xy 386.957818 -274.3509) (xy 386.913356 -274.371998) (xy 386.866085 -274.38569)
			(xy 386.81723 -274.391622) (xy 386.768055 -274.389641) (xy 386.719836 -274.379797) (xy 386.67382 -274.362345)
			(xy 386.631199 -274.337738) (xy 386.593078 -274.306613) (xy 386.560443 -274.269776) (xy 386.53414 -274.22818)
			(xy 386.514849 -274.182904) (xy 386.503072 -274.13512) (xy 386.499112 -274.086066) (xy 386.17017 -274.086066)
			(xy 386.169675 -274.110673) (xy 386.16178 -274.15925) (xy 386.146196 -274.205931) (xy 386.123325 -274.249508)
			(xy 386.09376 -274.288852) (xy 386.058267 -274.322944) (xy 386.017764 -274.3509) (xy 385.973302 -274.371998)
			(xy 385.926031 -274.38569) (xy 385.877176 -274.391622) (xy 385.828001 -274.389641) (xy 385.779782 -274.379797)
			(xy 385.733766 -274.362345) (xy 385.691145 -274.337738) (xy 385.653024 -274.306613) (xy 385.620389 -274.269776)
			(xy 385.594086 -274.22818) (xy 385.574795 -274.182904) (xy 385.563018 -274.13512) (xy 385.559058 -274.086066)
			(xy 385.230116 -274.086066) (xy 385.229621 -274.110673) (xy 385.221726 -274.15925) (xy 385.206142 -274.205931)
			(xy 385.183271 -274.249508) (xy 385.153706 -274.288852) (xy 385.118213 -274.322944) (xy 385.07771 -274.3509)
			(xy 385.033248 -274.371998) (xy 384.985977 -274.38569) (xy 384.937122 -274.391622) (xy 384.887947 -274.389641)
			(xy 384.839728 -274.379797) (xy 384.793712 -274.362345) (xy 384.751091 -274.337738) (xy 384.71297 -274.306613)
			(xy 384.680335 -274.269776) (xy 384.654032 -274.22818) (xy 384.634741 -274.182904) (xy 384.622964 -274.13512)
			(xy 384.619004 -274.086066) (xy 384.290062 -274.086066) (xy 384.289567 -274.110673) (xy 384.281672 -274.15925)
			(xy 384.266088 -274.205931) (xy 384.243217 -274.249508) (xy 384.213652 -274.288852) (xy 384.178159 -274.322944)
			(xy 384.137656 -274.3509) (xy 384.093194 -274.371998) (xy 384.045923 -274.38569) (xy 383.997068 -274.391622)
			(xy 383.947893 -274.389641) (xy 383.899674 -274.379797) (xy 383.853658 -274.362345) (xy 383.811037 -274.337738)
			(xy 383.772916 -274.306613) (xy 383.740281 -274.269776) (xy 383.713978 -274.22818) (xy 383.694687 -274.182904)
			(xy 383.68291 -274.13512) (xy 383.67895 -274.086066) (xy 383.350008 -274.086066) (xy 383.349513 -274.110673)
			(xy 383.341618 -274.15925) (xy 383.326034 -274.205931) (xy 383.303163 -274.249508) (xy 383.273598 -274.288852)
			(xy 383.238105 -274.322944) (xy 383.197602 -274.3509) (xy 383.15314 -274.371998) (xy 383.105869 -274.38569)
			(xy 383.057014 -274.391622) (xy 383.007839 -274.389641) (xy 382.95962 -274.379797) (xy 382.913604 -274.362345)
			(xy 382.870983 -274.337738) (xy 382.832862 -274.306613) (xy 382.800227 -274.269776) (xy 382.773924 -274.22818)
			(xy 382.754633 -274.182904) (xy 382.742856 -274.13512) (xy 382.738896 -274.086066) (xy 382.410208 -274.086066)
			(xy 382.409713 -274.110673) (xy 382.401818 -274.15925) (xy 382.386234 -274.205931) (xy 382.363363 -274.249508)
			(xy 382.333798 -274.288852) (xy 382.298305 -274.322944) (xy 382.257802 -274.3509) (xy 382.21334 -274.371998)
			(xy 382.166069 -274.38569) (xy 382.117214 -274.391622) (xy 382.068039 -274.389641) (xy 382.01982 -274.379797)
			(xy 381.973804 -274.362345) (xy 381.931183 -274.337738) (xy 381.893062 -274.306613) (xy 381.860427 -274.269776)
			(xy 381.834124 -274.22818) (xy 381.814833 -274.182904) (xy 381.803056 -274.13512) (xy 381.799096 -274.086066)
			(xy 381.480568 -274.086066) (xy 381.480056 -274.111512) (xy 381.471892 -274.161746) (xy 381.455776 -274.21002)
			(xy 381.432125 -274.255083) (xy 381.401552 -274.295769) (xy 381.364848 -274.331024) (xy 381.322964 -274.359934)
			(xy 381.276985 -274.381751) (xy 381.228101 -274.395911) (xy 381.17758 -274.402045) (xy 381.126728 -274.399996)
			(xy 381.076864 -274.389816) (xy 381.029278 -274.371769) (xy 380.985204 -274.346323) (xy 380.945782 -274.314136)
			(xy 380.912034 -274.276042) (xy 380.884833 -274.233028) (xy 380.864885 -274.186208) (xy 380.852706 -274.136794)
			(xy 380.848611 -274.086066) (xy 380.5301 -274.086066) (xy 380.529605 -274.110673) (xy 380.52171 -274.15925)
			(xy 380.506126 -274.205931) (xy 380.483255 -274.249508) (xy 380.45369 -274.288852) (xy 380.418197 -274.322944)
			(xy 380.377694 -274.3509) (xy 380.333232 -274.371998) (xy 380.285961 -274.38569) (xy 380.237106 -274.391622)
			(xy 380.187931 -274.389641) (xy 380.139712 -274.379797) (xy 380.093696 -274.362345) (xy 380.051075 -274.337738)
			(xy 380.012954 -274.306613) (xy 379.980319 -274.269776) (xy 379.954016 -274.22818) (xy 379.934725 -274.182904)
			(xy 379.922948 -274.13512) (xy 379.918988 -274.086066) (xy 379.60046 -274.086066) (xy 379.599948 -274.111512)
			(xy 379.591784 -274.161746) (xy 379.575668 -274.21002) (xy 379.552017 -274.255083) (xy 379.521444 -274.295769)
			(xy 379.48474 -274.331024) (xy 379.442856 -274.359934) (xy 379.396877 -274.381751) (xy 379.347993 -274.395911)
			(xy 379.297472 -274.402045) (xy 379.24662 -274.399996) (xy 379.196756 -274.389816) (xy 379.14917 -274.371769)
			(xy 379.105096 -274.346323) (xy 379.065674 -274.314136) (xy 379.031926 -274.276042) (xy 379.004725 -274.233028)
			(xy 378.984777 -274.186208) (xy 378.972598 -274.136794) (xy 378.968503 -274.086066) (xy 378.650246 -274.086066)
			(xy 378.649751 -274.110673) (xy 378.641856 -274.15925) (xy 378.626272 -274.205931) (xy 378.603401 -274.249508)
			(xy 378.573836 -274.288852) (xy 378.538343 -274.322944) (xy 378.49784 -274.3509) (xy 378.453378 -274.371998)
			(xy 378.406107 -274.38569) (xy 378.357252 -274.391622) (xy 378.308077 -274.389641) (xy 378.259858 -274.379797)
			(xy 378.213842 -274.362345) (xy 378.171221 -274.337738) (xy 378.1331 -274.306613) (xy 378.100465 -274.269776)
			(xy 378.074162 -274.22818) (xy 378.054871 -274.182904) (xy 378.043094 -274.13512) (xy 378.039134 -274.086066)
			(xy 377.720606 -274.086066) (xy 377.720094 -274.111512) (xy 377.71193 -274.161746) (xy 377.695814 -274.21002)
			(xy 377.672163 -274.255083) (xy 377.64159 -274.295769) (xy 377.604886 -274.331024) (xy 377.563002 -274.359934)
			(xy 377.517023 -274.381751) (xy 377.468139 -274.395911) (xy 377.417618 -274.402045) (xy 377.366766 -274.399996)
			(xy 377.316902 -274.389816) (xy 377.269316 -274.371769) (xy 377.225242 -274.346323) (xy 377.18582 -274.314136)
			(xy 377.152072 -274.276042) (xy 377.124871 -274.233028) (xy 377.104923 -274.186208) (xy 377.092744 -274.136794)
			(xy 377.088649 -274.086066) (xy 376.780552 -274.086066) (xy 376.78004 -274.111512) (xy 376.771876 -274.161746)
			(xy 376.75576 -274.21002) (xy 376.732109 -274.255083) (xy 376.701536 -274.295769) (xy 376.664832 -274.331024)
			(xy 376.622948 -274.359934) (xy 376.576969 -274.381751) (xy 376.528085 -274.395911) (xy 376.477564 -274.402045)
			(xy 376.426712 -274.399996) (xy 376.376848 -274.389816) (xy 376.329262 -274.371769) (xy 376.285188 -274.346323)
			(xy 376.245766 -274.314136) (xy 376.212018 -274.276042) (xy 376.184817 -274.233028) (xy 376.164869 -274.186208)
			(xy 376.15269 -274.136794) (xy 376.148595 -274.086066) (xy 375.235978 -274.086066) (xy 375.235978 -274.615402)
			(xy 375.236994 -274.625562) (xy 375.24055 -274.636484) (xy 375.25325 -274.663916) (xy 375.260616 -274.67052)
			(xy 375.279042 -274.688006) (xy 375.310392 -274.727973) (xy 375.334695 -274.772578) (xy 375.35128 -274.820589)
			(xy 375.35969 -274.870683) (xy 375.359691 -274.896072) (xy 375.678695 -274.896072) (xy 375.68279 -274.845344)
			(xy 375.694969 -274.79593) (xy 375.714917 -274.74911) (xy 375.742118 -274.706096) (xy 375.775866 -274.668002)
			(xy 375.815288 -274.635815) (xy 375.859362 -274.610369) (xy 375.906948 -274.592322) (xy 375.956812 -274.582142)
			(xy 376.007664 -274.580093) (xy 376.058185 -274.586227) (xy 376.107069 -274.600387) (xy 376.153048 -274.622204)
			(xy 376.194932 -274.651114) (xy 376.231636 -274.686369) (xy 376.262209 -274.727055) (xy 376.28586 -274.772118)
			(xy 376.301976 -274.820392) (xy 376.31014 -274.870626) (xy 376.310652 -274.896072) (xy 376.628926 -274.896072)
			(xy 376.632886 -274.847018) (xy 376.644663 -274.799234) (xy 376.663954 -274.753958) (xy 376.690257 -274.712362)
			(xy 376.722892 -274.675525) (xy 376.761013 -274.6444) (xy 376.803634 -274.619793) (xy 376.84965 -274.602341)
			(xy 376.897869 -274.592497) (xy 376.947044 -274.590516) (xy 376.995899 -274.596448) (xy 377.04317 -274.61014)
			(xy 377.087632 -274.631238) (xy 377.128135 -274.659194) (xy 377.163628 -274.693286) (xy 377.193193 -274.73263)
			(xy 377.216064 -274.776207) (xy 377.231648 -274.822888) (xy 377.239543 -274.871465) (xy 377.240038 -274.896072)
			(xy 377.558549 -274.896072) (xy 377.562644 -274.845344) (xy 377.574823 -274.79593) (xy 377.594771 -274.74911)
			(xy 377.621972 -274.706096) (xy 377.65572 -274.668002) (xy 377.695142 -274.635815) (xy 377.739216 -274.610369)
			(xy 377.786802 -274.592322) (xy 377.836666 -274.582142) (xy 377.887518 -274.580093) (xy 377.938039 -274.586227)
			(xy 377.986923 -274.600387) (xy 378.032902 -274.622204) (xy 378.074786 -274.651114) (xy 378.11149 -274.686369)
			(xy 378.142063 -274.727055) (xy 378.165714 -274.772118) (xy 378.18183 -274.820392) (xy 378.189994 -274.870626)
			(xy 378.190506 -274.896072) (xy 378.509034 -274.896072) (xy 378.512994 -274.847018) (xy 378.524771 -274.799234)
			(xy 378.544062 -274.753958) (xy 378.570365 -274.712362) (xy 378.603 -274.675525) (xy 378.641121 -274.6444)
			(xy 378.683742 -274.619793) (xy 378.729758 -274.602341) (xy 378.777977 -274.592497) (xy 378.827152 -274.590516)
			(xy 378.876007 -274.596448) (xy 378.923278 -274.61014) (xy 378.96774 -274.631238) (xy 379.008243 -274.659194)
			(xy 379.043736 -274.693286) (xy 379.073301 -274.73263) (xy 379.096172 -274.776207) (xy 379.111756 -274.822888)
			(xy 379.119651 -274.871465) (xy 379.120146 -274.896072) (xy 379.438657 -274.896072) (xy 379.442752 -274.845344)
			(xy 379.454931 -274.79593) (xy 379.474879 -274.74911) (xy 379.50208 -274.706096) (xy 379.535828 -274.668002)
			(xy 379.57525 -274.635815) (xy 379.619324 -274.610369) (xy 379.66691 -274.592322) (xy 379.716774 -274.582142)
			(xy 379.767626 -274.580093) (xy 379.818147 -274.586227) (xy 379.867031 -274.600387) (xy 379.91301 -274.622204)
			(xy 379.954894 -274.651114) (xy 379.991598 -274.686369) (xy 380.022171 -274.727055) (xy 380.045822 -274.772118)
			(xy 380.061938 -274.820392) (xy 380.070102 -274.870626) (xy 380.070614 -274.896072) (xy 380.378711 -274.896072)
			(xy 380.382806 -274.845344) (xy 380.394985 -274.79593) (xy 380.414933 -274.74911) (xy 380.442134 -274.706096)
			(xy 380.475882 -274.668002) (xy 380.515304 -274.635815) (xy 380.559378 -274.610369) (xy 380.606964 -274.592322)
			(xy 380.656828 -274.582142) (xy 380.70768 -274.580093) (xy 380.758201 -274.586227) (xy 380.807085 -274.600387)
			(xy 380.853064 -274.622204) (xy 380.894948 -274.651114) (xy 380.931652 -274.686369) (xy 380.962225 -274.727055)
			(xy 380.985876 -274.772118) (xy 381.001992 -274.820392) (xy 381.010156 -274.870626) (xy 381.010668 -274.896072)
			(xy 381.328942 -274.896072) (xy 381.332902 -274.847018) (xy 381.344679 -274.799234) (xy 381.36397 -274.753958)
			(xy 381.390273 -274.712362) (xy 381.422908 -274.675525) (xy 381.461029 -274.6444) (xy 381.50365 -274.619793)
			(xy 381.549666 -274.602341) (xy 381.597885 -274.592497) (xy 381.64706 -274.590516) (xy 381.695915 -274.596448)
			(xy 381.743186 -274.61014) (xy 381.787648 -274.631238) (xy 381.828151 -274.659194) (xy 381.863644 -274.693286)
			(xy 381.893209 -274.73263) (xy 381.91608 -274.776207) (xy 381.931664 -274.822888) (xy 381.939559 -274.871465)
			(xy 381.940054 -274.896072) (xy 382.268996 -274.896072) (xy 382.272956 -274.847018) (xy 382.284733 -274.799234)
			(xy 382.304024 -274.753958) (xy 382.330327 -274.712362) (xy 382.362962 -274.675525) (xy 382.401083 -274.6444)
			(xy 382.443704 -274.619793) (xy 382.48972 -274.602341) (xy 382.537939 -274.592497) (xy 382.587114 -274.590516)
			(xy 382.635969 -274.596448) (xy 382.68324 -274.61014) (xy 382.727702 -274.631238) (xy 382.768205 -274.659194)
			(xy 382.803698 -274.693286) (xy 382.833263 -274.73263) (xy 382.856134 -274.776207) (xy 382.871718 -274.822888)
			(xy 382.879613 -274.871465) (xy 382.880108 -274.896072) (xy 383.20905 -274.896072) (xy 383.21301 -274.847018)
			(xy 383.224787 -274.799234) (xy 383.244078 -274.753958) (xy 383.270381 -274.712362) (xy 383.303016 -274.675525)
			(xy 383.341137 -274.6444) (xy 383.383758 -274.619793) (xy 383.429774 -274.602341) (xy 383.477993 -274.592497)
			(xy 383.527168 -274.590516) (xy 383.576023 -274.596448) (xy 383.623294 -274.61014) (xy 383.667756 -274.631238)
			(xy 383.708259 -274.659194) (xy 383.743752 -274.693286) (xy 383.773317 -274.73263) (xy 383.796188 -274.776207)
			(xy 383.811772 -274.822888) (xy 383.819667 -274.871465) (xy 383.820162 -274.896072) (xy 384.149104 -274.896072)
			(xy 384.153064 -274.847018) (xy 384.164841 -274.799234) (xy 384.184132 -274.753958) (xy 384.210435 -274.712362)
			(xy 384.24307 -274.675525) (xy 384.281191 -274.6444) (xy 384.323812 -274.619793) (xy 384.369828 -274.602341)
			(xy 384.418047 -274.592497) (xy 384.467222 -274.590516) (xy 384.516077 -274.596448) (xy 384.563348 -274.61014)
			(xy 384.60781 -274.631238) (xy 384.648313 -274.659194) (xy 384.683806 -274.693286) (xy 384.713371 -274.73263)
			(xy 384.736242 -274.776207) (xy 384.751826 -274.822888) (xy 384.759721 -274.871465) (xy 384.760216 -274.896072)
			(xy 385.088904 -274.896072) (xy 385.092864 -274.847018) (xy 385.104641 -274.799234) (xy 385.123932 -274.753958)
			(xy 385.150235 -274.712362) (xy 385.18287 -274.675525) (xy 385.220991 -274.6444) (xy 385.263612 -274.619793)
			(xy 385.309628 -274.602341) (xy 385.357847 -274.592497) (xy 385.407022 -274.590516) (xy 385.455877 -274.596448)
			(xy 385.503148 -274.61014) (xy 385.54761 -274.631238) (xy 385.588113 -274.659194) (xy 385.623606 -274.693286)
			(xy 385.653171 -274.73263) (xy 385.676042 -274.776207) (xy 385.691626 -274.822888) (xy 385.699521 -274.871465)
			(xy 385.700016 -274.896072) (xy 386.028958 -274.896072) (xy 386.032918 -274.847018) (xy 386.044695 -274.799234)
			(xy 386.063986 -274.753958) (xy 386.090289 -274.712362) (xy 386.122924 -274.675525) (xy 386.161045 -274.6444)
			(xy 386.203666 -274.619793) (xy 386.249682 -274.602341) (xy 386.297901 -274.592497) (xy 386.347076 -274.590516)
			(xy 386.395931 -274.596448) (xy 386.443202 -274.61014) (xy 386.487664 -274.631238) (xy 386.528167 -274.659194)
			(xy 386.56366 -274.693286) (xy 386.593225 -274.73263) (xy 386.616096 -274.776207) (xy 386.63168 -274.822888)
			(xy 386.639575 -274.871465) (xy 386.64007 -274.896072) (xy 386.969012 -274.896072) (xy 386.972972 -274.847018)
			(xy 386.984749 -274.799234) (xy 387.00404 -274.753958) (xy 387.030343 -274.712362) (xy 387.062978 -274.675525)
			(xy 387.101099 -274.6444) (xy 387.14372 -274.619793) (xy 387.189736 -274.602341) (xy 387.237955 -274.592497)
			(xy 387.28713 -274.590516) (xy 387.335985 -274.596448) (xy 387.383256 -274.61014) (xy 387.427718 -274.631238)
			(xy 387.468221 -274.659194) (xy 387.503714 -274.693286) (xy 387.533279 -274.73263) (xy 387.55615 -274.776207)
			(xy 387.571734 -274.822888) (xy 387.579629 -274.871465) (xy 387.580124 -274.896072) (xy 387.579629 -274.920679)
			(xy 387.571734 -274.969256) (xy 387.55615 -275.015937) (xy 387.533279 -275.059514) (xy 387.503714 -275.098858)
			(xy 387.468221 -275.13295) (xy 387.427718 -275.160906) (xy 387.383256 -275.182004) (xy 387.335985 -275.195696)
			(xy 387.28713 -275.201628) (xy 387.237955 -275.199647) (xy 387.189736 -275.189803) (xy 387.14372 -275.172351)
			(xy 387.101099 -275.147744) (xy 387.062978 -275.116619) (xy 387.030343 -275.079782) (xy 387.00404 -275.038186)
			(xy 386.984749 -274.99291) (xy 386.972972 -274.945126) (xy 386.969012 -274.896072) (xy 386.64007 -274.896072)
			(xy 386.639575 -274.920679) (xy 386.63168 -274.969256) (xy 386.616096 -275.015937) (xy 386.593225 -275.059514)
			(xy 386.56366 -275.098858) (xy 386.528167 -275.13295) (xy 386.487664 -275.160906) (xy 386.443202 -275.182004)
			(xy 386.395931 -275.195696) (xy 386.347076 -275.201628) (xy 386.297901 -275.199647) (xy 386.249682 -275.189803)
			(xy 386.203666 -275.172351) (xy 386.161045 -275.147744) (xy 386.122924 -275.116619) (xy 386.090289 -275.079782)
			(xy 386.063986 -275.038186) (xy 386.044695 -274.99291) (xy 386.032918 -274.945126) (xy 386.028958 -274.896072)
			(xy 385.700016 -274.896072) (xy 385.699521 -274.920679) (xy 385.691626 -274.969256) (xy 385.676042 -275.015937)
			(xy 385.653171 -275.059514) (xy 385.623606 -275.098858) (xy 385.588113 -275.13295) (xy 385.54761 -275.160906)
			(xy 385.503148 -275.182004) (xy 385.455877 -275.195696) (xy 385.407022 -275.201628) (xy 385.357847 -275.199647)
			(xy 385.309628 -275.189803) (xy 385.263612 -275.172351) (xy 385.220991 -275.147744) (xy 385.18287 -275.116619)
			(xy 385.150235 -275.079782) (xy 385.123932 -275.038186) (xy 385.104641 -274.99291) (xy 385.092864 -274.945126)
			(xy 385.088904 -274.896072) (xy 384.760216 -274.896072) (xy 384.759721 -274.920679) (xy 384.751826 -274.969256)
			(xy 384.736242 -275.015937) (xy 384.713371 -275.059514) (xy 384.683806 -275.098858) (xy 384.648313 -275.13295)
			(xy 384.60781 -275.160906) (xy 384.563348 -275.182004) (xy 384.516077 -275.195696) (xy 384.467222 -275.201628)
			(xy 384.418047 -275.199647) (xy 384.369828 -275.189803) (xy 384.323812 -275.172351) (xy 384.281191 -275.147744)
			(xy 384.24307 -275.116619) (xy 384.210435 -275.079782) (xy 384.184132 -275.038186) (xy 384.164841 -274.99291)
			(xy 384.153064 -274.945126) (xy 384.149104 -274.896072) (xy 383.820162 -274.896072) (xy 383.819667 -274.920679)
			(xy 383.811772 -274.969256) (xy 383.796188 -275.015937) (xy 383.773317 -275.059514) (xy 383.743752 -275.098858)
			(xy 383.708259 -275.13295) (xy 383.667756 -275.160906) (xy 383.623294 -275.182004) (xy 383.576023 -275.195696)
			(xy 383.527168 -275.201628) (xy 383.477993 -275.199647) (xy 383.429774 -275.189803) (xy 383.383758 -275.172351)
			(xy 383.341137 -275.147744) (xy 383.303016 -275.116619) (xy 383.270381 -275.079782) (xy 383.244078 -275.038186)
			(xy 383.224787 -274.99291) (xy 383.21301 -274.945126) (xy 383.20905 -274.896072) (xy 382.880108 -274.896072)
			(xy 382.879613 -274.920679) (xy 382.871718 -274.969256) (xy 382.856134 -275.015937) (xy 382.833263 -275.059514)
			(xy 382.803698 -275.098858) (xy 382.768205 -275.13295) (xy 382.727702 -275.160906) (xy 382.68324 -275.182004)
			(xy 382.635969 -275.195696) (xy 382.587114 -275.201628) (xy 382.537939 -275.199647) (xy 382.48972 -275.189803)
			(xy 382.443704 -275.172351) (xy 382.401083 -275.147744) (xy 382.362962 -275.116619) (xy 382.330327 -275.079782)
			(xy 382.304024 -275.038186) (xy 382.284733 -274.99291) (xy 382.272956 -274.945126) (xy 382.268996 -274.896072)
			(xy 381.940054 -274.896072) (xy 381.939559 -274.920679) (xy 381.931664 -274.969256) (xy 381.91608 -275.015937)
			(xy 381.893209 -275.059514) (xy 381.863644 -275.098858) (xy 381.828151 -275.13295) (xy 381.787648 -275.160906)
			(xy 381.743186 -275.182004) (xy 381.695915 -275.195696) (xy 381.64706 -275.201628) (xy 381.597885 -275.199647)
			(xy 381.549666 -275.189803) (xy 381.50365 -275.172351) (xy 381.461029 -275.147744) (xy 381.422908 -275.116619)
			(xy 381.390273 -275.079782) (xy 381.36397 -275.038186) (xy 381.344679 -274.99291) (xy 381.332902 -274.945126)
			(xy 381.328942 -274.896072) (xy 381.010668 -274.896072) (xy 381.010156 -274.921518) (xy 381.001992 -274.971752)
			(xy 380.985876 -275.020026) (xy 380.962225 -275.065089) (xy 380.931652 -275.105775) (xy 380.894948 -275.14103)
			(xy 380.853064 -275.16994) (xy 380.807085 -275.191757) (xy 380.758201 -275.205917) (xy 380.70768 -275.212051)
			(xy 380.656828 -275.210002) (xy 380.606964 -275.199822) (xy 380.559378 -275.181775) (xy 380.515304 -275.156329)
			(xy 380.475882 -275.124142) (xy 380.442134 -275.086048) (xy 380.414933 -275.043034) (xy 380.394985 -274.996214)
			(xy 380.382806 -274.9468) (xy 380.378711 -274.896072) (xy 380.070614 -274.896072) (xy 380.070102 -274.921518)
			(xy 380.061938 -274.971752) (xy 380.045822 -275.020026) (xy 380.022171 -275.065089) (xy 379.991598 -275.105775)
			(xy 379.954894 -275.14103) (xy 379.91301 -275.16994) (xy 379.867031 -275.191757) (xy 379.818147 -275.205917)
			(xy 379.767626 -275.212051) (xy 379.716774 -275.210002) (xy 379.66691 -275.199822) (xy 379.619324 -275.181775)
			(xy 379.57525 -275.156329) (xy 379.535828 -275.124142) (xy 379.50208 -275.086048) (xy 379.474879 -275.043034)
			(xy 379.454931 -274.996214) (xy 379.442752 -274.9468) (xy 379.438657 -274.896072) (xy 379.120146 -274.896072)
			(xy 379.119651 -274.920679) (xy 379.111756 -274.969256) (xy 379.096172 -275.015937) (xy 379.073301 -275.059514)
			(xy 379.043736 -275.098858) (xy 379.008243 -275.13295) (xy 378.96774 -275.160906) (xy 378.923278 -275.182004)
			(xy 378.876007 -275.195696) (xy 378.827152 -275.201628) (xy 378.777977 -275.199647) (xy 378.729758 -275.189803)
			(xy 378.683742 -275.172351) (xy 378.641121 -275.147744) (xy 378.603 -275.116619) (xy 378.570365 -275.079782)
			(xy 378.544062 -275.038186) (xy 378.524771 -274.99291) (xy 378.512994 -274.945126) (xy 378.509034 -274.896072)
			(xy 378.190506 -274.896072) (xy 378.189994 -274.921518) (xy 378.18183 -274.971752) (xy 378.165714 -275.020026)
			(xy 378.142063 -275.065089) (xy 378.11149 -275.105775) (xy 378.074786 -275.14103) (xy 378.032902 -275.16994)
			(xy 377.986923 -275.191757) (xy 377.938039 -275.205917) (xy 377.887518 -275.212051) (xy 377.836666 -275.210002)
			(xy 377.786802 -275.199822) (xy 377.739216 -275.181775) (xy 377.695142 -275.156329) (xy 377.65572 -275.124142)
			(xy 377.621972 -275.086048) (xy 377.594771 -275.043034) (xy 377.574823 -274.996214) (xy 377.562644 -274.9468)
			(xy 377.558549 -274.896072) (xy 377.240038 -274.896072) (xy 377.239543 -274.920679) (xy 377.231648 -274.969256)
			(xy 377.216064 -275.015937) (xy 377.193193 -275.059514) (xy 377.163628 -275.098858) (xy 377.128135 -275.13295)
			(xy 377.087632 -275.160906) (xy 377.04317 -275.182004) (xy 376.995899 -275.195696) (xy 376.947044 -275.201628)
			(xy 376.897869 -275.199647) (xy 376.84965 -275.189803) (xy 376.803634 -275.172351) (xy 376.761013 -275.147744)
			(xy 376.722892 -275.116619) (xy 376.690257 -275.079782) (xy 376.663954 -275.038186) (xy 376.644663 -274.99291)
			(xy 376.632886 -274.945126) (xy 376.628926 -274.896072) (xy 376.310652 -274.896072) (xy 376.31014 -274.921518)
			(xy 376.301976 -274.971752) (xy 376.28586 -275.020026) (xy 376.262209 -275.065089) (xy 376.231636 -275.105775)
			(xy 376.194932 -275.14103) (xy 376.153048 -275.16994) (xy 376.107069 -275.191757) (xy 376.058185 -275.205917)
			(xy 376.007664 -275.212051) (xy 375.956812 -275.210002) (xy 375.906948 -275.199822) (xy 375.859362 -275.181775)
			(xy 375.815288 -275.156329) (xy 375.775866 -275.124142) (xy 375.742118 -275.086048) (xy 375.714917 -275.043034)
			(xy 375.694969 -274.996214) (xy 375.68279 -274.9468) (xy 375.678695 -274.896072) (xy 375.359691 -274.896072)
			(xy 375.359693 -274.921479) (xy 375.351289 -274.971574) (xy 375.33471 -275.019588) (xy 375.310413 -275.064195)
			(xy 375.279068 -275.104166) (xy 375.260616 -275.121624) (xy 375.25325 -275.128228) (xy 375.240804 -275.155406)
			(xy 375.23674 -275.167852) (xy 375.235978 -275.176488) (xy 375.235978 -275.34743) (xy 375.236371 -275.355986)
			(xy 375.242161 -275.372095) (xy 375.252971 -275.385367) (xy 375.260108 -275.390102) (xy 375.315734 -275.42363)
			(xy 375.336054 -275.435822) (xy 375.34124 -275.438352) (xy 375.352394 -275.441293) (xy 375.358152 -275.441664)
			(xy 375.370852 -275.441918) (xy 375.382536 -275.435822) (xy 375.40453 -275.424825) (xy 375.451159 -275.409223)
			(xy 375.499684 -275.401286) (xy 375.524268 -275.40077) (xy 375.530364 -275.40077) (xy 375.55532 -275.401722)
			(xy 375.604436 -275.410743) (xy 375.65143 -275.427636) (xy 375.69505 -275.45195) (xy 375.734132 -275.483036)
			(xy 375.767636 -275.520067) (xy 375.794668 -275.562056) (xy 375.814508 -275.607883) (xy 375.826628 -275.656328)
			(xy 375.830702 -275.706078) (xy 376.148595 -275.706078) (xy 376.15269 -275.65535) (xy 376.164869 -275.605936)
			(xy 376.184817 -275.559116) (xy 376.212018 -275.516102) (xy 376.245766 -275.478008) (xy 376.285188 -275.445821)
			(xy 376.329262 -275.420375) (xy 376.376848 -275.402328) (xy 376.426712 -275.392148) (xy 376.477564 -275.390099)
			(xy 376.528085 -275.396233) (xy 376.576969 -275.410393) (xy 376.622948 -275.43221) (xy 376.664832 -275.46112)
			(xy 376.701536 -275.496375) (xy 376.732109 -275.537061) (xy 376.75576 -275.582124) (xy 376.771876 -275.630398)
			(xy 376.78004 -275.680632) (xy 376.780552 -275.706078) (xy 377.088649 -275.706078) (xy 377.092744 -275.65535)
			(xy 377.104923 -275.605936) (xy 377.124871 -275.559116) (xy 377.152072 -275.516102) (xy 377.18582 -275.478008)
			(xy 377.225242 -275.445821) (xy 377.269316 -275.420375) (xy 377.316902 -275.402328) (xy 377.366766 -275.392148)
			(xy 377.417618 -275.390099) (xy 377.468139 -275.396233) (xy 377.517023 -275.410393) (xy 377.563002 -275.43221)
			(xy 377.604886 -275.46112) (xy 377.64159 -275.496375) (xy 377.672163 -275.537061) (xy 377.695814 -275.582124)
			(xy 377.71193 -275.630398) (xy 377.720094 -275.680632) (xy 377.720606 -275.706078) (xy 378.968503 -275.706078)
			(xy 378.972598 -275.65535) (xy 378.984777 -275.605936) (xy 379.004725 -275.559116) (xy 379.031926 -275.516102)
			(xy 379.065674 -275.478008) (xy 379.105096 -275.445821) (xy 379.14917 -275.420375) (xy 379.196756 -275.402328)
			(xy 379.24662 -275.392148) (xy 379.297472 -275.390099) (xy 379.347993 -275.396233) (xy 379.396877 -275.410393)
			(xy 379.442856 -275.43221) (xy 379.48474 -275.46112) (xy 379.521444 -275.496375) (xy 379.552017 -275.537061)
			(xy 379.575668 -275.582124) (xy 379.591784 -275.630398) (xy 379.599948 -275.680632) (xy 379.60046 -275.706078)
			(xy 379.918988 -275.706078) (xy 379.922948 -275.657024) (xy 379.934725 -275.60924) (xy 379.954016 -275.563964)
			(xy 379.980319 -275.522368) (xy 380.012954 -275.485531) (xy 380.051075 -275.454406) (xy 380.093696 -275.429799)
			(xy 380.139712 -275.412347) (xy 380.187931 -275.402503) (xy 380.237106 -275.400522) (xy 380.285961 -275.406454)
			(xy 380.333232 -275.420146) (xy 380.377694 -275.441244) (xy 380.418197 -275.4692) (xy 380.45369 -275.503292)
			(xy 380.483255 -275.542636) (xy 380.506126 -275.586213) (xy 380.52171 -275.632894) (xy 380.529605 -275.681471)
			(xy 380.5301 -275.706078) (xy 380.848611 -275.706078) (xy 380.852706 -275.65535) (xy 380.864885 -275.605936)
			(xy 380.884833 -275.559116) (xy 380.912034 -275.516102) (xy 380.945782 -275.478008) (xy 380.985204 -275.445821)
			(xy 381.029278 -275.420375) (xy 381.076864 -275.402328) (xy 381.126728 -275.392148) (xy 381.17758 -275.390099)
			(xy 381.228101 -275.396233) (xy 381.276985 -275.410393) (xy 381.322964 -275.43221) (xy 381.364848 -275.46112)
			(xy 381.401552 -275.496375) (xy 381.432125 -275.537061) (xy 381.455776 -275.582124) (xy 381.471892 -275.630398)
			(xy 381.480056 -275.680632) (xy 381.480568 -275.706078) (xy 381.799096 -275.706078) (xy 381.803056 -275.657024)
			(xy 381.814833 -275.60924) (xy 381.834124 -275.563964) (xy 381.860427 -275.522368) (xy 381.893062 -275.485531)
			(xy 381.931183 -275.454406) (xy 381.973804 -275.429799) (xy 382.01982 -275.412347) (xy 382.068039 -275.402503)
			(xy 382.117214 -275.400522) (xy 382.166069 -275.406454) (xy 382.21334 -275.420146) (xy 382.257802 -275.441244)
			(xy 382.298305 -275.4692) (xy 382.333798 -275.503292) (xy 382.363363 -275.542636) (xy 382.386234 -275.586213)
			(xy 382.401818 -275.632894) (xy 382.409713 -275.681471) (xy 382.410208 -275.706078) (xy 382.738896 -275.706078)
			(xy 382.742856 -275.657024) (xy 382.754633 -275.60924) (xy 382.773924 -275.563964) (xy 382.800227 -275.522368)
			(xy 382.832862 -275.485531) (xy 382.870983 -275.454406) (xy 382.913604 -275.429799) (xy 382.95962 -275.412347)
			(xy 383.007839 -275.402503) (xy 383.057014 -275.400522) (xy 383.105869 -275.406454) (xy 383.15314 -275.420146)
			(xy 383.197602 -275.441244) (xy 383.238105 -275.4692) (xy 383.273598 -275.503292) (xy 383.303163 -275.542636)
			(xy 383.326034 -275.586213) (xy 383.341618 -275.632894) (xy 383.349513 -275.681471) (xy 383.350008 -275.706078)
			(xy 383.67895 -275.706078) (xy 383.68291 -275.657024) (xy 383.694687 -275.60924) (xy 383.713978 -275.563964)
			(xy 383.740281 -275.522368) (xy 383.772916 -275.485531) (xy 383.811037 -275.454406) (xy 383.853658 -275.429799)
			(xy 383.899674 -275.412347) (xy 383.947893 -275.402503) (xy 383.997068 -275.400522) (xy 384.045923 -275.406454)
			(xy 384.093194 -275.420146) (xy 384.137656 -275.441244) (xy 384.178159 -275.4692) (xy 384.213652 -275.503292)
			(xy 384.243217 -275.542636) (xy 384.266088 -275.586213) (xy 384.281672 -275.632894) (xy 384.289567 -275.681471)
			(xy 384.290062 -275.706078) (xy 385.559058 -275.706078) (xy 385.563018 -275.657024) (xy 385.574795 -275.60924)
			(xy 385.594086 -275.563964) (xy 385.620389 -275.522368) (xy 385.653024 -275.485531) (xy 385.691145 -275.454406)
			(xy 385.733766 -275.429799) (xy 385.779782 -275.412347) (xy 385.828001 -275.402503) (xy 385.877176 -275.400522)
			(xy 385.926031 -275.406454) (xy 385.973302 -275.420146) (xy 386.017764 -275.441244) (xy 386.058267 -275.4692)
			(xy 386.09376 -275.503292) (xy 386.123325 -275.542636) (xy 386.146196 -275.586213) (xy 386.16178 -275.632894)
			(xy 386.169675 -275.681471) (xy 386.17017 -275.706078) (xy 386.499112 -275.706078) (xy 386.503072 -275.657024)
			(xy 386.514849 -275.60924) (xy 386.53414 -275.563964) (xy 386.560443 -275.522368) (xy 386.593078 -275.485531)
			(xy 386.631199 -275.454406) (xy 386.67382 -275.429799) (xy 386.719836 -275.412347) (xy 386.768055 -275.402503)
			(xy 386.81723 -275.400522) (xy 386.866085 -275.406454) (xy 386.913356 -275.420146) (xy 386.957818 -275.441244)
			(xy 386.998321 -275.4692) (xy 387.033814 -275.503292) (xy 387.063379 -275.542636) (xy 387.08625 -275.586213)
			(xy 387.101834 -275.632894) (xy 387.109729 -275.681471) (xy 387.110224 -275.706078) (xy 387.438912 -275.706078)
			(xy 387.442872 -275.657024) (xy 387.454649 -275.60924) (xy 387.47394 -275.563964) (xy 387.500243 -275.522368)
			(xy 387.532878 -275.485531) (xy 387.570999 -275.454406) (xy 387.61362 -275.429799) (xy 387.659636 -275.412347)
			(xy 387.707855 -275.402503) (xy 387.75703 -275.400522) (xy 387.805885 -275.406454) (xy 387.853156 -275.420146)
			(xy 387.897618 -275.441244) (xy 387.938121 -275.4692) (xy 387.973614 -275.503292) (xy 388.003179 -275.542636)
			(xy 388.02605 -275.586213) (xy 388.041634 -275.632894) (xy 388.049529 -275.681471) (xy 388.050024 -275.706078)
			(xy 388.049529 -275.730685) (xy 388.041634 -275.779262) (xy 388.02605 -275.825943) (xy 388.003179 -275.86952)
			(xy 387.973614 -275.908864) (xy 387.938121 -275.942956) (xy 387.897618 -275.970912) (xy 387.853156 -275.99201)
			(xy 387.805885 -276.005702) (xy 387.75703 -276.011634) (xy 387.707855 -276.009653) (xy 387.659636 -275.999809)
			(xy 387.61362 -275.982357) (xy 387.570999 -275.95775) (xy 387.532878 -275.926625) (xy 387.500243 -275.889788)
			(xy 387.47394 -275.848192) (xy 387.454649 -275.802916) (xy 387.442872 -275.755132) (xy 387.438912 -275.706078)
			(xy 387.110224 -275.706078) (xy 387.109729 -275.730685) (xy 387.101834 -275.779262) (xy 387.08625 -275.825943)
			(xy 387.063379 -275.86952) (xy 387.033814 -275.908864) (xy 386.998321 -275.942956) (xy 386.957818 -275.970912)
			(xy 386.913356 -275.99201) (xy 386.866085 -276.005702) (xy 386.81723 -276.011634) (xy 386.768055 -276.009653)
			(xy 386.719836 -275.999809) (xy 386.67382 -275.982357) (xy 386.631199 -275.95775) (xy 386.593078 -275.926625)
			(xy 386.560443 -275.889788) (xy 386.53414 -275.848192) (xy 386.514849 -275.802916) (xy 386.503072 -275.755132)
			(xy 386.499112 -275.706078) (xy 386.17017 -275.706078) (xy 386.169675 -275.730685) (xy 386.16178 -275.779262)
			(xy 386.146196 -275.825943) (xy 386.123325 -275.86952) (xy 386.09376 -275.908864) (xy 386.058267 -275.942956)
			(xy 386.017764 -275.970912) (xy 385.973302 -275.99201) (xy 385.926031 -276.005702) (xy 385.877176 -276.011634)
			(xy 385.828001 -276.009653) (xy 385.779782 -275.999809) (xy 385.733766 -275.982357) (xy 385.691145 -275.95775)
			(xy 385.653024 -275.926625) (xy 385.620389 -275.889788) (xy 385.594086 -275.848192) (xy 385.574795 -275.802916)
			(xy 385.563018 -275.755132) (xy 385.559058 -275.706078) (xy 384.290062 -275.706078) (xy 384.289567 -275.730685)
			(xy 384.281672 -275.779262) (xy 384.266088 -275.825943) (xy 384.243217 -275.86952) (xy 384.213652 -275.908864)
			(xy 384.178159 -275.942956) (xy 384.137656 -275.970912) (xy 384.093194 -275.99201) (xy 384.045923 -276.005702)
			(xy 383.997068 -276.011634) (xy 383.947893 -276.009653) (xy 383.899674 -275.999809) (xy 383.853658 -275.982357)
			(xy 383.811037 -275.95775) (xy 383.772916 -275.926625) (xy 383.740281 -275.889788) (xy 383.713978 -275.848192)
			(xy 383.694687 -275.802916) (xy 383.68291 -275.755132) (xy 383.67895 -275.706078) (xy 383.350008 -275.706078)
			(xy 383.349513 -275.730685) (xy 383.341618 -275.779262) (xy 383.326034 -275.825943) (xy 383.303163 -275.86952)
			(xy 383.273598 -275.908864) (xy 383.238105 -275.942956) (xy 383.197602 -275.970912) (xy 383.15314 -275.99201)
			(xy 383.105869 -276.005702) (xy 383.057014 -276.011634) (xy 383.007839 -276.009653) (xy 382.95962 -275.999809)
			(xy 382.913604 -275.982357) (xy 382.870983 -275.95775) (xy 382.832862 -275.926625) (xy 382.800227 -275.889788)
			(xy 382.773924 -275.848192) (xy 382.754633 -275.802916) (xy 382.742856 -275.755132) (xy 382.738896 -275.706078)
			(xy 382.410208 -275.706078) (xy 382.409713 -275.730685) (xy 382.401818 -275.779262) (xy 382.386234 -275.825943)
			(xy 382.363363 -275.86952) (xy 382.333798 -275.908864) (xy 382.298305 -275.942956) (xy 382.257802 -275.970912)
			(xy 382.21334 -275.99201) (xy 382.166069 -276.005702) (xy 382.117214 -276.011634) (xy 382.068039 -276.009653)
			(xy 382.01982 -275.999809) (xy 381.973804 -275.982357) (xy 381.931183 -275.95775) (xy 381.893062 -275.926625)
			(xy 381.860427 -275.889788) (xy 381.834124 -275.848192) (xy 381.814833 -275.802916) (xy 381.803056 -275.755132)
			(xy 381.799096 -275.706078) (xy 381.480568 -275.706078) (xy 381.480056 -275.731524) (xy 381.471892 -275.781758)
			(xy 381.455776 -275.830032) (xy 381.432125 -275.875095) (xy 381.401552 -275.915781) (xy 381.364848 -275.951036)
			(xy 381.322964 -275.979946) (xy 381.276985 -276.001763) (xy 381.228101 -276.015923) (xy 381.17758 -276.022057)
			(xy 381.126728 -276.020008) (xy 381.076864 -276.009828) (xy 381.029278 -275.991781) (xy 380.985204 -275.966335)
			(xy 380.945782 -275.934148) (xy 380.912034 -275.896054) (xy 380.884833 -275.85304) (xy 380.864885 -275.80622)
			(xy 380.852706 -275.756806) (xy 380.848611 -275.706078) (xy 380.5301 -275.706078) (xy 380.529605 -275.730685)
			(xy 380.52171 -275.779262) (xy 380.506126 -275.825943) (xy 380.483255 -275.86952) (xy 380.45369 -275.908864)
			(xy 380.418197 -275.942956) (xy 380.377694 -275.970912) (xy 380.333232 -275.99201) (xy 380.285961 -276.005702)
			(xy 380.237106 -276.011634) (xy 380.187931 -276.009653) (xy 380.139712 -275.999809) (xy 380.093696 -275.982357)
			(xy 380.051075 -275.95775) (xy 380.012954 -275.926625) (xy 379.980319 -275.889788) (xy 379.954016 -275.848192)
			(xy 379.934725 -275.802916) (xy 379.922948 -275.755132) (xy 379.918988 -275.706078) (xy 379.60046 -275.706078)
			(xy 379.599948 -275.731524) (xy 379.591784 -275.781758) (xy 379.575668 -275.830032) (xy 379.552017 -275.875095)
			(xy 379.521444 -275.915781) (xy 379.48474 -275.951036) (xy 379.442856 -275.979946) (xy 379.396877 -276.001763)
			(xy 379.347993 -276.015923) (xy 379.297472 -276.022057) (xy 379.24662 -276.020008) (xy 379.196756 -276.009828)
			(xy 379.14917 -275.991781) (xy 379.105096 -275.966335) (xy 379.065674 -275.934148) (xy 379.031926 -275.896054)
			(xy 379.004725 -275.85304) (xy 378.984777 -275.80622) (xy 378.972598 -275.756806) (xy 378.968503 -275.706078)
			(xy 377.720606 -275.706078) (xy 377.720094 -275.731524) (xy 377.71193 -275.781758) (xy 377.695814 -275.830032)
			(xy 377.672163 -275.875095) (xy 377.64159 -275.915781) (xy 377.604886 -275.951036) (xy 377.563002 -275.979946)
			(xy 377.517023 -276.001763) (xy 377.468139 -276.015923) (xy 377.417618 -276.022057) (xy 377.366766 -276.020008)
			(xy 377.316902 -276.009828) (xy 377.269316 -275.991781) (xy 377.225242 -275.966335) (xy 377.18582 -275.934148)
			(xy 377.152072 -275.896054) (xy 377.124871 -275.85304) (xy 377.104923 -275.80622) (xy 377.092744 -275.756806)
			(xy 377.088649 -275.706078) (xy 376.780552 -275.706078) (xy 376.78004 -275.731524) (xy 376.771876 -275.781758)
			(xy 376.75576 -275.830032) (xy 376.732109 -275.875095) (xy 376.701536 -275.915781) (xy 376.664832 -275.951036)
			(xy 376.622948 -275.979946) (xy 376.576969 -276.001763) (xy 376.528085 -276.015923) (xy 376.477564 -276.022057)
			(xy 376.426712 -276.020008) (xy 376.376848 -276.009828) (xy 376.329262 -275.991781) (xy 376.285188 -275.966335)
			(xy 376.245766 -275.934148) (xy 376.212018 -275.896054) (xy 376.184817 -275.85304) (xy 376.164869 -275.80622)
			(xy 376.15269 -275.756806) (xy 376.148595 -275.706078) (xy 375.830702 -275.706078) (xy 375.830704 -275.7061)
			(xy 375.826628 -275.755871) (xy 375.814509 -275.804316) (xy 375.794668 -275.850143) (xy 375.767636 -275.892132)
			(xy 375.734132 -275.929163) (xy 375.69505 -275.96025) (xy 375.651431 -275.984564) (xy 375.604437 -276.001456)
			(xy 375.555321 -276.010478) (xy 375.530364 -276.011386) (xy 375.524268 -276.011386) (xy 375.499681 -276.010898)
			(xy 375.45115 -276.00297) (xy 375.40452 -275.987355) (xy 375.382536 -275.976334) (xy 375.376694 -275.973286)
			(xy 375.364248 -275.970492) (xy 375.358152 -275.970492) (xy 375.352388 -275.97082) (xy 375.34123 -275.973775)
			(xy 375.336054 -275.976334) (xy 375.315734 -275.988526) (xy 375.260108 -276.022054) (xy 375.252943 -276.026767)
			(xy 375.242079 -276.040019) (xy 375.236314 -276.056157) (xy 375.235978 -276.064726) (xy 375.235978 -276.235414)
			(xy 375.236994 -276.245574) (xy 375.24055 -276.256496) (xy 375.25325 -276.283928) (xy 375.260616 -276.290532)
			(xy 375.279041 -276.308018) (xy 375.310389 -276.347985) (xy 375.33469 -276.392589) (xy 375.351273 -276.440599)
			(xy 375.359682 -276.490692) (xy 375.359682 -276.516084) (xy 375.678695 -276.516084) (xy 375.68279 -276.465356)
			(xy 375.694969 -276.415942) (xy 375.714917 -276.369122) (xy 375.742118 -276.326108) (xy 375.775866 -276.288014)
			(xy 375.815288 -276.255827) (xy 375.859362 -276.230381) (xy 375.906948 -276.212334) (xy 375.956812 -276.202154)
			(xy 376.007664 -276.200105) (xy 376.058185 -276.206239) (xy 376.107069 -276.220399) (xy 376.153048 -276.242216)
			(xy 376.194932 -276.271126) (xy 376.231636 -276.306381) (xy 376.262209 -276.347067) (xy 376.28586 -276.39213)
			(xy 376.301976 -276.440404) (xy 376.31014 -276.490638) (xy 376.310652 -276.516084) (xy 376.628926 -276.516084)
			(xy 376.632886 -276.46703) (xy 376.644663 -276.419246) (xy 376.663954 -276.37397) (xy 376.690257 -276.332374)
			(xy 376.722892 -276.295537) (xy 376.761013 -276.264412) (xy 376.803634 -276.239805) (xy 376.84965 -276.222353)
			(xy 376.897869 -276.212509) (xy 376.947044 -276.210528) (xy 376.995899 -276.21646) (xy 377.04317 -276.230152)
			(xy 377.087632 -276.25125) (xy 377.128135 -276.279206) (xy 377.163628 -276.313298) (xy 377.193193 -276.352642)
			(xy 377.216064 -276.396219) (xy 377.231648 -276.4429) (xy 377.239543 -276.491477) (xy 377.240038 -276.516084)
			(xy 377.558549 -276.516084) (xy 377.562644 -276.465356) (xy 377.574823 -276.415942) (xy 377.594771 -276.369122)
			(xy 377.621972 -276.326108) (xy 377.65572 -276.288014) (xy 377.695142 -276.255827) (xy 377.739216 -276.230381)
			(xy 377.786802 -276.212334) (xy 377.836666 -276.202154) (xy 377.887518 -276.200105) (xy 377.938039 -276.206239)
			(xy 377.986923 -276.220399) (xy 378.032902 -276.242216) (xy 378.074786 -276.271126) (xy 378.11149 -276.306381)
			(xy 378.142063 -276.347067) (xy 378.165714 -276.39213) (xy 378.18183 -276.440404) (xy 378.189994 -276.490638)
			(xy 378.190506 -276.516084) (xy 378.509034 -276.516084) (xy 378.512994 -276.46703) (xy 378.524771 -276.419246)
			(xy 378.544062 -276.37397) (xy 378.570365 -276.332374) (xy 378.603 -276.295537) (xy 378.641121 -276.264412)
			(xy 378.683742 -276.239805) (xy 378.729758 -276.222353) (xy 378.777977 -276.212509) (xy 378.827152 -276.210528)
			(xy 378.876007 -276.21646) (xy 378.923278 -276.230152) (xy 378.96774 -276.25125) (xy 379.008243 -276.279206)
			(xy 379.043736 -276.313298) (xy 379.073301 -276.352642) (xy 379.096172 -276.396219) (xy 379.111756 -276.4429)
			(xy 379.119651 -276.491477) (xy 379.120146 -276.516084) (xy 379.438657 -276.516084) (xy 379.442752 -276.465356)
			(xy 379.454931 -276.415942) (xy 379.474879 -276.369122) (xy 379.50208 -276.326108) (xy 379.535828 -276.288014)
			(xy 379.57525 -276.255827) (xy 379.619324 -276.230381) (xy 379.66691 -276.212334) (xy 379.716774 -276.202154)
			(xy 379.767626 -276.200105) (xy 379.818147 -276.206239) (xy 379.867031 -276.220399) (xy 379.91301 -276.242216)
			(xy 379.954894 -276.271126) (xy 379.991598 -276.306381) (xy 380.022171 -276.347067) (xy 380.045822 -276.39213)
			(xy 380.061938 -276.440404) (xy 380.070102 -276.490638) (xy 380.070614 -276.516084) (xy 380.378711 -276.516084)
			(xy 380.382806 -276.465356) (xy 380.394985 -276.415942) (xy 380.414933 -276.369122) (xy 380.442134 -276.326108)
			(xy 380.475882 -276.288014) (xy 380.515304 -276.255827) (xy 380.559378 -276.230381) (xy 380.606964 -276.212334)
			(xy 380.656828 -276.202154) (xy 380.70768 -276.200105) (xy 380.758201 -276.206239) (xy 380.807085 -276.220399)
			(xy 380.853064 -276.242216) (xy 380.894948 -276.271126) (xy 380.931652 -276.306381) (xy 380.962225 -276.347067)
			(xy 380.985876 -276.39213) (xy 381.001992 -276.440404) (xy 381.010156 -276.490638) (xy 381.010668 -276.516084)
			(xy 381.328942 -276.516084) (xy 381.332902 -276.46703) (xy 381.344679 -276.419246) (xy 381.36397 -276.37397)
			(xy 381.390273 -276.332374) (xy 381.422908 -276.295537) (xy 381.461029 -276.264412) (xy 381.50365 -276.239805)
			(xy 381.549666 -276.222353) (xy 381.597885 -276.212509) (xy 381.64706 -276.210528) (xy 381.695915 -276.21646)
			(xy 381.743186 -276.230152) (xy 381.787648 -276.25125) (xy 381.828151 -276.279206) (xy 381.863644 -276.313298)
			(xy 381.893209 -276.352642) (xy 381.91608 -276.396219) (xy 381.931664 -276.4429) (xy 381.939559 -276.491477)
			(xy 381.940054 -276.516084) (xy 382.268996 -276.516084) (xy 382.272956 -276.46703) (xy 382.284733 -276.419246)
			(xy 382.304024 -276.37397) (xy 382.330327 -276.332374) (xy 382.362962 -276.295537) (xy 382.401083 -276.264412)
			(xy 382.443704 -276.239805) (xy 382.48972 -276.222353) (xy 382.537939 -276.212509) (xy 382.587114 -276.210528)
			(xy 382.635969 -276.21646) (xy 382.68324 -276.230152) (xy 382.727702 -276.25125) (xy 382.768205 -276.279206)
			(xy 382.803698 -276.313298) (xy 382.833263 -276.352642) (xy 382.856134 -276.396219) (xy 382.871718 -276.4429)
			(xy 382.879613 -276.491477) (xy 382.880108 -276.516084) (xy 383.20905 -276.516084) (xy 383.21301 -276.46703)
			(xy 383.224787 -276.419246) (xy 383.244078 -276.37397) (xy 383.270381 -276.332374) (xy 383.303016 -276.295537)
			(xy 383.341137 -276.264412) (xy 383.383758 -276.239805) (xy 383.429774 -276.222353) (xy 383.477993 -276.212509)
			(xy 383.527168 -276.210528) (xy 383.576023 -276.21646) (xy 383.623294 -276.230152) (xy 383.667756 -276.25125)
			(xy 383.708259 -276.279206) (xy 383.743752 -276.313298) (xy 383.773317 -276.352642) (xy 383.796188 -276.396219)
			(xy 383.811772 -276.4429) (xy 383.819667 -276.491477) (xy 383.820162 -276.516084) (xy 384.149104 -276.516084)
			(xy 384.153064 -276.46703) (xy 384.164841 -276.419246) (xy 384.184132 -276.37397) (xy 384.210435 -276.332374)
			(xy 384.24307 -276.295537) (xy 384.281191 -276.264412) (xy 384.323812 -276.239805) (xy 384.369828 -276.222353)
			(xy 384.418047 -276.212509) (xy 384.467222 -276.210528) (xy 384.516077 -276.21646) (xy 384.563348 -276.230152)
			(xy 384.60781 -276.25125) (xy 384.648313 -276.279206) (xy 384.683806 -276.313298) (xy 384.713371 -276.352642)
			(xy 384.736242 -276.396219) (xy 384.751826 -276.4429) (xy 384.759721 -276.491477) (xy 384.760216 -276.516084)
			(xy 385.088904 -276.516084) (xy 385.092864 -276.46703) (xy 385.104641 -276.419246) (xy 385.123932 -276.37397)
			(xy 385.150235 -276.332374) (xy 385.18287 -276.295537) (xy 385.220991 -276.264412) (xy 385.263612 -276.239805)
			(xy 385.309628 -276.222353) (xy 385.357847 -276.212509) (xy 385.407022 -276.210528) (xy 385.455877 -276.21646)
			(xy 385.503148 -276.230152) (xy 385.54761 -276.25125) (xy 385.588113 -276.279206) (xy 385.623606 -276.313298)
			(xy 385.653171 -276.352642) (xy 385.676042 -276.396219) (xy 385.691626 -276.4429) (xy 385.699521 -276.491477)
			(xy 385.700016 -276.516084) (xy 386.028958 -276.516084) (xy 386.032918 -276.46703) (xy 386.044695 -276.419246)
			(xy 386.063986 -276.37397) (xy 386.090289 -276.332374) (xy 386.122924 -276.295537) (xy 386.161045 -276.264412)
			(xy 386.203666 -276.239805) (xy 386.249682 -276.222353) (xy 386.297901 -276.212509) (xy 386.347076 -276.210528)
			(xy 386.395931 -276.21646) (xy 386.443202 -276.230152) (xy 386.487664 -276.25125) (xy 386.528167 -276.279206)
			(xy 386.56366 -276.313298) (xy 386.593225 -276.352642) (xy 386.616096 -276.396219) (xy 386.63168 -276.4429)
			(xy 386.639575 -276.491477) (xy 386.64007 -276.516084) (xy 386.969012 -276.516084) (xy 386.972972 -276.46703)
			(xy 386.984749 -276.419246) (xy 387.00404 -276.37397) (xy 387.030343 -276.332374) (xy 387.062978 -276.295537)
			(xy 387.101099 -276.264412) (xy 387.14372 -276.239805) (xy 387.189736 -276.222353) (xy 387.237955 -276.212509)
			(xy 387.28713 -276.210528) (xy 387.335985 -276.21646) (xy 387.383256 -276.230152) (xy 387.427718 -276.25125)
			(xy 387.468221 -276.279206) (xy 387.503714 -276.313298) (xy 387.533279 -276.352642) (xy 387.55615 -276.396219)
			(xy 387.571734 -276.4429) (xy 387.579629 -276.491477) (xy 387.580124 -276.516084) (xy 387.579629 -276.540691)
			(xy 387.571734 -276.589268) (xy 387.55615 -276.635949) (xy 387.533279 -276.679526) (xy 387.503714 -276.71887)
			(xy 387.468221 -276.752962) (xy 387.427718 -276.780918) (xy 387.383256 -276.802016) (xy 387.335985 -276.815708)
			(xy 387.28713 -276.82164) (xy 387.237955 -276.819659) (xy 387.189736 -276.809815) (xy 387.14372 -276.792363)
			(xy 387.101099 -276.767756) (xy 387.062978 -276.736631) (xy 387.030343 -276.699794) (xy 387.00404 -276.658198)
			(xy 386.984749 -276.612922) (xy 386.972972 -276.565138) (xy 386.969012 -276.516084) (xy 386.64007 -276.516084)
			(xy 386.639575 -276.540691) (xy 386.63168 -276.589268) (xy 386.616096 -276.635949) (xy 386.593225 -276.679526)
			(xy 386.56366 -276.71887) (xy 386.528167 -276.752962) (xy 386.487664 -276.780918) (xy 386.443202 -276.802016)
			(xy 386.395931 -276.815708) (xy 386.347076 -276.82164) (xy 386.297901 -276.819659) (xy 386.249682 -276.809815)
			(xy 386.203666 -276.792363) (xy 386.161045 -276.767756) (xy 386.122924 -276.736631) (xy 386.090289 -276.699794)
			(xy 386.063986 -276.658198) (xy 386.044695 -276.612922) (xy 386.032918 -276.565138) (xy 386.028958 -276.516084)
			(xy 385.700016 -276.516084) (xy 385.699521 -276.540691) (xy 385.691626 -276.589268) (xy 385.676042 -276.635949)
			(xy 385.653171 -276.679526) (xy 385.623606 -276.71887) (xy 385.588113 -276.752962) (xy 385.54761 -276.780918)
			(xy 385.503148 -276.802016) (xy 385.455877 -276.815708) (xy 385.407022 -276.82164) (xy 385.357847 -276.819659)
			(xy 385.309628 -276.809815) (xy 385.263612 -276.792363) (xy 385.220991 -276.767756) (xy 385.18287 -276.736631)
			(xy 385.150235 -276.699794) (xy 385.123932 -276.658198) (xy 385.104641 -276.612922) (xy 385.092864 -276.565138)
			(xy 385.088904 -276.516084) (xy 384.760216 -276.516084) (xy 384.759721 -276.540691) (xy 384.751826 -276.589268)
			(xy 384.736242 -276.635949) (xy 384.713371 -276.679526) (xy 384.683806 -276.71887) (xy 384.648313 -276.752962)
			(xy 384.60781 -276.780918) (xy 384.563348 -276.802016) (xy 384.516077 -276.815708) (xy 384.467222 -276.82164)
			(xy 384.418047 -276.819659) (xy 384.369828 -276.809815) (xy 384.323812 -276.792363) (xy 384.281191 -276.767756)
			(xy 384.24307 -276.736631) (xy 384.210435 -276.699794) (xy 384.184132 -276.658198) (xy 384.164841 -276.612922)
			(xy 384.153064 -276.565138) (xy 384.149104 -276.516084) (xy 383.820162 -276.516084) (xy 383.819667 -276.540691)
			(xy 383.811772 -276.589268) (xy 383.796188 -276.635949) (xy 383.773317 -276.679526) (xy 383.743752 -276.71887)
			(xy 383.708259 -276.752962) (xy 383.667756 -276.780918) (xy 383.623294 -276.802016) (xy 383.576023 -276.815708)
			(xy 383.527168 -276.82164) (xy 383.477993 -276.819659) (xy 383.429774 -276.809815) (xy 383.383758 -276.792363)
			(xy 383.341137 -276.767756) (xy 383.303016 -276.736631) (xy 383.270381 -276.699794) (xy 383.244078 -276.658198)
			(xy 383.224787 -276.612922) (xy 383.21301 -276.565138) (xy 383.20905 -276.516084) (xy 382.880108 -276.516084)
			(xy 382.879613 -276.540691) (xy 382.871718 -276.589268) (xy 382.856134 -276.635949) (xy 382.833263 -276.679526)
			(xy 382.803698 -276.71887) (xy 382.768205 -276.752962) (xy 382.727702 -276.780918) (xy 382.68324 -276.802016)
			(xy 382.635969 -276.815708) (xy 382.587114 -276.82164) (xy 382.537939 -276.819659) (xy 382.48972 -276.809815)
			(xy 382.443704 -276.792363) (xy 382.401083 -276.767756) (xy 382.362962 -276.736631) (xy 382.330327 -276.699794)
			(xy 382.304024 -276.658198) (xy 382.284733 -276.612922) (xy 382.272956 -276.565138) (xy 382.268996 -276.516084)
			(xy 381.940054 -276.516084) (xy 381.939559 -276.540691) (xy 381.931664 -276.589268) (xy 381.91608 -276.635949)
			(xy 381.893209 -276.679526) (xy 381.863644 -276.71887) (xy 381.828151 -276.752962) (xy 381.787648 -276.780918)
			(xy 381.743186 -276.802016) (xy 381.695915 -276.815708) (xy 381.64706 -276.82164) (xy 381.597885 -276.819659)
			(xy 381.549666 -276.809815) (xy 381.50365 -276.792363) (xy 381.461029 -276.767756) (xy 381.422908 -276.736631)
			(xy 381.390273 -276.699794) (xy 381.36397 -276.658198) (xy 381.344679 -276.612922) (xy 381.332902 -276.565138)
			(xy 381.328942 -276.516084) (xy 381.010668 -276.516084) (xy 381.010156 -276.54153) (xy 381.001992 -276.591764)
			(xy 380.985876 -276.640038) (xy 380.962225 -276.685101) (xy 380.931652 -276.725787) (xy 380.894948 -276.761042)
			(xy 380.853064 -276.789952) (xy 380.807085 -276.811769) (xy 380.758201 -276.825929) (xy 380.70768 -276.832063)
			(xy 380.656828 -276.830014) (xy 380.606964 -276.819834) (xy 380.559378 -276.801787) (xy 380.515304 -276.776341)
			(xy 380.475882 -276.744154) (xy 380.442134 -276.70606) (xy 380.414933 -276.663046) (xy 380.394985 -276.616226)
			(xy 380.382806 -276.566812) (xy 380.378711 -276.516084) (xy 380.070614 -276.516084) (xy 380.070102 -276.54153)
			(xy 380.061938 -276.591764) (xy 380.045822 -276.640038) (xy 380.022171 -276.685101) (xy 379.991598 -276.725787)
			(xy 379.954894 -276.761042) (xy 379.91301 -276.789952) (xy 379.867031 -276.811769) (xy 379.818147 -276.825929)
			(xy 379.767626 -276.832063) (xy 379.716774 -276.830014) (xy 379.66691 -276.819834) (xy 379.619324 -276.801787)
			(xy 379.57525 -276.776341) (xy 379.535828 -276.744154) (xy 379.50208 -276.70606) (xy 379.474879 -276.663046)
			(xy 379.454931 -276.616226) (xy 379.442752 -276.566812) (xy 379.438657 -276.516084) (xy 379.120146 -276.516084)
			(xy 379.119651 -276.540691) (xy 379.111756 -276.589268) (xy 379.096172 -276.635949) (xy 379.073301 -276.679526)
			(xy 379.043736 -276.71887) (xy 379.008243 -276.752962) (xy 378.96774 -276.780918) (xy 378.923278 -276.802016)
			(xy 378.876007 -276.815708) (xy 378.827152 -276.82164) (xy 378.777977 -276.819659) (xy 378.729758 -276.809815)
			(xy 378.683742 -276.792363) (xy 378.641121 -276.767756) (xy 378.603 -276.736631) (xy 378.570365 -276.699794)
			(xy 378.544062 -276.658198) (xy 378.524771 -276.612922) (xy 378.512994 -276.565138) (xy 378.509034 -276.516084)
			(xy 378.190506 -276.516084) (xy 378.189994 -276.54153) (xy 378.18183 -276.591764) (xy 378.165714 -276.640038)
			(xy 378.142063 -276.685101) (xy 378.11149 -276.725787) (xy 378.074786 -276.761042) (xy 378.032902 -276.789952)
			(xy 377.986923 -276.811769) (xy 377.938039 -276.825929) (xy 377.887518 -276.832063) (xy 377.836666 -276.830014)
			(xy 377.786802 -276.819834) (xy 377.739216 -276.801787) (xy 377.695142 -276.776341) (xy 377.65572 -276.744154)
			(xy 377.621972 -276.70606) (xy 377.594771 -276.663046) (xy 377.574823 -276.616226) (xy 377.562644 -276.566812)
			(xy 377.558549 -276.516084) (xy 377.240038 -276.516084) (xy 377.239543 -276.540691) (xy 377.231648 -276.589268)
			(xy 377.216064 -276.635949) (xy 377.193193 -276.679526) (xy 377.163628 -276.71887) (xy 377.128135 -276.752962)
			(xy 377.087632 -276.780918) (xy 377.04317 -276.802016) (xy 376.995899 -276.815708) (xy 376.947044 -276.82164)
			(xy 376.897869 -276.819659) (xy 376.84965 -276.809815) (xy 376.803634 -276.792363) (xy 376.761013 -276.767756)
			(xy 376.722892 -276.736631) (xy 376.690257 -276.699794) (xy 376.663954 -276.658198) (xy 376.644663 -276.612922)
			(xy 376.632886 -276.565138) (xy 376.628926 -276.516084) (xy 376.310652 -276.516084) (xy 376.31014 -276.54153)
			(xy 376.301976 -276.591764) (xy 376.28586 -276.640038) (xy 376.262209 -276.685101) (xy 376.231636 -276.725787)
			(xy 376.194932 -276.761042) (xy 376.153048 -276.789952) (xy 376.107069 -276.811769) (xy 376.058185 -276.825929)
			(xy 376.007664 -276.832063) (xy 375.956812 -276.830014) (xy 375.906948 -276.819834) (xy 375.859362 -276.801787)
			(xy 375.815288 -276.776341) (xy 375.775866 -276.744154) (xy 375.742118 -276.70606) (xy 375.714917 -276.663046)
			(xy 375.694969 -276.616226) (xy 375.68279 -276.566812) (xy 375.678695 -276.516084) (xy 375.359682 -276.516084)
			(xy 375.359683 -276.541486) (xy 375.351278 -276.59158) (xy 375.334698 -276.639592) (xy 375.310401 -276.684197)
			(xy 375.279056 -276.724166) (xy 375.260616 -276.741636) (xy 375.25325 -276.74824) (xy 375.240804 -276.775418)
			(xy 375.23674 -276.787864) (xy 375.235978 -276.7965) (xy 375.235978 -277.32609) (xy 376.148595 -277.32609)
			(xy 376.15269 -277.275362) (xy 376.164869 -277.225948) (xy 376.184817 -277.179128) (xy 376.212018 -277.136114)
			(xy 376.245766 -277.09802) (xy 376.285188 -277.065833) (xy 376.329262 -277.040387) (xy 376.376848 -277.02234)
			(xy 376.426712 -277.01216) (xy 376.477564 -277.010111) (xy 376.528085 -277.016245) (xy 376.576969 -277.030405)
			(xy 376.622948 -277.052222) (xy 376.664832 -277.081132) (xy 376.701536 -277.116387) (xy 376.732109 -277.157073)
			(xy 376.75576 -277.202136) (xy 376.771876 -277.25041) (xy 376.78004 -277.300644) (xy 376.780552 -277.32609)
			(xy 377.088649 -277.32609) (xy 377.092744 -277.275362) (xy 377.104923 -277.225948) (xy 377.124871 -277.179128)
			(xy 377.152072 -277.136114) (xy 377.18582 -277.09802) (xy 377.225242 -277.065833) (xy 377.269316 -277.040387)
			(xy 377.316902 -277.02234) (xy 377.366766 -277.01216) (xy 377.417618 -277.010111) (xy 377.468139 -277.016245)
			(xy 377.517023 -277.030405) (xy 377.563002 -277.052222) (xy 377.604886 -277.081132) (xy 377.64159 -277.116387)
			(xy 377.672163 -277.157073) (xy 377.695814 -277.202136) (xy 377.71193 -277.25041) (xy 377.720094 -277.300644)
			(xy 377.720606 -277.32609) (xy 378.039134 -277.32609) (xy 378.043094 -277.277036) (xy 378.054871 -277.229252)
			(xy 378.074162 -277.183976) (xy 378.100465 -277.14238) (xy 378.1331 -277.105543) (xy 378.171221 -277.074418)
			(xy 378.213842 -277.049811) (xy 378.259858 -277.032359) (xy 378.308077 -277.022515) (xy 378.357252 -277.020534)
			(xy 378.406107 -277.026466) (xy 378.453378 -277.040158) (xy 378.49784 -277.061256) (xy 378.538343 -277.089212)
			(xy 378.573836 -277.123304) (xy 378.603401 -277.162648) (xy 378.626272 -277.206225) (xy 378.641856 -277.252906)
			(xy 378.649751 -277.301483) (xy 378.650246 -277.32609) (xy 378.968503 -277.32609) (xy 378.972598 -277.275362)
			(xy 378.984777 -277.225948) (xy 379.004725 -277.179128) (xy 379.031926 -277.136114) (xy 379.065674 -277.09802)
			(xy 379.105096 -277.065833) (xy 379.14917 -277.040387) (xy 379.196756 -277.02234) (xy 379.24662 -277.01216)
			(xy 379.297472 -277.010111) (xy 379.347993 -277.016245) (xy 379.396877 -277.030405) (xy 379.442856 -277.052222)
			(xy 379.48474 -277.081132) (xy 379.521444 -277.116387) (xy 379.552017 -277.157073) (xy 379.575668 -277.202136)
			(xy 379.591784 -277.25041) (xy 379.599948 -277.300644) (xy 379.60046 -277.32609) (xy 379.918988 -277.32609)
			(xy 379.922948 -277.277036) (xy 379.934725 -277.229252) (xy 379.954016 -277.183976) (xy 379.980319 -277.14238)
			(xy 380.012954 -277.105543) (xy 380.051075 -277.074418) (xy 380.093696 -277.049811) (xy 380.139712 -277.032359)
			(xy 380.187931 -277.022515) (xy 380.237106 -277.020534) (xy 380.285961 -277.026466) (xy 380.333232 -277.040158)
			(xy 380.377694 -277.061256) (xy 380.418197 -277.089212) (xy 380.45369 -277.123304) (xy 380.483255 -277.162648)
			(xy 380.506126 -277.206225) (xy 380.52171 -277.252906) (xy 380.529605 -277.301483) (xy 380.5301 -277.32609)
			(xy 380.848611 -277.32609) (xy 380.852706 -277.275362) (xy 380.864885 -277.225948) (xy 380.884833 -277.179128)
			(xy 380.912034 -277.136114) (xy 380.945782 -277.09802) (xy 380.985204 -277.065833) (xy 381.029278 -277.040387)
			(xy 381.076864 -277.02234) (xy 381.126728 -277.01216) (xy 381.17758 -277.010111) (xy 381.228101 -277.016245)
			(xy 381.276985 -277.030405) (xy 381.322964 -277.052222) (xy 381.364848 -277.081132) (xy 381.401552 -277.116387)
			(xy 381.432125 -277.157073) (xy 381.455776 -277.202136) (xy 381.471892 -277.25041) (xy 381.480056 -277.300644)
			(xy 381.480568 -277.32609) (xy 381.799096 -277.32609) (xy 381.803056 -277.277036) (xy 381.814833 -277.229252)
			(xy 381.834124 -277.183976) (xy 381.860427 -277.14238) (xy 381.893062 -277.105543) (xy 381.931183 -277.074418)
			(xy 381.973804 -277.049811) (xy 382.01982 -277.032359) (xy 382.068039 -277.022515) (xy 382.117214 -277.020534)
			(xy 382.166069 -277.026466) (xy 382.21334 -277.040158) (xy 382.257802 -277.061256) (xy 382.298305 -277.089212)
			(xy 382.333798 -277.123304) (xy 382.363363 -277.162648) (xy 382.386234 -277.206225) (xy 382.401818 -277.252906)
			(xy 382.409713 -277.301483) (xy 382.410208 -277.32609) (xy 382.738896 -277.32609) (xy 382.742856 -277.277036)
			(xy 382.754633 -277.229252) (xy 382.773924 -277.183976) (xy 382.800227 -277.14238) (xy 382.832862 -277.105543)
			(xy 382.870983 -277.074418) (xy 382.913604 -277.049811) (xy 382.95962 -277.032359) (xy 383.007839 -277.022515)
			(xy 383.057014 -277.020534) (xy 383.105869 -277.026466) (xy 383.15314 -277.040158) (xy 383.197602 -277.061256)
			(xy 383.238105 -277.089212) (xy 383.273598 -277.123304) (xy 383.303163 -277.162648) (xy 383.326034 -277.206225)
			(xy 383.341618 -277.252906) (xy 383.349513 -277.301483) (xy 383.350008 -277.32609) (xy 383.67895 -277.32609)
			(xy 383.68291 -277.277036) (xy 383.694687 -277.229252) (xy 383.713978 -277.183976) (xy 383.740281 -277.14238)
			(xy 383.772916 -277.105543) (xy 383.811037 -277.074418) (xy 383.853658 -277.049811) (xy 383.899674 -277.032359)
			(xy 383.947893 -277.022515) (xy 383.997068 -277.020534) (xy 384.045923 -277.026466) (xy 384.093194 -277.040158)
			(xy 384.137656 -277.061256) (xy 384.178159 -277.089212) (xy 384.213652 -277.123304) (xy 384.243217 -277.162648)
			(xy 384.266088 -277.206225) (xy 384.281672 -277.252906) (xy 384.289567 -277.301483) (xy 384.290062 -277.32609)
			(xy 384.619004 -277.32609) (xy 384.622964 -277.277036) (xy 384.634741 -277.229252) (xy 384.654032 -277.183976)
			(xy 384.680335 -277.14238) (xy 384.71297 -277.105543) (xy 384.751091 -277.074418) (xy 384.793712 -277.049811)
			(xy 384.839728 -277.032359) (xy 384.887947 -277.022515) (xy 384.937122 -277.020534) (xy 384.985977 -277.026466)
			(xy 385.033248 -277.040158) (xy 385.07771 -277.061256) (xy 385.118213 -277.089212) (xy 385.153706 -277.123304)
			(xy 385.183271 -277.162648) (xy 385.206142 -277.206225) (xy 385.221726 -277.252906) (xy 385.229621 -277.301483)
			(xy 385.230116 -277.32609) (xy 385.559058 -277.32609) (xy 385.563018 -277.277036) (xy 385.574795 -277.229252)
			(xy 385.594086 -277.183976) (xy 385.620389 -277.14238) (xy 385.653024 -277.105543) (xy 385.691145 -277.074418)
			(xy 385.733766 -277.049811) (xy 385.779782 -277.032359) (xy 385.828001 -277.022515) (xy 385.877176 -277.020534)
			(xy 385.926031 -277.026466) (xy 385.973302 -277.040158) (xy 386.017764 -277.061256) (xy 386.058267 -277.089212)
			(xy 386.09376 -277.123304) (xy 386.123325 -277.162648) (xy 386.146196 -277.206225) (xy 386.16178 -277.252906)
			(xy 386.169675 -277.301483) (xy 386.17017 -277.32609) (xy 386.499112 -277.32609) (xy 386.503072 -277.277036)
			(xy 386.514849 -277.229252) (xy 386.53414 -277.183976) (xy 386.560443 -277.14238) (xy 386.593078 -277.105543)
			(xy 386.631199 -277.074418) (xy 386.67382 -277.049811) (xy 386.719836 -277.032359) (xy 386.768055 -277.022515)
			(xy 386.81723 -277.020534) (xy 386.866085 -277.026466) (xy 386.913356 -277.040158) (xy 386.957818 -277.061256)
			(xy 386.998321 -277.089212) (xy 387.033814 -277.123304) (xy 387.063379 -277.162648) (xy 387.08625 -277.206225)
			(xy 387.101834 -277.252906) (xy 387.109729 -277.301483) (xy 387.110224 -277.32609) (xy 387.438912 -277.32609)
			(xy 387.442872 -277.277036) (xy 387.454649 -277.229252) (xy 387.47394 -277.183976) (xy 387.500243 -277.14238)
			(xy 387.532878 -277.105543) (xy 387.570999 -277.074418) (xy 387.61362 -277.049811) (xy 387.659636 -277.032359)
			(xy 387.707855 -277.022515) (xy 387.75703 -277.020534) (xy 387.805885 -277.026466) (xy 387.853156 -277.040158)
			(xy 387.897618 -277.061256) (xy 387.938121 -277.089212) (xy 387.973614 -277.123304) (xy 388.003179 -277.162648)
			(xy 388.02605 -277.206225) (xy 388.041634 -277.252906) (xy 388.049529 -277.301483) (xy 388.050024 -277.32609)
			(xy 388.049529 -277.350697) (xy 388.041634 -277.399274) (xy 388.02605 -277.445955) (xy 388.003179 -277.489532)
			(xy 387.973614 -277.528876) (xy 387.938121 -277.562968) (xy 387.897618 -277.590924) (xy 387.853156 -277.612022)
			(xy 387.805885 -277.625714) (xy 387.75703 -277.631646) (xy 387.707855 -277.629665) (xy 387.659636 -277.619821)
			(xy 387.61362 -277.602369) (xy 387.570999 -277.577762) (xy 387.532878 -277.546637) (xy 387.500243 -277.5098)
			(xy 387.47394 -277.468204) (xy 387.454649 -277.422928) (xy 387.442872 -277.375144) (xy 387.438912 -277.32609)
			(xy 387.110224 -277.32609) (xy 387.109729 -277.350697) (xy 387.101834 -277.399274) (xy 387.08625 -277.445955)
			(xy 387.063379 -277.489532) (xy 387.033814 -277.528876) (xy 386.998321 -277.562968) (xy 386.957818 -277.590924)
			(xy 386.913356 -277.612022) (xy 386.866085 -277.625714) (xy 386.81723 -277.631646) (xy 386.768055 -277.629665)
			(xy 386.719836 -277.619821) (xy 386.67382 -277.602369) (xy 386.631199 -277.577762) (xy 386.593078 -277.546637)
			(xy 386.560443 -277.5098) (xy 386.53414 -277.468204) (xy 386.514849 -277.422928) (xy 386.503072 -277.375144)
			(xy 386.499112 -277.32609) (xy 386.17017 -277.32609) (xy 386.169675 -277.350697) (xy 386.16178 -277.399274)
			(xy 386.146196 -277.445955) (xy 386.123325 -277.489532) (xy 386.09376 -277.528876) (xy 386.058267 -277.562968)
			(xy 386.017764 -277.590924) (xy 385.973302 -277.612022) (xy 385.926031 -277.625714) (xy 385.877176 -277.631646)
			(xy 385.828001 -277.629665) (xy 385.779782 -277.619821) (xy 385.733766 -277.602369) (xy 385.691145 -277.577762)
			(xy 385.653024 -277.546637) (xy 385.620389 -277.5098) (xy 385.594086 -277.468204) (xy 385.574795 -277.422928)
			(xy 385.563018 -277.375144) (xy 385.559058 -277.32609) (xy 385.230116 -277.32609) (xy 385.229621 -277.350697)
			(xy 385.221726 -277.399274) (xy 385.206142 -277.445955) (xy 385.183271 -277.489532) (xy 385.153706 -277.528876)
			(xy 385.118213 -277.562968) (xy 385.07771 -277.590924) (xy 385.033248 -277.612022) (xy 384.985977 -277.625714)
			(xy 384.937122 -277.631646) (xy 384.887947 -277.629665) (xy 384.839728 -277.619821) (xy 384.793712 -277.602369)
			(xy 384.751091 -277.577762) (xy 384.71297 -277.546637) (xy 384.680335 -277.5098) (xy 384.654032 -277.468204)
			(xy 384.634741 -277.422928) (xy 384.622964 -277.375144) (xy 384.619004 -277.32609) (xy 384.290062 -277.32609)
			(xy 384.289567 -277.350697) (xy 384.281672 -277.399274) (xy 384.266088 -277.445955) (xy 384.243217 -277.489532)
			(xy 384.213652 -277.528876) (xy 384.178159 -277.562968) (xy 384.137656 -277.590924) (xy 384.093194 -277.612022)
			(xy 384.045923 -277.625714) (xy 383.997068 -277.631646) (xy 383.947893 -277.629665) (xy 383.899674 -277.619821)
			(xy 383.853658 -277.602369) (xy 383.811037 -277.577762) (xy 383.772916 -277.546637) (xy 383.740281 -277.5098)
			(xy 383.713978 -277.468204) (xy 383.694687 -277.422928) (xy 383.68291 -277.375144) (xy 383.67895 -277.32609)
			(xy 383.350008 -277.32609) (xy 383.349513 -277.350697) (xy 383.341618 -277.399274) (xy 383.326034 -277.445955)
			(xy 383.303163 -277.489532) (xy 383.273598 -277.528876) (xy 383.238105 -277.562968) (xy 383.197602 -277.590924)
			(xy 383.15314 -277.612022) (xy 383.105869 -277.625714) (xy 383.057014 -277.631646) (xy 383.007839 -277.629665)
			(xy 382.95962 -277.619821) (xy 382.913604 -277.602369) (xy 382.870983 -277.577762) (xy 382.832862 -277.546637)
			(xy 382.800227 -277.5098) (xy 382.773924 -277.468204) (xy 382.754633 -277.422928) (xy 382.742856 -277.375144)
			(xy 382.738896 -277.32609) (xy 382.410208 -277.32609) (xy 382.409713 -277.350697) (xy 382.401818 -277.399274)
			(xy 382.386234 -277.445955) (xy 382.363363 -277.489532) (xy 382.333798 -277.528876) (xy 382.298305 -277.562968)
			(xy 382.257802 -277.590924) (xy 382.21334 -277.612022) (xy 382.166069 -277.625714) (xy 382.117214 -277.631646)
			(xy 382.068039 -277.629665) (xy 382.01982 -277.619821) (xy 381.973804 -277.602369) (xy 381.931183 -277.577762)
			(xy 381.893062 -277.546637) (xy 381.860427 -277.5098) (xy 381.834124 -277.468204) (xy 381.814833 -277.422928)
			(xy 381.803056 -277.375144) (xy 381.799096 -277.32609) (xy 381.480568 -277.32609) (xy 381.480056 -277.351536)
			(xy 381.471892 -277.40177) (xy 381.455776 -277.450044) (xy 381.432125 -277.495107) (xy 381.401552 -277.535793)
			(xy 381.364848 -277.571048) (xy 381.322964 -277.599958) (xy 381.276985 -277.621775) (xy 381.228101 -277.635935)
			(xy 381.17758 -277.642069) (xy 381.126728 -277.64002) (xy 381.076864 -277.62984) (xy 381.029278 -277.611793)
			(xy 380.985204 -277.586347) (xy 380.945782 -277.55416) (xy 380.912034 -277.516066) (xy 380.884833 -277.473052)
			(xy 380.864885 -277.426232) (xy 380.852706 -277.376818) (xy 380.848611 -277.32609) (xy 380.5301 -277.32609)
			(xy 380.529605 -277.350697) (xy 380.52171 -277.399274) (xy 380.506126 -277.445955) (xy 380.483255 -277.489532)
			(xy 380.45369 -277.528876) (xy 380.418197 -277.562968) (xy 380.377694 -277.590924) (xy 380.333232 -277.612022)
			(xy 380.285961 -277.625714) (xy 380.237106 -277.631646) (xy 380.187931 -277.629665) (xy 380.139712 -277.619821)
			(xy 380.093696 -277.602369) (xy 380.051075 -277.577762) (xy 380.012954 -277.546637) (xy 379.980319 -277.5098)
			(xy 379.954016 -277.468204) (xy 379.934725 -277.422928) (xy 379.922948 -277.375144) (xy 379.918988 -277.32609)
			(xy 379.60046 -277.32609) (xy 379.599948 -277.351536) (xy 379.591784 -277.40177) (xy 379.575668 -277.450044)
			(xy 379.552017 -277.495107) (xy 379.521444 -277.535793) (xy 379.48474 -277.571048) (xy 379.442856 -277.599958)
			(xy 379.396877 -277.621775) (xy 379.347993 -277.635935) (xy 379.297472 -277.642069) (xy 379.24662 -277.64002)
			(xy 379.196756 -277.62984) (xy 379.14917 -277.611793) (xy 379.105096 -277.586347) (xy 379.065674 -277.55416)
			(xy 379.031926 -277.516066) (xy 379.004725 -277.473052) (xy 378.984777 -277.426232) (xy 378.972598 -277.376818)
			(xy 378.968503 -277.32609) (xy 378.650246 -277.32609) (xy 378.649751 -277.350697) (xy 378.641856 -277.399274)
			(xy 378.626272 -277.445955) (xy 378.603401 -277.489532) (xy 378.573836 -277.528876) (xy 378.538343 -277.562968)
			(xy 378.49784 -277.590924) (xy 378.453378 -277.612022) (xy 378.406107 -277.625714) (xy 378.357252 -277.631646)
			(xy 378.308077 -277.629665) (xy 378.259858 -277.619821) (xy 378.213842 -277.602369) (xy 378.171221 -277.577762)
			(xy 378.1331 -277.546637) (xy 378.100465 -277.5098) (xy 378.074162 -277.468204) (xy 378.054871 -277.422928)
			(xy 378.043094 -277.375144) (xy 378.039134 -277.32609) (xy 377.720606 -277.32609) (xy 377.720094 -277.351536)
			(xy 377.71193 -277.40177) (xy 377.695814 -277.450044) (xy 377.672163 -277.495107) (xy 377.64159 -277.535793)
			(xy 377.604886 -277.571048) (xy 377.563002 -277.599958) (xy 377.517023 -277.621775) (xy 377.468139 -277.635935)
			(xy 377.417618 -277.642069) (xy 377.366766 -277.64002) (xy 377.316902 -277.62984) (xy 377.269316 -277.611793)
			(xy 377.225242 -277.586347) (xy 377.18582 -277.55416) (xy 377.152072 -277.516066) (xy 377.124871 -277.473052)
			(xy 377.104923 -277.426232) (xy 377.092744 -277.376818) (xy 377.088649 -277.32609) (xy 376.780552 -277.32609)
			(xy 376.78004 -277.351536) (xy 376.771876 -277.40177) (xy 376.75576 -277.450044) (xy 376.732109 -277.495107)
			(xy 376.701536 -277.535793) (xy 376.664832 -277.571048) (xy 376.622948 -277.599958) (xy 376.576969 -277.621775)
			(xy 376.528085 -277.635935) (xy 376.477564 -277.642069) (xy 376.426712 -277.64002) (xy 376.376848 -277.62984)
			(xy 376.329262 -277.611793) (xy 376.285188 -277.586347) (xy 376.245766 -277.55416) (xy 376.212018 -277.516066)
			(xy 376.184817 -277.473052) (xy 376.164869 -277.426232) (xy 376.15269 -277.376818) (xy 376.148595 -277.32609)
			(xy 375.235978 -277.32609) (xy 375.235978 -277.855426) (xy 375.236994 -277.865586) (xy 375.24055 -277.876508)
			(xy 375.25325 -277.90394) (xy 375.260616 -277.910544) (xy 375.27904 -277.92803) (xy 375.310386 -277.967997)
			(xy 375.334685 -278.0126) (xy 375.351266 -278.060609) (xy 375.359673 -278.110701) (xy 375.359673 -278.136096)
			(xy 375.678695 -278.136096) (xy 375.68279 -278.085368) (xy 375.694969 -278.035954) (xy 375.714917 -277.989134)
			(xy 375.742118 -277.94612) (xy 375.775866 -277.908026) (xy 375.815288 -277.875839) (xy 375.859362 -277.850393)
			(xy 375.906948 -277.832346) (xy 375.956812 -277.822166) (xy 376.007664 -277.820117) (xy 376.058185 -277.826251)
			(xy 376.107069 -277.840411) (xy 376.153048 -277.862228) (xy 376.194932 -277.891138) (xy 376.231636 -277.926393)
			(xy 376.262209 -277.967079) (xy 376.28586 -278.012142) (xy 376.301976 -278.060416) (xy 376.31014 -278.11065)
			(xy 376.310652 -278.136096) (xy 376.628926 -278.136096) (xy 376.632886 -278.087042) (xy 376.644663 -278.039258)
			(xy 376.663954 -277.993982) (xy 376.690257 -277.952386) (xy 376.722892 -277.915549) (xy 376.761013 -277.884424)
			(xy 376.803634 -277.859817) (xy 376.84965 -277.842365) (xy 376.897869 -277.832521) (xy 376.947044 -277.83054)
			(xy 376.995899 -277.836472) (xy 377.04317 -277.850164) (xy 377.087632 -277.871262) (xy 377.128135 -277.899218)
			(xy 377.163628 -277.93331) (xy 377.193193 -277.972654) (xy 377.216064 -278.016231) (xy 377.231648 -278.062912)
			(xy 377.239543 -278.111489) (xy 377.240038 -278.136096) (xy 377.558549 -278.136096) (xy 377.562644 -278.085368)
			(xy 377.574823 -278.035954) (xy 377.594771 -277.989134) (xy 377.621972 -277.94612) (xy 377.65572 -277.908026)
			(xy 377.695142 -277.875839) (xy 377.739216 -277.850393) (xy 377.786802 -277.832346) (xy 377.836666 -277.822166)
			(xy 377.887518 -277.820117) (xy 377.938039 -277.826251) (xy 377.986923 -277.840411) (xy 378.032902 -277.862228)
			(xy 378.074786 -277.891138) (xy 378.11149 -277.926393) (xy 378.142063 -277.967079) (xy 378.165714 -278.012142)
			(xy 378.18183 -278.060416) (xy 378.189994 -278.11065) (xy 378.190506 -278.136096) (xy 379.438657 -278.136096)
			(xy 379.442752 -278.085368) (xy 379.454931 -278.035954) (xy 379.474879 -277.989134) (xy 379.50208 -277.94612)
			(xy 379.535828 -277.908026) (xy 379.57525 -277.875839) (xy 379.619324 -277.850393) (xy 379.66691 -277.832346)
			(xy 379.716774 -277.822166) (xy 379.767626 -277.820117) (xy 379.818147 -277.826251) (xy 379.867031 -277.840411)
			(xy 379.91301 -277.862228) (xy 379.954894 -277.891138) (xy 379.991598 -277.926393) (xy 380.022171 -277.967079)
			(xy 380.045822 -278.012142) (xy 380.061938 -278.060416) (xy 380.070102 -278.11065) (xy 380.070614 -278.136096)
			(xy 380.378711 -278.136096) (xy 380.382806 -278.085368) (xy 380.394985 -278.035954) (xy 380.414933 -277.989134)
			(xy 380.442134 -277.94612) (xy 380.475882 -277.908026) (xy 380.515304 -277.875839) (xy 380.559378 -277.850393)
			(xy 380.606964 -277.832346) (xy 380.656828 -277.822166) (xy 380.70768 -277.820117) (xy 380.758201 -277.826251)
			(xy 380.807085 -277.840411) (xy 380.853064 -277.862228) (xy 380.894948 -277.891138) (xy 380.931652 -277.926393)
			(xy 380.962225 -277.967079) (xy 380.985876 -278.012142) (xy 381.001992 -278.060416) (xy 381.010156 -278.11065)
			(xy 381.010668 -278.136096) (xy 381.328942 -278.136096) (xy 381.332902 -278.087042) (xy 381.344679 -278.039258)
			(xy 381.36397 -277.993982) (xy 381.390273 -277.952386) (xy 381.422908 -277.915549) (xy 381.461029 -277.884424)
			(xy 381.50365 -277.859817) (xy 381.549666 -277.842365) (xy 381.597885 -277.832521) (xy 381.64706 -277.83054)
			(xy 381.695915 -277.836472) (xy 381.743186 -277.850164) (xy 381.787648 -277.871262) (xy 381.828151 -277.899218)
			(xy 381.863644 -277.93331) (xy 381.893209 -277.972654) (xy 381.91608 -278.016231) (xy 381.931664 -278.062912)
			(xy 381.939559 -278.111489) (xy 381.940054 -278.136096) (xy 382.268996 -278.136096) (xy 382.272956 -278.087042)
			(xy 382.284733 -278.039258) (xy 382.304024 -277.993982) (xy 382.330327 -277.952386) (xy 382.362962 -277.915549)
			(xy 382.401083 -277.884424) (xy 382.443704 -277.859817) (xy 382.48972 -277.842365) (xy 382.537939 -277.832521)
			(xy 382.587114 -277.83054) (xy 382.635969 -277.836472) (xy 382.68324 -277.850164) (xy 382.727702 -277.871262)
			(xy 382.768205 -277.899218) (xy 382.803698 -277.93331) (xy 382.833263 -277.972654) (xy 382.856134 -278.016231)
			(xy 382.871718 -278.062912) (xy 382.879613 -278.111489) (xy 382.880108 -278.136096) (xy 383.20905 -278.136096)
			(xy 383.21301 -278.087042) (xy 383.224787 -278.039258) (xy 383.244078 -277.993982) (xy 383.270381 -277.952386)
			(xy 383.303016 -277.915549) (xy 383.341137 -277.884424) (xy 383.383758 -277.859817) (xy 383.429774 -277.842365)
			(xy 383.477993 -277.832521) (xy 383.527168 -277.83054) (xy 383.576023 -277.836472) (xy 383.623294 -277.850164)
			(xy 383.667756 -277.871262) (xy 383.708259 -277.899218) (xy 383.743752 -277.93331) (xy 383.773317 -277.972654)
			(xy 383.796188 -278.016231) (xy 383.811772 -278.062912) (xy 383.819667 -278.111489) (xy 383.820162 -278.136096)
			(xy 384.149104 -278.136096) (xy 384.153064 -278.087042) (xy 384.164841 -278.039258) (xy 384.184132 -277.993982)
			(xy 384.210435 -277.952386) (xy 384.24307 -277.915549) (xy 384.281191 -277.884424) (xy 384.323812 -277.859817)
			(xy 384.369828 -277.842365) (xy 384.418047 -277.832521) (xy 384.467222 -277.83054) (xy 384.516077 -277.836472)
			(xy 384.563348 -277.850164) (xy 384.60781 -277.871262) (xy 384.648313 -277.899218) (xy 384.683806 -277.93331)
			(xy 384.713371 -277.972654) (xy 384.736242 -278.016231) (xy 384.751826 -278.062912) (xy 384.759721 -278.111489)
			(xy 384.760216 -278.136096) (xy 386.028958 -278.136096) (xy 386.032918 -278.087042) (xy 386.044695 -278.039258)
			(xy 386.063986 -277.993982) (xy 386.090289 -277.952386) (xy 386.122924 -277.915549) (xy 386.161045 -277.884424)
			(xy 386.203666 -277.859817) (xy 386.249682 -277.842365) (xy 386.297901 -277.832521) (xy 386.347076 -277.83054)
			(xy 386.395931 -277.836472) (xy 386.443202 -277.850164) (xy 386.487664 -277.871262) (xy 386.528167 -277.899218)
			(xy 386.56366 -277.93331) (xy 386.593225 -277.972654) (xy 386.616096 -278.016231) (xy 386.63168 -278.062912)
			(xy 386.639575 -278.111489) (xy 386.64007 -278.136096) (xy 386.969012 -278.136096) (xy 386.972972 -278.087042)
			(xy 386.984749 -278.039258) (xy 387.00404 -277.993982) (xy 387.030343 -277.952386) (xy 387.062978 -277.915549)
			(xy 387.101099 -277.884424) (xy 387.14372 -277.859817) (xy 387.189736 -277.842365) (xy 387.237955 -277.832521)
			(xy 387.28713 -277.83054) (xy 387.335985 -277.836472) (xy 387.383256 -277.850164) (xy 387.427718 -277.871262)
			(xy 387.468221 -277.899218) (xy 387.503714 -277.93331) (xy 387.533279 -277.972654) (xy 387.55615 -278.016231)
			(xy 387.571734 -278.062912) (xy 387.579629 -278.111489) (xy 387.580124 -278.136096) (xy 387.579629 -278.160703)
			(xy 387.571734 -278.20928) (xy 387.55615 -278.255961) (xy 387.533279 -278.299538) (xy 387.503714 -278.338882)
			(xy 387.468221 -278.372974) (xy 387.427718 -278.40093) (xy 387.383256 -278.422028) (xy 387.335985 -278.43572)
			(xy 387.28713 -278.441652) (xy 387.237955 -278.439671) (xy 387.189736 -278.429827) (xy 387.14372 -278.412375)
			(xy 387.101099 -278.387768) (xy 387.062978 -278.356643) (xy 387.030343 -278.319806) (xy 387.00404 -278.27821)
			(xy 386.984749 -278.232934) (xy 386.972972 -278.18515) (xy 386.969012 -278.136096) (xy 386.64007 -278.136096)
			(xy 386.639575 -278.160703) (xy 386.63168 -278.20928) (xy 386.616096 -278.255961) (xy 386.593225 -278.299538)
			(xy 386.56366 -278.338882) (xy 386.528167 -278.372974) (xy 386.487664 -278.40093) (xy 386.443202 -278.422028)
			(xy 386.395931 -278.43572) (xy 386.347076 -278.441652) (xy 386.297901 -278.439671) (xy 386.249682 -278.429827)
			(xy 386.203666 -278.412375) (xy 386.161045 -278.387768) (xy 386.122924 -278.356643) (xy 386.090289 -278.319806)
			(xy 386.063986 -278.27821) (xy 386.044695 -278.232934) (xy 386.032918 -278.18515) (xy 386.028958 -278.136096)
			(xy 384.760216 -278.136096) (xy 384.759721 -278.160703) (xy 384.751826 -278.20928) (xy 384.736242 -278.255961)
			(xy 384.713371 -278.299538) (xy 384.683806 -278.338882) (xy 384.648313 -278.372974) (xy 384.60781 -278.40093)
			(xy 384.563348 -278.422028) (xy 384.516077 -278.43572) (xy 384.467222 -278.441652) (xy 384.418047 -278.439671)
			(xy 384.369828 -278.429827) (xy 384.323812 -278.412375) (xy 384.281191 -278.387768) (xy 384.24307 -278.356643)
			(xy 384.210435 -278.319806) (xy 384.184132 -278.27821) (xy 384.164841 -278.232934) (xy 384.153064 -278.18515)
			(xy 384.149104 -278.136096) (xy 383.820162 -278.136096) (xy 383.819667 -278.160703) (xy 383.811772 -278.20928)
			(xy 383.796188 -278.255961) (xy 383.773317 -278.299538) (xy 383.743752 -278.338882) (xy 383.708259 -278.372974)
			(xy 383.667756 -278.40093) (xy 383.623294 -278.422028) (xy 383.576023 -278.43572) (xy 383.527168 -278.441652)
			(xy 383.477993 -278.439671) (xy 383.429774 -278.429827) (xy 383.383758 -278.412375) (xy 383.341137 -278.387768)
			(xy 383.303016 -278.356643) (xy 383.270381 -278.319806) (xy 383.244078 -278.27821) (xy 383.224787 -278.232934)
			(xy 383.21301 -278.18515) (xy 383.20905 -278.136096) (xy 382.880108 -278.136096) (xy 382.879613 -278.160703)
			(xy 382.871718 -278.20928) (xy 382.856134 -278.255961) (xy 382.833263 -278.299538) (xy 382.803698 -278.338882)
			(xy 382.768205 -278.372974) (xy 382.727702 -278.40093) (xy 382.68324 -278.422028) (xy 382.635969 -278.43572)
			(xy 382.587114 -278.441652) (xy 382.537939 -278.439671) (xy 382.48972 -278.429827) (xy 382.443704 -278.412375)
			(xy 382.401083 -278.387768) (xy 382.362962 -278.356643) (xy 382.330327 -278.319806) (xy 382.304024 -278.27821)
			(xy 382.284733 -278.232934) (xy 382.272956 -278.18515) (xy 382.268996 -278.136096) (xy 381.940054 -278.136096)
			(xy 381.939559 -278.160703) (xy 381.931664 -278.20928) (xy 381.91608 -278.255961) (xy 381.893209 -278.299538)
			(xy 381.863644 -278.338882) (xy 381.828151 -278.372974) (xy 381.787648 -278.40093) (xy 381.743186 -278.422028)
			(xy 381.695915 -278.43572) (xy 381.64706 -278.441652) (xy 381.597885 -278.439671) (xy 381.549666 -278.429827)
			(xy 381.50365 -278.412375) (xy 381.461029 -278.387768) (xy 381.422908 -278.356643) (xy 381.390273 -278.319806)
			(xy 381.36397 -278.27821) (xy 381.344679 -278.232934) (xy 381.332902 -278.18515) (xy 381.328942 -278.136096)
			(xy 381.010668 -278.136096) (xy 381.010156 -278.161542) (xy 381.001992 -278.211776) (xy 380.985876 -278.26005)
			(xy 380.962225 -278.305113) (xy 380.931652 -278.345799) (xy 380.894948 -278.381054) (xy 380.853064 -278.409964)
			(xy 380.807085 -278.431781) (xy 380.758201 -278.445941) (xy 380.70768 -278.452075) (xy 380.656828 -278.450026)
			(xy 380.606964 -278.439846) (xy 380.559378 -278.421799) (xy 380.515304 -278.396353) (xy 380.475882 -278.364166)
			(xy 380.442134 -278.326072) (xy 380.414933 -278.283058) (xy 380.394985 -278.236238) (xy 380.382806 -278.186824)
			(xy 380.378711 -278.136096) (xy 380.070614 -278.136096) (xy 380.070102 -278.161542) (xy 380.061938 -278.211776)
			(xy 380.045822 -278.26005) (xy 380.022171 -278.305113) (xy 379.991598 -278.345799) (xy 379.954894 -278.381054)
			(xy 379.91301 -278.409964) (xy 379.867031 -278.431781) (xy 379.818147 -278.445941) (xy 379.767626 -278.452075)
			(xy 379.716774 -278.450026) (xy 379.66691 -278.439846) (xy 379.619324 -278.421799) (xy 379.57525 -278.396353)
			(xy 379.535828 -278.364166) (xy 379.50208 -278.326072) (xy 379.474879 -278.283058) (xy 379.454931 -278.236238)
			(xy 379.442752 -278.186824) (xy 379.438657 -278.136096) (xy 378.190506 -278.136096) (xy 378.189994 -278.161542)
			(xy 378.18183 -278.211776) (xy 378.165714 -278.26005) (xy 378.142063 -278.305113) (xy 378.11149 -278.345799)
			(xy 378.074786 -278.381054) (xy 378.032902 -278.409964) (xy 377.986923 -278.431781) (xy 377.938039 -278.445941)
			(xy 377.887518 -278.452075) (xy 377.836666 -278.450026) (xy 377.786802 -278.439846) (xy 377.739216 -278.421799)
			(xy 377.695142 -278.396353) (xy 377.65572 -278.364166) (xy 377.621972 -278.326072) (xy 377.594771 -278.283058)
			(xy 377.574823 -278.236238) (xy 377.562644 -278.186824) (xy 377.558549 -278.136096) (xy 377.240038 -278.136096)
			(xy 377.239543 -278.160703) (xy 377.231648 -278.20928) (xy 377.216064 -278.255961) (xy 377.193193 -278.299538)
			(xy 377.163628 -278.338882) (xy 377.128135 -278.372974) (xy 377.087632 -278.40093) (xy 377.04317 -278.422028)
			(xy 376.995899 -278.43572) (xy 376.947044 -278.441652) (xy 376.897869 -278.439671) (xy 376.84965 -278.429827)
			(xy 376.803634 -278.412375) (xy 376.761013 -278.387768) (xy 376.722892 -278.356643) (xy 376.690257 -278.319806)
			(xy 376.663954 -278.27821) (xy 376.644663 -278.232934) (xy 376.632886 -278.18515) (xy 376.628926 -278.136096)
			(xy 376.310652 -278.136096) (xy 376.31014 -278.161542) (xy 376.301976 -278.211776) (xy 376.28586 -278.26005)
			(xy 376.262209 -278.305113) (xy 376.231636 -278.345799) (xy 376.194932 -278.381054) (xy 376.153048 -278.409964)
			(xy 376.107069 -278.431781) (xy 376.058185 -278.445941) (xy 376.007664 -278.452075) (xy 375.956812 -278.450026)
			(xy 375.906948 -278.439846) (xy 375.859362 -278.421799) (xy 375.815288 -278.396353) (xy 375.775866 -278.364166)
			(xy 375.742118 -278.326072) (xy 375.714917 -278.283058) (xy 375.694969 -278.236238) (xy 375.68279 -278.186824)
			(xy 375.678695 -278.136096) (xy 375.359673 -278.136096) (xy 375.359674 -278.161494) (xy 375.351268 -278.211586)
			(xy 375.334687 -278.259595) (xy 375.310389 -278.304199) (xy 375.279044 -278.344166) (xy 375.260616 -278.361648)
			(xy 375.25325 -278.368252) (xy 375.240804 -278.39543) (xy 375.23674 -278.407876) (xy 375.235978 -278.416512)
			(xy 375.235978 -278.587454) (xy 375.236375 -278.596008) (xy 375.24217 -278.612111) (xy 375.252982 -278.625377)
			(xy 375.260108 -278.630126) (xy 375.315734 -278.663654) (xy 375.336054 -278.675846) (xy 375.34124 -278.678375)
			(xy 375.352394 -278.681314) (xy 375.358152 -278.681688) (xy 375.370852 -278.681942) (xy 375.382536 -278.675846)
			(xy 375.40453 -278.664848) (xy 375.451159 -278.649245) (xy 375.499684 -278.641307) (xy 375.524268 -278.640794)
			(xy 375.530364 -278.640794) (xy 375.555318 -278.641746) (xy 375.60443 -278.650767) (xy 375.651421 -278.667658)
			(xy 375.695037 -278.69197) (xy 375.734116 -278.723054) (xy 375.767617 -278.760082) (xy 375.794647 -278.802068)
			(xy 375.814486 -278.847891) (xy 375.826604 -278.896333) (xy 375.83068 -278.9461) (xy 375.83068 -278.946102)
			(xy 376.148595 -278.946102) (xy 376.15269 -278.895374) (xy 376.164869 -278.84596) (xy 376.184817 -278.79914)
			(xy 376.212018 -278.756126) (xy 376.245766 -278.718032) (xy 376.285188 -278.685845) (xy 376.329262 -278.660399)
			(xy 376.376848 -278.642352) (xy 376.426712 -278.632172) (xy 376.477564 -278.630123) (xy 376.528085 -278.636257)
			(xy 376.576969 -278.650417) (xy 376.622948 -278.672234) (xy 376.664832 -278.701144) (xy 376.701536 -278.736399)
			(xy 376.732109 -278.777085) (xy 376.75576 -278.822148) (xy 376.771876 -278.870422) (xy 376.78004 -278.920656)
			(xy 376.780552 -278.946102) (xy 377.088649 -278.946102) (xy 377.092744 -278.895374) (xy 377.104923 -278.84596)
			(xy 377.124871 -278.79914) (xy 377.152072 -278.756126) (xy 377.18582 -278.718032) (xy 377.225242 -278.685845)
			(xy 377.269316 -278.660399) (xy 377.316902 -278.642352) (xy 377.366766 -278.632172) (xy 377.417618 -278.630123)
			(xy 377.468139 -278.636257) (xy 377.517023 -278.650417) (xy 377.563002 -278.672234) (xy 377.604886 -278.701144)
			(xy 377.64159 -278.736399) (xy 377.672163 -278.777085) (xy 377.695814 -278.822148) (xy 377.71193 -278.870422)
			(xy 377.720094 -278.920656) (xy 377.720606 -278.946102) (xy 378.039134 -278.946102) (xy 378.043094 -278.897048)
			(xy 378.054871 -278.849264) (xy 378.074162 -278.803988) (xy 378.100465 -278.762392) (xy 378.1331 -278.725555)
			(xy 378.171221 -278.69443) (xy 378.213842 -278.669823) (xy 378.259858 -278.652371) (xy 378.308077 -278.642527)
			(xy 378.357252 -278.640546) (xy 378.406107 -278.646478) (xy 378.453378 -278.66017) (xy 378.49784 -278.681268)
			(xy 378.538343 -278.709224) (xy 378.573836 -278.743316) (xy 378.603401 -278.78266) (xy 378.626272 -278.826237)
			(xy 378.641856 -278.872918) (xy 378.649751 -278.921495) (xy 378.650246 -278.946102) (xy 378.968503 -278.946102)
			(xy 378.972598 -278.895374) (xy 378.984777 -278.84596) (xy 379.004725 -278.79914) (xy 379.031926 -278.756126)
			(xy 379.065674 -278.718032) (xy 379.105096 -278.685845) (xy 379.14917 -278.660399) (xy 379.196756 -278.642352)
			(xy 379.24662 -278.632172) (xy 379.297472 -278.630123) (xy 379.347993 -278.636257) (xy 379.396877 -278.650417)
			(xy 379.442856 -278.672234) (xy 379.48474 -278.701144) (xy 379.521444 -278.736399) (xy 379.552017 -278.777085)
			(xy 379.575668 -278.822148) (xy 379.591784 -278.870422) (xy 379.599948 -278.920656) (xy 379.60046 -278.946102)
			(xy 379.918988 -278.946102) (xy 379.922948 -278.897048) (xy 379.934725 -278.849264) (xy 379.954016 -278.803988)
			(xy 379.980319 -278.762392) (xy 380.012954 -278.725555) (xy 380.051075 -278.69443) (xy 380.093696 -278.669823)
			(xy 380.139712 -278.652371) (xy 380.187931 -278.642527) (xy 380.237106 -278.640546) (xy 380.285961 -278.646478)
			(xy 380.333232 -278.66017) (xy 380.377694 -278.681268) (xy 380.418197 -278.709224) (xy 380.45369 -278.743316)
			(xy 380.483255 -278.78266) (xy 380.506126 -278.826237) (xy 380.52171 -278.872918) (xy 380.529605 -278.921495)
			(xy 380.5301 -278.946102) (xy 380.848611 -278.946102) (xy 380.852706 -278.895374) (xy 380.864885 -278.84596)
			(xy 380.884833 -278.79914) (xy 380.912034 -278.756126) (xy 380.945782 -278.718032) (xy 380.985204 -278.685845)
			(xy 381.029278 -278.660399) (xy 381.076864 -278.642352) (xy 381.126728 -278.632172) (xy 381.17758 -278.630123)
			(xy 381.228101 -278.636257) (xy 381.276985 -278.650417) (xy 381.322964 -278.672234) (xy 381.364848 -278.701144)
			(xy 381.401552 -278.736399) (xy 381.432125 -278.777085) (xy 381.455776 -278.822148) (xy 381.471892 -278.870422)
			(xy 381.480056 -278.920656) (xy 381.480568 -278.946102) (xy 381.799096 -278.946102) (xy 381.803056 -278.897048)
			(xy 381.814833 -278.849264) (xy 381.834124 -278.803988) (xy 381.860427 -278.762392) (xy 381.893062 -278.725555)
			(xy 381.931183 -278.69443) (xy 381.973804 -278.669823) (xy 382.01982 -278.652371) (xy 382.068039 -278.642527)
			(xy 382.117214 -278.640546) (xy 382.166069 -278.646478) (xy 382.21334 -278.66017) (xy 382.257802 -278.681268)
			(xy 382.298305 -278.709224) (xy 382.333798 -278.743316) (xy 382.363363 -278.78266) (xy 382.386234 -278.826237)
			(xy 382.401818 -278.872918) (xy 382.409713 -278.921495) (xy 382.410208 -278.946102) (xy 382.738896 -278.946102)
			(xy 382.742856 -278.897048) (xy 382.754633 -278.849264) (xy 382.773924 -278.803988) (xy 382.800227 -278.762392)
			(xy 382.832862 -278.725555) (xy 382.870983 -278.69443) (xy 382.913604 -278.669823) (xy 382.95962 -278.652371)
			(xy 383.007839 -278.642527) (xy 383.057014 -278.640546) (xy 383.105869 -278.646478) (xy 383.15314 -278.66017)
			(xy 383.197602 -278.681268) (xy 383.238105 -278.709224) (xy 383.273598 -278.743316) (xy 383.303163 -278.78266)
			(xy 383.326034 -278.826237) (xy 383.341618 -278.872918) (xy 383.349513 -278.921495) (xy 383.350008 -278.946102)
			(xy 383.67895 -278.946102) (xy 383.68291 -278.897048) (xy 383.694687 -278.849264) (xy 383.713978 -278.803988)
			(xy 383.740281 -278.762392) (xy 383.772916 -278.725555) (xy 383.811037 -278.69443) (xy 383.853658 -278.669823)
			(xy 383.899674 -278.652371) (xy 383.947893 -278.642527) (xy 383.997068 -278.640546) (xy 384.045923 -278.646478)
			(xy 384.093194 -278.66017) (xy 384.137656 -278.681268) (xy 384.178159 -278.709224) (xy 384.213652 -278.743316)
			(xy 384.243217 -278.78266) (xy 384.266088 -278.826237) (xy 384.281672 -278.872918) (xy 384.289567 -278.921495)
			(xy 384.290062 -278.946102) (xy 384.619004 -278.946102) (xy 384.622964 -278.897048) (xy 384.634741 -278.849264)
			(xy 384.654032 -278.803988) (xy 384.680335 -278.762392) (xy 384.71297 -278.725555) (xy 384.751091 -278.69443)
			(xy 384.793712 -278.669823) (xy 384.839728 -278.652371) (xy 384.887947 -278.642527) (xy 384.937122 -278.640546)
			(xy 384.985977 -278.646478) (xy 385.033248 -278.66017) (xy 385.07771 -278.681268) (xy 385.118213 -278.709224)
			(xy 385.153706 -278.743316) (xy 385.183271 -278.78266) (xy 385.206142 -278.826237) (xy 385.221726 -278.872918)
			(xy 385.229621 -278.921495) (xy 385.230116 -278.946102) (xy 385.559058 -278.946102) (xy 385.563018 -278.897048)
			(xy 385.574795 -278.849264) (xy 385.594086 -278.803988) (xy 385.620389 -278.762392) (xy 385.653024 -278.725555)
			(xy 385.691145 -278.69443) (xy 385.733766 -278.669823) (xy 385.779782 -278.652371) (xy 385.828001 -278.642527)
			(xy 385.877176 -278.640546) (xy 385.926031 -278.646478) (xy 385.973302 -278.66017) (xy 386.017764 -278.681268)
			(xy 386.058267 -278.709224) (xy 386.09376 -278.743316) (xy 386.123325 -278.78266) (xy 386.146196 -278.826237)
			(xy 386.16178 -278.872918) (xy 386.169675 -278.921495) (xy 386.17017 -278.946102) (xy 386.499112 -278.946102)
			(xy 386.503072 -278.897048) (xy 386.514849 -278.849264) (xy 386.53414 -278.803988) (xy 386.560443 -278.762392)
			(xy 386.593078 -278.725555) (xy 386.631199 -278.69443) (xy 386.67382 -278.669823) (xy 386.719836 -278.652371)
			(xy 386.768055 -278.642527) (xy 386.81723 -278.640546) (xy 386.866085 -278.646478) (xy 386.913356 -278.66017)
			(xy 386.957818 -278.681268) (xy 386.998321 -278.709224) (xy 387.033814 -278.743316) (xy 387.063379 -278.78266)
			(xy 387.08625 -278.826237) (xy 387.101834 -278.872918) (xy 387.109729 -278.921495) (xy 387.110224 -278.946102)
			(xy 387.438912 -278.946102) (xy 387.442872 -278.897048) (xy 387.454649 -278.849264) (xy 387.47394 -278.803988)
			(xy 387.500243 -278.762392) (xy 387.532878 -278.725555) (xy 387.570999 -278.69443) (xy 387.61362 -278.669823)
			(xy 387.659636 -278.652371) (xy 387.707855 -278.642527) (xy 387.75703 -278.640546) (xy 387.805885 -278.646478)
			(xy 387.853156 -278.66017) (xy 387.897618 -278.681268) (xy 387.938121 -278.709224) (xy 387.973614 -278.743316)
			(xy 388.003179 -278.78266) (xy 388.02605 -278.826237) (xy 388.041634 -278.872918) (xy 388.049529 -278.921495)
			(xy 388.050024 -278.946102) (xy 388.049529 -278.970709) (xy 388.041634 -279.019286) (xy 388.02605 -279.065967)
			(xy 388.003179 -279.109544) (xy 387.973614 -279.148888) (xy 387.938121 -279.18298) (xy 387.897618 -279.210936)
			(xy 387.853156 -279.232034) (xy 387.805885 -279.245726) (xy 387.75703 -279.251658) (xy 387.707855 -279.249677)
			(xy 387.659636 -279.239833) (xy 387.61362 -279.222381) (xy 387.570999 -279.197774) (xy 387.532878 -279.166649)
			(xy 387.500243 -279.129812) (xy 387.47394 -279.088216) (xy 387.454649 -279.04294) (xy 387.442872 -278.995156)
			(xy 387.438912 -278.946102) (xy 387.110224 -278.946102) (xy 387.109729 -278.970709) (xy 387.101834 -279.019286)
			(xy 387.08625 -279.065967) (xy 387.063379 -279.109544) (xy 387.033814 -279.148888) (xy 386.998321 -279.18298)
			(xy 386.957818 -279.210936) (xy 386.913356 -279.232034) (xy 386.866085 -279.245726) (xy 386.81723 -279.251658)
			(xy 386.768055 -279.249677) (xy 386.719836 -279.239833) (xy 386.67382 -279.222381) (xy 386.631199 -279.197774)
			(xy 386.593078 -279.166649) (xy 386.560443 -279.129812) (xy 386.53414 -279.088216) (xy 386.514849 -279.04294)
			(xy 386.503072 -278.995156) (xy 386.499112 -278.946102) (xy 386.17017 -278.946102) (xy 386.169675 -278.970709)
			(xy 386.16178 -279.019286) (xy 386.146196 -279.065967) (xy 386.123325 -279.109544) (xy 386.09376 -279.148888)
			(xy 386.058267 -279.18298) (xy 386.017764 -279.210936) (xy 385.973302 -279.232034) (xy 385.926031 -279.245726)
			(xy 385.877176 -279.251658) (xy 385.828001 -279.249677) (xy 385.779782 -279.239833) (xy 385.733766 -279.222381)
			(xy 385.691145 -279.197774) (xy 385.653024 -279.166649) (xy 385.620389 -279.129812) (xy 385.594086 -279.088216)
			(xy 385.574795 -279.04294) (xy 385.563018 -278.995156) (xy 385.559058 -278.946102) (xy 385.230116 -278.946102)
			(xy 385.229621 -278.970709) (xy 385.221726 -279.019286) (xy 385.206142 -279.065967) (xy 385.183271 -279.109544)
			(xy 385.153706 -279.148888) (xy 385.118213 -279.18298) (xy 385.07771 -279.210936) (xy 385.033248 -279.232034)
			(xy 384.985977 -279.245726) (xy 384.937122 -279.251658) (xy 384.887947 -279.249677) (xy 384.839728 -279.239833)
			(xy 384.793712 -279.222381) (xy 384.751091 -279.197774) (xy 384.71297 -279.166649) (xy 384.680335 -279.129812)
			(xy 384.654032 -279.088216) (xy 384.634741 -279.04294) (xy 384.622964 -278.995156) (xy 384.619004 -278.946102)
			(xy 384.290062 -278.946102) (xy 384.289567 -278.970709) (xy 384.281672 -279.019286) (xy 384.266088 -279.065967)
			(xy 384.243217 -279.109544) (xy 384.213652 -279.148888) (xy 384.178159 -279.18298) (xy 384.137656 -279.210936)
			(xy 384.093194 -279.232034) (xy 384.045923 -279.245726) (xy 383.997068 -279.251658) (xy 383.947893 -279.249677)
			(xy 383.899674 -279.239833) (xy 383.853658 -279.222381) (xy 383.811037 -279.197774) (xy 383.772916 -279.166649)
			(xy 383.740281 -279.129812) (xy 383.713978 -279.088216) (xy 383.694687 -279.04294) (xy 383.68291 -278.995156)
			(xy 383.67895 -278.946102) (xy 383.350008 -278.946102) (xy 383.349513 -278.970709) (xy 383.341618 -279.019286)
			(xy 383.326034 -279.065967) (xy 383.303163 -279.109544) (xy 383.273598 -279.148888) (xy 383.238105 -279.18298)
			(xy 383.197602 -279.210936) (xy 383.15314 -279.232034) (xy 383.105869 -279.245726) (xy 383.057014 -279.251658)
			(xy 383.007839 -279.249677) (xy 382.95962 -279.239833) (xy 382.913604 -279.222381) (xy 382.870983 -279.197774)
			(xy 382.832862 -279.166649) (xy 382.800227 -279.129812) (xy 382.773924 -279.088216) (xy 382.754633 -279.04294)
			(xy 382.742856 -278.995156) (xy 382.738896 -278.946102) (xy 382.410208 -278.946102) (xy 382.409713 -278.970709)
			(xy 382.401818 -279.019286) (xy 382.386234 -279.065967) (xy 382.363363 -279.109544) (xy 382.333798 -279.148888)
			(xy 382.298305 -279.18298) (xy 382.257802 -279.210936) (xy 382.21334 -279.232034) (xy 382.166069 -279.245726)
			(xy 382.117214 -279.251658) (xy 382.068039 -279.249677) (xy 382.01982 -279.239833) (xy 381.973804 -279.222381)
			(xy 381.931183 -279.197774) (xy 381.893062 -279.166649) (xy 381.860427 -279.129812) (xy 381.834124 -279.088216)
			(xy 381.814833 -279.04294) (xy 381.803056 -278.995156) (xy 381.799096 -278.946102) (xy 381.480568 -278.946102)
			(xy 381.480056 -278.971548) (xy 381.471892 -279.021782) (xy 381.455776 -279.070056) (xy 381.432125 -279.115119)
			(xy 381.401552 -279.155805) (xy 381.364848 -279.19106) (xy 381.322964 -279.21997) (xy 381.276985 -279.241787)
			(xy 381.228101 -279.255947) (xy 381.17758 -279.262081) (xy 381.126728 -279.260032) (xy 381.076864 -279.249852)
			(xy 381.029278 -279.231805) (xy 380.985204 -279.206359) (xy 380.945782 -279.174172) (xy 380.912034 -279.136078)
			(xy 380.884833 -279.093064) (xy 380.864885 -279.046244) (xy 380.852706 -278.99683) (xy 380.848611 -278.946102)
			(xy 380.5301 -278.946102) (xy 380.529605 -278.970709) (xy 380.52171 -279.019286) (xy 380.506126 -279.065967)
			(xy 380.483255 -279.109544) (xy 380.45369 -279.148888) (xy 380.418197 -279.18298) (xy 380.377694 -279.210936)
			(xy 380.333232 -279.232034) (xy 380.285961 -279.245726) (xy 380.237106 -279.251658) (xy 380.187931 -279.249677)
			(xy 380.139712 -279.239833) (xy 380.093696 -279.222381) (xy 380.051075 -279.197774) (xy 380.012954 -279.166649)
			(xy 379.980319 -279.129812) (xy 379.954016 -279.088216) (xy 379.934725 -279.04294) (xy 379.922948 -278.995156)
			(xy 379.918988 -278.946102) (xy 379.60046 -278.946102) (xy 379.599948 -278.971548) (xy 379.591784 -279.021782)
			(xy 379.575668 -279.070056) (xy 379.552017 -279.115119) (xy 379.521444 -279.155805) (xy 379.48474 -279.19106)
			(xy 379.442856 -279.21997) (xy 379.396877 -279.241787) (xy 379.347993 -279.255947) (xy 379.297472 -279.262081)
			(xy 379.24662 -279.260032) (xy 379.196756 -279.249852) (xy 379.14917 -279.231805) (xy 379.105096 -279.206359)
			(xy 379.065674 -279.174172) (xy 379.031926 -279.136078) (xy 379.004725 -279.093064) (xy 378.984777 -279.046244)
			(xy 378.972598 -278.99683) (xy 378.968503 -278.946102) (xy 378.650246 -278.946102) (xy 378.649751 -278.970709)
			(xy 378.641856 -279.019286) (xy 378.626272 -279.065967) (xy 378.603401 -279.109544) (xy 378.573836 -279.148888)
			(xy 378.538343 -279.18298) (xy 378.49784 -279.210936) (xy 378.453378 -279.232034) (xy 378.406107 -279.245726)
			(xy 378.357252 -279.251658) (xy 378.308077 -279.249677) (xy 378.259858 -279.239833) (xy 378.213842 -279.222381)
			(xy 378.171221 -279.197774) (xy 378.1331 -279.166649) (xy 378.100465 -279.129812) (xy 378.074162 -279.088216)
			(xy 378.054871 -279.04294) (xy 378.043094 -278.995156) (xy 378.039134 -278.946102) (xy 377.720606 -278.946102)
			(xy 377.720094 -278.971548) (xy 377.71193 -279.021782) (xy 377.695814 -279.070056) (xy 377.672163 -279.115119)
			(xy 377.64159 -279.155805) (xy 377.604886 -279.19106) (xy 377.563002 -279.21997) (xy 377.517023 -279.241787)
			(xy 377.468139 -279.255947) (xy 377.417618 -279.262081) (xy 377.366766 -279.260032) (xy 377.316902 -279.249852)
			(xy 377.269316 -279.231805) (xy 377.225242 -279.206359) (xy 377.18582 -279.174172) (xy 377.152072 -279.136078)
			(xy 377.124871 -279.093064) (xy 377.104923 -279.046244) (xy 377.092744 -278.99683) (xy 377.088649 -278.946102)
			(xy 376.780552 -278.946102) (xy 376.78004 -278.971548) (xy 376.771876 -279.021782) (xy 376.75576 -279.070056)
			(xy 376.732109 -279.115119) (xy 376.701536 -279.155805) (xy 376.664832 -279.19106) (xy 376.622948 -279.21997)
			(xy 376.576969 -279.241787) (xy 376.528085 -279.255947) (xy 376.477564 -279.262081) (xy 376.426712 -279.260032)
			(xy 376.376848 -279.249852) (xy 376.329262 -279.231805) (xy 376.285188 -279.206359) (xy 376.245766 -279.174172)
			(xy 376.212018 -279.136078) (xy 376.184817 -279.093064) (xy 376.164869 -279.046244) (xy 376.15269 -278.99683)
			(xy 376.148595 -278.946102) (xy 375.83068 -278.946102) (xy 375.826604 -278.995867) (xy 375.814486 -279.044309)
			(xy 375.794647 -279.090133) (xy 375.767617 -279.132118) (xy 375.734116 -279.169146) (xy 375.695037 -279.20023)
			(xy 375.651421 -279.224542) (xy 375.60443 -279.241433) (xy 375.555318 -279.250454) (xy 375.530364 -279.25141)
			(xy 375.524268 -279.25141) (xy 375.499681 -279.250923) (xy 375.45115 -279.242994) (xy 375.40452 -279.22738)
			(xy 375.382536 -279.216358) (xy 375.376694 -279.21331) (xy 375.364248 -279.210516) (xy 375.358152 -279.210516)
			(xy 375.352388 -279.210845) (xy 375.341231 -279.213801) (xy 375.336054 -279.216358) (xy 375.315734 -279.22855)
			(xy 375.260108 -279.262078) (xy 375.252946 -279.266792) (xy 375.242088 -279.280046) (xy 375.236331 -279.296183)
			(xy 375.235978 -279.30475) (xy 375.235978 -279.441656) (xy 375.236138 -279.446889) (xy 375.238319 -279.457128)
			(xy 375.240296 -279.461976) (xy 375.251472 -279.484836) (xy 375.25706 -279.492964) (xy 375.263918 -279.499822)
			(xy 375.284266 -279.517075) (xy 375.319658 -279.556989) (xy 375.348184 -279.602067) (xy 375.369106 -279.651139)
			(xy 375.381879 -279.702933) (xy 375.386173 -279.756105) (xy 375.386173 -279.756108) (xy 375.678695 -279.756108)
			(xy 375.68279 -279.70538) (xy 375.694969 -279.655966) (xy 375.714917 -279.609146) (xy 375.742118 -279.566132)
			(xy 375.775866 -279.528038) (xy 375.815288 -279.495851) (xy 375.859362 -279.470405) (xy 375.906948 -279.452358)
			(xy 375.956812 -279.442178) (xy 376.007664 -279.440129) (xy 376.058185 -279.446263) (xy 376.107069 -279.460423)
			(xy 376.153048 -279.48224) (xy 376.194932 -279.51115) (xy 376.231636 -279.546405) (xy 376.262209 -279.587091)
			(xy 376.28586 -279.632154) (xy 376.301976 -279.680428) (xy 376.31014 -279.730662) (xy 376.310652 -279.756108)
			(xy 376.628926 -279.756108) (xy 376.632886 -279.707054) (xy 376.644663 -279.65927) (xy 376.663954 -279.613994)
			(xy 376.690257 -279.572398) (xy 376.722892 -279.535561) (xy 376.761013 -279.504436) (xy 376.803634 -279.479829)
			(xy 376.84965 -279.462377) (xy 376.897869 -279.452533) (xy 376.947044 -279.450552) (xy 376.995899 -279.456484)
			(xy 377.04317 -279.470176) (xy 377.087632 -279.491274) (xy 377.128135 -279.51923) (xy 377.163628 -279.553322)
			(xy 377.193193 -279.592666) (xy 377.216064 -279.636243) (xy 377.231648 -279.682924) (xy 377.239543 -279.731501)
			(xy 377.240038 -279.756108) (xy 377.558549 -279.756108) (xy 377.562644 -279.70538) (xy 377.574823 -279.655966)
			(xy 377.594771 -279.609146) (xy 377.621972 -279.566132) (xy 377.65572 -279.528038) (xy 377.695142 -279.495851)
			(xy 377.739216 -279.470405) (xy 377.786802 -279.452358) (xy 377.836666 -279.442178) (xy 377.887518 -279.440129)
			(xy 377.938039 -279.446263) (xy 377.986923 -279.460423) (xy 378.032902 -279.48224) (xy 378.074786 -279.51115)
			(xy 378.11149 -279.546405) (xy 378.142063 -279.587091) (xy 378.165714 -279.632154) (xy 378.18183 -279.680428)
			(xy 378.189994 -279.730662) (xy 378.190506 -279.756108) (xy 378.509034 -279.756108) (xy 378.512994 -279.707054)
			(xy 378.524771 -279.65927) (xy 378.544062 -279.613994) (xy 378.570365 -279.572398) (xy 378.603 -279.535561)
			(xy 378.641121 -279.504436) (xy 378.683742 -279.479829) (xy 378.729758 -279.462377) (xy 378.777977 -279.452533)
			(xy 378.827152 -279.450552) (xy 378.876007 -279.456484) (xy 378.923278 -279.470176) (xy 378.96774 -279.491274)
			(xy 379.008243 -279.51923) (xy 379.043736 -279.553322) (xy 379.073301 -279.592666) (xy 379.096172 -279.636243)
			(xy 379.111756 -279.682924) (xy 379.119651 -279.731501) (xy 379.120146 -279.756108) (xy 379.438657 -279.756108)
			(xy 379.442752 -279.70538) (xy 379.454931 -279.655966) (xy 379.474879 -279.609146) (xy 379.50208 -279.566132)
			(xy 379.535828 -279.528038) (xy 379.57525 -279.495851) (xy 379.619324 -279.470405) (xy 379.66691 -279.452358)
			(xy 379.716774 -279.442178) (xy 379.767626 -279.440129) (xy 379.818147 -279.446263) (xy 379.867031 -279.460423)
			(xy 379.91301 -279.48224) (xy 379.954894 -279.51115) (xy 379.991598 -279.546405) (xy 380.022171 -279.587091)
			(xy 380.045822 -279.632154) (xy 380.061938 -279.680428) (xy 380.070102 -279.730662) (xy 380.070614 -279.756108)
			(xy 380.378711 -279.756108) (xy 380.382806 -279.70538) (xy 380.394985 -279.655966) (xy 380.414933 -279.609146)
			(xy 380.442134 -279.566132) (xy 380.475882 -279.528038) (xy 380.515304 -279.495851) (xy 380.559378 -279.470405)
			(xy 380.606964 -279.452358) (xy 380.656828 -279.442178) (xy 380.70768 -279.440129) (xy 380.758201 -279.446263)
			(xy 380.807085 -279.460423) (xy 380.853064 -279.48224) (xy 380.894948 -279.51115) (xy 380.931652 -279.546405)
			(xy 380.962225 -279.587091) (xy 380.985876 -279.632154) (xy 381.001992 -279.680428) (xy 381.010156 -279.730662)
			(xy 381.010668 -279.756108) (xy 381.328942 -279.756108) (xy 381.332902 -279.707054) (xy 381.344679 -279.65927)
			(xy 381.36397 -279.613994) (xy 381.390273 -279.572398) (xy 381.422908 -279.535561) (xy 381.461029 -279.504436)
			(xy 381.50365 -279.479829) (xy 381.549666 -279.462377) (xy 381.597885 -279.452533) (xy 381.64706 -279.450552)
			(xy 381.695915 -279.456484) (xy 381.743186 -279.470176) (xy 381.787648 -279.491274) (xy 381.828151 -279.51923)
			(xy 381.863644 -279.553322) (xy 381.893209 -279.592666) (xy 381.91608 -279.636243) (xy 381.931664 -279.682924)
			(xy 381.939559 -279.731501) (xy 381.940054 -279.756108) (xy 382.268996 -279.756108) (xy 382.272956 -279.707054)
			(xy 382.284733 -279.65927) (xy 382.304024 -279.613994) (xy 382.330327 -279.572398) (xy 382.362962 -279.535561)
			(xy 382.401083 -279.504436) (xy 382.443704 -279.479829) (xy 382.48972 -279.462377) (xy 382.537939 -279.452533)
			(xy 382.587114 -279.450552) (xy 382.635969 -279.456484) (xy 382.68324 -279.470176) (xy 382.727702 -279.491274)
			(xy 382.768205 -279.51923) (xy 382.803698 -279.553322) (xy 382.833263 -279.592666) (xy 382.856134 -279.636243)
			(xy 382.871718 -279.682924) (xy 382.879613 -279.731501) (xy 382.880108 -279.756108) (xy 383.20905 -279.756108)
			(xy 383.21301 -279.707054) (xy 383.224787 -279.65927) (xy 383.244078 -279.613994) (xy 383.270381 -279.572398)
			(xy 383.303016 -279.535561) (xy 383.341137 -279.504436) (xy 383.383758 -279.479829) (xy 383.429774 -279.462377)
			(xy 383.477993 -279.452533) (xy 383.527168 -279.450552) (xy 383.576023 -279.456484) (xy 383.623294 -279.470176)
			(xy 383.667756 -279.491274) (xy 383.708259 -279.51923) (xy 383.743752 -279.553322) (xy 383.773317 -279.592666)
			(xy 383.796188 -279.636243) (xy 383.811772 -279.682924) (xy 383.819667 -279.731501) (xy 383.820162 -279.756108)
			(xy 384.149104 -279.756108) (xy 384.153064 -279.707054) (xy 384.164841 -279.65927) (xy 384.184132 -279.613994)
			(xy 384.210435 -279.572398) (xy 384.24307 -279.535561) (xy 384.281191 -279.504436) (xy 384.323812 -279.479829)
			(xy 384.369828 -279.462377) (xy 384.418047 -279.452533) (xy 384.467222 -279.450552) (xy 384.516077 -279.456484)
			(xy 384.563348 -279.470176) (xy 384.60781 -279.491274) (xy 384.648313 -279.51923) (xy 384.683806 -279.553322)
			(xy 384.713371 -279.592666) (xy 384.736242 -279.636243) (xy 384.751826 -279.682924) (xy 384.759721 -279.731501)
			(xy 384.760216 -279.756108) (xy 385.088904 -279.756108) (xy 385.092864 -279.707054) (xy 385.104641 -279.65927)
			(xy 385.123932 -279.613994) (xy 385.150235 -279.572398) (xy 385.18287 -279.535561) (xy 385.220991 -279.504436)
			(xy 385.263612 -279.479829) (xy 385.309628 -279.462377) (xy 385.357847 -279.452533) (xy 385.407022 -279.450552)
			(xy 385.455877 -279.456484) (xy 385.503148 -279.470176) (xy 385.54761 -279.491274) (xy 385.588113 -279.51923)
			(xy 385.623606 -279.553322) (xy 385.653171 -279.592666) (xy 385.676042 -279.636243) (xy 385.691626 -279.682924)
			(xy 385.699521 -279.731501) (xy 385.700016 -279.756108) (xy 386.028958 -279.756108) (xy 386.032918 -279.707054)
			(xy 386.044695 -279.65927) (xy 386.063986 -279.613994) (xy 386.090289 -279.572398) (xy 386.122924 -279.535561)
			(xy 386.161045 -279.504436) (xy 386.203666 -279.479829) (xy 386.249682 -279.462377) (xy 386.297901 -279.452533)
			(xy 386.347076 -279.450552) (xy 386.395931 -279.456484) (xy 386.443202 -279.470176) (xy 386.487664 -279.491274)
			(xy 386.528167 -279.51923) (xy 386.56366 -279.553322) (xy 386.593225 -279.592666) (xy 386.616096 -279.636243)
			(xy 386.63168 -279.682924) (xy 386.639575 -279.731501) (xy 386.64007 -279.756108) (xy 386.969012 -279.756108)
			(xy 386.972972 -279.707054) (xy 386.984749 -279.65927) (xy 387.00404 -279.613994) (xy 387.030343 -279.572398)
			(xy 387.062978 -279.535561) (xy 387.101099 -279.504436) (xy 387.14372 -279.479829) (xy 387.189736 -279.462377)
			(xy 387.237955 -279.452533) (xy 387.28713 -279.450552) (xy 387.335985 -279.456484) (xy 387.383256 -279.470176)
			(xy 387.427718 -279.491274) (xy 387.468221 -279.51923) (xy 387.503714 -279.553322) (xy 387.533279 -279.592666)
			(xy 387.55615 -279.636243) (xy 387.571734 -279.682924) (xy 387.579629 -279.731501) (xy 387.580124 -279.756108)
			(xy 387.579629 -279.780715) (xy 387.571734 -279.829292) (xy 387.55615 -279.875973) (xy 387.533279 -279.91955)
			(xy 387.503714 -279.958894) (xy 387.468221 -279.992986) (xy 387.427718 -280.020942) (xy 387.383256 -280.04204)
			(xy 387.335985 -280.055732) (xy 387.28713 -280.061664) (xy 387.237955 -280.059683) (xy 387.189736 -280.049839)
			(xy 387.14372 -280.032387) (xy 387.101099 -280.00778) (xy 387.062978 -279.976655) (xy 387.030343 -279.939818)
			(xy 387.00404 -279.898222) (xy 386.984749 -279.852946) (xy 386.972972 -279.805162) (xy 386.969012 -279.756108)
			(xy 386.64007 -279.756108) (xy 386.639575 -279.780715) (xy 386.63168 -279.829292) (xy 386.616096 -279.875973)
			(xy 386.593225 -279.91955) (xy 386.56366 -279.958894) (xy 386.528167 -279.992986) (xy 386.487664 -280.020942)
			(xy 386.443202 -280.04204) (xy 386.395931 -280.055732) (xy 386.347076 -280.061664) (xy 386.297901 -280.059683)
			(xy 386.249682 -280.049839) (xy 386.203666 -280.032387) (xy 386.161045 -280.00778) (xy 386.122924 -279.976655)
			(xy 386.090289 -279.939818) (xy 386.063986 -279.898222) (xy 386.044695 -279.852946) (xy 386.032918 -279.805162)
			(xy 386.028958 -279.756108) (xy 385.700016 -279.756108) (xy 385.699521 -279.780715) (xy 385.691626 -279.829292)
			(xy 385.676042 -279.875973) (xy 385.653171 -279.91955) (xy 385.623606 -279.958894) (xy 385.588113 -279.992986)
			(xy 385.54761 -280.020942) (xy 385.503148 -280.04204) (xy 385.455877 -280.055732) (xy 385.407022 -280.061664)
			(xy 385.357847 -280.059683) (xy 385.309628 -280.049839) (xy 385.263612 -280.032387) (xy 385.220991 -280.00778)
			(xy 385.18287 -279.976655) (xy 385.150235 -279.939818) (xy 385.123932 -279.898222) (xy 385.104641 -279.852946)
			(xy 385.092864 -279.805162) (xy 385.088904 -279.756108) (xy 384.760216 -279.756108) (xy 384.759721 -279.780715)
			(xy 384.751826 -279.829292) (xy 384.736242 -279.875973) (xy 384.713371 -279.91955) (xy 384.683806 -279.958894)
			(xy 384.648313 -279.992986) (xy 384.60781 -280.020942) (xy 384.563348 -280.04204) (xy 384.516077 -280.055732)
			(xy 384.467222 -280.061664) (xy 384.418047 -280.059683) (xy 384.369828 -280.049839) (xy 384.323812 -280.032387)
			(xy 384.281191 -280.00778) (xy 384.24307 -279.976655) (xy 384.210435 -279.939818) (xy 384.184132 -279.898222)
			(xy 384.164841 -279.852946) (xy 384.153064 -279.805162) (xy 384.149104 -279.756108) (xy 383.820162 -279.756108)
			(xy 383.819667 -279.780715) (xy 383.811772 -279.829292) (xy 383.796188 -279.875973) (xy 383.773317 -279.91955)
			(xy 383.743752 -279.958894) (xy 383.708259 -279.992986) (xy 383.667756 -280.020942) (xy 383.623294 -280.04204)
			(xy 383.576023 -280.055732) (xy 383.527168 -280.061664) (xy 383.477993 -280.059683) (xy 383.429774 -280.049839)
			(xy 383.383758 -280.032387) (xy 383.341137 -280.00778) (xy 383.303016 -279.976655) (xy 383.270381 -279.939818)
			(xy 383.244078 -279.898222) (xy 383.224787 -279.852946) (xy 383.21301 -279.805162) (xy 383.20905 -279.756108)
			(xy 382.880108 -279.756108) (xy 382.879613 -279.780715) (xy 382.871718 -279.829292) (xy 382.856134 -279.875973)
			(xy 382.833263 -279.91955) (xy 382.803698 -279.958894) (xy 382.768205 -279.992986) (xy 382.727702 -280.020942)
			(xy 382.68324 -280.04204) (xy 382.635969 -280.055732) (xy 382.587114 -280.061664) (xy 382.537939 -280.059683)
			(xy 382.48972 -280.049839) (xy 382.443704 -280.032387) (xy 382.401083 -280.00778) (xy 382.362962 -279.976655)
			(xy 382.330327 -279.939818) (xy 382.304024 -279.898222) (xy 382.284733 -279.852946) (xy 382.272956 -279.805162)
			(xy 382.268996 -279.756108) (xy 381.940054 -279.756108) (xy 381.939559 -279.780715) (xy 381.931664 -279.829292)
			(xy 381.91608 -279.875973) (xy 381.893209 -279.91955) (xy 381.863644 -279.958894) (xy 381.828151 -279.992986)
			(xy 381.787648 -280.020942) (xy 381.743186 -280.04204) (xy 381.695915 -280.055732) (xy 381.64706 -280.061664)
			(xy 381.597885 -280.059683) (xy 381.549666 -280.049839) (xy 381.50365 -280.032387) (xy 381.461029 -280.00778)
			(xy 381.422908 -279.976655) (xy 381.390273 -279.939818) (xy 381.36397 -279.898222) (xy 381.344679 -279.852946)
			(xy 381.332902 -279.805162) (xy 381.328942 -279.756108) (xy 381.010668 -279.756108) (xy 381.010156 -279.781554)
			(xy 381.001992 -279.831788) (xy 380.985876 -279.880062) (xy 380.962225 -279.925125) (xy 380.931652 -279.965811)
			(xy 380.894948 -280.001066) (xy 380.853064 -280.029976) (xy 380.807085 -280.051793) (xy 380.758201 -280.065953)
			(xy 380.70768 -280.072087) (xy 380.656828 -280.070038) (xy 380.606964 -280.059858) (xy 380.559378 -280.041811)
			(xy 380.515304 -280.016365) (xy 380.475882 -279.984178) (xy 380.442134 -279.946084) (xy 380.414933 -279.90307)
			(xy 380.394985 -279.85625) (xy 380.382806 -279.806836) (xy 380.378711 -279.756108) (xy 380.070614 -279.756108)
			(xy 380.070102 -279.781554) (xy 380.061938 -279.831788) (xy 380.045822 -279.880062) (xy 380.022171 -279.925125)
			(xy 379.991598 -279.965811) (xy 379.954894 -280.001066) (xy 379.91301 -280.029976) (xy 379.867031 -280.051793)
			(xy 379.818147 -280.065953) (xy 379.767626 -280.072087) (xy 379.716774 -280.070038) (xy 379.66691 -280.059858)
			(xy 379.619324 -280.041811) (xy 379.57525 -280.016365) (xy 379.535828 -279.984178) (xy 379.50208 -279.946084)
			(xy 379.474879 -279.90307) (xy 379.454931 -279.85625) (xy 379.442752 -279.806836) (xy 379.438657 -279.756108)
			(xy 379.120146 -279.756108) (xy 379.119651 -279.780715) (xy 379.111756 -279.829292) (xy 379.096172 -279.875973)
			(xy 379.073301 -279.91955) (xy 379.043736 -279.958894) (xy 379.008243 -279.992986) (xy 378.96774 -280.020942)
			(xy 378.923278 -280.04204) (xy 378.876007 -280.055732) (xy 378.827152 -280.061664) (xy 378.777977 -280.059683)
			(xy 378.729758 -280.049839) (xy 378.683742 -280.032387) (xy 378.641121 -280.00778) (xy 378.603 -279.976655)
			(xy 378.570365 -279.939818) (xy 378.544062 -279.898222) (xy 378.524771 -279.852946) (xy 378.512994 -279.805162)
			(xy 378.509034 -279.756108) (xy 378.190506 -279.756108) (xy 378.189994 -279.781554) (xy 378.18183 -279.831788)
			(xy 378.165714 -279.880062) (xy 378.142063 -279.925125) (xy 378.11149 -279.965811) (xy 378.074786 -280.001066)
			(xy 378.032902 -280.029976) (xy 377.986923 -280.051793) (xy 377.938039 -280.065953) (xy 377.887518 -280.072087)
			(xy 377.836666 -280.070038) (xy 377.786802 -280.059858) (xy 377.739216 -280.041811) (xy 377.695142 -280.016365)
			(xy 377.65572 -279.984178) (xy 377.621972 -279.946084) (xy 377.594771 -279.90307) (xy 377.574823 -279.85625)
			(xy 377.562644 -279.806836) (xy 377.558549 -279.756108) (xy 377.240038 -279.756108) (xy 377.239543 -279.780715)
			(xy 377.231648 -279.829292) (xy 377.216064 -279.875973) (xy 377.193193 -279.91955) (xy 377.163628 -279.958894)
			(xy 377.128135 -279.992986) (xy 377.087632 -280.020942) (xy 377.04317 -280.04204) (xy 376.995899 -280.055732)
			(xy 376.947044 -280.061664) (xy 376.897869 -280.059683) (xy 376.84965 -280.049839) (xy 376.803634 -280.032387)
			(xy 376.761013 -280.00778) (xy 376.722892 -279.976655) (xy 376.690257 -279.939818) (xy 376.663954 -279.898222)
			(xy 376.644663 -279.852946) (xy 376.632886 -279.805162) (xy 376.628926 -279.756108) (xy 376.310652 -279.756108)
			(xy 376.31014 -279.781554) (xy 376.301976 -279.831788) (xy 376.28586 -279.880062) (xy 376.262209 -279.925125)
			(xy 376.231636 -279.965811) (xy 376.194932 -280.001066) (xy 376.153048 -280.029976) (xy 376.107069 -280.051793)
			(xy 376.058185 -280.065953) (xy 376.007664 -280.072087) (xy 375.956812 -280.070038) (xy 375.906948 -280.059858)
			(xy 375.859362 -280.041811) (xy 375.815288 -280.016365) (xy 375.775866 -279.984178) (xy 375.742118 -279.946084)
			(xy 375.714917 -279.90307) (xy 375.694969 -279.85625) (xy 375.68279 -279.806836) (xy 375.678695 -279.756108)
			(xy 375.386173 -279.756108) (xy 375.381877 -279.809277) (xy 375.369102 -279.861071) (xy 375.34818 -279.910142)
			(xy 375.319652 -279.955219) (xy 375.284259 -279.995132) (xy 375.263918 -280.012394) (xy 375.25706 -280.019252)
			(xy 375.251472 -280.02738) (xy 375.240296 -280.05024) (xy 375.238293 -280.05508) (xy 375.236114 -280.065324)
			(xy 375.235978 -280.07056) (xy 375.235978 -280.207466) (xy 375.236377 -280.216019) (xy 375.242174 -280.232119)
			(xy 375.252987 -280.245382) (xy 375.260108 -280.250138) (xy 375.315734 -280.283666) (xy 375.336054 -280.295858)
			(xy 375.34124 -280.298386) (xy 375.352394 -280.301325) (xy 375.358152 -280.3017) (xy 375.370852 -280.301954)
			(xy 375.382536 -280.295858) (xy 375.404529 -280.28486) (xy 375.451158 -280.269256) (xy 375.499684 -280.261318)
			(xy 375.524268 -280.260806) (xy 375.530364 -280.260806) (xy 375.555317 -280.261758) (xy 375.604427 -280.270779)
			(xy 375.651416 -280.28767) (xy 375.69503 -280.31198) (xy 375.734107 -280.343063) (xy 375.767607 -280.38009)
			(xy 375.794636 -280.422074) (xy 375.814474 -280.467896) (xy 375.826592 -280.516335) (xy 375.830668 -280.5661)
			(xy 375.830667 -280.566114) (xy 376.148595 -280.566114) (xy 376.15269 -280.515386) (xy 376.164869 -280.465972)
			(xy 376.184817 -280.419152) (xy 376.212018 -280.376138) (xy 376.245766 -280.338044) (xy 376.285188 -280.305857)
			(xy 376.329262 -280.280411) (xy 376.376848 -280.262364) (xy 376.426712 -280.252184) (xy 376.477564 -280.250135)
			(xy 376.528085 -280.256269) (xy 376.576969 -280.270429) (xy 376.622948 -280.292246) (xy 376.664832 -280.321156)
			(xy 376.701536 -280.356411) (xy 376.732109 -280.397097) (xy 376.75576 -280.44216) (xy 376.771876 -280.490434)
			(xy 376.78004 -280.540668) (xy 376.780552 -280.566114) (xy 377.088649 -280.566114) (xy 377.092744 -280.515386)
			(xy 377.104923 -280.465972) (xy 377.124871 -280.419152) (xy 377.152072 -280.376138) (xy 377.18582 -280.338044)
			(xy 377.225242 -280.305857) (xy 377.269316 -280.280411) (xy 377.316902 -280.262364) (xy 377.366766 -280.252184)
			(xy 377.417618 -280.250135) (xy 377.468139 -280.256269) (xy 377.517023 -280.270429) (xy 377.563002 -280.292246)
			(xy 377.604886 -280.321156) (xy 377.64159 -280.356411) (xy 377.672163 -280.397097) (xy 377.695814 -280.44216)
			(xy 377.71193 -280.490434) (xy 377.720094 -280.540668) (xy 377.720606 -280.566114) (xy 378.968503 -280.566114)
			(xy 378.972598 -280.515386) (xy 378.984777 -280.465972) (xy 379.004725 -280.419152) (xy 379.031926 -280.376138)
			(xy 379.065674 -280.338044) (xy 379.105096 -280.305857) (xy 379.14917 -280.280411) (xy 379.196756 -280.262364)
			(xy 379.24662 -280.252184) (xy 379.297472 -280.250135) (xy 379.347993 -280.256269) (xy 379.396877 -280.270429)
			(xy 379.442856 -280.292246) (xy 379.48474 -280.321156) (xy 379.521444 -280.356411) (xy 379.552017 -280.397097)
			(xy 379.575668 -280.44216) (xy 379.591784 -280.490434) (xy 379.599948 -280.540668) (xy 379.60046 -280.566114)
			(xy 379.918988 -280.566114) (xy 379.922948 -280.51706) (xy 379.934725 -280.469276) (xy 379.954016 -280.424)
			(xy 379.980319 -280.382404) (xy 380.012954 -280.345567) (xy 380.051075 -280.314442) (xy 380.093696 -280.289835)
			(xy 380.139712 -280.272383) (xy 380.187931 -280.262539) (xy 380.237106 -280.260558) (xy 380.285961 -280.26649)
			(xy 380.333232 -280.280182) (xy 380.377694 -280.30128) (xy 380.418197 -280.329236) (xy 380.45369 -280.363328)
			(xy 380.483255 -280.402672) (xy 380.506126 -280.446249) (xy 380.52171 -280.49293) (xy 380.529605 -280.541507)
			(xy 380.5301 -280.566114) (xy 380.848611 -280.566114) (xy 380.852706 -280.515386) (xy 380.864885 -280.465972)
			(xy 380.884833 -280.419152) (xy 380.912034 -280.376138) (xy 380.945782 -280.338044) (xy 380.985204 -280.305857)
			(xy 381.029278 -280.280411) (xy 381.076864 -280.262364) (xy 381.126728 -280.252184) (xy 381.17758 -280.250135)
			(xy 381.228101 -280.256269) (xy 381.276985 -280.270429) (xy 381.322964 -280.292246) (xy 381.364848 -280.321156)
			(xy 381.401552 -280.356411) (xy 381.432125 -280.397097) (xy 381.455776 -280.44216) (xy 381.471892 -280.490434)
			(xy 381.480056 -280.540668) (xy 381.480568 -280.566114) (xy 381.799096 -280.566114) (xy 381.803056 -280.51706)
			(xy 381.814833 -280.469276) (xy 381.834124 -280.424) (xy 381.860427 -280.382404) (xy 381.893062 -280.345567)
			(xy 381.931183 -280.314442) (xy 381.973804 -280.289835) (xy 382.01982 -280.272383) (xy 382.068039 -280.262539)
			(xy 382.117214 -280.260558) (xy 382.166069 -280.26649) (xy 382.21334 -280.280182) (xy 382.257802 -280.30128)
			(xy 382.298305 -280.329236) (xy 382.333798 -280.363328) (xy 382.363363 -280.402672) (xy 382.386234 -280.446249)
			(xy 382.401818 -280.49293) (xy 382.409713 -280.541507) (xy 382.410208 -280.566114) (xy 382.738896 -280.566114)
			(xy 382.742856 -280.51706) (xy 382.754633 -280.469276) (xy 382.773924 -280.424) (xy 382.800227 -280.382404)
			(xy 382.832862 -280.345567) (xy 382.870983 -280.314442) (xy 382.913604 -280.289835) (xy 382.95962 -280.272383)
			(xy 383.007839 -280.262539) (xy 383.057014 -280.260558) (xy 383.105869 -280.26649) (xy 383.15314 -280.280182)
			(xy 383.197602 -280.30128) (xy 383.238105 -280.329236) (xy 383.273598 -280.363328) (xy 383.303163 -280.402672)
			(xy 383.326034 -280.446249) (xy 383.341618 -280.49293) (xy 383.349513 -280.541507) (xy 383.350008 -280.566114)
			(xy 383.67895 -280.566114) (xy 383.68291 -280.51706) (xy 383.694687 -280.469276) (xy 383.713978 -280.424)
			(xy 383.740281 -280.382404) (xy 383.772916 -280.345567) (xy 383.811037 -280.314442) (xy 383.853658 -280.289835)
			(xy 383.899674 -280.272383) (xy 383.947893 -280.262539) (xy 383.997068 -280.260558) (xy 384.045923 -280.26649)
			(xy 384.093194 -280.280182) (xy 384.137656 -280.30128) (xy 384.178159 -280.329236) (xy 384.213652 -280.363328)
			(xy 384.243217 -280.402672) (xy 384.266088 -280.446249) (xy 384.281672 -280.49293) (xy 384.289567 -280.541507)
			(xy 384.290062 -280.566114) (xy 385.559058 -280.566114) (xy 385.563018 -280.51706) (xy 385.574795 -280.469276)
			(xy 385.594086 -280.424) (xy 385.620389 -280.382404) (xy 385.653024 -280.345567) (xy 385.691145 -280.314442)
			(xy 385.733766 -280.289835) (xy 385.779782 -280.272383) (xy 385.828001 -280.262539) (xy 385.877176 -280.260558)
			(xy 385.926031 -280.26649) (xy 385.973302 -280.280182) (xy 386.017764 -280.30128) (xy 386.058267 -280.329236)
			(xy 386.09376 -280.363328) (xy 386.123325 -280.402672) (xy 386.146196 -280.446249) (xy 386.16178 -280.49293)
			(xy 386.169675 -280.541507) (xy 386.17017 -280.566114) (xy 386.499112 -280.566114) (xy 386.503072 -280.51706)
			(xy 386.514849 -280.469276) (xy 386.53414 -280.424) (xy 386.560443 -280.382404) (xy 386.593078 -280.345567)
			(xy 386.631199 -280.314442) (xy 386.67382 -280.289835) (xy 386.719836 -280.272383) (xy 386.768055 -280.262539)
			(xy 386.81723 -280.260558) (xy 386.866085 -280.26649) (xy 386.913356 -280.280182) (xy 386.957818 -280.30128)
			(xy 386.998321 -280.329236) (xy 387.033814 -280.363328) (xy 387.063379 -280.402672) (xy 387.08625 -280.446249)
			(xy 387.101834 -280.49293) (xy 387.109729 -280.541507) (xy 387.110224 -280.566114) (xy 387.438912 -280.566114)
			(xy 387.442872 -280.51706) (xy 387.454649 -280.469276) (xy 387.47394 -280.424) (xy 387.500243 -280.382404)
			(xy 387.532878 -280.345567) (xy 387.570999 -280.314442) (xy 387.61362 -280.289835) (xy 387.659636 -280.272383)
			(xy 387.707855 -280.262539) (xy 387.75703 -280.260558) (xy 387.805885 -280.26649) (xy 387.853156 -280.280182)
			(xy 387.897618 -280.30128) (xy 387.938121 -280.329236) (xy 387.973614 -280.363328) (xy 388.003179 -280.402672)
			(xy 388.02605 -280.446249) (xy 388.041634 -280.49293) (xy 388.049529 -280.541507) (xy 388.050024 -280.566114)
			(xy 388.049529 -280.590721) (xy 388.041634 -280.639298) (xy 388.02605 -280.685979) (xy 388.003179 -280.729556)
			(xy 387.973614 -280.7689) (xy 387.938121 -280.802992) (xy 387.897618 -280.830948) (xy 387.853156 -280.852046)
			(xy 387.805885 -280.865738) (xy 387.75703 -280.87167) (xy 387.707855 -280.869689) (xy 387.659636 -280.859845)
			(xy 387.61362 -280.842393) (xy 387.570999 -280.817786) (xy 387.532878 -280.786661) (xy 387.500243 -280.749824)
			(xy 387.47394 -280.708228) (xy 387.454649 -280.662952) (xy 387.442872 -280.615168) (xy 387.438912 -280.566114)
			(xy 387.110224 -280.566114) (xy 387.109729 -280.590721) (xy 387.101834 -280.639298) (xy 387.08625 -280.685979)
			(xy 387.063379 -280.729556) (xy 387.033814 -280.7689) (xy 386.998321 -280.802992) (xy 386.957818 -280.830948)
			(xy 386.913356 -280.852046) (xy 386.866085 -280.865738) (xy 386.81723 -280.87167) (xy 386.768055 -280.869689)
			(xy 386.719836 -280.859845) (xy 386.67382 -280.842393) (xy 386.631199 -280.817786) (xy 386.593078 -280.786661)
			(xy 386.560443 -280.749824) (xy 386.53414 -280.708228) (xy 386.514849 -280.662952) (xy 386.503072 -280.615168)
			(xy 386.499112 -280.566114) (xy 386.17017 -280.566114) (xy 386.169675 -280.590721) (xy 386.16178 -280.639298)
			(xy 386.146196 -280.685979) (xy 386.123325 -280.729556) (xy 386.09376 -280.7689) (xy 386.058267 -280.802992)
			(xy 386.017764 -280.830948) (xy 385.973302 -280.852046) (xy 385.926031 -280.865738) (xy 385.877176 -280.87167)
			(xy 385.828001 -280.869689) (xy 385.779782 -280.859845) (xy 385.733766 -280.842393) (xy 385.691145 -280.817786)
			(xy 385.653024 -280.786661) (xy 385.620389 -280.749824) (xy 385.594086 -280.708228) (xy 385.574795 -280.662952)
			(xy 385.563018 -280.615168) (xy 385.559058 -280.566114) (xy 384.290062 -280.566114) (xy 384.289567 -280.590721)
			(xy 384.281672 -280.639298) (xy 384.266088 -280.685979) (xy 384.243217 -280.729556) (xy 384.213652 -280.7689)
			(xy 384.178159 -280.802992) (xy 384.137656 -280.830948) (xy 384.093194 -280.852046) (xy 384.045923 -280.865738)
			(xy 383.997068 -280.87167) (xy 383.947893 -280.869689) (xy 383.899674 -280.859845) (xy 383.853658 -280.842393)
			(xy 383.811037 -280.817786) (xy 383.772916 -280.786661) (xy 383.740281 -280.749824) (xy 383.713978 -280.708228)
			(xy 383.694687 -280.662952) (xy 383.68291 -280.615168) (xy 383.67895 -280.566114) (xy 383.350008 -280.566114)
			(xy 383.349513 -280.590721) (xy 383.341618 -280.639298) (xy 383.326034 -280.685979) (xy 383.303163 -280.729556)
			(xy 383.273598 -280.7689) (xy 383.238105 -280.802992) (xy 383.197602 -280.830948) (xy 383.15314 -280.852046)
			(xy 383.105869 -280.865738) (xy 383.057014 -280.87167) (xy 383.007839 -280.869689) (xy 382.95962 -280.859845)
			(xy 382.913604 -280.842393) (xy 382.870983 -280.817786) (xy 382.832862 -280.786661) (xy 382.800227 -280.749824)
			(xy 382.773924 -280.708228) (xy 382.754633 -280.662952) (xy 382.742856 -280.615168) (xy 382.738896 -280.566114)
			(xy 382.410208 -280.566114) (xy 382.409713 -280.590721) (xy 382.401818 -280.639298) (xy 382.386234 -280.685979)
			(xy 382.363363 -280.729556) (xy 382.333798 -280.7689) (xy 382.298305 -280.802992) (xy 382.257802 -280.830948)
			(xy 382.21334 -280.852046) (xy 382.166069 -280.865738) (xy 382.117214 -280.87167) (xy 382.068039 -280.869689)
			(xy 382.01982 -280.859845) (xy 381.973804 -280.842393) (xy 381.931183 -280.817786) (xy 381.893062 -280.786661)
			(xy 381.860427 -280.749824) (xy 381.834124 -280.708228) (xy 381.814833 -280.662952) (xy 381.803056 -280.615168)
			(xy 381.799096 -280.566114) (xy 381.480568 -280.566114) (xy 381.480056 -280.59156) (xy 381.471892 -280.641794)
			(xy 381.455776 -280.690068) (xy 381.432125 -280.735131) (xy 381.401552 -280.775817) (xy 381.364848 -280.811072)
			(xy 381.322964 -280.839982) (xy 381.276985 -280.861799) (xy 381.228101 -280.875959) (xy 381.17758 -280.882093)
			(xy 381.126728 -280.880044) (xy 381.076864 -280.869864) (xy 381.029278 -280.851817) (xy 380.985204 -280.826371)
			(xy 380.945782 -280.794184) (xy 380.912034 -280.75609) (xy 380.884833 -280.713076) (xy 380.864885 -280.666256)
			(xy 380.852706 -280.616842) (xy 380.848611 -280.566114) (xy 380.5301 -280.566114) (xy 380.529605 -280.590721)
			(xy 380.52171 -280.639298) (xy 380.506126 -280.685979) (xy 380.483255 -280.729556) (xy 380.45369 -280.7689)
			(xy 380.418197 -280.802992) (xy 380.377694 -280.830948) (xy 380.333232 -280.852046) (xy 380.285961 -280.865738)
			(xy 380.237106 -280.87167) (xy 380.187931 -280.869689) (xy 380.139712 -280.859845) (xy 380.093696 -280.842393)
			(xy 380.051075 -280.817786) (xy 380.012954 -280.786661) (xy 379.980319 -280.749824) (xy 379.954016 -280.708228)
			(xy 379.934725 -280.662952) (xy 379.922948 -280.615168) (xy 379.918988 -280.566114) (xy 379.60046 -280.566114)
			(xy 379.599948 -280.59156) (xy 379.591784 -280.641794) (xy 379.575668 -280.690068) (xy 379.552017 -280.735131)
			(xy 379.521444 -280.775817) (xy 379.48474 -280.811072) (xy 379.442856 -280.839982) (xy 379.396877 -280.861799)
			(xy 379.347993 -280.875959) (xy 379.297472 -280.882093) (xy 379.24662 -280.880044) (xy 379.196756 -280.869864)
			(xy 379.14917 -280.851817) (xy 379.105096 -280.826371) (xy 379.065674 -280.794184) (xy 379.031926 -280.75609)
			(xy 379.004725 -280.713076) (xy 378.984777 -280.666256) (xy 378.972598 -280.616842) (xy 378.968503 -280.566114)
			(xy 377.720606 -280.566114) (xy 377.720094 -280.59156) (xy 377.71193 -280.641794) (xy 377.695814 -280.690068)
			(xy 377.672163 -280.735131) (xy 377.64159 -280.775817) (xy 377.604886 -280.811072) (xy 377.563002 -280.839982)
			(xy 377.517023 -280.861799) (xy 377.468139 -280.875959) (xy 377.417618 -280.882093) (xy 377.366766 -280.880044)
			(xy 377.316902 -280.869864) (xy 377.269316 -280.851817) (xy 377.225242 -280.826371) (xy 377.18582 -280.794184)
			(xy 377.152072 -280.75609) (xy 377.124871 -280.713076) (xy 377.104923 -280.666256) (xy 377.092744 -280.616842)
			(xy 377.088649 -280.566114) (xy 376.780552 -280.566114) (xy 376.78004 -280.59156) (xy 376.771876 -280.641794)
			(xy 376.75576 -280.690068) (xy 376.732109 -280.735131) (xy 376.701536 -280.775817) (xy 376.664832 -280.811072)
			(xy 376.622948 -280.839982) (xy 376.576969 -280.861799) (xy 376.528085 -280.875959) (xy 376.477564 -280.882093)
			(xy 376.426712 -280.880044) (xy 376.376848 -280.869864) (xy 376.329262 -280.851817) (xy 376.285188 -280.826371)
			(xy 376.245766 -280.794184) (xy 376.212018 -280.75609) (xy 376.184817 -280.713076) (xy 376.164869 -280.666256)
			(xy 376.15269 -280.616842) (xy 376.148595 -280.566114) (xy 375.830667 -280.566114) (xy 375.826592 -280.615866)
			(xy 375.814474 -280.664305) (xy 375.794636 -280.710127) (xy 375.767607 -280.752111) (xy 375.734107 -280.789137)
			(xy 375.695029 -280.82022) (xy 375.651415 -280.844531) (xy 375.604427 -280.861421) (xy 375.555316 -280.870442)
			(xy 375.530364 -280.871422) (xy 375.524268 -280.871422) (xy 375.499681 -280.870935) (xy 375.451149 -280.863006)
			(xy 375.404519 -280.847393) (xy 375.382536 -280.83637) (xy 375.376694 -280.833322) (xy 375.364248 -280.830528)
			(xy 375.358152 -280.830528) (xy 375.352388 -280.830857) (xy 375.341231 -280.833813) (xy 375.336054 -280.83637)
			(xy 375.315734 -280.848562) (xy 375.260108 -280.88209) (xy 375.252947 -280.886804) (xy 375.242092 -280.900059)
			(xy 375.236339 -280.916196) (xy 375.235978 -280.924762) (xy 375.235978 -281.09545) (xy 375.236994 -281.10561)
			(xy 375.24055 -281.116532) (xy 375.25325 -281.143964) (xy 375.260616 -281.150568) (xy 375.279038 -281.168054)
			(xy 375.31038 -281.20802) (xy 375.334675 -281.252622) (xy 375.351253 -281.300629) (xy 375.359657 -281.350719)
			(xy 375.359656 -281.37612) (xy 375.678695 -281.37612) (xy 375.68279 -281.325392) (xy 375.694969 -281.275978)
			(xy 375.714917 -281.229158) (xy 375.742118 -281.186144) (xy 375.775866 -281.14805) (xy 375.815288 -281.115863)
			(xy 375.859362 -281.090417) (xy 375.906948 -281.07237) (xy 375.956812 -281.06219) (xy 376.007664 -281.060141)
			(xy 376.058185 -281.066275) (xy 376.107069 -281.080435) (xy 376.153048 -281.102252) (xy 376.194932 -281.131162)
			(xy 376.231636 -281.166417) (xy 376.262209 -281.207103) (xy 376.28586 -281.252166) (xy 376.301976 -281.30044)
			(xy 376.31014 -281.350674) (xy 376.310652 -281.37612) (xy 376.628926 -281.37612) (xy 376.632886 -281.327066)
			(xy 376.644663 -281.279282) (xy 376.663954 -281.234006) (xy 376.690257 -281.19241) (xy 376.722892 -281.155573)
			(xy 376.761013 -281.124448) (xy 376.803634 -281.099841) (xy 376.84965 -281.082389) (xy 376.897869 -281.072545)
			(xy 376.947044 -281.070564) (xy 376.995899 -281.076496) (xy 377.04317 -281.090188) (xy 377.087632 -281.111286)
			(xy 377.128135 -281.139242) (xy 377.163628 -281.173334) (xy 377.193193 -281.212678) (xy 377.216064 -281.256255)
			(xy 377.231648 -281.302936) (xy 377.239543 -281.351513) (xy 377.240038 -281.37612) (xy 377.558549 -281.37612)
			(xy 377.562644 -281.325392) (xy 377.574823 -281.275978) (xy 377.594771 -281.229158) (xy 377.621972 -281.186144)
			(xy 377.65572 -281.14805) (xy 377.695142 -281.115863) (xy 377.739216 -281.090417) (xy 377.786802 -281.07237)
			(xy 377.836666 -281.06219) (xy 377.887518 -281.060141) (xy 377.938039 -281.066275) (xy 377.986923 -281.080435)
			(xy 378.032902 -281.102252) (xy 378.074786 -281.131162) (xy 378.11149 -281.166417) (xy 378.142063 -281.207103)
			(xy 378.165714 -281.252166) (xy 378.18183 -281.30044) (xy 378.189994 -281.350674) (xy 378.190506 -281.37612)
			(xy 378.509034 -281.37612) (xy 378.512994 -281.327066) (xy 378.524771 -281.279282) (xy 378.544062 -281.234006)
			(xy 378.570365 -281.19241) (xy 378.603 -281.155573) (xy 378.641121 -281.124448) (xy 378.683742 -281.099841)
			(xy 378.729758 -281.082389) (xy 378.777977 -281.072545) (xy 378.827152 -281.070564) (xy 378.876007 -281.076496)
			(xy 378.923278 -281.090188) (xy 378.96774 -281.111286) (xy 379.008243 -281.139242) (xy 379.043736 -281.173334)
			(xy 379.073301 -281.212678) (xy 379.096172 -281.256255) (xy 379.111756 -281.302936) (xy 379.119651 -281.351513)
			(xy 379.120146 -281.37612) (xy 379.438657 -281.37612) (xy 379.442752 -281.325392) (xy 379.454931 -281.275978)
			(xy 379.474879 -281.229158) (xy 379.50208 -281.186144) (xy 379.535828 -281.14805) (xy 379.57525 -281.115863)
			(xy 379.619324 -281.090417) (xy 379.66691 -281.07237) (xy 379.716774 -281.06219) (xy 379.767626 -281.060141)
			(xy 379.818147 -281.066275) (xy 379.867031 -281.080435) (xy 379.91301 -281.102252) (xy 379.954894 -281.131162)
			(xy 379.991598 -281.166417) (xy 380.022171 -281.207103) (xy 380.045822 -281.252166) (xy 380.061938 -281.30044)
			(xy 380.070102 -281.350674) (xy 380.070614 -281.37612) (xy 380.378711 -281.37612) (xy 380.382806 -281.325392)
			(xy 380.394985 -281.275978) (xy 380.414933 -281.229158) (xy 380.442134 -281.186144) (xy 380.475882 -281.14805)
			(xy 380.515304 -281.115863) (xy 380.559378 -281.090417) (xy 380.606964 -281.07237) (xy 380.656828 -281.06219)
			(xy 380.70768 -281.060141) (xy 380.758201 -281.066275) (xy 380.807085 -281.080435) (xy 380.853064 -281.102252)
			(xy 380.894948 -281.131162) (xy 380.931652 -281.166417) (xy 380.962225 -281.207103) (xy 380.985876 -281.252166)
			(xy 381.001992 -281.30044) (xy 381.010156 -281.350674) (xy 381.010668 -281.37612) (xy 381.328942 -281.37612)
			(xy 381.332902 -281.327066) (xy 381.344679 -281.279282) (xy 381.36397 -281.234006) (xy 381.390273 -281.19241)
			(xy 381.422908 -281.155573) (xy 381.461029 -281.124448) (xy 381.50365 -281.099841) (xy 381.549666 -281.082389)
			(xy 381.597885 -281.072545) (xy 381.64706 -281.070564) (xy 381.695915 -281.076496) (xy 381.743186 -281.090188)
			(xy 381.787648 -281.111286) (xy 381.828151 -281.139242) (xy 381.863644 -281.173334) (xy 381.893209 -281.212678)
			(xy 381.91608 -281.256255) (xy 381.931664 -281.302936) (xy 381.939559 -281.351513) (xy 381.940054 -281.37612)
			(xy 382.268996 -281.37612) (xy 382.272956 -281.327066) (xy 382.284733 -281.279282) (xy 382.304024 -281.234006)
			(xy 382.330327 -281.19241) (xy 382.362962 -281.155573) (xy 382.401083 -281.124448) (xy 382.443704 -281.099841)
			(xy 382.48972 -281.082389) (xy 382.537939 -281.072545) (xy 382.587114 -281.070564) (xy 382.635969 -281.076496)
			(xy 382.68324 -281.090188) (xy 382.727702 -281.111286) (xy 382.768205 -281.139242) (xy 382.803698 -281.173334)
			(xy 382.833263 -281.212678) (xy 382.856134 -281.256255) (xy 382.871718 -281.302936) (xy 382.879613 -281.351513)
			(xy 382.880108 -281.37612) (xy 383.20905 -281.37612) (xy 383.21301 -281.327066) (xy 383.224787 -281.279282)
			(xy 383.244078 -281.234006) (xy 383.270381 -281.19241) (xy 383.303016 -281.155573) (xy 383.341137 -281.124448)
			(xy 383.383758 -281.099841) (xy 383.429774 -281.082389) (xy 383.477993 -281.072545) (xy 383.527168 -281.070564)
			(xy 383.576023 -281.076496) (xy 383.623294 -281.090188) (xy 383.667756 -281.111286) (xy 383.708259 -281.139242)
			(xy 383.743752 -281.173334) (xy 383.773317 -281.212678) (xy 383.796188 -281.256255) (xy 383.811772 -281.302936)
			(xy 383.819667 -281.351513) (xy 383.820162 -281.37612) (xy 384.149104 -281.37612) (xy 384.153064 -281.327066)
			(xy 384.164841 -281.279282) (xy 384.184132 -281.234006) (xy 384.210435 -281.19241) (xy 384.24307 -281.155573)
			(xy 384.281191 -281.124448) (xy 384.323812 -281.099841) (xy 384.369828 -281.082389) (xy 384.418047 -281.072545)
			(xy 384.467222 -281.070564) (xy 384.516077 -281.076496) (xy 384.563348 -281.090188) (xy 384.60781 -281.111286)
			(xy 384.648313 -281.139242) (xy 384.683806 -281.173334) (xy 384.713371 -281.212678) (xy 384.736242 -281.256255)
			(xy 384.751826 -281.302936) (xy 384.759721 -281.351513) (xy 384.760216 -281.37612) (xy 385.088904 -281.37612)
			(xy 385.092864 -281.327066) (xy 385.104641 -281.279282) (xy 385.123932 -281.234006) (xy 385.150235 -281.19241)
			(xy 385.18287 -281.155573) (xy 385.220991 -281.124448) (xy 385.263612 -281.099841) (xy 385.309628 -281.082389)
			(xy 385.357847 -281.072545) (xy 385.407022 -281.070564) (xy 385.455877 -281.076496) (xy 385.503148 -281.090188)
			(xy 385.54761 -281.111286) (xy 385.588113 -281.139242) (xy 385.623606 -281.173334) (xy 385.653171 -281.212678)
			(xy 385.676042 -281.256255) (xy 385.691626 -281.302936) (xy 385.699521 -281.351513) (xy 385.700016 -281.37612)
			(xy 386.028958 -281.37612) (xy 386.032918 -281.327066) (xy 386.044695 -281.279282) (xy 386.063986 -281.234006)
			(xy 386.090289 -281.19241) (xy 386.122924 -281.155573) (xy 386.161045 -281.124448) (xy 386.203666 -281.099841)
			(xy 386.249682 -281.082389) (xy 386.297901 -281.072545) (xy 386.347076 -281.070564) (xy 386.395931 -281.076496)
			(xy 386.443202 -281.090188) (xy 386.487664 -281.111286) (xy 386.528167 -281.139242) (xy 386.56366 -281.173334)
			(xy 386.593225 -281.212678) (xy 386.616096 -281.256255) (xy 386.63168 -281.302936) (xy 386.639575 -281.351513)
			(xy 386.64007 -281.37612) (xy 386.969012 -281.37612) (xy 386.972972 -281.327066) (xy 386.984749 -281.279282)
			(xy 387.00404 -281.234006) (xy 387.030343 -281.19241) (xy 387.062978 -281.155573) (xy 387.101099 -281.124448)
			(xy 387.14372 -281.099841) (xy 387.189736 -281.082389) (xy 387.237955 -281.072545) (xy 387.28713 -281.070564)
			(xy 387.335985 -281.076496) (xy 387.383256 -281.090188) (xy 387.427718 -281.111286) (xy 387.468221 -281.139242)
			(xy 387.503714 -281.173334) (xy 387.533279 -281.212678) (xy 387.55615 -281.256255) (xy 387.571734 -281.302936)
			(xy 387.579629 -281.351513) (xy 387.580124 -281.37612) (xy 387.579629 -281.400727) (xy 387.571734 -281.449304)
			(xy 387.55615 -281.495985) (xy 387.533279 -281.539562) (xy 387.503714 -281.578906) (xy 387.468221 -281.612998)
			(xy 387.427718 -281.640954) (xy 387.383256 -281.662052) (xy 387.335985 -281.675744) (xy 387.28713 -281.681676)
			(xy 387.237955 -281.679695) (xy 387.189736 -281.669851) (xy 387.14372 -281.652399) (xy 387.101099 -281.627792)
			(xy 387.062978 -281.596667) (xy 387.030343 -281.55983) (xy 387.00404 -281.518234) (xy 386.984749 -281.472958)
			(xy 386.972972 -281.425174) (xy 386.969012 -281.37612) (xy 386.64007 -281.37612) (xy 386.639575 -281.400727)
			(xy 386.63168 -281.449304) (xy 386.616096 -281.495985) (xy 386.593225 -281.539562) (xy 386.56366 -281.578906)
			(xy 386.528167 -281.612998) (xy 386.487664 -281.640954) (xy 386.443202 -281.662052) (xy 386.395931 -281.675744)
			(xy 386.347076 -281.681676) (xy 386.297901 -281.679695) (xy 386.249682 -281.669851) (xy 386.203666 -281.652399)
			(xy 386.161045 -281.627792) (xy 386.122924 -281.596667) (xy 386.090289 -281.55983) (xy 386.063986 -281.518234)
			(xy 386.044695 -281.472958) (xy 386.032918 -281.425174) (xy 386.028958 -281.37612) (xy 385.700016 -281.37612)
			(xy 385.699521 -281.400727) (xy 385.691626 -281.449304) (xy 385.676042 -281.495985) (xy 385.653171 -281.539562)
			(xy 385.623606 -281.578906) (xy 385.588113 -281.612998) (xy 385.54761 -281.640954) (xy 385.503148 -281.662052)
			(xy 385.455877 -281.675744) (xy 385.407022 -281.681676) (xy 385.357847 -281.679695) (xy 385.309628 -281.669851)
			(xy 385.263612 -281.652399) (xy 385.220991 -281.627792) (xy 385.18287 -281.596667) (xy 385.150235 -281.55983)
			(xy 385.123932 -281.518234) (xy 385.104641 -281.472958) (xy 385.092864 -281.425174) (xy 385.088904 -281.37612)
			(xy 384.760216 -281.37612) (xy 384.759721 -281.400727) (xy 384.751826 -281.449304) (xy 384.736242 -281.495985)
			(xy 384.713371 -281.539562) (xy 384.683806 -281.578906) (xy 384.648313 -281.612998) (xy 384.60781 -281.640954)
			(xy 384.563348 -281.662052) (xy 384.516077 -281.675744) (xy 384.467222 -281.681676) (xy 384.418047 -281.679695)
			(xy 384.369828 -281.669851) (xy 384.323812 -281.652399) (xy 384.281191 -281.627792) (xy 384.24307 -281.596667)
			(xy 384.210435 -281.55983) (xy 384.184132 -281.518234) (xy 384.164841 -281.472958) (xy 384.153064 -281.425174)
			(xy 384.149104 -281.37612) (xy 383.820162 -281.37612) (xy 383.819667 -281.400727) (xy 383.811772 -281.449304)
			(xy 383.796188 -281.495985) (xy 383.773317 -281.539562) (xy 383.743752 -281.578906) (xy 383.708259 -281.612998)
			(xy 383.667756 -281.640954) (xy 383.623294 -281.662052) (xy 383.576023 -281.675744) (xy 383.527168 -281.681676)
			(xy 383.477993 -281.679695) (xy 383.429774 -281.669851) (xy 383.383758 -281.652399) (xy 383.341137 -281.627792)
			(xy 383.303016 -281.596667) (xy 383.270381 -281.55983) (xy 383.244078 -281.518234) (xy 383.224787 -281.472958)
			(xy 383.21301 -281.425174) (xy 383.20905 -281.37612) (xy 382.880108 -281.37612) (xy 382.879613 -281.400727)
			(xy 382.871718 -281.449304) (xy 382.856134 -281.495985) (xy 382.833263 -281.539562) (xy 382.803698 -281.578906)
			(xy 382.768205 -281.612998) (xy 382.727702 -281.640954) (xy 382.68324 -281.662052) (xy 382.635969 -281.675744)
			(xy 382.587114 -281.681676) (xy 382.537939 -281.679695) (xy 382.48972 -281.669851) (xy 382.443704 -281.652399)
			(xy 382.401083 -281.627792) (xy 382.362962 -281.596667) (xy 382.330327 -281.55983) (xy 382.304024 -281.518234)
			(xy 382.284733 -281.472958) (xy 382.272956 -281.425174) (xy 382.268996 -281.37612) (xy 381.940054 -281.37612)
			(xy 381.939559 -281.400727) (xy 381.931664 -281.449304) (xy 381.91608 -281.495985) (xy 381.893209 -281.539562)
			(xy 381.863644 -281.578906) (xy 381.828151 -281.612998) (xy 381.787648 -281.640954) (xy 381.743186 -281.662052)
			(xy 381.695915 -281.675744) (xy 381.64706 -281.681676) (xy 381.597885 -281.679695) (xy 381.549666 -281.669851)
			(xy 381.50365 -281.652399) (xy 381.461029 -281.627792) (xy 381.422908 -281.596667) (xy 381.390273 -281.55983)
			(xy 381.36397 -281.518234) (xy 381.344679 -281.472958) (xy 381.332902 -281.425174) (xy 381.328942 -281.37612)
			(xy 381.010668 -281.37612) (xy 381.010156 -281.401566) (xy 381.001992 -281.4518) (xy 380.985876 -281.500074)
			(xy 380.962225 -281.545137) (xy 380.931652 -281.585823) (xy 380.894948 -281.621078) (xy 380.853064 -281.649988)
			(xy 380.807085 -281.671805) (xy 380.758201 -281.685965) (xy 380.70768 -281.692099) (xy 380.656828 -281.69005)
			(xy 380.606964 -281.67987) (xy 380.559378 -281.661823) (xy 380.515304 -281.636377) (xy 380.475882 -281.60419)
			(xy 380.442134 -281.566096) (xy 380.414933 -281.523082) (xy 380.394985 -281.476262) (xy 380.382806 -281.426848)
			(xy 380.378711 -281.37612) (xy 380.070614 -281.37612) (xy 380.070102 -281.401566) (xy 380.061938 -281.4518)
			(xy 380.045822 -281.500074) (xy 380.022171 -281.545137) (xy 379.991598 -281.585823) (xy 379.954894 -281.621078)
			(xy 379.91301 -281.649988) (xy 379.867031 -281.671805) (xy 379.818147 -281.685965) (xy 379.767626 -281.692099)
			(xy 379.716774 -281.69005) (xy 379.66691 -281.67987) (xy 379.619324 -281.661823) (xy 379.57525 -281.636377)
			(xy 379.535828 -281.60419) (xy 379.50208 -281.566096) (xy 379.474879 -281.523082) (xy 379.454931 -281.476262)
			(xy 379.442752 -281.426848) (xy 379.438657 -281.37612) (xy 379.120146 -281.37612) (xy 379.119651 -281.400727)
			(xy 379.111756 -281.449304) (xy 379.096172 -281.495985) (xy 379.073301 -281.539562) (xy 379.043736 -281.578906)
			(xy 379.008243 -281.612998) (xy 378.96774 -281.640954) (xy 378.923278 -281.662052) (xy 378.876007 -281.675744)
			(xy 378.827152 -281.681676) (xy 378.777977 -281.679695) (xy 378.729758 -281.669851) (xy 378.683742 -281.652399)
			(xy 378.641121 -281.627792) (xy 378.603 -281.596667) (xy 378.570365 -281.55983) (xy 378.544062 -281.518234)
			(xy 378.524771 -281.472958) (xy 378.512994 -281.425174) (xy 378.509034 -281.37612) (xy 378.190506 -281.37612)
			(xy 378.189994 -281.401566) (xy 378.18183 -281.4518) (xy 378.165714 -281.500074) (xy 378.142063 -281.545137)
			(xy 378.11149 -281.585823) (xy 378.074786 -281.621078) (xy 378.032902 -281.649988) (xy 377.986923 -281.671805)
			(xy 377.938039 -281.685965) (xy 377.887518 -281.692099) (xy 377.836666 -281.69005) (xy 377.786802 -281.67987)
			(xy 377.739216 -281.661823) (xy 377.695142 -281.636377) (xy 377.65572 -281.60419) (xy 377.621972 -281.566096)
			(xy 377.594771 -281.523082) (xy 377.574823 -281.476262) (xy 377.562644 -281.426848) (xy 377.558549 -281.37612)
			(xy 377.240038 -281.37612) (xy 377.239543 -281.400727) (xy 377.231648 -281.449304) (xy 377.216064 -281.495985)
			(xy 377.193193 -281.539562) (xy 377.163628 -281.578906) (xy 377.128135 -281.612998) (xy 377.087632 -281.640954)
			(xy 377.04317 -281.662052) (xy 376.995899 -281.675744) (xy 376.947044 -281.681676) (xy 376.897869 -281.679695)
			(xy 376.84965 -281.669851) (xy 376.803634 -281.652399) (xy 376.761013 -281.627792) (xy 376.722892 -281.596667)
			(xy 376.690257 -281.55983) (xy 376.663954 -281.518234) (xy 376.644663 -281.472958) (xy 376.632886 -281.425174)
			(xy 376.628926 -281.37612) (xy 376.310652 -281.37612) (xy 376.31014 -281.401566) (xy 376.301976 -281.4518)
			(xy 376.28586 -281.500074) (xy 376.262209 -281.545137) (xy 376.231636 -281.585823) (xy 376.194932 -281.621078)
			(xy 376.153048 -281.649988) (xy 376.107069 -281.671805) (xy 376.058185 -281.685965) (xy 376.007664 -281.692099)
			(xy 375.956812 -281.69005) (xy 375.906948 -281.67987) (xy 375.859362 -281.661823) (xy 375.815288 -281.636377)
			(xy 375.775866 -281.60419) (xy 375.742118 -281.566096) (xy 375.714917 -281.523082) (xy 375.694969 -281.476262)
			(xy 375.68279 -281.426848) (xy 375.678695 -281.37612) (xy 375.359656 -281.37612) (xy 375.359655 -281.401508)
			(xy 375.351247 -281.451597) (xy 375.334664 -281.499603) (xy 375.310365 -281.544203) (xy 375.27902 -281.584166)
			(xy 375.260616 -281.601672) (xy 375.25325 -281.608276) (xy 375.240804 -281.635454) (xy 375.23674 -281.6479)
			(xy 375.235978 -281.656536) (xy 375.235978 -282.186126) (xy 376.148595 -282.186126) (xy 376.15269 -282.135398)
			(xy 376.164869 -282.085984) (xy 376.184817 -282.039164) (xy 376.212018 -281.99615) (xy 376.245766 -281.958056)
			(xy 376.285188 -281.925869) (xy 376.329262 -281.900423) (xy 376.376848 -281.882376) (xy 376.426712 -281.872196)
			(xy 376.477564 -281.870147) (xy 376.528085 -281.876281) (xy 376.576969 -281.890441) (xy 376.622948 -281.912258)
			(xy 376.664832 -281.941168) (xy 376.701536 -281.976423) (xy 376.732109 -282.017109) (xy 376.75576 -282.062172)
			(xy 376.771876 -282.110446) (xy 376.78004 -282.16068) (xy 376.780552 -282.186126) (xy 377.088649 -282.186126)
			(xy 377.092744 -282.135398) (xy 377.104923 -282.085984) (xy 377.124871 -282.039164) (xy 377.152072 -281.99615)
			(xy 377.18582 -281.958056) (xy 377.225242 -281.925869) (xy 377.269316 -281.900423) (xy 377.316902 -281.882376)
			(xy 377.366766 -281.872196) (xy 377.417618 -281.870147) (xy 377.468139 -281.876281) (xy 377.517023 -281.890441)
			(xy 377.563002 -281.912258) (xy 377.604886 -281.941168) (xy 377.64159 -281.976423) (xy 377.672163 -282.017109)
			(xy 377.695814 -282.062172) (xy 377.71193 -282.110446) (xy 377.720094 -282.16068) (xy 377.720606 -282.186126)
			(xy 378.039134 -282.186126) (xy 378.043094 -282.137072) (xy 378.054871 -282.089288) (xy 378.074162 -282.044012)
			(xy 378.100465 -282.002416) (xy 378.1331 -281.965579) (xy 378.171221 -281.934454) (xy 378.213842 -281.909847)
			(xy 378.259858 -281.892395) (xy 378.308077 -281.882551) (xy 378.357252 -281.88057) (xy 378.406107 -281.886502)
			(xy 378.453378 -281.900194) (xy 378.49784 -281.921292) (xy 378.538343 -281.949248) (xy 378.573836 -281.98334)
			(xy 378.603401 -282.022684) (xy 378.626272 -282.066261) (xy 378.641856 -282.112942) (xy 378.649751 -282.161519)
			(xy 378.650246 -282.186126) (xy 378.968503 -282.186126) (xy 378.972598 -282.135398) (xy 378.984777 -282.085984)
			(xy 379.004725 -282.039164) (xy 379.031926 -281.99615) (xy 379.065674 -281.958056) (xy 379.105096 -281.925869)
			(xy 379.14917 -281.900423) (xy 379.196756 -281.882376) (xy 379.24662 -281.872196) (xy 379.297472 -281.870147)
			(xy 379.347993 -281.876281) (xy 379.396877 -281.890441) (xy 379.442856 -281.912258) (xy 379.48474 -281.941168)
			(xy 379.521444 -281.976423) (xy 379.552017 -282.017109) (xy 379.575668 -282.062172) (xy 379.591784 -282.110446)
			(xy 379.599948 -282.16068) (xy 379.60046 -282.186126) (xy 379.918988 -282.186126) (xy 379.922948 -282.137072)
			(xy 379.934725 -282.089288) (xy 379.954016 -282.044012) (xy 379.980319 -282.002416) (xy 380.012954 -281.965579)
			(xy 380.051075 -281.934454) (xy 380.093696 -281.909847) (xy 380.139712 -281.892395) (xy 380.187931 -281.882551)
			(xy 380.237106 -281.88057) (xy 380.285961 -281.886502) (xy 380.333232 -281.900194) (xy 380.377694 -281.921292)
			(xy 380.418197 -281.949248) (xy 380.45369 -281.98334) (xy 380.483255 -282.022684) (xy 380.506126 -282.066261)
			(xy 380.52171 -282.112942) (xy 380.529605 -282.161519) (xy 380.5301 -282.186126) (xy 380.848611 -282.186126)
			(xy 380.852706 -282.135398) (xy 380.864885 -282.085984) (xy 380.884833 -282.039164) (xy 380.912034 -281.99615)
			(xy 380.945782 -281.958056) (xy 380.985204 -281.925869) (xy 381.029278 -281.900423) (xy 381.076864 -281.882376)
			(xy 381.126728 -281.872196) (xy 381.17758 -281.870147) (xy 381.228101 -281.876281) (xy 381.276985 -281.890441)
			(xy 381.322964 -281.912258) (xy 381.364848 -281.941168) (xy 381.401552 -281.976423) (xy 381.432125 -282.017109)
			(xy 381.455776 -282.062172) (xy 381.471892 -282.110446) (xy 381.480056 -282.16068) (xy 381.480568 -282.186126)
			(xy 381.799096 -282.186126) (xy 381.803056 -282.137072) (xy 381.814833 -282.089288) (xy 381.834124 -282.044012)
			(xy 381.860427 -282.002416) (xy 381.893062 -281.965579) (xy 381.931183 -281.934454) (xy 381.973804 -281.909847)
			(xy 382.01982 -281.892395) (xy 382.068039 -281.882551) (xy 382.117214 -281.88057) (xy 382.166069 -281.886502)
			(xy 382.21334 -281.900194) (xy 382.257802 -281.921292) (xy 382.298305 -281.949248) (xy 382.333798 -281.98334)
			(xy 382.363363 -282.022684) (xy 382.386234 -282.066261) (xy 382.401818 -282.112942) (xy 382.409713 -282.161519)
			(xy 382.410208 -282.186126) (xy 382.738896 -282.186126) (xy 382.742856 -282.137072) (xy 382.754633 -282.089288)
			(xy 382.773924 -282.044012) (xy 382.800227 -282.002416) (xy 382.832862 -281.965579) (xy 382.870983 -281.934454)
			(xy 382.913604 -281.909847) (xy 382.95962 -281.892395) (xy 383.007839 -281.882551) (xy 383.057014 -281.88057)
			(xy 383.105869 -281.886502) (xy 383.15314 -281.900194) (xy 383.197602 -281.921292) (xy 383.238105 -281.949248)
			(xy 383.273598 -281.98334) (xy 383.303163 -282.022684) (xy 383.326034 -282.066261) (xy 383.341618 -282.112942)
			(xy 383.349513 -282.161519) (xy 383.350008 -282.186126) (xy 383.67895 -282.186126) (xy 383.68291 -282.137072)
			(xy 383.694687 -282.089288) (xy 383.713978 -282.044012) (xy 383.740281 -282.002416) (xy 383.772916 -281.965579)
			(xy 383.811037 -281.934454) (xy 383.853658 -281.909847) (xy 383.899674 -281.892395) (xy 383.947893 -281.882551)
			(xy 383.997068 -281.88057) (xy 384.045923 -281.886502) (xy 384.093194 -281.900194) (xy 384.137656 -281.921292)
			(xy 384.178159 -281.949248) (xy 384.213652 -281.98334) (xy 384.243217 -282.022684) (xy 384.266088 -282.066261)
			(xy 384.281672 -282.112942) (xy 384.289567 -282.161519) (xy 384.290062 -282.186126) (xy 384.619004 -282.186126)
			(xy 384.622964 -282.137072) (xy 384.634741 -282.089288) (xy 384.654032 -282.044012) (xy 384.680335 -282.002416)
			(xy 384.71297 -281.965579) (xy 384.751091 -281.934454) (xy 384.793712 -281.909847) (xy 384.839728 -281.892395)
			(xy 384.887947 -281.882551) (xy 384.937122 -281.88057) (xy 384.985977 -281.886502) (xy 385.033248 -281.900194)
			(xy 385.07771 -281.921292) (xy 385.118213 -281.949248) (xy 385.153706 -281.98334) (xy 385.183271 -282.022684)
			(xy 385.206142 -282.066261) (xy 385.221726 -282.112942) (xy 385.229621 -282.161519) (xy 385.230116 -282.186126)
			(xy 385.559058 -282.186126) (xy 385.563018 -282.137072) (xy 385.574795 -282.089288) (xy 385.594086 -282.044012)
			(xy 385.620389 -282.002416) (xy 385.653024 -281.965579) (xy 385.691145 -281.934454) (xy 385.733766 -281.909847)
			(xy 385.779782 -281.892395) (xy 385.828001 -281.882551) (xy 385.877176 -281.88057) (xy 385.926031 -281.886502)
			(xy 385.973302 -281.900194) (xy 386.017764 -281.921292) (xy 386.058267 -281.949248) (xy 386.09376 -281.98334)
			(xy 386.123325 -282.022684) (xy 386.146196 -282.066261) (xy 386.16178 -282.112942) (xy 386.169675 -282.161519)
			(xy 386.17017 -282.186126) (xy 386.499112 -282.186126) (xy 386.503072 -282.137072) (xy 386.514849 -282.089288)
			(xy 386.53414 -282.044012) (xy 386.560443 -282.002416) (xy 386.593078 -281.965579) (xy 386.631199 -281.934454)
			(xy 386.67382 -281.909847) (xy 386.719836 -281.892395) (xy 386.768055 -281.882551) (xy 386.81723 -281.88057)
			(xy 386.866085 -281.886502) (xy 386.913356 -281.900194) (xy 386.957818 -281.921292) (xy 386.998321 -281.949248)
			(xy 387.033814 -281.98334) (xy 387.063379 -282.022684) (xy 387.08625 -282.066261) (xy 387.101834 -282.112942)
			(xy 387.109729 -282.161519) (xy 387.110224 -282.186126) (xy 387.438912 -282.186126) (xy 387.442872 -282.137072)
			(xy 387.454649 -282.089288) (xy 387.47394 -282.044012) (xy 387.500243 -282.002416) (xy 387.532878 -281.965579)
			(xy 387.570999 -281.934454) (xy 387.61362 -281.909847) (xy 387.659636 -281.892395) (xy 387.707855 -281.882551)
			(xy 387.75703 -281.88057) (xy 387.805885 -281.886502) (xy 387.853156 -281.900194) (xy 387.897618 -281.921292)
			(xy 387.938121 -281.949248) (xy 387.973614 -281.98334) (xy 388.003179 -282.022684) (xy 388.02605 -282.066261)
			(xy 388.041634 -282.112942) (xy 388.049529 -282.161519) (xy 388.050024 -282.186126) (xy 388.049529 -282.210733)
			(xy 388.041634 -282.25931) (xy 388.02605 -282.305991) (xy 388.003179 -282.349568) (xy 387.973614 -282.388912)
			(xy 387.938121 -282.423004) (xy 387.897618 -282.45096) (xy 387.853156 -282.472058) (xy 387.805885 -282.48575)
			(xy 387.75703 -282.491682) (xy 387.707855 -282.489701) (xy 387.659636 -282.479857) (xy 387.61362 -282.462405)
			(xy 387.570999 -282.437798) (xy 387.532878 -282.406673) (xy 387.500243 -282.369836) (xy 387.47394 -282.32824)
			(xy 387.454649 -282.282964) (xy 387.442872 -282.23518) (xy 387.438912 -282.186126) (xy 387.110224 -282.186126)
			(xy 387.109729 -282.210733) (xy 387.101834 -282.25931) (xy 387.08625 -282.305991) (xy 387.063379 -282.349568)
			(xy 387.033814 -282.388912) (xy 386.998321 -282.423004) (xy 386.957818 -282.45096) (xy 386.913356 -282.472058)
			(xy 386.866085 -282.48575) (xy 386.81723 -282.491682) (xy 386.768055 -282.489701) (xy 386.719836 -282.479857)
			(xy 386.67382 -282.462405) (xy 386.631199 -282.437798) (xy 386.593078 -282.406673) (xy 386.560443 -282.369836)
			(xy 386.53414 -282.32824) (xy 386.514849 -282.282964) (xy 386.503072 -282.23518) (xy 386.499112 -282.186126)
			(xy 386.17017 -282.186126) (xy 386.169675 -282.210733) (xy 386.16178 -282.25931) (xy 386.146196 -282.305991)
			(xy 386.123325 -282.349568) (xy 386.09376 -282.388912) (xy 386.058267 -282.423004) (xy 386.017764 -282.45096)
			(xy 385.973302 -282.472058) (xy 385.926031 -282.48575) (xy 385.877176 -282.491682) (xy 385.828001 -282.489701)
			(xy 385.779782 -282.479857) (xy 385.733766 -282.462405) (xy 385.691145 -282.437798) (xy 385.653024 -282.406673)
			(xy 385.620389 -282.369836) (xy 385.594086 -282.32824) (xy 385.574795 -282.282964) (xy 385.563018 -282.23518)
			(xy 385.559058 -282.186126) (xy 385.230116 -282.186126) (xy 385.229621 -282.210733) (xy 385.221726 -282.25931)
			(xy 385.206142 -282.305991) (xy 385.183271 -282.349568) (xy 385.153706 -282.388912) (xy 385.118213 -282.423004)
			(xy 385.07771 -282.45096) (xy 385.033248 -282.472058) (xy 384.985977 -282.48575) (xy 384.937122 -282.491682)
			(xy 384.887947 -282.489701) (xy 384.839728 -282.479857) (xy 384.793712 -282.462405) (xy 384.751091 -282.437798)
			(xy 384.71297 -282.406673) (xy 384.680335 -282.369836) (xy 384.654032 -282.32824) (xy 384.634741 -282.282964)
			(xy 384.622964 -282.23518) (xy 384.619004 -282.186126) (xy 384.290062 -282.186126) (xy 384.289567 -282.210733)
			(xy 384.281672 -282.25931) (xy 384.266088 -282.305991) (xy 384.243217 -282.349568) (xy 384.213652 -282.388912)
			(xy 384.178159 -282.423004) (xy 384.137656 -282.45096) (xy 384.093194 -282.472058) (xy 384.045923 -282.48575)
			(xy 383.997068 -282.491682) (xy 383.947893 -282.489701) (xy 383.899674 -282.479857) (xy 383.853658 -282.462405)
			(xy 383.811037 -282.437798) (xy 383.772916 -282.406673) (xy 383.740281 -282.369836) (xy 383.713978 -282.32824)
			(xy 383.694687 -282.282964) (xy 383.68291 -282.23518) (xy 383.67895 -282.186126) (xy 383.350008 -282.186126)
			(xy 383.349513 -282.210733) (xy 383.341618 -282.25931) (xy 383.326034 -282.305991) (xy 383.303163 -282.349568)
			(xy 383.273598 -282.388912) (xy 383.238105 -282.423004) (xy 383.197602 -282.45096) (xy 383.15314 -282.472058)
			(xy 383.105869 -282.48575) (xy 383.057014 -282.491682) (xy 383.007839 -282.489701) (xy 382.95962 -282.479857)
			(xy 382.913604 -282.462405) (xy 382.870983 -282.437798) (xy 382.832862 -282.406673) (xy 382.800227 -282.369836)
			(xy 382.773924 -282.32824) (xy 382.754633 -282.282964) (xy 382.742856 -282.23518) (xy 382.738896 -282.186126)
			(xy 382.410208 -282.186126) (xy 382.409713 -282.210733) (xy 382.401818 -282.25931) (xy 382.386234 -282.305991)
			(xy 382.363363 -282.349568) (xy 382.333798 -282.388912) (xy 382.298305 -282.423004) (xy 382.257802 -282.45096)
			(xy 382.21334 -282.472058) (xy 382.166069 -282.48575) (xy 382.117214 -282.491682) (xy 382.068039 -282.489701)
			(xy 382.01982 -282.479857) (xy 381.973804 -282.462405) (xy 381.931183 -282.437798) (xy 381.893062 -282.406673)
			(xy 381.860427 -282.369836) (xy 381.834124 -282.32824) (xy 381.814833 -282.282964) (xy 381.803056 -282.23518)
			(xy 381.799096 -282.186126) (xy 381.480568 -282.186126) (xy 381.480056 -282.211572) (xy 381.471892 -282.261806)
			(xy 381.455776 -282.31008) (xy 381.432125 -282.355143) (xy 381.401552 -282.395829) (xy 381.364848 -282.431084)
			(xy 381.322964 -282.459994) (xy 381.276985 -282.481811) (xy 381.228101 -282.495971) (xy 381.17758 -282.502105)
			(xy 381.126728 -282.500056) (xy 381.076864 -282.489876) (xy 381.029278 -282.471829) (xy 380.985204 -282.446383)
			(xy 380.945782 -282.414196) (xy 380.912034 -282.376102) (xy 380.884833 -282.333088) (xy 380.864885 -282.286268)
			(xy 380.852706 -282.236854) (xy 380.848611 -282.186126) (xy 380.5301 -282.186126) (xy 380.529605 -282.210733)
			(xy 380.52171 -282.25931) (xy 380.506126 -282.305991) (xy 380.483255 -282.349568) (xy 380.45369 -282.388912)
			(xy 380.418197 -282.423004) (xy 380.377694 -282.45096) (xy 380.333232 -282.472058) (xy 380.285961 -282.48575)
			(xy 380.237106 -282.491682) (xy 380.187931 -282.489701) (xy 380.139712 -282.479857) (xy 380.093696 -282.462405)
			(xy 380.051075 -282.437798) (xy 380.012954 -282.406673) (xy 379.980319 -282.369836) (xy 379.954016 -282.32824)
			(xy 379.934725 -282.282964) (xy 379.922948 -282.23518) (xy 379.918988 -282.186126) (xy 379.60046 -282.186126)
			(xy 379.599948 -282.211572) (xy 379.591784 -282.261806) (xy 379.575668 -282.31008) (xy 379.552017 -282.355143)
			(xy 379.521444 -282.395829) (xy 379.48474 -282.431084) (xy 379.442856 -282.459994) (xy 379.396877 -282.481811)
			(xy 379.347993 -282.495971) (xy 379.297472 -282.502105) (xy 379.24662 -282.500056) (xy 379.196756 -282.489876)
			(xy 379.14917 -282.471829) (xy 379.105096 -282.446383) (xy 379.065674 -282.414196) (xy 379.031926 -282.376102)
			(xy 379.004725 -282.333088) (xy 378.984777 -282.286268) (xy 378.972598 -282.236854) (xy 378.968503 -282.186126)
			(xy 378.650246 -282.186126) (xy 378.649751 -282.210733) (xy 378.641856 -282.25931) (xy 378.626272 -282.305991)
			(xy 378.603401 -282.349568) (xy 378.573836 -282.388912) (xy 378.538343 -282.423004) (xy 378.49784 -282.45096)
			(xy 378.453378 -282.472058) (xy 378.406107 -282.48575) (xy 378.357252 -282.491682) (xy 378.308077 -282.489701)
			(xy 378.259858 -282.479857) (xy 378.213842 -282.462405) (xy 378.171221 -282.437798) (xy 378.1331 -282.406673)
			(xy 378.100465 -282.369836) (xy 378.074162 -282.32824) (xy 378.054871 -282.282964) (xy 378.043094 -282.23518)
			(xy 378.039134 -282.186126) (xy 377.720606 -282.186126) (xy 377.720094 -282.211572) (xy 377.71193 -282.261806)
			(xy 377.695814 -282.31008) (xy 377.672163 -282.355143) (xy 377.64159 -282.395829) (xy 377.604886 -282.431084)
			(xy 377.563002 -282.459994) (xy 377.517023 -282.481811) (xy 377.468139 -282.495971) (xy 377.417618 -282.502105)
			(xy 377.366766 -282.500056) (xy 377.316902 -282.489876) (xy 377.269316 -282.471829) (xy 377.225242 -282.446383)
			(xy 377.18582 -282.414196) (xy 377.152072 -282.376102) (xy 377.124871 -282.333088) (xy 377.104923 -282.286268)
			(xy 377.092744 -282.236854) (xy 377.088649 -282.186126) (xy 376.780552 -282.186126) (xy 376.78004 -282.211572)
			(xy 376.771876 -282.261806) (xy 376.75576 -282.31008) (xy 376.732109 -282.355143) (xy 376.701536 -282.395829)
			(xy 376.664832 -282.431084) (xy 376.622948 -282.459994) (xy 376.576969 -282.481811) (xy 376.528085 -282.495971)
			(xy 376.477564 -282.502105) (xy 376.426712 -282.500056) (xy 376.376848 -282.489876) (xy 376.329262 -282.471829)
			(xy 376.285188 -282.446383) (xy 376.245766 -282.414196) (xy 376.212018 -282.376102) (xy 376.184817 -282.333088)
			(xy 376.164869 -282.286268) (xy 376.15269 -282.236854) (xy 376.148595 -282.186126) (xy 375.235978 -282.186126)
			(xy 375.235978 -282.715462) (xy 375.236994 -282.725622) (xy 375.24055 -282.736544) (xy 375.25325 -282.763976)
			(xy 375.260616 -282.77058) (xy 375.279037 -282.788066) (xy 375.310377 -282.828031) (xy 375.33467 -282.872633)
			(xy 375.351247 -282.920639) (xy 375.359649 -282.970728) (xy 375.359647 -282.996132) (xy 375.678695 -282.996132)
			(xy 375.68279 -282.945404) (xy 375.694969 -282.89599) (xy 375.714917 -282.84917) (xy 375.742118 -282.806156)
			(xy 375.775866 -282.768062) (xy 375.815288 -282.735875) (xy 375.859362 -282.710429) (xy 375.906948 -282.692382)
			(xy 375.956812 -282.682202) (xy 376.007664 -282.680153) (xy 376.058185 -282.686287) (xy 376.107069 -282.700447)
			(xy 376.153048 -282.722264) (xy 376.194932 -282.751174) (xy 376.231636 -282.786429) (xy 376.262209 -282.827115)
			(xy 376.28586 -282.872178) (xy 376.301976 -282.920452) (xy 376.31014 -282.970686) (xy 376.310652 -282.996132)
			(xy 376.628926 -282.996132) (xy 376.632886 -282.947078) (xy 376.644663 -282.899294) (xy 376.663954 -282.854018)
			(xy 376.690257 -282.812422) (xy 376.722892 -282.775585) (xy 376.761013 -282.74446) (xy 376.803634 -282.719853)
			(xy 376.84965 -282.702401) (xy 376.897869 -282.692557) (xy 376.947044 -282.690576) (xy 376.995899 -282.696508)
			(xy 377.04317 -282.7102) (xy 377.087632 -282.731298) (xy 377.128135 -282.759254) (xy 377.163628 -282.793346)
			(xy 377.193193 -282.83269) (xy 377.216064 -282.876267) (xy 377.231648 -282.922948) (xy 377.239543 -282.971525)
			(xy 377.240038 -282.996132) (xy 377.558549 -282.996132) (xy 377.562644 -282.945404) (xy 377.574823 -282.89599)
			(xy 377.594771 -282.84917) (xy 377.621972 -282.806156) (xy 377.65572 -282.768062) (xy 377.695142 -282.735875)
			(xy 377.739216 -282.710429) (xy 377.786802 -282.692382) (xy 377.836666 -282.682202) (xy 377.887518 -282.680153)
			(xy 377.938039 -282.686287) (xy 377.986923 -282.700447) (xy 378.032902 -282.722264) (xy 378.074786 -282.751174)
			(xy 378.11149 -282.786429) (xy 378.142063 -282.827115) (xy 378.165714 -282.872178) (xy 378.18183 -282.920452)
			(xy 378.189994 -282.970686) (xy 378.190506 -282.996132) (xy 379.438657 -282.996132) (xy 379.442752 -282.945404)
			(xy 379.454931 -282.89599) (xy 379.474879 -282.84917) (xy 379.50208 -282.806156) (xy 379.535828 -282.768062)
			(xy 379.57525 -282.735875) (xy 379.619324 -282.710429) (xy 379.66691 -282.692382) (xy 379.716774 -282.682202)
			(xy 379.767626 -282.680153) (xy 379.818147 -282.686287) (xy 379.867031 -282.700447) (xy 379.91301 -282.722264)
			(xy 379.954894 -282.751174) (xy 379.991598 -282.786429) (xy 380.022171 -282.827115) (xy 380.045822 -282.872178)
			(xy 380.061938 -282.920452) (xy 380.070102 -282.970686) (xy 380.070614 -282.996132) (xy 380.378711 -282.996132)
			(xy 380.382806 -282.945404) (xy 380.394985 -282.89599) (xy 380.414933 -282.84917) (xy 380.442134 -282.806156)
			(xy 380.475882 -282.768062) (xy 380.515304 -282.735875) (xy 380.559378 -282.710429) (xy 380.606964 -282.692382)
			(xy 380.656828 -282.682202) (xy 380.70768 -282.680153) (xy 380.758201 -282.686287) (xy 380.807085 -282.700447)
			(xy 380.853064 -282.722264) (xy 380.894948 -282.751174) (xy 380.931652 -282.786429) (xy 380.962225 -282.827115)
			(xy 380.985876 -282.872178) (xy 381.001992 -282.920452) (xy 381.010156 -282.970686) (xy 381.010668 -282.996132)
			(xy 381.328942 -282.996132) (xy 381.332902 -282.947078) (xy 381.344679 -282.899294) (xy 381.36397 -282.854018)
			(xy 381.390273 -282.812422) (xy 381.422908 -282.775585) (xy 381.461029 -282.74446) (xy 381.50365 -282.719853)
			(xy 381.549666 -282.702401) (xy 381.597885 -282.692557) (xy 381.64706 -282.690576) (xy 381.695915 -282.696508)
			(xy 381.743186 -282.7102) (xy 381.787648 -282.731298) (xy 381.828151 -282.759254) (xy 381.863644 -282.793346)
			(xy 381.893209 -282.83269) (xy 381.91608 -282.876267) (xy 381.931664 -282.922948) (xy 381.939559 -282.971525)
			(xy 381.940054 -282.996132) (xy 382.268996 -282.996132) (xy 382.272956 -282.947078) (xy 382.284733 -282.899294)
			(xy 382.304024 -282.854018) (xy 382.330327 -282.812422) (xy 382.362962 -282.775585) (xy 382.401083 -282.74446)
			(xy 382.443704 -282.719853) (xy 382.48972 -282.702401) (xy 382.537939 -282.692557) (xy 382.587114 -282.690576)
			(xy 382.635969 -282.696508) (xy 382.68324 -282.7102) (xy 382.727702 -282.731298) (xy 382.768205 -282.759254)
			(xy 382.803698 -282.793346) (xy 382.833263 -282.83269) (xy 382.856134 -282.876267) (xy 382.871718 -282.922948)
			(xy 382.879613 -282.971525) (xy 382.880108 -282.996132) (xy 383.20905 -282.996132) (xy 383.21301 -282.947078)
			(xy 383.224787 -282.899294) (xy 383.244078 -282.854018) (xy 383.270381 -282.812422) (xy 383.303016 -282.775585)
			(xy 383.341137 -282.74446) (xy 383.383758 -282.719853) (xy 383.429774 -282.702401) (xy 383.477993 -282.692557)
			(xy 383.527168 -282.690576) (xy 383.576023 -282.696508) (xy 383.623294 -282.7102) (xy 383.667756 -282.731298)
			(xy 383.708259 -282.759254) (xy 383.743752 -282.793346) (xy 383.773317 -282.83269) (xy 383.796188 -282.876267)
			(xy 383.811772 -282.922948) (xy 383.819667 -282.971525) (xy 383.820162 -282.996132) (xy 384.149104 -282.996132)
			(xy 384.153064 -282.947078) (xy 384.164841 -282.899294) (xy 384.184132 -282.854018) (xy 384.210435 -282.812422)
			(xy 384.24307 -282.775585) (xy 384.281191 -282.74446) (xy 384.323812 -282.719853) (xy 384.369828 -282.702401)
			(xy 384.418047 -282.692557) (xy 384.467222 -282.690576) (xy 384.516077 -282.696508) (xy 384.563348 -282.7102)
			(xy 384.60781 -282.731298) (xy 384.648313 -282.759254) (xy 384.683806 -282.793346) (xy 384.713371 -282.83269)
			(xy 384.736242 -282.876267) (xy 384.751826 -282.922948) (xy 384.759721 -282.971525) (xy 384.760216 -282.996132)
			(xy 386.028958 -282.996132) (xy 386.032918 -282.947078) (xy 386.044695 -282.899294) (xy 386.063986 -282.854018)
			(xy 386.090289 -282.812422) (xy 386.122924 -282.775585) (xy 386.161045 -282.74446) (xy 386.203666 -282.719853)
			(xy 386.249682 -282.702401) (xy 386.297901 -282.692557) (xy 386.347076 -282.690576) (xy 386.395931 -282.696508)
			(xy 386.443202 -282.7102) (xy 386.487664 -282.731298) (xy 386.528167 -282.759254) (xy 386.56366 -282.793346)
			(xy 386.593225 -282.83269) (xy 386.616096 -282.876267) (xy 386.63168 -282.922948) (xy 386.639575 -282.971525)
			(xy 386.64007 -282.996132) (xy 386.969012 -282.996132) (xy 386.972972 -282.947078) (xy 386.984749 -282.899294)
			(xy 387.00404 -282.854018) (xy 387.030343 -282.812422) (xy 387.062978 -282.775585) (xy 387.101099 -282.74446)
			(xy 387.14372 -282.719853) (xy 387.189736 -282.702401) (xy 387.237955 -282.692557) (xy 387.28713 -282.690576)
			(xy 387.335985 -282.696508) (xy 387.383256 -282.7102) (xy 387.427718 -282.731298) (xy 387.468221 -282.759254)
			(xy 387.503714 -282.793346) (xy 387.533279 -282.83269) (xy 387.55615 -282.876267) (xy 387.571734 -282.922948)
			(xy 387.579629 -282.971525) (xy 387.580124 -282.996132) (xy 387.579629 -283.020739) (xy 387.571734 -283.069316)
			(xy 387.55615 -283.115997) (xy 387.533279 -283.159574) (xy 387.503714 -283.198918) (xy 387.468221 -283.23301)
			(xy 387.427718 -283.260966) (xy 387.383256 -283.282064) (xy 387.335985 -283.295756) (xy 387.28713 -283.301688)
			(xy 387.237955 -283.299707) (xy 387.189736 -283.289863) (xy 387.14372 -283.272411) (xy 387.101099 -283.247804)
			(xy 387.062978 -283.216679) (xy 387.030343 -283.179842) (xy 387.00404 -283.138246) (xy 386.984749 -283.09297)
			(xy 386.972972 -283.045186) (xy 386.969012 -282.996132) (xy 386.64007 -282.996132) (xy 386.639575 -283.020739)
			(xy 386.63168 -283.069316) (xy 386.616096 -283.115997) (xy 386.593225 -283.159574) (xy 386.56366 -283.198918)
			(xy 386.528167 -283.23301) (xy 386.487664 -283.260966) (xy 386.443202 -283.282064) (xy 386.395931 -283.295756)
			(xy 386.347076 -283.301688) (xy 386.297901 -283.299707) (xy 386.249682 -283.289863) (xy 386.203666 -283.272411)
			(xy 386.161045 -283.247804) (xy 386.122924 -283.216679) (xy 386.090289 -283.179842) (xy 386.063986 -283.138246)
			(xy 386.044695 -283.09297) (xy 386.032918 -283.045186) (xy 386.028958 -282.996132) (xy 384.760216 -282.996132)
			(xy 384.759721 -283.020739) (xy 384.751826 -283.069316) (xy 384.736242 -283.115997) (xy 384.713371 -283.159574)
			(xy 384.683806 -283.198918) (xy 384.648313 -283.23301) (xy 384.60781 -283.260966) (xy 384.563348 -283.282064)
			(xy 384.516077 -283.295756) (xy 384.467222 -283.301688) (xy 384.418047 -283.299707) (xy 384.369828 -283.289863)
			(xy 384.323812 -283.272411) (xy 384.281191 -283.247804) (xy 384.24307 -283.216679) (xy 384.210435 -283.179842)
			(xy 384.184132 -283.138246) (xy 384.164841 -283.09297) (xy 384.153064 -283.045186) (xy 384.149104 -282.996132)
			(xy 383.820162 -282.996132) (xy 383.819667 -283.020739) (xy 383.811772 -283.069316) (xy 383.796188 -283.115997)
			(xy 383.773317 -283.159574) (xy 383.743752 -283.198918) (xy 383.708259 -283.23301) (xy 383.667756 -283.260966)
			(xy 383.623294 -283.282064) (xy 383.576023 -283.295756) (xy 383.527168 -283.301688) (xy 383.477993 -283.299707)
			(xy 383.429774 -283.289863) (xy 383.383758 -283.272411) (xy 383.341137 -283.247804) (xy 383.303016 -283.216679)
			(xy 383.270381 -283.179842) (xy 383.244078 -283.138246) (xy 383.224787 -283.09297) (xy 383.21301 -283.045186)
			(xy 383.20905 -282.996132) (xy 382.880108 -282.996132) (xy 382.879613 -283.020739) (xy 382.871718 -283.069316)
			(xy 382.856134 -283.115997) (xy 382.833263 -283.159574) (xy 382.803698 -283.198918) (xy 382.768205 -283.23301)
			(xy 382.727702 -283.260966) (xy 382.68324 -283.282064) (xy 382.635969 -283.295756) (xy 382.587114 -283.301688)
			(xy 382.537939 -283.299707) (xy 382.48972 -283.289863) (xy 382.443704 -283.272411) (xy 382.401083 -283.247804)
			(xy 382.362962 -283.216679) (xy 382.330327 -283.179842) (xy 382.304024 -283.138246) (xy 382.284733 -283.09297)
			(xy 382.272956 -283.045186) (xy 382.268996 -282.996132) (xy 381.940054 -282.996132) (xy 381.939559 -283.020739)
			(xy 381.931664 -283.069316) (xy 381.91608 -283.115997) (xy 381.893209 -283.159574) (xy 381.863644 -283.198918)
			(xy 381.828151 -283.23301) (xy 381.787648 -283.260966) (xy 381.743186 -283.282064) (xy 381.695915 -283.295756)
			(xy 381.64706 -283.301688) (xy 381.597885 -283.299707) (xy 381.549666 -283.289863) (xy 381.50365 -283.272411)
			(xy 381.461029 -283.247804) (xy 381.422908 -283.216679) (xy 381.390273 -283.179842) (xy 381.36397 -283.138246)
			(xy 381.344679 -283.09297) (xy 381.332902 -283.045186) (xy 381.328942 -282.996132) (xy 381.010668 -282.996132)
			(xy 381.010156 -283.021578) (xy 381.001992 -283.071812) (xy 380.985876 -283.120086) (xy 380.962225 -283.165149)
			(xy 380.931652 -283.205835) (xy 380.894948 -283.24109) (xy 380.853064 -283.27) (xy 380.807085 -283.291817)
			(xy 380.758201 -283.305977) (xy 380.70768 -283.312111) (xy 380.656828 -283.310062) (xy 380.606964 -283.299882)
			(xy 380.559378 -283.281835) (xy 380.515304 -283.256389) (xy 380.475882 -283.224202) (xy 380.442134 -283.186108)
			(xy 380.414933 -283.143094) (xy 380.394985 -283.096274) (xy 380.382806 -283.04686) (xy 380.378711 -282.996132)
			(xy 380.070614 -282.996132) (xy 380.070102 -283.021578) (xy 380.061938 -283.071812) (xy 380.045822 -283.120086)
			(xy 380.022171 -283.165149) (xy 379.991598 -283.205835) (xy 379.954894 -283.24109) (xy 379.91301 -283.27)
			(xy 379.867031 -283.291817) (xy 379.818147 -283.305977) (xy 379.767626 -283.312111) (xy 379.716774 -283.310062)
			(xy 379.66691 -283.299882) (xy 379.619324 -283.281835) (xy 379.57525 -283.256389) (xy 379.535828 -283.224202)
			(xy 379.50208 -283.186108) (xy 379.474879 -283.143094) (xy 379.454931 -283.096274) (xy 379.442752 -283.04686)
			(xy 379.438657 -282.996132) (xy 378.190506 -282.996132) (xy 378.189994 -283.021578) (xy 378.18183 -283.071812)
			(xy 378.165714 -283.120086) (xy 378.142063 -283.165149) (xy 378.11149 -283.205835) (xy 378.074786 -283.24109)
			(xy 378.032902 -283.27) (xy 377.986923 -283.291817) (xy 377.938039 -283.305977) (xy 377.887518 -283.312111)
			(xy 377.836666 -283.310062) (xy 377.786802 -283.299882) (xy 377.739216 -283.281835) (xy 377.695142 -283.256389)
			(xy 377.65572 -283.224202) (xy 377.621972 -283.186108) (xy 377.594771 -283.143094) (xy 377.574823 -283.096274)
			(xy 377.562644 -283.04686) (xy 377.558549 -282.996132) (xy 377.240038 -282.996132) (xy 377.239543 -283.020739)
			(xy 377.231648 -283.069316) (xy 377.216064 -283.115997) (xy 377.193193 -283.159574) (xy 377.163628 -283.198918)
			(xy 377.128135 -283.23301) (xy 377.087632 -283.260966) (xy 377.04317 -283.282064) (xy 376.995899 -283.295756)
			(xy 376.947044 -283.301688) (xy 376.897869 -283.299707) (xy 376.84965 -283.289863) (xy 376.803634 -283.272411)
			(xy 376.761013 -283.247804) (xy 376.722892 -283.216679) (xy 376.690257 -283.179842) (xy 376.663954 -283.138246)
			(xy 376.644663 -283.09297) (xy 376.632886 -283.045186) (xy 376.628926 -282.996132) (xy 376.310652 -282.996132)
			(xy 376.31014 -283.021578) (xy 376.301976 -283.071812) (xy 376.28586 -283.120086) (xy 376.262209 -283.165149)
			(xy 376.231636 -283.205835) (xy 376.194932 -283.24109) (xy 376.153048 -283.27) (xy 376.107069 -283.291817)
			(xy 376.058185 -283.305977) (xy 376.007664 -283.312111) (xy 375.956812 -283.310062) (xy 375.906948 -283.299882)
			(xy 375.859362 -283.281835) (xy 375.815288 -283.256389) (xy 375.775866 -283.224202) (xy 375.742118 -283.186108)
			(xy 375.714917 -283.143094) (xy 375.694969 -283.096274) (xy 375.68279 -283.04686) (xy 375.678695 -282.996132)
			(xy 375.359647 -282.996132) (xy 375.359645 -283.021516) (xy 375.351236 -283.071602) (xy 375.334653 -283.119607)
			(xy 375.310353 -283.164205) (xy 375.279008 -283.204166) (xy 375.260616 -283.221684) (xy 375.25325 -283.228288)
			(xy 375.240804 -283.255466) (xy 375.23674 -283.267912) (xy 375.235978 -283.276548) (xy 375.235978 -283.44749)
			(xy 375.23638 -283.456041) (xy 375.242183 -283.472135) (xy 375.252998 -283.485391) (xy 375.260108 -283.490162)
			(xy 375.315734 -283.52369) (xy 375.336054 -283.535882) (xy 375.341239 -283.538414) (xy 375.352393 -283.541357)
			(xy 375.358152 -283.541724) (xy 375.370852 -283.541978) (xy 375.382536 -283.535882) (xy 375.404529 -283.524884)
			(xy 375.451158 -283.509279) (xy 375.499683 -283.501339) (xy 375.524268 -283.50083) (xy 375.530364 -283.50083)
			(xy 375.555315 -283.501782) (xy 375.604421 -283.510802) (xy 375.651406 -283.527692) (xy 375.695017 -283.552)
			(xy 375.734091 -283.583081) (xy 375.767588 -283.620105) (xy 375.794615 -283.662085) (xy 375.814451 -283.707904)
			(xy 375.826569 -283.756339) (xy 375.830644 -283.806101) (xy 375.830641 -283.806138) (xy 376.148595 -283.806138)
			(xy 376.15269 -283.75541) (xy 376.164869 -283.705996) (xy 376.184817 -283.659176) (xy 376.212018 -283.616162)
			(xy 376.245766 -283.578068) (xy 376.285188 -283.545881) (xy 376.329262 -283.520435) (xy 376.376848 -283.502388)
			(xy 376.426712 -283.492208) (xy 376.477564 -283.490159) (xy 376.528085 -283.496293) (xy 376.576969 -283.510453)
			(xy 376.622948 -283.53227) (xy 376.664832 -283.56118) (xy 376.701536 -283.596435) (xy 376.732109 -283.637121)
			(xy 376.75576 -283.682184) (xy 376.771876 -283.730458) (xy 376.78004 -283.780692) (xy 376.780552 -283.806138)
			(xy 377.088649 -283.806138) (xy 377.092744 -283.75541) (xy 377.104923 -283.705996) (xy 377.124871 -283.659176)
			(xy 377.152072 -283.616162) (xy 377.18582 -283.578068) (xy 377.225242 -283.545881) (xy 377.269316 -283.520435)
			(xy 377.316902 -283.502388) (xy 377.366766 -283.492208) (xy 377.417618 -283.490159) (xy 377.468139 -283.496293)
			(xy 377.517023 -283.510453) (xy 377.563002 -283.53227) (xy 377.604886 -283.56118) (xy 377.64159 -283.596435)
			(xy 377.672163 -283.637121) (xy 377.695814 -283.682184) (xy 377.71193 -283.730458) (xy 377.720094 -283.780692)
			(xy 377.720606 -283.806138) (xy 378.039134 -283.806138) (xy 378.043094 -283.757084) (xy 378.054871 -283.7093)
			(xy 378.074162 -283.664024) (xy 378.100465 -283.622428) (xy 378.1331 -283.585591) (xy 378.171221 -283.554466)
			(xy 378.213842 -283.529859) (xy 378.259858 -283.512407) (xy 378.308077 -283.502563) (xy 378.357252 -283.500582)
			(xy 378.406107 -283.506514) (xy 378.453378 -283.520206) (xy 378.49784 -283.541304) (xy 378.538343 -283.56926)
			(xy 378.573836 -283.603352) (xy 378.603401 -283.642696) (xy 378.626272 -283.686273) (xy 378.641856 -283.732954)
			(xy 378.649751 -283.781531) (xy 378.650246 -283.806138) (xy 378.968503 -283.806138) (xy 378.972598 -283.75541)
			(xy 378.984777 -283.705996) (xy 379.004725 -283.659176) (xy 379.031926 -283.616162) (xy 379.065674 -283.578068)
			(xy 379.105096 -283.545881) (xy 379.14917 -283.520435) (xy 379.196756 -283.502388) (xy 379.24662 -283.492208)
			(xy 379.297472 -283.490159) (xy 379.347993 -283.496293) (xy 379.396877 -283.510453) (xy 379.442856 -283.53227)
			(xy 379.48474 -283.56118) (xy 379.521444 -283.596435) (xy 379.552017 -283.637121) (xy 379.575668 -283.682184)
			(xy 379.591784 -283.730458) (xy 379.599948 -283.780692) (xy 379.60046 -283.806138) (xy 379.918988 -283.806138)
			(xy 379.922948 -283.757084) (xy 379.934725 -283.7093) (xy 379.954016 -283.664024) (xy 379.980319 -283.622428)
			(xy 380.012954 -283.585591) (xy 380.051075 -283.554466) (xy 380.093696 -283.529859) (xy 380.139712 -283.512407)
			(xy 380.187931 -283.502563) (xy 380.237106 -283.500582) (xy 380.285961 -283.506514) (xy 380.333232 -283.520206)
			(xy 380.377694 -283.541304) (xy 380.418197 -283.56926) (xy 380.45369 -283.603352) (xy 380.483255 -283.642696)
			(xy 380.506126 -283.686273) (xy 380.52171 -283.732954) (xy 380.529605 -283.781531) (xy 380.5301 -283.806138)
			(xy 380.848611 -283.806138) (xy 380.852706 -283.75541) (xy 380.864885 -283.705996) (xy 380.884833 -283.659176)
			(xy 380.912034 -283.616162) (xy 380.945782 -283.578068) (xy 380.985204 -283.545881) (xy 381.029278 -283.520435)
			(xy 381.076864 -283.502388) (xy 381.126728 -283.492208) (xy 381.17758 -283.490159) (xy 381.228101 -283.496293)
			(xy 381.276985 -283.510453) (xy 381.322964 -283.53227) (xy 381.364848 -283.56118) (xy 381.401552 -283.596435)
			(xy 381.432125 -283.637121) (xy 381.455776 -283.682184) (xy 381.471892 -283.730458) (xy 381.480056 -283.780692)
			(xy 381.480568 -283.806138) (xy 381.799096 -283.806138) (xy 381.803056 -283.757084) (xy 381.814833 -283.7093)
			(xy 381.834124 -283.664024) (xy 381.860427 -283.622428) (xy 381.893062 -283.585591) (xy 381.931183 -283.554466)
			(xy 381.973804 -283.529859) (xy 382.01982 -283.512407) (xy 382.068039 -283.502563) (xy 382.117214 -283.500582)
			(xy 382.166069 -283.506514) (xy 382.21334 -283.520206) (xy 382.257802 -283.541304) (xy 382.298305 -283.56926)
			(xy 382.333798 -283.603352) (xy 382.363363 -283.642696) (xy 382.386234 -283.686273) (xy 382.401818 -283.732954)
			(xy 382.409713 -283.781531) (xy 382.410208 -283.806138) (xy 382.738896 -283.806138) (xy 382.742856 -283.757084)
			(xy 382.754633 -283.7093) (xy 382.773924 -283.664024) (xy 382.800227 -283.622428) (xy 382.832862 -283.585591)
			(xy 382.870983 -283.554466) (xy 382.913604 -283.529859) (xy 382.95962 -283.512407) (xy 383.007839 -283.502563)
			(xy 383.057014 -283.500582) (xy 383.105869 -283.506514) (xy 383.15314 -283.520206) (xy 383.197602 -283.541304)
			(xy 383.238105 -283.56926) (xy 383.273598 -283.603352) (xy 383.303163 -283.642696) (xy 383.326034 -283.686273)
			(xy 383.341618 -283.732954) (xy 383.349513 -283.781531) (xy 383.350008 -283.806138) (xy 383.67895 -283.806138)
			(xy 383.68291 -283.757084) (xy 383.694687 -283.7093) (xy 383.713978 -283.664024) (xy 383.740281 -283.622428)
			(xy 383.772916 -283.585591) (xy 383.811037 -283.554466) (xy 383.853658 -283.529859) (xy 383.899674 -283.512407)
			(xy 383.947893 -283.502563) (xy 383.997068 -283.500582) (xy 384.045923 -283.506514) (xy 384.093194 -283.520206)
			(xy 384.137656 -283.541304) (xy 384.178159 -283.56926) (xy 384.213652 -283.603352) (xy 384.243217 -283.642696)
			(xy 384.266088 -283.686273) (xy 384.281672 -283.732954) (xy 384.289567 -283.781531) (xy 384.290062 -283.806138)
			(xy 384.619004 -283.806138) (xy 384.622964 -283.757084) (xy 384.634741 -283.7093) (xy 384.654032 -283.664024)
			(xy 384.680335 -283.622428) (xy 384.71297 -283.585591) (xy 384.751091 -283.554466) (xy 384.793712 -283.529859)
			(xy 384.839728 -283.512407) (xy 384.887947 -283.502563) (xy 384.937122 -283.500582) (xy 384.985977 -283.506514)
			(xy 385.033248 -283.520206) (xy 385.07771 -283.541304) (xy 385.118213 -283.56926) (xy 385.153706 -283.603352)
			(xy 385.183271 -283.642696) (xy 385.206142 -283.686273) (xy 385.221726 -283.732954) (xy 385.229621 -283.781531)
			(xy 385.230116 -283.806138) (xy 385.559058 -283.806138) (xy 385.563018 -283.757084) (xy 385.574795 -283.7093)
			(xy 385.594086 -283.664024) (xy 385.620389 -283.622428) (xy 385.653024 -283.585591) (xy 385.691145 -283.554466)
			(xy 385.733766 -283.529859) (xy 385.779782 -283.512407) (xy 385.828001 -283.502563) (xy 385.877176 -283.500582)
			(xy 385.926031 -283.506514) (xy 385.973302 -283.520206) (xy 386.017764 -283.541304) (xy 386.058267 -283.56926)
			(xy 386.09376 -283.603352) (xy 386.123325 -283.642696) (xy 386.146196 -283.686273) (xy 386.16178 -283.732954)
			(xy 386.169675 -283.781531) (xy 386.17017 -283.806138) (xy 386.499112 -283.806138) (xy 386.503072 -283.757084)
			(xy 386.514849 -283.7093) (xy 386.53414 -283.664024) (xy 386.560443 -283.622428) (xy 386.593078 -283.585591)
			(xy 386.631199 -283.554466) (xy 386.67382 -283.529859) (xy 386.719836 -283.512407) (xy 386.768055 -283.502563)
			(xy 386.81723 -283.500582) (xy 386.866085 -283.506514) (xy 386.913356 -283.520206) (xy 386.957818 -283.541304)
			(xy 386.998321 -283.56926) (xy 387.033814 -283.603352) (xy 387.063379 -283.642696) (xy 387.08625 -283.686273)
			(xy 387.101834 -283.732954) (xy 387.109729 -283.781531) (xy 387.110224 -283.806138) (xy 387.438912 -283.806138)
			(xy 387.442872 -283.757084) (xy 387.454649 -283.7093) (xy 387.47394 -283.664024) (xy 387.500243 -283.622428)
			(xy 387.532878 -283.585591) (xy 387.570999 -283.554466) (xy 387.61362 -283.529859) (xy 387.659636 -283.512407)
			(xy 387.707855 -283.502563) (xy 387.75703 -283.500582) (xy 387.805885 -283.506514) (xy 387.853156 -283.520206)
			(xy 387.897618 -283.541304) (xy 387.938121 -283.56926) (xy 387.973614 -283.603352) (xy 388.003179 -283.642696)
			(xy 388.02605 -283.686273) (xy 388.041634 -283.732954) (xy 388.049529 -283.781531) (xy 388.050024 -283.806138)
			(xy 388.049529 -283.830745) (xy 388.041634 -283.879322) (xy 388.02605 -283.926003) (xy 388.003179 -283.96958)
			(xy 387.973614 -284.008924) (xy 387.938121 -284.043016) (xy 387.897618 -284.070972) (xy 387.853156 -284.09207)
			(xy 387.805885 -284.105762) (xy 387.75703 -284.111694) (xy 387.707855 -284.109713) (xy 387.659636 -284.099869)
			(xy 387.61362 -284.082417) (xy 387.570999 -284.05781) (xy 387.532878 -284.026685) (xy 387.500243 -283.989848)
			(xy 387.47394 -283.948252) (xy 387.454649 -283.902976) (xy 387.442872 -283.855192) (xy 387.438912 -283.806138)
			(xy 387.110224 -283.806138) (xy 387.109729 -283.830745) (xy 387.101834 -283.879322) (xy 387.08625 -283.926003)
			(xy 387.063379 -283.96958) (xy 387.033814 -284.008924) (xy 386.998321 -284.043016) (xy 386.957818 -284.070972)
			(xy 386.913356 -284.09207) (xy 386.866085 -284.105762) (xy 386.81723 -284.111694) (xy 386.768055 -284.109713)
			(xy 386.719836 -284.099869) (xy 386.67382 -284.082417) (xy 386.631199 -284.05781) (xy 386.593078 -284.026685)
			(xy 386.560443 -283.989848) (xy 386.53414 -283.948252) (xy 386.514849 -283.902976) (xy 386.503072 -283.855192)
			(xy 386.499112 -283.806138) (xy 386.17017 -283.806138) (xy 386.169675 -283.830745) (xy 386.16178 -283.879322)
			(xy 386.146196 -283.926003) (xy 386.123325 -283.96958) (xy 386.09376 -284.008924) (xy 386.058267 -284.043016)
			(xy 386.017764 -284.070972) (xy 385.973302 -284.09207) (xy 385.926031 -284.105762) (xy 385.877176 -284.111694)
			(xy 385.828001 -284.109713) (xy 385.779782 -284.099869) (xy 385.733766 -284.082417) (xy 385.691145 -284.05781)
			(xy 385.653024 -284.026685) (xy 385.620389 -283.989848) (xy 385.594086 -283.948252) (xy 385.574795 -283.902976)
			(xy 385.563018 -283.855192) (xy 385.559058 -283.806138) (xy 385.230116 -283.806138) (xy 385.229621 -283.830745)
			(xy 385.221726 -283.879322) (xy 385.206142 -283.926003) (xy 385.183271 -283.96958) (xy 385.153706 -284.008924)
			(xy 385.118213 -284.043016) (xy 385.07771 -284.070972) (xy 385.033248 -284.09207) (xy 384.985977 -284.105762)
			(xy 384.937122 -284.111694) (xy 384.887947 -284.109713) (xy 384.839728 -284.099869) (xy 384.793712 -284.082417)
			(xy 384.751091 -284.05781) (xy 384.71297 -284.026685) (xy 384.680335 -283.989848) (xy 384.654032 -283.948252)
			(xy 384.634741 -283.902976) (xy 384.622964 -283.855192) (xy 384.619004 -283.806138) (xy 384.290062 -283.806138)
			(xy 384.289567 -283.830745) (xy 384.281672 -283.879322) (xy 384.266088 -283.926003) (xy 384.243217 -283.96958)
			(xy 384.213652 -284.008924) (xy 384.178159 -284.043016) (xy 384.137656 -284.070972) (xy 384.093194 -284.09207)
			(xy 384.045923 -284.105762) (xy 383.997068 -284.111694) (xy 383.947893 -284.109713) (xy 383.899674 -284.099869)
			(xy 383.853658 -284.082417) (xy 383.811037 -284.05781) (xy 383.772916 -284.026685) (xy 383.740281 -283.989848)
			(xy 383.713978 -283.948252) (xy 383.694687 -283.902976) (xy 383.68291 -283.855192) (xy 383.67895 -283.806138)
			(xy 383.350008 -283.806138) (xy 383.349513 -283.830745) (xy 383.341618 -283.879322) (xy 383.326034 -283.926003)
			(xy 383.303163 -283.96958) (xy 383.273598 -284.008924) (xy 383.238105 -284.043016) (xy 383.197602 -284.070972)
			(xy 383.15314 -284.09207) (xy 383.105869 -284.105762) (xy 383.057014 -284.111694) (xy 383.007839 -284.109713)
			(xy 382.95962 -284.099869) (xy 382.913604 -284.082417) (xy 382.870983 -284.05781) (xy 382.832862 -284.026685)
			(xy 382.800227 -283.989848) (xy 382.773924 -283.948252) (xy 382.754633 -283.902976) (xy 382.742856 -283.855192)
			(xy 382.738896 -283.806138) (xy 382.410208 -283.806138) (xy 382.409713 -283.830745) (xy 382.401818 -283.879322)
			(xy 382.386234 -283.926003) (xy 382.363363 -283.96958) (xy 382.333798 -284.008924) (xy 382.298305 -284.043016)
			(xy 382.257802 -284.070972) (xy 382.21334 -284.09207) (xy 382.166069 -284.105762) (xy 382.117214 -284.111694)
			(xy 382.068039 -284.109713) (xy 382.01982 -284.099869) (xy 381.973804 -284.082417) (xy 381.931183 -284.05781)
			(xy 381.893062 -284.026685) (xy 381.860427 -283.989848) (xy 381.834124 -283.948252) (xy 381.814833 -283.902976)
			(xy 381.803056 -283.855192) (xy 381.799096 -283.806138) (xy 381.480568 -283.806138) (xy 381.480056 -283.831584)
			(xy 381.471892 -283.881818) (xy 381.455776 -283.930092) (xy 381.432125 -283.975155) (xy 381.401552 -284.015841)
			(xy 381.364848 -284.051096) (xy 381.322964 -284.080006) (xy 381.276985 -284.101823) (xy 381.228101 -284.115983)
			(xy 381.17758 -284.122117) (xy 381.126728 -284.120068) (xy 381.076864 -284.109888) (xy 381.029278 -284.091841)
			(xy 380.985204 -284.066395) (xy 380.945782 -284.034208) (xy 380.912034 -283.996114) (xy 380.884833 -283.9531)
			(xy 380.864885 -283.90628) (xy 380.852706 -283.856866) (xy 380.848611 -283.806138) (xy 380.5301 -283.806138)
			(xy 380.529605 -283.830745) (xy 380.52171 -283.879322) (xy 380.506126 -283.926003) (xy 380.483255 -283.96958)
			(xy 380.45369 -284.008924) (xy 380.418197 -284.043016) (xy 380.377694 -284.070972) (xy 380.333232 -284.09207)
			(xy 380.285961 -284.105762) (xy 380.237106 -284.111694) (xy 380.187931 -284.109713) (xy 380.139712 -284.099869)
			(xy 380.093696 -284.082417) (xy 380.051075 -284.05781) (xy 380.012954 -284.026685) (xy 379.980319 -283.989848)
			(xy 379.954016 -283.948252) (xy 379.934725 -283.902976) (xy 379.922948 -283.855192) (xy 379.918988 -283.806138)
			(xy 379.60046 -283.806138) (xy 379.599948 -283.831584) (xy 379.591784 -283.881818) (xy 379.575668 -283.930092)
			(xy 379.552017 -283.975155) (xy 379.521444 -284.015841) (xy 379.48474 -284.051096) (xy 379.442856 -284.080006)
			(xy 379.396877 -284.101823) (xy 379.347993 -284.115983) (xy 379.297472 -284.122117) (xy 379.24662 -284.120068)
			(xy 379.196756 -284.109888) (xy 379.14917 -284.091841) (xy 379.105096 -284.066395) (xy 379.065674 -284.034208)
			(xy 379.031926 -283.996114) (xy 379.004725 -283.9531) (xy 378.984777 -283.90628) (xy 378.972598 -283.856866)
			(xy 378.968503 -283.806138) (xy 378.650246 -283.806138) (xy 378.649751 -283.830745) (xy 378.641856 -283.879322)
			(xy 378.626272 -283.926003) (xy 378.603401 -283.96958) (xy 378.573836 -284.008924) (xy 378.538343 -284.043016)
			(xy 378.49784 -284.070972) (xy 378.453378 -284.09207) (xy 378.406107 -284.105762) (xy 378.357252 -284.111694)
			(xy 378.308077 -284.109713) (xy 378.259858 -284.099869) (xy 378.213842 -284.082417) (xy 378.171221 -284.05781)
			(xy 378.1331 -284.026685) (xy 378.100465 -283.989848) (xy 378.074162 -283.948252) (xy 378.054871 -283.902976)
			(xy 378.043094 -283.855192) (xy 378.039134 -283.806138) (xy 377.720606 -283.806138) (xy 377.720094 -283.831584)
			(xy 377.71193 -283.881818) (xy 377.695814 -283.930092) (xy 377.672163 -283.975155) (xy 377.64159 -284.015841)
			(xy 377.604886 -284.051096) (xy 377.563002 -284.080006) (xy 377.517023 -284.101823) (xy 377.468139 -284.115983)
			(xy 377.417618 -284.122117) (xy 377.366766 -284.120068) (xy 377.316902 -284.109888) (xy 377.269316 -284.091841)
			(xy 377.225242 -284.066395) (xy 377.18582 -284.034208) (xy 377.152072 -283.996114) (xy 377.124871 -283.9531)
			(xy 377.104923 -283.90628) (xy 377.092744 -283.856866) (xy 377.088649 -283.806138) (xy 376.780552 -283.806138)
			(xy 376.78004 -283.831584) (xy 376.771876 -283.881818) (xy 376.75576 -283.930092) (xy 376.732109 -283.975155)
			(xy 376.701536 -284.015841) (xy 376.664832 -284.051096) (xy 376.622948 -284.080006) (xy 376.576969 -284.101823)
			(xy 376.528085 -284.115983) (xy 376.477564 -284.122117) (xy 376.426712 -284.120068) (xy 376.376848 -284.109888)
			(xy 376.329262 -284.091841) (xy 376.285188 -284.066395) (xy 376.245766 -284.034208) (xy 376.212018 -283.996114)
			(xy 376.184817 -283.9531) (xy 376.164869 -283.90628) (xy 376.15269 -283.856866) (xy 376.148595 -283.806138)
			(xy 375.830641 -283.806138) (xy 375.826568 -283.855862) (xy 375.814451 -283.904297) (xy 375.794614 -283.950116)
			(xy 375.767587 -283.992096) (xy 375.73409 -284.02912) (xy 375.695016 -284.0602) (xy 375.651405 -284.084509)
			(xy 375.60442 -284.101398) (xy 375.555313 -284.110418) (xy 375.530364 -284.111446) (xy 375.524268 -284.111446)
			(xy 375.499681 -284.110958) (xy 375.45115 -284.103028) (xy 375.404522 -284.087412) (xy 375.382536 -284.076394)
			(xy 375.376694 -284.073346) (xy 375.364248 -284.070552) (xy 375.358152 -284.070552) (xy 375.352388 -284.070881)
			(xy 375.341232 -284.073839) (xy 375.336054 -284.076394) (xy 375.315734 -284.088586) (xy 375.260108 -284.122114)
			(xy 375.252939 -284.126825) (xy 375.242064 -284.140076) (xy 375.236286 -284.156215) (xy 375.235978 -284.164786)
			(xy 375.235978 -284.335474) (xy 375.236994 -284.345634) (xy 375.24055 -284.356556) (xy 375.25325 -284.383988)
			(xy 375.260616 -284.390592) (xy 375.280672 -284.409646) (xy 375.314218 -284.453628) (xy 375.339295 -284.502933)
			(xy 375.347738 -284.529276) (xy 375.349008 -284.534102) (xy 375.351548 -284.543754) (xy 375.351548 -284.544262)
			(xy 375.353649 -284.552998) (xy 375.356951 -284.570663) (xy 375.358152 -284.579568) (xy 375.358914 -284.584902)
			(xy 375.369836 -284.607762) (xy 375.371806 -284.611693) (xy 375.37498 -284.616144) (xy 375.678695 -284.616144)
			(xy 375.68279 -284.565416) (xy 375.694969 -284.516002) (xy 375.714917 -284.469182) (xy 375.742118 -284.426168)
			(xy 375.775866 -284.388074) (xy 375.815288 -284.355887) (xy 375.859362 -284.330441) (xy 375.906948 -284.312394)
			(xy 375.956812 -284.302214) (xy 376.007664 -284.300165) (xy 376.058185 -284.306299) (xy 376.107069 -284.320459)
			(xy 376.153048 -284.342276) (xy 376.194932 -284.371186) (xy 376.231636 -284.406441) (xy 376.262209 -284.447127)
			(xy 376.28586 -284.49219) (xy 376.301976 -284.540464) (xy 376.31014 -284.590698) (xy 376.310652 -284.616144)
			(xy 376.628926 -284.616144) (xy 376.632886 -284.56709) (xy 376.644663 -284.519306) (xy 376.663954 -284.47403)
			(xy 376.690257 -284.432434) (xy 376.722892 -284.395597) (xy 376.761013 -284.364472) (xy 376.803634 -284.339865)
			(xy 376.84965 -284.322413) (xy 376.897869 -284.312569) (xy 376.947044 -284.310588) (xy 376.995899 -284.31652)
			(xy 377.04317 -284.330212) (xy 377.087632 -284.35131) (xy 377.128135 -284.379266) (xy 377.163628 -284.413358)
			(xy 377.193193 -284.452702) (xy 377.216064 -284.496279) (xy 377.231648 -284.54296) (xy 377.239543 -284.591537)
			(xy 377.240038 -284.616144) (xy 377.558549 -284.616144) (xy 377.562644 -284.565416) (xy 377.574823 -284.516002)
			(xy 377.594771 -284.469182) (xy 377.621972 -284.426168) (xy 377.65572 -284.388074) (xy 377.695142 -284.355887)
			(xy 377.739216 -284.330441) (xy 377.786802 -284.312394) (xy 377.836666 -284.302214) (xy 377.887518 -284.300165)
			(xy 377.938039 -284.306299) (xy 377.986923 -284.320459) (xy 378.032902 -284.342276) (xy 378.074786 -284.371186)
			(xy 378.11149 -284.406441) (xy 378.142063 -284.447127) (xy 378.165714 -284.49219) (xy 378.18183 -284.540464)
			(xy 378.189994 -284.590698) (xy 378.190506 -284.616144) (xy 378.509034 -284.616144) (xy 378.512994 -284.56709)
			(xy 378.524771 -284.519306) (xy 378.544062 -284.47403) (xy 378.570365 -284.432434) (xy 378.603 -284.395597)
			(xy 378.641121 -284.364472) (xy 378.683742 -284.339865) (xy 378.729758 -284.322413) (xy 378.777977 -284.312569)
			(xy 378.827152 -284.310588) (xy 378.876007 -284.31652) (xy 378.923278 -284.330212) (xy 378.96774 -284.35131)
			(xy 379.008243 -284.379266) (xy 379.043736 -284.413358) (xy 379.073301 -284.452702) (xy 379.096172 -284.496279)
			(xy 379.111756 -284.54296) (xy 379.119651 -284.591537) (xy 379.120146 -284.616144) (xy 379.438657 -284.616144)
			(xy 379.442752 -284.565416) (xy 379.454931 -284.516002) (xy 379.474879 -284.469182) (xy 379.50208 -284.426168)
			(xy 379.535828 -284.388074) (xy 379.57525 -284.355887) (xy 379.619324 -284.330441) (xy 379.66691 -284.312394)
			(xy 379.716774 -284.302214) (xy 379.767626 -284.300165) (xy 379.818147 -284.306299) (xy 379.867031 -284.320459)
			(xy 379.91301 -284.342276) (xy 379.954894 -284.371186) (xy 379.991598 -284.406441) (xy 380.022171 -284.447127)
			(xy 380.045822 -284.49219) (xy 380.061938 -284.540464) (xy 380.070102 -284.590698) (xy 380.070614 -284.616144)
			(xy 380.378711 -284.616144) (xy 380.382806 -284.565416) (xy 380.394985 -284.516002) (xy 380.414933 -284.469182)
			(xy 380.442134 -284.426168) (xy 380.475882 -284.388074) (xy 380.515304 -284.355887) (xy 380.559378 -284.330441)
			(xy 380.606964 -284.312394) (xy 380.656828 -284.302214) (xy 380.70768 -284.300165) (xy 380.758201 -284.306299)
			(xy 380.807085 -284.320459) (xy 380.853064 -284.342276) (xy 380.894948 -284.371186) (xy 380.931652 -284.406441)
			(xy 380.962225 -284.447127) (xy 380.985876 -284.49219) (xy 381.001992 -284.540464) (xy 381.010156 -284.590698)
			(xy 381.010668 -284.616144) (xy 381.328942 -284.616144) (xy 381.332902 -284.56709) (xy 381.344679 -284.519306)
			(xy 381.36397 -284.47403) (xy 381.390273 -284.432434) (xy 381.422908 -284.395597) (xy 381.461029 -284.364472)
			(xy 381.50365 -284.339865) (xy 381.549666 -284.322413) (xy 381.597885 -284.312569) (xy 381.64706 -284.310588)
			(xy 381.695915 -284.31652) (xy 381.743186 -284.330212) (xy 381.787648 -284.35131) (xy 381.828151 -284.379266)
			(xy 381.863644 -284.413358) (xy 381.893209 -284.452702) (xy 381.91608 -284.496279) (xy 381.931664 -284.54296)
			(xy 381.939559 -284.591537) (xy 381.940054 -284.616144) (xy 382.268996 -284.616144) (xy 382.272956 -284.56709)
			(xy 382.284733 -284.519306) (xy 382.304024 -284.47403) (xy 382.330327 -284.432434) (xy 382.362962 -284.395597)
			(xy 382.401083 -284.364472) (xy 382.443704 -284.339865) (xy 382.48972 -284.322413) (xy 382.537939 -284.312569)
			(xy 382.587114 -284.310588) (xy 382.635969 -284.31652) (xy 382.68324 -284.330212) (xy 382.727702 -284.35131)
			(xy 382.768205 -284.379266) (xy 382.803698 -284.413358) (xy 382.833263 -284.452702) (xy 382.856134 -284.496279)
			(xy 382.871718 -284.54296) (xy 382.879613 -284.591537) (xy 382.880108 -284.616144) (xy 383.20905 -284.616144)
			(xy 383.21301 -284.56709) (xy 383.224787 -284.519306) (xy 383.244078 -284.47403) (xy 383.270381 -284.432434)
			(xy 383.303016 -284.395597) (xy 383.341137 -284.364472) (xy 383.383758 -284.339865) (xy 383.429774 -284.322413)
			(xy 383.477993 -284.312569) (xy 383.527168 -284.310588) (xy 383.576023 -284.31652) (xy 383.623294 -284.330212)
			(xy 383.667756 -284.35131) (xy 383.708259 -284.379266) (xy 383.743752 -284.413358) (xy 383.773317 -284.452702)
			(xy 383.796188 -284.496279) (xy 383.811772 -284.54296) (xy 383.819667 -284.591537) (xy 383.820162 -284.616144)
			(xy 384.149104 -284.616144) (xy 384.153064 -284.56709) (xy 384.164841 -284.519306) (xy 384.184132 -284.47403)
			(xy 384.210435 -284.432434) (xy 384.24307 -284.395597) (xy 384.281191 -284.364472) (xy 384.323812 -284.339865)
			(xy 384.369828 -284.322413) (xy 384.418047 -284.312569) (xy 384.467222 -284.310588) (xy 384.516077 -284.31652)
			(xy 384.563348 -284.330212) (xy 384.60781 -284.35131) (xy 384.648313 -284.379266) (xy 384.683806 -284.413358)
			(xy 384.713371 -284.452702) (xy 384.736242 -284.496279) (xy 384.751826 -284.54296) (xy 384.759721 -284.591537)
			(xy 384.760216 -284.616144) (xy 385.088904 -284.616144) (xy 385.092864 -284.56709) (xy 385.104641 -284.519306)
			(xy 385.123932 -284.47403) (xy 385.150235 -284.432434) (xy 385.18287 -284.395597) (xy 385.220991 -284.364472)
			(xy 385.263612 -284.339865) (xy 385.309628 -284.322413) (xy 385.357847 -284.312569) (xy 385.407022 -284.310588)
			(xy 385.455877 -284.31652) (xy 385.503148 -284.330212) (xy 385.54761 -284.35131) (xy 385.588113 -284.379266)
			(xy 385.623606 -284.413358) (xy 385.653171 -284.452702) (xy 385.676042 -284.496279) (xy 385.691626 -284.54296)
			(xy 385.699521 -284.591537) (xy 385.700016 -284.616144) (xy 386.028958 -284.616144) (xy 386.032918 -284.56709)
			(xy 386.044695 -284.519306) (xy 386.063986 -284.47403) (xy 386.090289 -284.432434) (xy 386.122924 -284.395597)
			(xy 386.161045 -284.364472) (xy 386.203666 -284.339865) (xy 386.249682 -284.322413) (xy 386.297901 -284.312569)
			(xy 386.347076 -284.310588) (xy 386.395931 -284.31652) (xy 386.443202 -284.330212) (xy 386.487664 -284.35131)
			(xy 386.528167 -284.379266) (xy 386.56366 -284.413358) (xy 386.593225 -284.452702) (xy 386.616096 -284.496279)
			(xy 386.63168 -284.54296) (xy 386.639575 -284.591537) (xy 386.64007 -284.616144) (xy 386.969012 -284.616144)
			(xy 386.972972 -284.56709) (xy 386.984749 -284.519306) (xy 387.00404 -284.47403) (xy 387.030343 -284.432434)
			(xy 387.062978 -284.395597) (xy 387.101099 -284.364472) (xy 387.14372 -284.339865) (xy 387.189736 -284.322413)
			(xy 387.237955 -284.312569) (xy 387.28713 -284.310588) (xy 387.335985 -284.31652) (xy 387.383256 -284.330212)
			(xy 387.427718 -284.35131) (xy 387.468221 -284.379266) (xy 387.503714 -284.413358) (xy 387.533279 -284.452702)
			(xy 387.55615 -284.496279) (xy 387.571734 -284.54296) (xy 387.579629 -284.591537) (xy 387.580124 -284.616144)
			(xy 387.579629 -284.640751) (xy 387.571734 -284.689328) (xy 387.55615 -284.736009) (xy 387.533279 -284.779586)
			(xy 387.503714 -284.81893) (xy 387.468221 -284.853022) (xy 387.427718 -284.880978) (xy 387.383256 -284.902076)
			(xy 387.335985 -284.915768) (xy 387.28713 -284.9217) (xy 387.237955 -284.919719) (xy 387.189736 -284.909875)
			(xy 387.14372 -284.892423) (xy 387.101099 -284.867816) (xy 387.062978 -284.836691) (xy 387.030343 -284.799854)
			(xy 387.00404 -284.758258) (xy 386.984749 -284.712982) (xy 386.972972 -284.665198) (xy 386.969012 -284.616144)
			(xy 386.64007 -284.616144) (xy 386.639575 -284.640751) (xy 386.63168 -284.689328) (xy 386.616096 -284.736009)
			(xy 386.593225 -284.779586) (xy 386.56366 -284.81893) (xy 386.528167 -284.853022) (xy 386.487664 -284.880978)
			(xy 386.443202 -284.902076) (xy 386.395931 -284.915768) (xy 386.347076 -284.9217) (xy 386.297901 -284.919719)
			(xy 386.249682 -284.909875) (xy 386.203666 -284.892423) (xy 386.161045 -284.867816) (xy 386.122924 -284.836691)
			(xy 386.090289 -284.799854) (xy 386.063986 -284.758258) (xy 386.044695 -284.712982) (xy 386.032918 -284.665198)
			(xy 386.028958 -284.616144) (xy 385.700016 -284.616144) (xy 385.699521 -284.640751) (xy 385.691626 -284.689328)
			(xy 385.676042 -284.736009) (xy 385.653171 -284.779586) (xy 385.623606 -284.81893) (xy 385.588113 -284.853022)
			(xy 385.54761 -284.880978) (xy 385.503148 -284.902076) (xy 385.455877 -284.915768) (xy 385.407022 -284.9217)
			(xy 385.357847 -284.919719) (xy 385.309628 -284.909875) (xy 385.263612 -284.892423) (xy 385.220991 -284.867816)
			(xy 385.18287 -284.836691) (xy 385.150235 -284.799854) (xy 385.123932 -284.758258) (xy 385.104641 -284.712982)
			(xy 385.092864 -284.665198) (xy 385.088904 -284.616144) (xy 384.760216 -284.616144) (xy 384.759721 -284.640751)
			(xy 384.751826 -284.689328) (xy 384.736242 -284.736009) (xy 384.713371 -284.779586) (xy 384.683806 -284.81893)
			(xy 384.648313 -284.853022) (xy 384.60781 -284.880978) (xy 384.563348 -284.902076) (xy 384.516077 -284.915768)
			(xy 384.467222 -284.9217) (xy 384.418047 -284.919719) (xy 384.369828 -284.909875) (xy 384.323812 -284.892423)
			(xy 384.281191 -284.867816) (xy 384.24307 -284.836691) (xy 384.210435 -284.799854) (xy 384.184132 -284.758258)
			(xy 384.164841 -284.712982) (xy 384.153064 -284.665198) (xy 384.149104 -284.616144) (xy 383.820162 -284.616144)
			(xy 383.819667 -284.640751) (xy 383.811772 -284.689328) (xy 383.796188 -284.736009) (xy 383.773317 -284.779586)
			(xy 383.743752 -284.81893) (xy 383.708259 -284.853022) (xy 383.667756 -284.880978) (xy 383.623294 -284.902076)
			(xy 383.576023 -284.915768) (xy 383.527168 -284.9217) (xy 383.477993 -284.919719) (xy 383.429774 -284.909875)
			(xy 383.383758 -284.892423) (xy 383.341137 -284.867816) (xy 383.303016 -284.836691) (xy 383.270381 -284.799854)
			(xy 383.244078 -284.758258) (xy 383.224787 -284.712982) (xy 383.21301 -284.665198) (xy 383.20905 -284.616144)
			(xy 382.880108 -284.616144) (xy 382.879613 -284.640751) (xy 382.871718 -284.689328) (xy 382.856134 -284.736009)
			(xy 382.833263 -284.779586) (xy 382.803698 -284.81893) (xy 382.768205 -284.853022) (xy 382.727702 -284.880978)
			(xy 382.68324 -284.902076) (xy 382.635969 -284.915768) (xy 382.587114 -284.9217) (xy 382.537939 -284.919719)
			(xy 382.48972 -284.909875) (xy 382.443704 -284.892423) (xy 382.401083 -284.867816) (xy 382.362962 -284.836691)
			(xy 382.330327 -284.799854) (xy 382.304024 -284.758258) (xy 382.284733 -284.712982) (xy 382.272956 -284.665198)
			(xy 382.268996 -284.616144) (xy 381.940054 -284.616144) (xy 381.939559 -284.640751) (xy 381.931664 -284.689328)
			(xy 381.91608 -284.736009) (xy 381.893209 -284.779586) (xy 381.863644 -284.81893) (xy 381.828151 -284.853022)
			(xy 381.787648 -284.880978) (xy 381.743186 -284.902076) (xy 381.695915 -284.915768) (xy 381.64706 -284.9217)
			(xy 381.597885 -284.919719) (xy 381.549666 -284.909875) (xy 381.50365 -284.892423) (xy 381.461029 -284.867816)
			(xy 381.422908 -284.836691) (xy 381.390273 -284.799854) (xy 381.36397 -284.758258) (xy 381.344679 -284.712982)
			(xy 381.332902 -284.665198) (xy 381.328942 -284.616144) (xy 381.010668 -284.616144) (xy 381.010156 -284.64159)
			(xy 381.001992 -284.691824) (xy 380.985876 -284.740098) (xy 380.962225 -284.785161) (xy 380.931652 -284.825847)
			(xy 380.894948 -284.861102) (xy 380.853064 -284.890012) (xy 380.807085 -284.911829) (xy 380.758201 -284.925989)
			(xy 380.70768 -284.932123) (xy 380.656828 -284.930074) (xy 380.606964 -284.919894) (xy 380.559378 -284.901847)
			(xy 380.515304 -284.876401) (xy 380.475882 -284.844214) (xy 380.442134 -284.80612) (xy 380.414933 -284.763106)
			(xy 380.394985 -284.716286) (xy 380.382806 -284.666872) (xy 380.378711 -284.616144) (xy 380.070614 -284.616144)
			(xy 380.070102 -284.64159) (xy 380.061938 -284.691824) (xy 380.045822 -284.740098) (xy 380.022171 -284.785161)
			(xy 379.991598 -284.825847) (xy 379.954894 -284.861102) (xy 379.91301 -284.890012) (xy 379.867031 -284.911829)
			(xy 379.818147 -284.925989) (xy 379.767626 -284.932123) (xy 379.716774 -284.930074) (xy 379.66691 -284.919894)
			(xy 379.619324 -284.901847) (xy 379.57525 -284.876401) (xy 379.535828 -284.844214) (xy 379.50208 -284.80612)
			(xy 379.474879 -284.763106) (xy 379.454931 -284.716286) (xy 379.442752 -284.666872) (xy 379.438657 -284.616144)
			(xy 379.120146 -284.616144) (xy 379.119651 -284.640751) (xy 379.111756 -284.689328) (xy 379.096172 -284.736009)
			(xy 379.073301 -284.779586) (xy 379.043736 -284.81893) (xy 379.008243 -284.853022) (xy 378.96774 -284.880978)
			(xy 378.923278 -284.902076) (xy 378.876007 -284.915768) (xy 378.827152 -284.9217) (xy 378.777977 -284.919719)
			(xy 378.729758 -284.909875) (xy 378.683742 -284.892423) (xy 378.641121 -284.867816) (xy 378.603 -284.836691)
			(xy 378.570365 -284.799854) (xy 378.544062 -284.758258) (xy 378.524771 -284.712982) (xy 378.512994 -284.665198)
			(xy 378.509034 -284.616144) (xy 378.190506 -284.616144) (xy 378.189994 -284.64159) (xy 378.18183 -284.691824)
			(xy 378.165714 -284.740098) (xy 378.142063 -284.785161) (xy 378.11149 -284.825847) (xy 378.074786 -284.861102)
			(xy 378.032902 -284.890012) (xy 377.986923 -284.911829) (xy 377.938039 -284.925989) (xy 377.887518 -284.932123)
			(xy 377.836666 -284.930074) (xy 377.786802 -284.919894) (xy 377.739216 -284.901847) (xy 377.695142 -284.876401)
			(xy 377.65572 -284.844214) (xy 377.621972 -284.80612) (xy 377.594771 -284.763106) (xy 377.574823 -284.716286)
			(xy 377.562644 -284.666872) (xy 377.558549 -284.616144) (xy 377.240038 -284.616144) (xy 377.239543 -284.640751)
			(xy 377.231648 -284.689328) (xy 377.216064 -284.736009) (xy 377.193193 -284.779586) (xy 377.163628 -284.81893)
			(xy 377.128135 -284.853022) (xy 377.087632 -284.880978) (xy 377.04317 -284.902076) (xy 376.995899 -284.915768)
			(xy 376.947044 -284.9217) (xy 376.897869 -284.919719) (xy 376.84965 -284.909875) (xy 376.803634 -284.892423)
			(xy 376.761013 -284.867816) (xy 376.722892 -284.836691) (xy 376.690257 -284.799854) (xy 376.663954 -284.758258)
			(xy 376.644663 -284.712982) (xy 376.632886 -284.665198) (xy 376.628926 -284.616144) (xy 376.310652 -284.616144)
			(xy 376.31014 -284.64159) (xy 376.301976 -284.691824) (xy 376.28586 -284.740098) (xy 376.262209 -284.785161)
			(xy 376.231636 -284.825847) (xy 376.194932 -284.861102) (xy 376.153048 -284.890012) (xy 376.107069 -284.911829)
			(xy 376.058185 -284.925989) (xy 376.007664 -284.932123) (xy 375.956812 -284.930074) (xy 375.906948 -284.919894)
			(xy 375.859362 -284.901847) (xy 375.815288 -284.876401) (xy 375.775866 -284.844214) (xy 375.742118 -284.80612)
			(xy 375.714917 -284.763106) (xy 375.694969 -284.716286) (xy 375.68279 -284.666872) (xy 375.678695 -284.616144)
			(xy 375.37498 -284.616144) (xy 375.376911 -284.618853) (xy 375.379996 -284.621986) (xy 375.421276 -284.663898)
			(xy 375.495848 -284.75489) (xy 375.52884 -284.803596) (xy 375.552211 -284.839783) (xy 375.594019 -284.915111)
			(xy 375.629976 -284.993402) (xy 375.659872 -285.074201) (xy 375.672096 -285.115508) (xy 375.675112 -285.123052)
			(xy 375.685091 -285.135863) (xy 375.691654 -285.140654) (xy 375.712653 -285.153423) (xy 375.750966 -285.184198)
			(xy 375.784296 -285.220313) (xy 375.811905 -285.260967) (xy 375.833183 -285.305265) (xy 375.847662 -285.352228)
			(xy 375.855021 -285.400817) (xy 375.855484 -285.425388) (xy 375.855484 -285.425896) (xy 375.855484 -285.42615)
			(xy 376.148595 -285.42615) (xy 376.15269 -285.375422) (xy 376.164869 -285.326008) (xy 376.184817 -285.279188)
			(xy 376.212018 -285.236174) (xy 376.245766 -285.19808) (xy 376.285188 -285.165893) (xy 376.329262 -285.140447)
			(xy 376.376848 -285.1224) (xy 376.426712 -285.11222) (xy 376.477564 -285.110171) (xy 376.528085 -285.116305)
			(xy 376.576969 -285.130465) (xy 376.622948 -285.152282) (xy 376.664832 -285.181192) (xy 376.701536 -285.216447)
			(xy 376.732109 -285.257133) (xy 376.75576 -285.302196) (xy 376.771876 -285.35047) (xy 376.78004 -285.400704)
			(xy 376.780552 -285.42615) (xy 377.088649 -285.42615) (xy 377.092744 -285.375422) (xy 377.104923 -285.326008)
			(xy 377.124871 -285.279188) (xy 377.152072 -285.236174) (xy 377.18582 -285.19808) (xy 377.225242 -285.165893)
			(xy 377.269316 -285.140447) (xy 377.316902 -285.1224) (xy 377.366766 -285.11222) (xy 377.417618 -285.110171)
			(xy 377.468139 -285.116305) (xy 377.517023 -285.130465) (xy 377.563002 -285.152282) (xy 377.604886 -285.181192)
			(xy 377.64159 -285.216447) (xy 377.672163 -285.257133) (xy 377.695814 -285.302196) (xy 377.71193 -285.35047)
			(xy 377.720094 -285.400704) (xy 377.720606 -285.42615) (xy 378.968503 -285.42615) (xy 378.972598 -285.375422)
			(xy 378.984777 -285.326008) (xy 379.004725 -285.279188) (xy 379.031926 -285.236174) (xy 379.065674 -285.19808)
			(xy 379.105096 -285.165893) (xy 379.14917 -285.140447) (xy 379.196756 -285.1224) (xy 379.24662 -285.11222)
			(xy 379.297472 -285.110171) (xy 379.347993 -285.116305) (xy 379.396877 -285.130465) (xy 379.442856 -285.152282)
			(xy 379.48474 -285.181192) (xy 379.521444 -285.216447) (xy 379.552017 -285.257133) (xy 379.575668 -285.302196)
			(xy 379.591784 -285.35047) (xy 379.599948 -285.400704) (xy 379.60046 -285.42615) (xy 379.918988 -285.42615)
			(xy 379.922948 -285.377096) (xy 379.934725 -285.329312) (xy 379.954016 -285.284036) (xy 379.980319 -285.24244)
			(xy 380.012954 -285.205603) (xy 380.051075 -285.174478) (xy 380.093696 -285.149871) (xy 380.139712 -285.132419)
			(xy 380.187931 -285.122575) (xy 380.237106 -285.120594) (xy 380.285961 -285.126526) (xy 380.333232 -285.140218)
			(xy 380.377694 -285.161316) (xy 380.418197 -285.189272) (xy 380.45369 -285.223364) (xy 380.483255 -285.262708)
			(xy 380.506126 -285.306285) (xy 380.52171 -285.352966) (xy 380.529605 -285.401543) (xy 380.5301 -285.42615)
			(xy 380.848611 -285.42615) (xy 380.852706 -285.375422) (xy 380.864885 -285.326008) (xy 380.884833 -285.279188)
			(xy 380.912034 -285.236174) (xy 380.945782 -285.19808) (xy 380.985204 -285.165893) (xy 381.029278 -285.140447)
			(xy 381.076864 -285.1224) (xy 381.126728 -285.11222) (xy 381.17758 -285.110171) (xy 381.228101 -285.116305)
			(xy 381.276985 -285.130465) (xy 381.322964 -285.152282) (xy 381.364848 -285.181192) (xy 381.401552 -285.216447)
			(xy 381.432125 -285.257133) (xy 381.455776 -285.302196) (xy 381.471892 -285.35047) (xy 381.480056 -285.400704)
			(xy 381.480568 -285.42615) (xy 381.799096 -285.42615) (xy 381.803056 -285.377096) (xy 381.814833 -285.329312)
			(xy 381.834124 -285.284036) (xy 381.860427 -285.24244) (xy 381.893062 -285.205603) (xy 381.931183 -285.174478)
			(xy 381.973804 -285.149871) (xy 382.01982 -285.132419) (xy 382.068039 -285.122575) (xy 382.117214 -285.120594)
			(xy 382.166069 -285.126526) (xy 382.21334 -285.140218) (xy 382.257802 -285.161316) (xy 382.298305 -285.189272)
			(xy 382.333798 -285.223364) (xy 382.363363 -285.262708) (xy 382.386234 -285.306285) (xy 382.401818 -285.352966)
			(xy 382.409713 -285.401543) (xy 382.410208 -285.42615) (xy 382.738896 -285.42615) (xy 382.742856 -285.377096)
			(xy 382.754633 -285.329312) (xy 382.773924 -285.284036) (xy 382.800227 -285.24244) (xy 382.832862 -285.205603)
			(xy 382.870983 -285.174478) (xy 382.913604 -285.149871) (xy 382.95962 -285.132419) (xy 383.007839 -285.122575)
			(xy 383.057014 -285.120594) (xy 383.105869 -285.126526) (xy 383.15314 -285.140218) (xy 383.197602 -285.161316)
			(xy 383.238105 -285.189272) (xy 383.273598 -285.223364) (xy 383.303163 -285.262708) (xy 383.326034 -285.306285)
			(xy 383.341618 -285.352966) (xy 383.349513 -285.401543) (xy 383.350008 -285.42615) (xy 383.67895 -285.42615)
			(xy 383.68291 -285.377096) (xy 383.694687 -285.329312) (xy 383.713978 -285.284036) (xy 383.740281 -285.24244)
			(xy 383.772916 -285.205603) (xy 383.811037 -285.174478) (xy 383.853658 -285.149871) (xy 383.899674 -285.132419)
			(xy 383.947893 -285.122575) (xy 383.997068 -285.120594) (xy 384.045923 -285.126526) (xy 384.093194 -285.140218)
			(xy 384.137656 -285.161316) (xy 384.178159 -285.189272) (xy 384.213652 -285.223364) (xy 384.243217 -285.262708)
			(xy 384.266088 -285.306285) (xy 384.281672 -285.352966) (xy 384.289567 -285.401543) (xy 384.290062 -285.42615)
			(xy 385.559058 -285.42615) (xy 385.563018 -285.377096) (xy 385.574795 -285.329312) (xy 385.594086 -285.284036)
			(xy 385.620389 -285.24244) (xy 385.653024 -285.205603) (xy 385.691145 -285.174478) (xy 385.733766 -285.149871)
			(xy 385.779782 -285.132419) (xy 385.828001 -285.122575) (xy 385.877176 -285.120594) (xy 385.926031 -285.126526)
			(xy 385.973302 -285.140218) (xy 386.017764 -285.161316) (xy 386.058267 -285.189272) (xy 386.09376 -285.223364)
			(xy 386.123325 -285.262708) (xy 386.146196 -285.306285) (xy 386.16178 -285.352966) (xy 386.169675 -285.401543)
			(xy 386.17017 -285.42615) (xy 386.499112 -285.42615) (xy 386.503072 -285.377096) (xy 386.514849 -285.329312)
			(xy 386.53414 -285.284036) (xy 386.560443 -285.24244) (xy 386.593078 -285.205603) (xy 386.631199 -285.174478)
			(xy 386.67382 -285.149871) (xy 386.719836 -285.132419) (xy 386.768055 -285.122575) (xy 386.81723 -285.120594)
			(xy 386.866085 -285.126526) (xy 386.913356 -285.140218) (xy 386.957818 -285.161316) (xy 386.998321 -285.189272)
			(xy 387.033814 -285.223364) (xy 387.063379 -285.262708) (xy 387.08625 -285.306285) (xy 387.101834 -285.352966)
			(xy 387.109729 -285.401543) (xy 387.110224 -285.42615) (xy 387.438912 -285.42615) (xy 387.442872 -285.377096)
			(xy 387.454649 -285.329312) (xy 387.47394 -285.284036) (xy 387.500243 -285.24244) (xy 387.532878 -285.205603)
			(xy 387.570999 -285.174478) (xy 387.61362 -285.149871) (xy 387.659636 -285.132419) (xy 387.707855 -285.122575)
			(xy 387.75703 -285.120594) (xy 387.805885 -285.126526) (xy 387.853156 -285.140218) (xy 387.897618 -285.161316)
			(xy 387.938121 -285.189272) (xy 387.973614 -285.223364) (xy 388.003179 -285.262708) (xy 388.02605 -285.306285)
			(xy 388.041634 -285.352966) (xy 388.049529 -285.401543) (xy 388.050024 -285.42615) (xy 388.049529 -285.450757)
			(xy 388.041634 -285.499334) (xy 388.02605 -285.546015) (xy 388.003179 -285.589592) (xy 387.973614 -285.628936)
			(xy 387.938121 -285.663028) (xy 387.897618 -285.690984) (xy 387.853156 -285.712082) (xy 387.805885 -285.725774)
			(xy 387.75703 -285.731706) (xy 387.707855 -285.729725) (xy 387.659636 -285.719881) (xy 387.61362 -285.702429)
			(xy 387.570999 -285.677822) (xy 387.532878 -285.646697) (xy 387.500243 -285.60986) (xy 387.47394 -285.568264)
			(xy 387.454649 -285.522988) (xy 387.442872 -285.475204) (xy 387.438912 -285.42615) (xy 387.110224 -285.42615)
			(xy 387.109729 -285.450757) (xy 387.101834 -285.499334) (xy 387.08625 -285.546015) (xy 387.063379 -285.589592)
			(xy 387.033814 -285.628936) (xy 386.998321 -285.663028) (xy 386.957818 -285.690984) (xy 386.913356 -285.712082)
			(xy 386.866085 -285.725774) (xy 386.81723 -285.731706) (xy 386.768055 -285.729725) (xy 386.719836 -285.719881)
			(xy 386.67382 -285.702429) (xy 386.631199 -285.677822) (xy 386.593078 -285.646697) (xy 386.560443 -285.60986)
			(xy 386.53414 -285.568264) (xy 386.514849 -285.522988) (xy 386.503072 -285.475204) (xy 386.499112 -285.42615)
			(xy 386.17017 -285.42615) (xy 386.169675 -285.450757) (xy 386.16178 -285.499334) (xy 386.146196 -285.546015)
			(xy 386.123325 -285.589592) (xy 386.09376 -285.628936) (xy 386.058267 -285.663028) (xy 386.017764 -285.690984)
			(xy 385.973302 -285.712082) (xy 385.926031 -285.725774) (xy 385.877176 -285.731706) (xy 385.828001 -285.729725)
			(xy 385.779782 -285.719881) (xy 385.733766 -285.702429) (xy 385.691145 -285.677822) (xy 385.653024 -285.646697)
			(xy 385.620389 -285.60986) (xy 385.594086 -285.568264) (xy 385.574795 -285.522988) (xy 385.563018 -285.475204)
			(xy 385.559058 -285.42615) (xy 384.290062 -285.42615) (xy 384.289567 -285.450757) (xy 384.281672 -285.499334)
			(xy 384.266088 -285.546015) (xy 384.243217 -285.589592) (xy 384.213652 -285.628936) (xy 384.178159 -285.663028)
			(xy 384.137656 -285.690984) (xy 384.093194 -285.712082) (xy 384.045923 -285.725774) (xy 383.997068 -285.731706)
			(xy 383.947893 -285.729725) (xy 383.899674 -285.719881) (xy 383.853658 -285.702429) (xy 383.811037 -285.677822)
			(xy 383.772916 -285.646697) (xy 383.740281 -285.60986) (xy 383.713978 -285.568264) (xy 383.694687 -285.522988)
			(xy 383.68291 -285.475204) (xy 383.67895 -285.42615) (xy 383.350008 -285.42615) (xy 383.349513 -285.450757)
			(xy 383.341618 -285.499334) (xy 383.326034 -285.546015) (xy 383.303163 -285.589592) (xy 383.273598 -285.628936)
			(xy 383.238105 -285.663028) (xy 383.197602 -285.690984) (xy 383.15314 -285.712082) (xy 383.105869 -285.725774)
			(xy 383.057014 -285.731706) (xy 383.007839 -285.729725) (xy 382.95962 -285.719881) (xy 382.913604 -285.702429)
			(xy 382.870983 -285.677822) (xy 382.832862 -285.646697) (xy 382.800227 -285.60986) (xy 382.773924 -285.568264)
			(xy 382.754633 -285.522988) (xy 382.742856 -285.475204) (xy 382.738896 -285.42615) (xy 382.410208 -285.42615)
			(xy 382.409713 -285.450757) (xy 382.401818 -285.499334) (xy 382.386234 -285.546015) (xy 382.363363 -285.589592)
			(xy 382.333798 -285.628936) (xy 382.298305 -285.663028) (xy 382.257802 -285.690984) (xy 382.21334 -285.712082)
			(xy 382.166069 -285.725774) (xy 382.117214 -285.731706) (xy 382.068039 -285.729725) (xy 382.01982 -285.719881)
			(xy 381.973804 -285.702429) (xy 381.931183 -285.677822) (xy 381.893062 -285.646697) (xy 381.860427 -285.60986)
			(xy 381.834124 -285.568264) (xy 381.814833 -285.522988) (xy 381.803056 -285.475204) (xy 381.799096 -285.42615)
			(xy 381.480568 -285.42615) (xy 381.480056 -285.451596) (xy 381.471892 -285.50183) (xy 381.455776 -285.550104)
			(xy 381.432125 -285.595167) (xy 381.401552 -285.635853) (xy 381.364848 -285.671108) (xy 381.322964 -285.700018)
			(xy 381.276985 -285.721835) (xy 381.228101 -285.735995) (xy 381.17758 -285.742129) (xy 381.126728 -285.74008)
			(xy 381.076864 -285.7299) (xy 381.029278 -285.711853) (xy 380.985204 -285.686407) (xy 380.945782 -285.65422)
			(xy 380.912034 -285.616126) (xy 380.884833 -285.573112) (xy 380.864885 -285.526292) (xy 380.852706 -285.476878)
			(xy 380.848611 -285.42615) (xy 380.5301 -285.42615) (xy 380.529605 -285.450757) (xy 380.52171 -285.499334)
			(xy 380.506126 -285.546015) (xy 380.483255 -285.589592) (xy 380.45369 -285.628936) (xy 380.418197 -285.663028)
			(xy 380.377694 -285.690984) (xy 380.333232 -285.712082) (xy 380.285961 -285.725774) (xy 380.237106 -285.731706)
			(xy 380.187931 -285.729725) (xy 380.139712 -285.719881) (xy 380.093696 -285.702429) (xy 380.051075 -285.677822)
			(xy 380.012954 -285.646697) (xy 379.980319 -285.60986) (xy 379.954016 -285.568264) (xy 379.934725 -285.522988)
			(xy 379.922948 -285.475204) (xy 379.918988 -285.42615) (xy 379.60046 -285.42615) (xy 379.599948 -285.451596)
			(xy 379.591784 -285.50183) (xy 379.575668 -285.550104) (xy 379.552017 -285.595167) (xy 379.521444 -285.635853)
			(xy 379.48474 -285.671108) (xy 379.442856 -285.700018) (xy 379.396877 -285.721835) (xy 379.347993 -285.735995)
			(xy 379.297472 -285.742129) (xy 379.24662 -285.74008) (xy 379.196756 -285.7299) (xy 379.14917 -285.711853)
			(xy 379.105096 -285.686407) (xy 379.065674 -285.65422) (xy 379.031926 -285.616126) (xy 379.004725 -285.573112)
			(xy 378.984777 -285.526292) (xy 378.972598 -285.476878) (xy 378.968503 -285.42615) (xy 377.720606 -285.42615)
			(xy 377.720094 -285.451596) (xy 377.71193 -285.50183) (xy 377.695814 -285.550104) (xy 377.672163 -285.595167)
			(xy 377.64159 -285.635853) (xy 377.604886 -285.671108) (xy 377.563002 -285.700018) (xy 377.517023 -285.721835)
			(xy 377.468139 -285.735995) (xy 377.417618 -285.742129) (xy 377.366766 -285.74008) (xy 377.316902 -285.7299)
			(xy 377.269316 -285.711853) (xy 377.225242 -285.686407) (xy 377.18582 -285.65422) (xy 377.152072 -285.616126)
			(xy 377.124871 -285.573112) (xy 377.104923 -285.526292) (xy 377.092744 -285.476878) (xy 377.088649 -285.42615)
			(xy 376.780552 -285.42615) (xy 376.78004 -285.451596) (xy 376.771876 -285.50183) (xy 376.75576 -285.550104)
			(xy 376.732109 -285.595167) (xy 376.701536 -285.635853) (xy 376.664832 -285.671108) (xy 376.622948 -285.700018)
			(xy 376.576969 -285.721835) (xy 376.528085 -285.735995) (xy 376.477564 -285.742129) (xy 376.426712 -285.74008)
			(xy 376.376848 -285.7299) (xy 376.329262 -285.711853) (xy 376.285188 -285.686407) (xy 376.245766 -285.65422)
			(xy 376.212018 -285.616126) (xy 376.184817 -285.573112) (xy 376.164869 -285.526292) (xy 376.15269 -285.476878)
			(xy 376.148595 -285.42615) (xy 375.855484 -285.42615) (xy 375.855484 -285.426404) (xy 375.85523 -285.437326)
			(xy 375.890751 -285.473187) (xy 375.955962 -285.550242) (xy 376.014038 -285.632808) (xy 376.064514 -285.720227)
			(xy 376.10699 -285.8118) (xy 376.141125 -285.906799) (xy 376.154442 -285.955486) (xy 376.15876 -285.966408)
			(xy 376.18153 -285.980888) (xy 376.222212 -286.016334) (xy 376.256285 -286.058172) (xy 376.282761 -286.105187)
			(xy 376.300871 -286.156014) (xy 376.310089 -286.209178) (xy 376.310652 -286.236156) (xy 376.628926 -286.236156)
			(xy 376.632886 -286.187102) (xy 376.644663 -286.139318) (xy 376.663954 -286.094042) (xy 376.690257 -286.052446)
			(xy 376.722892 -286.015609) (xy 376.761013 -285.984484) (xy 376.803634 -285.959877) (xy 376.84965 -285.942425)
			(xy 376.897869 -285.932581) (xy 376.947044 -285.9306) (xy 376.995899 -285.936532) (xy 377.04317 -285.950224)
			(xy 377.087632 -285.971322) (xy 377.128135 -285.999278) (xy 377.163628 -286.03337) (xy 377.193193 -286.072714)
			(xy 377.216064 -286.116291) (xy 377.231648 -286.162972) (xy 377.239543 -286.211549) (xy 377.240038 -286.236156)
			(xy 377.558549 -286.236156) (xy 377.562644 -286.185428) (xy 377.574823 -286.136014) (xy 377.594771 -286.089194)
			(xy 377.621972 -286.04618) (xy 377.65572 -286.008086) (xy 377.695142 -285.975899) (xy 377.739216 -285.950453)
			(xy 377.786802 -285.932406) (xy 377.836666 -285.922226) (xy 377.887518 -285.920177) (xy 377.938039 -285.926311)
			(xy 377.986923 -285.940471) (xy 378.032902 -285.962288) (xy 378.074786 -285.991198) (xy 378.11149 -286.026453)
			(xy 378.142063 -286.067139) (xy 378.165714 -286.112202) (xy 378.18183 -286.160476) (xy 378.189994 -286.21071)
			(xy 378.190506 -286.236156) (xy 378.509034 -286.236156) (xy 378.512994 -286.187102) (xy 378.524771 -286.139318)
			(xy 378.544062 -286.094042) (xy 378.570365 -286.052446) (xy 378.603 -286.015609) (xy 378.641121 -285.984484)
			(xy 378.683742 -285.959877) (xy 378.729758 -285.942425) (xy 378.777977 -285.932581) (xy 378.827152 -285.9306)
			(xy 378.876007 -285.936532) (xy 378.923278 -285.950224) (xy 378.96774 -285.971322) (xy 379.008243 -285.999278)
			(xy 379.043736 -286.03337) (xy 379.073301 -286.072714) (xy 379.096172 -286.116291) (xy 379.111756 -286.162972)
			(xy 379.119651 -286.211549) (xy 379.120146 -286.236156) (xy 379.438657 -286.236156) (xy 379.442752 -286.185428)
			(xy 379.454931 -286.136014) (xy 379.474879 -286.089194) (xy 379.50208 -286.04618) (xy 379.535828 -286.008086)
			(xy 379.57525 -285.975899) (xy 379.619324 -285.950453) (xy 379.66691 -285.932406) (xy 379.716774 -285.922226)
			(xy 379.767626 -285.920177) (xy 379.818147 -285.926311) (xy 379.867031 -285.940471) (xy 379.91301 -285.962288)
			(xy 379.954894 -285.991198) (xy 379.991598 -286.026453) (xy 380.022171 -286.067139) (xy 380.045822 -286.112202)
			(xy 380.061938 -286.160476) (xy 380.070102 -286.21071) (xy 380.070614 -286.236156) (xy 380.378711 -286.236156)
			(xy 380.382806 -286.185428) (xy 380.394985 -286.136014) (xy 380.414933 -286.089194) (xy 380.442134 -286.04618)
			(xy 380.475882 -286.008086) (xy 380.515304 -285.975899) (xy 380.559378 -285.950453) (xy 380.606964 -285.932406)
			(xy 380.656828 -285.922226) (xy 380.70768 -285.920177) (xy 380.758201 -285.926311) (xy 380.807085 -285.940471)
			(xy 380.853064 -285.962288) (xy 380.894948 -285.991198) (xy 380.931652 -286.026453) (xy 380.962225 -286.067139)
			(xy 380.985876 -286.112202) (xy 381.001992 -286.160476) (xy 381.010156 -286.21071) (xy 381.010668 -286.236156)
			(xy 381.328942 -286.236156) (xy 381.332902 -286.187102) (xy 381.344679 -286.139318) (xy 381.36397 -286.094042)
			(xy 381.390273 -286.052446) (xy 381.422908 -286.015609) (xy 381.461029 -285.984484) (xy 381.50365 -285.959877)
			(xy 381.549666 -285.942425) (xy 381.597885 -285.932581) (xy 381.64706 -285.9306) (xy 381.695915 -285.936532)
			(xy 381.743186 -285.950224) (xy 381.787648 -285.971322) (xy 381.828151 -285.999278) (xy 381.863644 -286.03337)
			(xy 381.893209 -286.072714) (xy 381.91608 -286.116291) (xy 381.931664 -286.162972) (xy 381.939559 -286.211549)
			(xy 381.940054 -286.236156) (xy 382.268996 -286.236156) (xy 382.272956 -286.187102) (xy 382.284733 -286.139318)
			(xy 382.304024 -286.094042) (xy 382.330327 -286.052446) (xy 382.362962 -286.015609) (xy 382.401083 -285.984484)
			(xy 382.443704 -285.959877) (xy 382.48972 -285.942425) (xy 382.537939 -285.932581) (xy 382.587114 -285.9306)
			(xy 382.635969 -285.936532) (xy 382.68324 -285.950224) (xy 382.727702 -285.971322) (xy 382.768205 -285.999278)
			(xy 382.803698 -286.03337) (xy 382.833263 -286.072714) (xy 382.856134 -286.116291) (xy 382.871718 -286.162972)
			(xy 382.879613 -286.211549) (xy 382.880108 -286.236156) (xy 383.20905 -286.236156) (xy 383.21301 -286.187102)
			(xy 383.224787 -286.139318) (xy 383.244078 -286.094042) (xy 383.270381 -286.052446) (xy 383.303016 -286.015609)
			(xy 383.341137 -285.984484) (xy 383.383758 -285.959877) (xy 383.429774 -285.942425) (xy 383.477993 -285.932581)
			(xy 383.527168 -285.9306) (xy 383.576023 -285.936532) (xy 383.623294 -285.950224) (xy 383.667756 -285.971322)
			(xy 383.708259 -285.999278) (xy 383.743752 -286.03337) (xy 383.773317 -286.072714) (xy 383.796188 -286.116291)
			(xy 383.811772 -286.162972) (xy 383.819667 -286.211549) (xy 383.820162 -286.236156) (xy 384.149104 -286.236156)
			(xy 384.153064 -286.187102) (xy 384.164841 -286.139318) (xy 384.184132 -286.094042) (xy 384.210435 -286.052446)
			(xy 384.24307 -286.015609) (xy 384.281191 -285.984484) (xy 384.323812 -285.959877) (xy 384.369828 -285.942425)
			(xy 384.418047 -285.932581) (xy 384.467222 -285.9306) (xy 384.516077 -285.936532) (xy 384.563348 -285.950224)
			(xy 384.60781 -285.971322) (xy 384.648313 -285.999278) (xy 384.683806 -286.03337) (xy 384.713371 -286.072714)
			(xy 384.736242 -286.116291) (xy 384.751826 -286.162972) (xy 384.759721 -286.211549) (xy 384.760216 -286.236156)
			(xy 385.088904 -286.236156) (xy 385.092864 -286.187102) (xy 385.104641 -286.139318) (xy 385.123932 -286.094042)
			(xy 385.150235 -286.052446) (xy 385.18287 -286.015609) (xy 385.220991 -285.984484) (xy 385.263612 -285.959877)
			(xy 385.309628 -285.942425) (xy 385.357847 -285.932581) (xy 385.407022 -285.9306) (xy 385.455877 -285.936532)
			(xy 385.503148 -285.950224) (xy 385.54761 -285.971322) (xy 385.588113 -285.999278) (xy 385.623606 -286.03337)
			(xy 385.653171 -286.072714) (xy 385.676042 -286.116291) (xy 385.691626 -286.162972) (xy 385.699521 -286.211549)
			(xy 385.700016 -286.236156) (xy 386.028958 -286.236156) (xy 386.032918 -286.187102) (xy 386.044695 -286.139318)
			(xy 386.063986 -286.094042) (xy 386.090289 -286.052446) (xy 386.122924 -286.015609) (xy 386.161045 -285.984484)
			(xy 386.203666 -285.959877) (xy 386.249682 -285.942425) (xy 386.297901 -285.932581) (xy 386.347076 -285.9306)
			(xy 386.395931 -285.936532) (xy 386.443202 -285.950224) (xy 386.487664 -285.971322) (xy 386.528167 -285.999278)
			(xy 386.56366 -286.03337) (xy 386.593225 -286.072714) (xy 386.616096 -286.116291) (xy 386.63168 -286.162972)
			(xy 386.639575 -286.211549) (xy 386.64007 -286.236156) (xy 386.969012 -286.236156) (xy 386.972972 -286.187102)
			(xy 386.984749 -286.139318) (xy 387.00404 -286.094042) (xy 387.030343 -286.052446) (xy 387.062978 -286.015609)
			(xy 387.101099 -285.984484) (xy 387.14372 -285.959877) (xy 387.189736 -285.942425) (xy 387.237955 -285.932581)
			(xy 387.28713 -285.9306) (xy 387.335985 -285.936532) (xy 387.383256 -285.950224) (xy 387.427718 -285.971322)
			(xy 387.468221 -285.999278) (xy 387.503714 -286.03337) (xy 387.533279 -286.072714) (xy 387.55615 -286.116291)
			(xy 387.571734 -286.162972) (xy 387.579629 -286.211549) (xy 387.580124 -286.236156) (xy 387.579629 -286.260763)
			(xy 387.571734 -286.30934) (xy 387.55615 -286.356021) (xy 387.533279 -286.399598) (xy 387.503714 -286.438942)
			(xy 387.468221 -286.473034) (xy 387.427718 -286.50099) (xy 387.383256 -286.522088) (xy 387.335985 -286.53578)
			(xy 387.28713 -286.541712) (xy 387.237955 -286.539731) (xy 387.189736 -286.529887) (xy 387.14372 -286.512435)
			(xy 387.101099 -286.487828) (xy 387.062978 -286.456703) (xy 387.030343 -286.419866) (xy 387.00404 -286.37827)
			(xy 386.984749 -286.332994) (xy 386.972972 -286.28521) (xy 386.969012 -286.236156) (xy 386.64007 -286.236156)
			(xy 386.639575 -286.260763) (xy 386.63168 -286.30934) (xy 386.616096 -286.356021) (xy 386.593225 -286.399598)
			(xy 386.56366 -286.438942) (xy 386.528167 -286.473034) (xy 386.487664 -286.50099) (xy 386.443202 -286.522088)
			(xy 386.395931 -286.53578) (xy 386.347076 -286.541712) (xy 386.297901 -286.539731) (xy 386.249682 -286.529887)
			(xy 386.203666 -286.512435) (xy 386.161045 -286.487828) (xy 386.122924 -286.456703) (xy 386.090289 -286.419866)
			(xy 386.063986 -286.37827) (xy 386.044695 -286.332994) (xy 386.032918 -286.28521) (xy 386.028958 -286.236156)
			(xy 385.700016 -286.236156) (xy 385.699521 -286.260763) (xy 385.691626 -286.30934) (xy 385.676042 -286.356021)
			(xy 385.653171 -286.399598) (xy 385.623606 -286.438942) (xy 385.588113 -286.473034) (xy 385.54761 -286.50099)
			(xy 385.503148 -286.522088) (xy 385.455877 -286.53578) (xy 385.407022 -286.541712) (xy 385.357847 -286.539731)
			(xy 385.309628 -286.529887) (xy 385.263612 -286.512435) (xy 385.220991 -286.487828) (xy 385.18287 -286.456703)
			(xy 385.150235 -286.419866) (xy 385.123932 -286.37827) (xy 385.104641 -286.332994) (xy 385.092864 -286.28521)
			(xy 385.088904 -286.236156) (xy 384.760216 -286.236156) (xy 384.759721 -286.260763) (xy 384.751826 -286.30934)
			(xy 384.736242 -286.356021) (xy 384.713371 -286.399598) (xy 384.683806 -286.438942) (xy 384.648313 -286.473034)
			(xy 384.60781 -286.50099) (xy 384.563348 -286.522088) (xy 384.516077 -286.53578) (xy 384.467222 -286.541712)
			(xy 384.418047 -286.539731) (xy 384.369828 -286.529887) (xy 384.323812 -286.512435) (xy 384.281191 -286.487828)
			(xy 384.24307 -286.456703) (xy 384.210435 -286.419866) (xy 384.184132 -286.37827) (xy 384.164841 -286.332994)
			(xy 384.153064 -286.28521) (xy 384.149104 -286.236156) (xy 383.820162 -286.236156) (xy 383.819667 -286.260763)
			(xy 383.811772 -286.30934) (xy 383.796188 -286.356021) (xy 383.773317 -286.399598) (xy 383.743752 -286.438942)
			(xy 383.708259 -286.473034) (xy 383.667756 -286.50099) (xy 383.623294 -286.522088) (xy 383.576023 -286.53578)
			(xy 383.527168 -286.541712) (xy 383.477993 -286.539731) (xy 383.429774 -286.529887) (xy 383.383758 -286.512435)
			(xy 383.341137 -286.487828) (xy 383.303016 -286.456703) (xy 383.270381 -286.419866) (xy 383.244078 -286.37827)
			(xy 383.224787 -286.332994) (xy 383.21301 -286.28521) (xy 383.20905 -286.236156) (xy 382.880108 -286.236156)
			(xy 382.879613 -286.260763) (xy 382.871718 -286.30934) (xy 382.856134 -286.356021) (xy 382.833263 -286.399598)
			(xy 382.803698 -286.438942) (xy 382.768205 -286.473034) (xy 382.727702 -286.50099) (xy 382.68324 -286.522088)
			(xy 382.635969 -286.53578) (xy 382.587114 -286.541712) (xy 382.537939 -286.539731) (xy 382.48972 -286.529887)
			(xy 382.443704 -286.512435) (xy 382.401083 -286.487828) (xy 382.362962 -286.456703) (xy 382.330327 -286.419866)
			(xy 382.304024 -286.37827) (xy 382.284733 -286.332994) (xy 382.272956 -286.28521) (xy 382.268996 -286.236156)
			(xy 381.940054 -286.236156) (xy 381.939559 -286.260763) (xy 381.931664 -286.30934) (xy 381.91608 -286.356021)
			(xy 381.893209 -286.399598) (xy 381.863644 -286.438942) (xy 381.828151 -286.473034) (xy 381.787648 -286.50099)
			(xy 381.743186 -286.522088) (xy 381.695915 -286.53578) (xy 381.64706 -286.541712) (xy 381.597885 -286.539731)
			(xy 381.549666 -286.529887) (xy 381.50365 -286.512435) (xy 381.461029 -286.487828) (xy 381.422908 -286.456703)
			(xy 381.390273 -286.419866) (xy 381.36397 -286.37827) (xy 381.344679 -286.332994) (xy 381.332902 -286.28521)
			(xy 381.328942 -286.236156) (xy 381.010668 -286.236156) (xy 381.010156 -286.261602) (xy 381.001992 -286.311836)
			(xy 380.985876 -286.36011) (xy 380.962225 -286.405173) (xy 380.931652 -286.445859) (xy 380.894948 -286.481114)
			(xy 380.853064 -286.510024) (xy 380.807085 -286.531841) (xy 380.758201 -286.546001) (xy 380.70768 -286.552135)
			(xy 380.656828 -286.550086) (xy 380.606964 -286.539906) (xy 380.559378 -286.521859) (xy 380.515304 -286.496413)
			(xy 380.475882 -286.464226) (xy 380.442134 -286.426132) (xy 380.414933 -286.383118) (xy 380.394985 -286.336298)
			(xy 380.382806 -286.286884) (xy 380.378711 -286.236156) (xy 380.070614 -286.236156) (xy 380.070102 -286.261602)
			(xy 380.061938 -286.311836) (xy 380.045822 -286.36011) (xy 380.022171 -286.405173) (xy 379.991598 -286.445859)
			(xy 379.954894 -286.481114) (xy 379.91301 -286.510024) (xy 379.867031 -286.531841) (xy 379.818147 -286.546001)
			(xy 379.767626 -286.552135) (xy 379.716774 -286.550086) (xy 379.66691 -286.539906) (xy 379.619324 -286.521859)
			(xy 379.57525 -286.496413) (xy 379.535828 -286.464226) (xy 379.50208 -286.426132) (xy 379.474879 -286.383118)
			(xy 379.454931 -286.336298) (xy 379.442752 -286.286884) (xy 379.438657 -286.236156) (xy 379.120146 -286.236156)
			(xy 379.119651 -286.260763) (xy 379.111756 -286.30934) (xy 379.096172 -286.356021) (xy 379.073301 -286.399598)
			(xy 379.043736 -286.438942) (xy 379.008243 -286.473034) (xy 378.96774 -286.50099) (xy 378.923278 -286.522088)
			(xy 378.876007 -286.53578) (xy 378.827152 -286.541712) (xy 378.777977 -286.539731) (xy 378.729758 -286.529887)
			(xy 378.683742 -286.512435) (xy 378.641121 -286.487828) (xy 378.603 -286.456703) (xy 378.570365 -286.419866)
			(xy 378.544062 -286.37827) (xy 378.524771 -286.332994) (xy 378.512994 -286.28521) (xy 378.509034 -286.236156)
			(xy 378.190506 -286.236156) (xy 378.189994 -286.261602) (xy 378.18183 -286.311836) (xy 378.165714 -286.36011)
			(xy 378.142063 -286.405173) (xy 378.11149 -286.445859) (xy 378.074786 -286.481114) (xy 378.032902 -286.510024)
			(xy 377.986923 -286.531841) (xy 377.938039 -286.546001) (xy 377.887518 -286.552135) (xy 377.836666 -286.550086)
			(xy 377.786802 -286.539906) (xy 377.739216 -286.521859) (xy 377.695142 -286.496413) (xy 377.65572 -286.464226)
			(xy 377.621972 -286.426132) (xy 377.594771 -286.383118) (xy 377.574823 -286.336298) (xy 377.562644 -286.286884)
			(xy 377.558549 -286.236156) (xy 377.240038 -286.236156) (xy 377.239543 -286.260763) (xy 377.231648 -286.30934)
			(xy 377.216064 -286.356021) (xy 377.193193 -286.399598) (xy 377.163628 -286.438942) (xy 377.128135 -286.473034)
			(xy 377.087632 -286.50099) (xy 377.04317 -286.522088) (xy 376.995899 -286.53578) (xy 376.947044 -286.541712)
			(xy 376.897869 -286.539731) (xy 376.84965 -286.529887) (xy 376.803634 -286.512435) (xy 376.761013 -286.487828)
			(xy 376.722892 -286.456703) (xy 376.690257 -286.419866) (xy 376.663954 -286.37827) (xy 376.644663 -286.332994)
			(xy 376.632886 -286.28521) (xy 376.628926 -286.236156) (xy 376.310652 -286.236156) (xy 376.310085 -286.262889)
			(xy 376.301066 -286.315588) (xy 376.283295 -286.366013) (xy 376.25728 -286.412722) (xy 376.223765 -286.454379)
			(xy 376.18371 -286.489792) (xy 376.1613 -286.50438) (xy 376.157236 -286.515048) (xy 376.145967 -286.558453)
			(xy 376.117459 -286.643485) (xy 376.082302 -286.72599) (xy 376.040718 -286.80545) (xy 375.992967 -286.881365)
			(xy 375.939351 -286.953256) (xy 375.880206 -287.020673) (xy 375.854772 -287.045908) (xy 376.148595 -287.045908)
			(xy 376.15269 -286.99518) (xy 376.164869 -286.945766) (xy 376.184817 -286.898946) (xy 376.212018 -286.855932)
			(xy 376.245766 -286.817838) (xy 376.285188 -286.785651) (xy 376.329262 -286.760205) (xy 376.376848 -286.742158)
			(xy 376.426712 -286.731978) (xy 376.477564 -286.729929) (xy 376.528085 -286.736063) (xy 376.576969 -286.750223)
			(xy 376.622948 -286.77204) (xy 376.664832 -286.80095) (xy 376.701536 -286.836205) (xy 376.732109 -286.876891)
			(xy 376.75576 -286.921954) (xy 376.771876 -286.970228) (xy 376.78004 -287.020462) (xy 376.780552 -287.045908)
			(xy 377.088649 -287.045908) (xy 377.092744 -286.99518) (xy 377.104923 -286.945766) (xy 377.124871 -286.898946)
			(xy 377.152072 -286.855932) (xy 377.18582 -286.817838) (xy 377.225242 -286.785651) (xy 377.269316 -286.760205)
			(xy 377.316902 -286.742158) (xy 377.366766 -286.731978) (xy 377.417618 -286.729929) (xy 377.468139 -286.736063)
			(xy 377.517023 -286.750223) (xy 377.563002 -286.77204) (xy 377.604886 -286.80095) (xy 377.64159 -286.836205)
			(xy 377.672163 -286.876891) (xy 377.695814 -286.921954) (xy 377.71193 -286.970228) (xy 377.720094 -287.020462)
			(xy 377.720606 -287.045908) (xy 377.720601 -287.046162) (xy 378.039134 -287.046162) (xy 378.043094 -286.997108)
			(xy 378.054871 -286.949324) (xy 378.074162 -286.904048) (xy 378.100465 -286.862452) (xy 378.1331 -286.825615)
			(xy 378.171221 -286.79449) (xy 378.213842 -286.769883) (xy 378.259858 -286.752431) (xy 378.308077 -286.742587)
			(xy 378.357252 -286.740606) (xy 378.406107 -286.746538) (xy 378.453378 -286.76023) (xy 378.49784 -286.781328)
			(xy 378.538343 -286.809284) (xy 378.573836 -286.843376) (xy 378.603401 -286.88272) (xy 378.626272 -286.926297)
			(xy 378.641856 -286.972978) (xy 378.649751 -287.021555) (xy 378.650241 -287.045908) (xy 378.968503 -287.045908)
			(xy 378.972598 -286.99518) (xy 378.984777 -286.945766) (xy 379.004725 -286.898946) (xy 379.031926 -286.855932)
			(xy 379.065674 -286.817838) (xy 379.105096 -286.785651) (xy 379.14917 -286.760205) (xy 379.196756 -286.742158)
			(xy 379.24662 -286.731978) (xy 379.297472 -286.729929) (xy 379.347993 -286.736063) (xy 379.396877 -286.750223)
			(xy 379.442856 -286.77204) (xy 379.48474 -286.80095) (xy 379.521444 -286.836205) (xy 379.552017 -286.876891)
			(xy 379.575668 -286.921954) (xy 379.591784 -286.970228) (xy 379.599948 -287.020462) (xy 379.60046 -287.045908)
			(xy 379.918988 -287.045908) (xy 379.922948 -286.996854) (xy 379.934725 -286.94907) (xy 379.954016 -286.903794)
			(xy 379.980319 -286.862198) (xy 380.012954 -286.825361) (xy 380.051075 -286.794236) (xy 380.093696 -286.769629)
			(xy 380.139712 -286.752177) (xy 380.187931 -286.742333) (xy 380.237106 -286.740352) (xy 380.285961 -286.746284)
			(xy 380.333232 -286.759976) (xy 380.377694 -286.781074) (xy 380.418197 -286.80903) (xy 380.45369 -286.843122)
			(xy 380.483255 -286.882466) (xy 380.506126 -286.926043) (xy 380.52171 -286.972724) (xy 380.529605 -287.021301)
			(xy 380.5301 -287.045908) (xy 380.848611 -287.045908) (xy 380.852706 -286.99518) (xy 380.864885 -286.945766)
			(xy 380.884833 -286.898946) (xy 380.912034 -286.855932) (xy 380.945782 -286.817838) (xy 380.985204 -286.785651)
			(xy 381.029278 -286.760205) (xy 381.076864 -286.742158) (xy 381.126728 -286.731978) (xy 381.17758 -286.729929)
			(xy 381.228101 -286.736063) (xy 381.276985 -286.750223) (xy 381.322964 -286.77204) (xy 381.364848 -286.80095)
			(xy 381.401552 -286.836205) (xy 381.432125 -286.876891) (xy 381.455776 -286.921954) (xy 381.471892 -286.970228)
			(xy 381.480056 -287.020462) (xy 381.480568 -287.045908) (xy 381.480563 -287.046162) (xy 381.799096 -287.046162)
			(xy 381.803056 -286.997108) (xy 381.814833 -286.949324) (xy 381.834124 -286.904048) (xy 381.860427 -286.862452)
			(xy 381.893062 -286.825615) (xy 381.931183 -286.79449) (xy 381.973804 -286.769883) (xy 382.01982 -286.752431)
			(xy 382.068039 -286.742587) (xy 382.117214 -286.740606) (xy 382.166069 -286.746538) (xy 382.21334 -286.76023)
			(xy 382.257802 -286.781328) (xy 382.298305 -286.809284) (xy 382.333798 -286.843376) (xy 382.363363 -286.88272)
			(xy 382.386234 -286.926297) (xy 382.401818 -286.972978) (xy 382.409713 -287.021555) (xy 382.410203 -287.045908)
			(xy 382.738896 -287.045908) (xy 382.742856 -286.996854) (xy 382.754633 -286.94907) (xy 382.773924 -286.903794)
			(xy 382.800227 -286.862198) (xy 382.832862 -286.825361) (xy 382.870983 -286.794236) (xy 382.913604 -286.769629)
			(xy 382.95962 -286.752177) (xy 383.007839 -286.742333) (xy 383.057014 -286.740352) (xy 383.105869 -286.746284)
			(xy 383.15314 -286.759976) (xy 383.197602 -286.781074) (xy 383.238105 -286.80903) (xy 383.273598 -286.843122)
			(xy 383.303163 -286.882466) (xy 383.326034 -286.926043) (xy 383.341618 -286.972724) (xy 383.349513 -287.021301)
			(xy 383.350008 -287.045908) (xy 383.67895 -287.045908) (xy 383.68291 -286.996854) (xy 383.694687 -286.94907)
			(xy 383.713978 -286.903794) (xy 383.740281 -286.862198) (xy 383.772916 -286.825361) (xy 383.811037 -286.794236)
			(xy 383.853658 -286.769629) (xy 383.899674 -286.752177) (xy 383.947893 -286.742333) (xy 383.997068 -286.740352)
			(xy 384.045923 -286.746284) (xy 384.093194 -286.759976) (xy 384.137656 -286.781074) (xy 384.178159 -286.80903)
			(xy 384.213652 -286.843122) (xy 384.243217 -286.882466) (xy 384.266088 -286.926043) (xy 384.281672 -286.972724)
			(xy 384.289567 -287.021301) (xy 384.290062 -287.045908) (xy 384.619004 -287.045908) (xy 384.622964 -286.996854)
			(xy 384.634741 -286.94907) (xy 384.654032 -286.903794) (xy 384.680335 -286.862198) (xy 384.71297 -286.825361)
			(xy 384.751091 -286.794236) (xy 384.793712 -286.769629) (xy 384.839728 -286.752177) (xy 384.887947 -286.742333)
			(xy 384.937122 -286.740352) (xy 384.985977 -286.746284) (xy 385.033248 -286.759976) (xy 385.07771 -286.781074)
			(xy 385.118213 -286.80903) (xy 385.153706 -286.843122) (xy 385.183271 -286.882466) (xy 385.206142 -286.926043)
			(xy 385.221726 -286.972724) (xy 385.229621 -287.021301) (xy 385.230116 -287.045908) (xy 385.559058 -287.045908)
			(xy 385.563018 -286.996854) (xy 385.574795 -286.94907) (xy 385.594086 -286.903794) (xy 385.620389 -286.862198)
			(xy 385.653024 -286.825361) (xy 385.691145 -286.794236) (xy 385.733766 -286.769629) (xy 385.779782 -286.752177)
			(xy 385.828001 -286.742333) (xy 385.877176 -286.740352) (xy 385.926031 -286.746284) (xy 385.973302 -286.759976)
			(xy 386.017764 -286.781074) (xy 386.058267 -286.80903) (xy 386.09376 -286.843122) (xy 386.123325 -286.882466)
			(xy 386.146196 -286.926043) (xy 386.16178 -286.972724) (xy 386.169675 -287.021301) (xy 386.17017 -287.045908)
			(xy 386.170165 -287.046162) (xy 386.499112 -287.046162) (xy 386.503072 -286.997108) (xy 386.514849 -286.949324)
			(xy 386.53414 -286.904048) (xy 386.560443 -286.862452) (xy 386.593078 -286.825615) (xy 386.631199 -286.79449)
			(xy 386.67382 -286.769883) (xy 386.719836 -286.752431) (xy 386.768055 -286.742587) (xy 386.81723 -286.740606)
			(xy 386.866085 -286.746538) (xy 386.913356 -286.76023) (xy 386.957818 -286.781328) (xy 386.998321 -286.809284)
			(xy 387.033814 -286.843376) (xy 387.063379 -286.88272) (xy 387.08625 -286.926297) (xy 387.101834 -286.972978)
			(xy 387.109729 -287.021555) (xy 387.110219 -287.045908) (xy 387.438912 -287.045908) (xy 387.442872 -286.996854)
			(xy 387.454649 -286.94907) (xy 387.47394 -286.903794) (xy 387.500243 -286.862198) (xy 387.532878 -286.825361)
			(xy 387.570999 -286.794236) (xy 387.61362 -286.769629) (xy 387.659636 -286.752177) (xy 387.707855 -286.742333)
			(xy 387.75703 -286.740352) (xy 387.805885 -286.746284) (xy 387.853156 -286.759976) (xy 387.897618 -286.781074)
			(xy 387.938121 -286.80903) (xy 387.973614 -286.843122) (xy 388.003179 -286.882466) (xy 388.02605 -286.926043)
			(xy 388.041634 -286.972724) (xy 388.049529 -287.021301) (xy 388.050024 -287.045908) (xy 388.049529 -287.070515)
			(xy 388.041634 -287.119092) (xy 388.02605 -287.165773) (xy 388.003179 -287.20935) (xy 387.973614 -287.248694)
			(xy 387.938121 -287.282786) (xy 387.897618 -287.310742) (xy 387.853156 -287.33184) (xy 387.805885 -287.345532)
			(xy 387.75703 -287.351464) (xy 387.707855 -287.349483) (xy 387.659636 -287.339639) (xy 387.61362 -287.322187)
			(xy 387.570999 -287.29758) (xy 387.532878 -287.266455) (xy 387.500243 -287.229618) (xy 387.47394 -287.188022)
			(xy 387.454649 -287.142746) (xy 387.442872 -287.094962) (xy 387.438912 -287.045908) (xy 387.110219 -287.045908)
			(xy 387.110224 -287.046162) (xy 387.109729 -287.070769) (xy 387.101834 -287.119346) (xy 387.08625 -287.166027)
			(xy 387.063379 -287.209604) (xy 387.033814 -287.248948) (xy 386.998321 -287.28304) (xy 386.957818 -287.310996)
			(xy 386.913356 -287.332094) (xy 386.866085 -287.345786) (xy 386.81723 -287.351718) (xy 386.768055 -287.349737)
			(xy 386.719836 -287.339893) (xy 386.67382 -287.322441) (xy 386.631199 -287.297834) (xy 386.593078 -287.266709)
			(xy 386.560443 -287.229872) (xy 386.53414 -287.188276) (xy 386.514849 -287.143) (xy 386.503072 -287.095216)
			(xy 386.499112 -287.046162) (xy 386.170165 -287.046162) (xy 386.169675 -287.070515) (xy 386.16178 -287.119092)
			(xy 386.146196 -287.165773) (xy 386.123325 -287.20935) (xy 386.09376 -287.248694) (xy 386.058267 -287.282786)
			(xy 386.017764 -287.310742) (xy 385.973302 -287.33184) (xy 385.926031 -287.345532) (xy 385.877176 -287.351464)
			(xy 385.828001 -287.349483) (xy 385.779782 -287.339639) (xy 385.733766 -287.322187) (xy 385.691145 -287.29758)
			(xy 385.653024 -287.266455) (xy 385.620389 -287.229618) (xy 385.594086 -287.188022) (xy 385.574795 -287.142746)
			(xy 385.563018 -287.094962) (xy 385.559058 -287.045908) (xy 385.230116 -287.045908) (xy 385.229621 -287.070515)
			(xy 385.221726 -287.119092) (xy 385.206142 -287.165773) (xy 385.183271 -287.20935) (xy 385.153706 -287.248694)
			(xy 385.118213 -287.282786) (xy 385.07771 -287.310742) (xy 385.033248 -287.33184) (xy 384.985977 -287.345532)
			(xy 384.937122 -287.351464) (xy 384.887947 -287.349483) (xy 384.839728 -287.339639) (xy 384.793712 -287.322187)
			(xy 384.751091 -287.29758) (xy 384.71297 -287.266455) (xy 384.680335 -287.229618) (xy 384.654032 -287.188022)
			(xy 384.634741 -287.142746) (xy 384.622964 -287.094962) (xy 384.619004 -287.045908) (xy 384.290062 -287.045908)
			(xy 384.289567 -287.070515) (xy 384.281672 -287.119092) (xy 384.266088 -287.165773) (xy 384.243217 -287.20935)
			(xy 384.213652 -287.248694) (xy 384.178159 -287.282786) (xy 384.137656 -287.310742) (xy 384.093194 -287.33184)
			(xy 384.045923 -287.345532) (xy 383.997068 -287.351464) (xy 383.947893 -287.349483) (xy 383.899674 -287.339639)
			(xy 383.853658 -287.322187) (xy 383.811037 -287.29758) (xy 383.772916 -287.266455) (xy 383.740281 -287.229618)
			(xy 383.713978 -287.188022) (xy 383.694687 -287.142746) (xy 383.68291 -287.094962) (xy 383.67895 -287.045908)
			(xy 383.350008 -287.045908) (xy 383.349513 -287.070515) (xy 383.341618 -287.119092) (xy 383.326034 -287.165773)
			(xy 383.303163 -287.20935) (xy 383.273598 -287.248694) (xy 383.238105 -287.282786) (xy 383.197602 -287.310742)
			(xy 383.15314 -287.33184) (xy 383.105869 -287.345532) (xy 383.057014 -287.351464) (xy 383.007839 -287.349483)
			(xy 382.95962 -287.339639) (xy 382.913604 -287.322187) (xy 382.870983 -287.29758) (xy 382.832862 -287.266455)
			(xy 382.800227 -287.229618) (xy 382.773924 -287.188022) (xy 382.754633 -287.142746) (xy 382.742856 -287.094962)
			(xy 382.738896 -287.045908) (xy 382.410203 -287.045908) (xy 382.410208 -287.046162) (xy 382.409713 -287.070769)
			(xy 382.401818 -287.119346) (xy 382.386234 -287.166027) (xy 382.363363 -287.209604) (xy 382.333798 -287.248948)
			(xy 382.298305 -287.28304) (xy 382.257802 -287.310996) (xy 382.21334 -287.332094) (xy 382.166069 -287.345786)
			(xy 382.117214 -287.351718) (xy 382.068039 -287.349737) (xy 382.01982 -287.339893) (xy 381.973804 -287.322441)
			(xy 381.931183 -287.297834) (xy 381.893062 -287.266709) (xy 381.860427 -287.229872) (xy 381.834124 -287.188276)
			(xy 381.814833 -287.143) (xy 381.803056 -287.095216) (xy 381.799096 -287.046162) (xy 381.480563 -287.046162)
			(xy 381.480056 -287.071354) (xy 381.471892 -287.121588) (xy 381.455776 -287.169862) (xy 381.432125 -287.214925)
			(xy 381.401552 -287.255611) (xy 381.364848 -287.290866) (xy 381.322964 -287.319776) (xy 381.276985 -287.341593)
			(xy 381.228101 -287.355753) (xy 381.17758 -287.361887) (xy 381.126728 -287.359838) (xy 381.076864 -287.349658)
			(xy 381.029278 -287.331611) (xy 380.985204 -287.306165) (xy 380.945782 -287.273978) (xy 380.912034 -287.235884)
			(xy 380.884833 -287.19287) (xy 380.864885 -287.14605) (xy 380.852706 -287.096636) (xy 380.848611 -287.045908)
			(xy 380.5301 -287.045908) (xy 380.529605 -287.070515) (xy 380.52171 -287.119092) (xy 380.506126 -287.165773)
			(xy 380.483255 -287.20935) (xy 380.45369 -287.248694) (xy 380.418197 -287.282786) (xy 380.377694 -287.310742)
			(xy 380.333232 -287.33184) (xy 380.285961 -287.345532) (xy 380.237106 -287.351464) (xy 380.187931 -287.349483)
			(xy 380.139712 -287.339639) (xy 380.093696 -287.322187) (xy 380.051075 -287.29758) (xy 380.012954 -287.266455)
			(xy 379.980319 -287.229618) (xy 379.954016 -287.188022) (xy 379.934725 -287.142746) (xy 379.922948 -287.094962)
			(xy 379.918988 -287.045908) (xy 379.60046 -287.045908) (xy 379.599948 -287.071354) (xy 379.591784 -287.121588)
			(xy 379.575668 -287.169862) (xy 379.552017 -287.214925) (xy 379.521444 -287.255611) (xy 379.48474 -287.290866)
			(xy 379.442856 -287.319776) (xy 379.396877 -287.341593) (xy 379.347993 -287.355753) (xy 379.297472 -287.361887)
			(xy 379.24662 -287.359838) (xy 379.196756 -287.349658) (xy 379.14917 -287.331611) (xy 379.105096 -287.306165)
			(xy 379.065674 -287.273978) (xy 379.031926 -287.235884) (xy 379.004725 -287.19287) (xy 378.984777 -287.14605)
			(xy 378.972598 -287.096636) (xy 378.968503 -287.045908) (xy 378.650241 -287.045908) (xy 378.650246 -287.046162)
			(xy 378.649751 -287.070769) (xy 378.641856 -287.119346) (xy 378.626272 -287.166027) (xy 378.603401 -287.209604)
			(xy 378.573836 -287.248948) (xy 378.538343 -287.28304) (xy 378.49784 -287.310996) (xy 378.453378 -287.332094)
			(xy 378.406107 -287.345786) (xy 378.357252 -287.351718) (xy 378.308077 -287.349737) (xy 378.259858 -287.339893)
			(xy 378.213842 -287.322441) (xy 378.171221 -287.297834) (xy 378.1331 -287.266709) (xy 378.100465 -287.229872)
			(xy 378.074162 -287.188276) (xy 378.054871 -287.143) (xy 378.043094 -287.095216) (xy 378.039134 -287.046162)
			(xy 377.720601 -287.046162) (xy 377.720094 -287.071354) (xy 377.71193 -287.121588) (xy 377.695814 -287.169862)
			(xy 377.672163 -287.214925) (xy 377.64159 -287.255611) (xy 377.604886 -287.290866) (xy 377.563002 -287.319776)
			(xy 377.517023 -287.341593) (xy 377.468139 -287.355753) (xy 377.417618 -287.361887) (xy 377.366766 -287.359838)
			(xy 377.316902 -287.349658) (xy 377.269316 -287.331611) (xy 377.225242 -287.306165) (xy 377.18582 -287.273978)
			(xy 377.152072 -287.235884) (xy 377.124871 -287.19287) (xy 377.104923 -287.14605) (xy 377.092744 -287.096636)
			(xy 377.088649 -287.045908) (xy 376.780552 -287.045908) (xy 376.78004 -287.071354) (xy 376.771876 -287.121588)
			(xy 376.75576 -287.169862) (xy 376.732109 -287.214925) (xy 376.701536 -287.255611) (xy 376.664832 -287.290866)
			(xy 376.622948 -287.319776) (xy 376.576969 -287.341593) (xy 376.528085 -287.355753) (xy 376.477564 -287.361887)
			(xy 376.426712 -287.359838) (xy 376.376848 -287.349658) (xy 376.329262 -287.331611) (xy 376.285188 -287.306165)
			(xy 376.245766 -287.273978) (xy 376.212018 -287.235884) (xy 376.184817 -287.19287) (xy 376.164869 -287.14605)
			(xy 376.15269 -287.096636) (xy 376.148595 -287.045908) (xy 375.854772 -287.045908) (xy 375.848372 -287.052258)
			(xy 375.842784 -287.057846) (xy 375.842276 -287.0581) (xy 375.827544 -287.087564) (xy 375.826274 -287.095184)
			(xy 375.821659 -287.120115) (xy 375.805276 -287.168094) (xy 375.781208 -287.212716) (xy 375.750114 -287.25276)
			(xy 375.712844 -287.287131) (xy 375.691908 -287.301432) (xy 375.68505 -287.306766) (xy 375.673989 -287.351544)
			(xy 375.645509 -287.43928) (xy 375.609969 -287.524401) (xy 375.567605 -287.606339) (xy 375.518698 -287.68455)
			(xy 375.491502 -287.721802) (xy 375.490994 -287.72231) (xy 375.471842 -287.748665) (xy 375.430922 -287.79937)
			(xy 375.409206 -287.823656) (xy 375.403359 -287.830596) (xy 375.396568 -287.847411) (xy 375.396337 -287.856168)
			(xy 375.678695 -287.856168) (xy 375.68279 -287.80544) (xy 375.694969 -287.756026) (xy 375.714917 -287.709206)
			(xy 375.742118 -287.666192) (xy 375.775866 -287.628098) (xy 375.815288 -287.595911) (xy 375.859362 -287.570465)
			(xy 375.906948 -287.552418) (xy 375.956812 -287.542238) (xy 376.007664 -287.540189) (xy 376.058185 -287.546323)
			(xy 376.107069 -287.560483) (xy 376.153048 -287.5823) (xy 376.194932 -287.61121) (xy 376.231636 -287.646465)
			(xy 376.262209 -287.687151) (xy 376.28586 -287.732214) (xy 376.301976 -287.780488) (xy 376.31014 -287.830722)
			(xy 376.310652 -287.856168) (xy 376.628926 -287.856168) (xy 376.632886 -287.807114) (xy 376.644663 -287.75933)
			(xy 376.663954 -287.714054) (xy 376.690257 -287.672458) (xy 376.722892 -287.635621) (xy 376.761013 -287.604496)
			(xy 376.803634 -287.579889) (xy 376.84965 -287.562437) (xy 376.897869 -287.552593) (xy 376.947044 -287.550612)
			(xy 376.995899 -287.556544) (xy 377.04317 -287.570236) (xy 377.087632 -287.591334) (xy 377.128135 -287.61929)
			(xy 377.163628 -287.653382) (xy 377.193193 -287.692726) (xy 377.216064 -287.736303) (xy 377.231648 -287.782984)
			(xy 377.239543 -287.831561) (xy 377.240038 -287.856168) (xy 377.558549 -287.856168) (xy 377.562644 -287.80544)
			(xy 377.574823 -287.756026) (xy 377.594771 -287.709206) (xy 377.621972 -287.666192) (xy 377.65572 -287.628098)
			(xy 377.695142 -287.595911) (xy 377.739216 -287.570465) (xy 377.786802 -287.552418) (xy 377.836666 -287.542238)
			(xy 377.887518 -287.540189) (xy 377.938039 -287.546323) (xy 377.986923 -287.560483) (xy 378.032902 -287.5823)
			(xy 378.074786 -287.61121) (xy 378.11149 -287.646465) (xy 378.142063 -287.687151) (xy 378.165714 -287.732214)
			(xy 378.18183 -287.780488) (xy 378.189994 -287.830722) (xy 378.190506 -287.856168) (xy 379.438657 -287.856168)
			(xy 379.442752 -287.80544) (xy 379.454931 -287.756026) (xy 379.474879 -287.709206) (xy 379.50208 -287.666192)
			(xy 379.535828 -287.628098) (xy 379.57525 -287.595911) (xy 379.619324 -287.570465) (xy 379.66691 -287.552418)
			(xy 379.716774 -287.542238) (xy 379.767626 -287.540189) (xy 379.818147 -287.546323) (xy 379.867031 -287.560483)
			(xy 379.91301 -287.5823) (xy 379.954894 -287.61121) (xy 379.991598 -287.646465) (xy 380.022171 -287.687151)
			(xy 380.045822 -287.732214) (xy 380.061938 -287.780488) (xy 380.070102 -287.830722) (xy 380.070614 -287.856168)
			(xy 380.378711 -287.856168) (xy 380.382806 -287.80544) (xy 380.394985 -287.756026) (xy 380.414933 -287.709206)
			(xy 380.442134 -287.666192) (xy 380.475882 -287.628098) (xy 380.515304 -287.595911) (xy 380.559378 -287.570465)
			(xy 380.606964 -287.552418) (xy 380.656828 -287.542238) (xy 380.70768 -287.540189) (xy 380.758201 -287.546323)
			(xy 380.807085 -287.560483) (xy 380.853064 -287.5823) (xy 380.894948 -287.61121) (xy 380.931652 -287.646465)
			(xy 380.962225 -287.687151) (xy 380.985876 -287.732214) (xy 381.001992 -287.780488) (xy 381.010156 -287.830722)
			(xy 381.010668 -287.856168) (xy 381.328942 -287.856168) (xy 381.332902 -287.807114) (xy 381.344679 -287.75933)
			(xy 381.36397 -287.714054) (xy 381.390273 -287.672458) (xy 381.422908 -287.635621) (xy 381.461029 -287.604496)
			(xy 381.50365 -287.579889) (xy 381.549666 -287.562437) (xy 381.597885 -287.552593) (xy 381.64706 -287.550612)
			(xy 381.695915 -287.556544) (xy 381.743186 -287.570236) (xy 381.787648 -287.591334) (xy 381.828151 -287.61929)
			(xy 381.863644 -287.653382) (xy 381.893209 -287.692726) (xy 381.91608 -287.736303) (xy 381.931664 -287.782984)
			(xy 381.939559 -287.831561) (xy 381.940054 -287.856168) (xy 382.268996 -287.856168) (xy 382.272956 -287.807114)
			(xy 382.284733 -287.75933) (xy 382.304024 -287.714054) (xy 382.330327 -287.672458) (xy 382.362962 -287.635621)
			(xy 382.401083 -287.604496) (xy 382.443704 -287.579889) (xy 382.48972 -287.562437) (xy 382.537939 -287.552593)
			(xy 382.587114 -287.550612) (xy 382.635969 -287.556544) (xy 382.68324 -287.570236) (xy 382.727702 -287.591334)
			(xy 382.768205 -287.61929) (xy 382.803698 -287.653382) (xy 382.833263 -287.692726) (xy 382.856134 -287.736303)
			(xy 382.871718 -287.782984) (xy 382.879613 -287.831561) (xy 382.880108 -287.856168) (xy 383.20905 -287.856168)
			(xy 383.21301 -287.807114) (xy 383.224787 -287.75933) (xy 383.244078 -287.714054) (xy 383.270381 -287.672458)
			(xy 383.303016 -287.635621) (xy 383.341137 -287.604496) (xy 383.383758 -287.579889) (xy 383.429774 -287.562437)
			(xy 383.477993 -287.552593) (xy 383.527168 -287.550612) (xy 383.576023 -287.556544) (xy 383.623294 -287.570236)
			(xy 383.667756 -287.591334) (xy 383.708259 -287.61929) (xy 383.743752 -287.653382) (xy 383.773317 -287.692726)
			(xy 383.796188 -287.736303) (xy 383.811772 -287.782984) (xy 383.819667 -287.831561) (xy 383.820162 -287.856168)
			(xy 384.149104 -287.856168) (xy 384.153064 -287.807114) (xy 384.164841 -287.75933) (xy 384.184132 -287.714054)
			(xy 384.210435 -287.672458) (xy 384.24307 -287.635621) (xy 384.281191 -287.604496) (xy 384.323812 -287.579889)
			(xy 384.369828 -287.562437) (xy 384.418047 -287.552593) (xy 384.467222 -287.550612) (xy 384.516077 -287.556544)
			(xy 384.563348 -287.570236) (xy 384.60781 -287.591334) (xy 384.648313 -287.61929) (xy 384.683806 -287.653382)
			(xy 384.713371 -287.692726) (xy 384.736242 -287.736303) (xy 384.751826 -287.782984) (xy 384.759721 -287.831561)
			(xy 384.760216 -287.856168) (xy 386.028958 -287.856168) (xy 386.032918 -287.807114) (xy 386.044695 -287.75933)
			(xy 386.063986 -287.714054) (xy 386.090289 -287.672458) (xy 386.122924 -287.635621) (xy 386.161045 -287.604496)
			(xy 386.203666 -287.579889) (xy 386.249682 -287.562437) (xy 386.297901 -287.552593) (xy 386.347076 -287.550612)
			(xy 386.395931 -287.556544) (xy 386.443202 -287.570236) (xy 386.487664 -287.591334) (xy 386.528167 -287.61929)
			(xy 386.56366 -287.653382) (xy 386.593225 -287.692726) (xy 386.616096 -287.736303) (xy 386.63168 -287.782984)
			(xy 386.639575 -287.831561) (xy 386.64007 -287.856168) (xy 386.969012 -287.856168) (xy 386.972972 -287.807114)
			(xy 386.984749 -287.75933) (xy 387.00404 -287.714054) (xy 387.030343 -287.672458) (xy 387.062978 -287.635621)
			(xy 387.101099 -287.604496) (xy 387.14372 -287.579889) (xy 387.189736 -287.562437) (xy 387.237955 -287.552593)
			(xy 387.28713 -287.550612) (xy 387.335985 -287.556544) (xy 387.383256 -287.570236) (xy 387.427718 -287.591334)
			(xy 387.468221 -287.61929) (xy 387.503714 -287.653382) (xy 387.533279 -287.692726) (xy 387.55615 -287.736303)
			(xy 387.571734 -287.782984) (xy 387.579629 -287.831561) (xy 387.580124 -287.856168) (xy 387.579629 -287.880775)
			(xy 387.571734 -287.929352) (xy 387.55615 -287.976033) (xy 387.533279 -288.01961) (xy 387.503714 -288.058954)
			(xy 387.468221 -288.093046) (xy 387.427718 -288.121002) (xy 387.383256 -288.1421) (xy 387.335985 -288.155792)
			(xy 387.28713 -288.161724) (xy 387.237955 -288.159743) (xy 387.189736 -288.149899) (xy 387.14372 -288.132447)
			(xy 387.101099 -288.10784) (xy 387.062978 -288.076715) (xy 387.030343 -288.039878) (xy 387.00404 -287.998282)
			(xy 386.984749 -287.953006) (xy 386.972972 -287.905222) (xy 386.969012 -287.856168) (xy 386.64007 -287.856168)
			(xy 386.639575 -287.880775) (xy 386.63168 -287.929352) (xy 386.616096 -287.976033) (xy 386.593225 -288.01961)
			(xy 386.56366 -288.058954) (xy 386.528167 -288.093046) (xy 386.487664 -288.121002) (xy 386.443202 -288.1421)
			(xy 386.395931 -288.155792) (xy 386.347076 -288.161724) (xy 386.297901 -288.159743) (xy 386.249682 -288.149899)
			(xy 386.203666 -288.132447) (xy 386.161045 -288.10784) (xy 386.122924 -288.076715) (xy 386.090289 -288.039878)
			(xy 386.063986 -287.998282) (xy 386.044695 -287.953006) (xy 386.032918 -287.905222) (xy 386.028958 -287.856168)
			(xy 384.760216 -287.856168) (xy 384.759721 -287.880775) (xy 384.751826 -287.929352) (xy 384.736242 -287.976033)
			(xy 384.713371 -288.01961) (xy 384.683806 -288.058954) (xy 384.648313 -288.093046) (xy 384.60781 -288.121002)
			(xy 384.563348 -288.1421) (xy 384.516077 -288.155792) (xy 384.467222 -288.161724) (xy 384.418047 -288.159743)
			(xy 384.369828 -288.149899) (xy 384.323812 -288.132447) (xy 384.281191 -288.10784) (xy 384.24307 -288.076715)
			(xy 384.210435 -288.039878) (xy 384.184132 -287.998282) (xy 384.164841 -287.953006) (xy 384.153064 -287.905222)
			(xy 384.149104 -287.856168) (xy 383.820162 -287.856168) (xy 383.819667 -287.880775) (xy 383.811772 -287.929352)
			(xy 383.796188 -287.976033) (xy 383.773317 -288.01961) (xy 383.743752 -288.058954) (xy 383.708259 -288.093046)
			(xy 383.667756 -288.121002) (xy 383.623294 -288.1421) (xy 383.576023 -288.155792) (xy 383.527168 -288.161724)
			(xy 383.477993 -288.159743) (xy 383.429774 -288.149899) (xy 383.383758 -288.132447) (xy 383.341137 -288.10784)
			(xy 383.303016 -288.076715) (xy 383.270381 -288.039878) (xy 383.244078 -287.998282) (xy 383.224787 -287.953006)
			(xy 383.21301 -287.905222) (xy 383.20905 -287.856168) (xy 382.880108 -287.856168) (xy 382.879613 -287.880775)
			(xy 382.871718 -287.929352) (xy 382.856134 -287.976033) (xy 382.833263 -288.01961) (xy 382.803698 -288.058954)
			(xy 382.768205 -288.093046) (xy 382.727702 -288.121002) (xy 382.68324 -288.1421) (xy 382.635969 -288.155792)
			(xy 382.587114 -288.161724) (xy 382.537939 -288.159743) (xy 382.48972 -288.149899) (xy 382.443704 -288.132447)
			(xy 382.401083 -288.10784) (xy 382.362962 -288.076715) (xy 382.330327 -288.039878) (xy 382.304024 -287.998282)
			(xy 382.284733 -287.953006) (xy 382.272956 -287.905222) (xy 382.268996 -287.856168) (xy 381.940054 -287.856168)
			(xy 381.939559 -287.880775) (xy 381.931664 -287.929352) (xy 381.91608 -287.976033) (xy 381.893209 -288.01961)
			(xy 381.863644 -288.058954) (xy 381.828151 -288.093046) (xy 381.787648 -288.121002) (xy 381.743186 -288.1421)
			(xy 381.695915 -288.155792) (xy 381.64706 -288.161724) (xy 381.597885 -288.159743) (xy 381.549666 -288.149899)
			(xy 381.50365 -288.132447) (xy 381.461029 -288.10784) (xy 381.422908 -288.076715) (xy 381.390273 -288.039878)
			(xy 381.36397 -287.998282) (xy 381.344679 -287.953006) (xy 381.332902 -287.905222) (xy 381.328942 -287.856168)
			(xy 381.010668 -287.856168) (xy 381.010156 -287.881614) (xy 381.001992 -287.931848) (xy 380.985876 -287.980122)
			(xy 380.962225 -288.025185) (xy 380.931652 -288.065871) (xy 380.894948 -288.101126) (xy 380.853064 -288.130036)
			(xy 380.807085 -288.151853) (xy 380.758201 -288.166013) (xy 380.70768 -288.172147) (xy 380.656828 -288.170098)
			(xy 380.606964 -288.159918) (xy 380.559378 -288.141871) (xy 380.515304 -288.116425) (xy 380.475882 -288.084238)
			(xy 380.442134 -288.046144) (xy 380.414933 -288.00313) (xy 380.394985 -287.95631) (xy 380.382806 -287.906896)
			(xy 380.378711 -287.856168) (xy 380.070614 -287.856168) (xy 380.070102 -287.881614) (xy 380.061938 -287.931848)
			(xy 380.045822 -287.980122) (xy 380.022171 -288.025185) (xy 379.991598 -288.065871) (xy 379.954894 -288.101126)
			(xy 379.91301 -288.130036) (xy 379.867031 -288.151853) (xy 379.818147 -288.166013) (xy 379.767626 -288.172147)
			(xy 379.716774 -288.170098) (xy 379.66691 -288.159918) (xy 379.619324 -288.141871) (xy 379.57525 -288.116425)
			(xy 379.535828 -288.084238) (xy 379.50208 -288.046144) (xy 379.474879 -288.00313) (xy 379.454931 -287.95631)
			(xy 379.442752 -287.906896) (xy 379.438657 -287.856168) (xy 378.190506 -287.856168) (xy 378.189994 -287.881614)
			(xy 378.18183 -287.931848) (xy 378.165714 -287.980122) (xy 378.142063 -288.025185) (xy 378.11149 -288.065871)
			(xy 378.074786 -288.101126) (xy 378.032902 -288.130036) (xy 377.986923 -288.151853) (xy 377.938039 -288.166013)
			(xy 377.887518 -288.172147) (xy 377.836666 -288.170098) (xy 377.786802 -288.159918) (xy 377.739216 -288.141871)
			(xy 377.695142 -288.116425) (xy 377.65572 -288.084238) (xy 377.621972 -288.046144) (xy 377.594771 -288.00313)
			(xy 377.574823 -287.95631) (xy 377.562644 -287.906896) (xy 377.558549 -287.856168) (xy 377.240038 -287.856168)
			(xy 377.239543 -287.880775) (xy 377.231648 -287.929352) (xy 377.216064 -287.976033) (xy 377.193193 -288.01961)
			(xy 377.163628 -288.058954) (xy 377.128135 -288.093046) (xy 377.087632 -288.121002) (xy 377.04317 -288.1421)
			(xy 376.995899 -288.155792) (xy 376.947044 -288.161724) (xy 376.897869 -288.159743) (xy 376.84965 -288.149899)
			(xy 376.803634 -288.132447) (xy 376.761013 -288.10784) (xy 376.722892 -288.076715) (xy 376.690257 -288.039878)
			(xy 376.663954 -287.998282) (xy 376.644663 -287.953006) (xy 376.632886 -287.905222) (xy 376.628926 -287.856168)
			(xy 376.310652 -287.856168) (xy 376.31014 -287.881614) (xy 376.301976 -287.931848) (xy 376.28586 -287.980122)
			(xy 376.262209 -288.025185) (xy 376.231636 -288.065871) (xy 376.194932 -288.101126) (xy 376.153048 -288.130036)
			(xy 376.107069 -288.151853) (xy 376.058185 -288.166013) (xy 376.007664 -288.172147) (xy 375.956812 -288.170098)
			(xy 375.906948 -288.159918) (xy 375.859362 -288.141871) (xy 375.815288 -288.116425) (xy 375.775866 -288.084238)
			(xy 375.742118 -288.046144) (xy 375.714917 -288.00313) (xy 375.694969 -287.95631) (xy 375.68279 -287.906896)
			(xy 375.678695 -287.856168) (xy 375.396337 -287.856168) (xy 375.396089 -287.865539) (xy 375.401983 -287.882688)
			(xy 375.407428 -287.88995) (xy 375.613168 -288.109406) (xy 375.604024 -288.159444) (xy 375.597674 -288.162746)
			(xy 375.60957 -288.187108) (xy 375.631298 -288.236786) (xy 375.641108 -288.26206) (xy 375.64949 -288.284317)
			(xy 375.664607 -288.329418) (xy 375.671334 -288.35223) (xy 375.671334 -288.352738) (xy 375.674354 -288.361644)
			(xy 375.685828 -288.376529) (xy 375.693686 -288.381694) (xy 375.694194 -288.381948) (xy 375.716509 -288.395851)
			(xy 375.756828 -288.429591) (xy 375.791299 -288.469286) (xy 375.819055 -288.513936) (xy 375.839395 -288.562415)
			(xy 375.851807 -288.613502) (xy 375.855978 -288.66591) (xy 375.855977 -288.66592) (xy 376.148595 -288.66592)
			(xy 376.15269 -288.615192) (xy 376.164869 -288.565778) (xy 376.184817 -288.518958) (xy 376.212018 -288.475944)
			(xy 376.245766 -288.43785) (xy 376.285188 -288.405663) (xy 376.329262 -288.380217) (xy 376.376848 -288.36217)
			(xy 376.426712 -288.35199) (xy 376.477564 -288.349941) (xy 376.528085 -288.356075) (xy 376.576969 -288.370235)
			(xy 376.622948 -288.392052) (xy 376.664832 -288.420962) (xy 376.701536 -288.456217) (xy 376.732109 -288.496903)
			(xy 376.75576 -288.541966) (xy 376.771876 -288.59024) (xy 376.78004 -288.640474) (xy 376.780552 -288.66592)
			(xy 377.088649 -288.66592) (xy 377.092744 -288.615192) (xy 377.104923 -288.565778) (xy 377.124871 -288.518958)
			(xy 377.152072 -288.475944) (xy 377.18582 -288.43785) (xy 377.225242 -288.405663) (xy 377.269316 -288.380217)
			(xy 377.316902 -288.36217) (xy 377.366766 -288.35199) (xy 377.417618 -288.349941) (xy 377.468139 -288.356075)
			(xy 377.517023 -288.370235) (xy 377.563002 -288.392052) (xy 377.604886 -288.420962) (xy 377.64159 -288.456217)
			(xy 377.672163 -288.496903) (xy 377.695814 -288.541966) (xy 377.71193 -288.59024) (xy 377.720094 -288.640474)
			(xy 377.720606 -288.66592) (xy 378.039134 -288.66592) (xy 378.043094 -288.616866) (xy 378.054871 -288.569082)
			(xy 378.074162 -288.523806) (xy 378.100465 -288.48221) (xy 378.1331 -288.445373) (xy 378.171221 -288.414248)
			(xy 378.213842 -288.389641) (xy 378.259858 -288.372189) (xy 378.308077 -288.362345) (xy 378.357252 -288.360364)
			(xy 378.406107 -288.366296) (xy 378.453378 -288.379988) (xy 378.49784 -288.401086) (xy 378.538343 -288.429042)
			(xy 378.573836 -288.463134) (xy 378.603401 -288.502478) (xy 378.626272 -288.546055) (xy 378.641856 -288.592736)
			(xy 378.649751 -288.641313) (xy 378.650246 -288.66592) (xy 378.968503 -288.66592) (xy 378.972598 -288.615192)
			(xy 378.984777 -288.565778) (xy 379.004725 -288.518958) (xy 379.031926 -288.475944) (xy 379.065674 -288.43785)
			(xy 379.105096 -288.405663) (xy 379.14917 -288.380217) (xy 379.196756 -288.36217) (xy 379.24662 -288.35199)
			(xy 379.297472 -288.349941) (xy 379.347993 -288.356075) (xy 379.396877 -288.370235) (xy 379.442856 -288.392052)
			(xy 379.48474 -288.420962) (xy 379.521444 -288.456217) (xy 379.552017 -288.496903) (xy 379.575668 -288.541966)
			(xy 379.591784 -288.59024) (xy 379.599948 -288.640474) (xy 379.60046 -288.66592) (xy 379.918988 -288.66592)
			(xy 379.922948 -288.616866) (xy 379.934725 -288.569082) (xy 379.954016 -288.523806) (xy 379.980319 -288.48221)
			(xy 380.012954 -288.445373) (xy 380.051075 -288.414248) (xy 380.093696 -288.389641) (xy 380.139712 -288.372189)
			(xy 380.187931 -288.362345) (xy 380.237106 -288.360364) (xy 380.285961 -288.366296) (xy 380.333232 -288.379988)
			(xy 380.377694 -288.401086) (xy 380.418197 -288.429042) (xy 380.45369 -288.463134) (xy 380.483255 -288.502478)
			(xy 380.506126 -288.546055) (xy 380.52171 -288.592736) (xy 380.529605 -288.641313) (xy 380.5301 -288.66592)
			(xy 380.848611 -288.66592) (xy 380.852706 -288.615192) (xy 380.864885 -288.565778) (xy 380.884833 -288.518958)
			(xy 380.912034 -288.475944) (xy 380.945782 -288.43785) (xy 380.985204 -288.405663) (xy 381.029278 -288.380217)
			(xy 381.076864 -288.36217) (xy 381.126728 -288.35199) (xy 381.17758 -288.349941) (xy 381.228101 -288.356075)
			(xy 381.276985 -288.370235) (xy 381.322964 -288.392052) (xy 381.364848 -288.420962) (xy 381.401552 -288.456217)
			(xy 381.432125 -288.496903) (xy 381.455776 -288.541966) (xy 381.471892 -288.59024) (xy 381.480056 -288.640474)
			(xy 381.480568 -288.66592) (xy 381.799096 -288.66592) (xy 381.803056 -288.616866) (xy 381.814833 -288.569082)
			(xy 381.834124 -288.523806) (xy 381.860427 -288.48221) (xy 381.893062 -288.445373) (xy 381.931183 -288.414248)
			(xy 381.973804 -288.389641) (xy 382.01982 -288.372189) (xy 382.068039 -288.362345) (xy 382.117214 -288.360364)
			(xy 382.166069 -288.366296) (xy 382.21334 -288.379988) (xy 382.257802 -288.401086) (xy 382.298305 -288.429042)
			(xy 382.333798 -288.463134) (xy 382.363363 -288.502478) (xy 382.386234 -288.546055) (xy 382.401818 -288.592736)
			(xy 382.409713 -288.641313) (xy 382.410208 -288.66592) (xy 382.738896 -288.66592) (xy 382.742856 -288.616866)
			(xy 382.754633 -288.569082) (xy 382.773924 -288.523806) (xy 382.800227 -288.48221) (xy 382.832862 -288.445373)
			(xy 382.870983 -288.414248) (xy 382.913604 -288.389641) (xy 382.95962 -288.372189) (xy 383.007839 -288.362345)
			(xy 383.057014 -288.360364) (xy 383.105869 -288.366296) (xy 383.15314 -288.379988) (xy 383.197602 -288.401086)
			(xy 383.238105 -288.429042) (xy 383.273598 -288.463134) (xy 383.303163 -288.502478) (xy 383.326034 -288.546055)
			(xy 383.341618 -288.592736) (xy 383.349513 -288.641313) (xy 383.350008 -288.66592) (xy 383.67895 -288.66592)
			(xy 383.68291 -288.616866) (xy 383.694687 -288.569082) (xy 383.713978 -288.523806) (xy 383.740281 -288.48221)
			(xy 383.772916 -288.445373) (xy 383.811037 -288.414248) (xy 383.853658 -288.389641) (xy 383.899674 -288.372189)
			(xy 383.947893 -288.362345) (xy 383.997068 -288.360364) (xy 384.045923 -288.366296) (xy 384.093194 -288.379988)
			(xy 384.137656 -288.401086) (xy 384.178159 -288.429042) (xy 384.213652 -288.463134) (xy 384.243217 -288.502478)
			(xy 384.266088 -288.546055) (xy 384.281672 -288.592736) (xy 384.289567 -288.641313) (xy 384.290062 -288.66592)
			(xy 384.619004 -288.66592) (xy 384.622964 -288.616866) (xy 384.634741 -288.569082) (xy 384.654032 -288.523806)
			(xy 384.680335 -288.48221) (xy 384.71297 -288.445373) (xy 384.751091 -288.414248) (xy 384.793712 -288.389641)
			(xy 384.839728 -288.372189) (xy 384.887947 -288.362345) (xy 384.937122 -288.360364) (xy 384.985977 -288.366296)
			(xy 385.033248 -288.379988) (xy 385.07771 -288.401086) (xy 385.118213 -288.429042) (xy 385.153706 -288.463134)
			(xy 385.183271 -288.502478) (xy 385.206142 -288.546055) (xy 385.221726 -288.592736) (xy 385.229621 -288.641313)
			(xy 385.230116 -288.66592) (xy 385.559058 -288.66592) (xy 385.563018 -288.616866) (xy 385.574795 -288.569082)
			(xy 385.594086 -288.523806) (xy 385.620389 -288.48221) (xy 385.653024 -288.445373) (xy 385.691145 -288.414248)
			(xy 385.733766 -288.389641) (xy 385.779782 -288.372189) (xy 385.828001 -288.362345) (xy 385.877176 -288.360364)
			(xy 385.926031 -288.366296) (xy 385.973302 -288.379988) (xy 386.017764 -288.401086) (xy 386.058267 -288.429042)
			(xy 386.09376 -288.463134) (xy 386.123325 -288.502478) (xy 386.146196 -288.546055) (xy 386.16178 -288.592736)
			(xy 386.169675 -288.641313) (xy 386.17017 -288.66592) (xy 386.499112 -288.66592) (xy 386.503072 -288.616866)
			(xy 386.514849 -288.569082) (xy 386.53414 -288.523806) (xy 386.560443 -288.48221) (xy 386.593078 -288.445373)
			(xy 386.631199 -288.414248) (xy 386.67382 -288.389641) (xy 386.719836 -288.372189) (xy 386.768055 -288.362345)
			(xy 386.81723 -288.360364) (xy 386.866085 -288.366296) (xy 386.913356 -288.379988) (xy 386.957818 -288.401086)
			(xy 386.998321 -288.429042) (xy 387.033814 -288.463134) (xy 387.063379 -288.502478) (xy 387.08625 -288.546055)
			(xy 387.101834 -288.592736) (xy 387.109729 -288.641313) (xy 387.110224 -288.66592) (xy 387.438912 -288.66592)
			(xy 387.442872 -288.616866) (xy 387.454649 -288.569082) (xy 387.47394 -288.523806) (xy 387.500243 -288.48221)
			(xy 387.532878 -288.445373) (xy 387.570999 -288.414248) (xy 387.61362 -288.389641) (xy 387.659636 -288.372189)
			(xy 387.707855 -288.362345) (xy 387.75703 -288.360364) (xy 387.805885 -288.366296) (xy 387.853156 -288.379988)
			(xy 387.897618 -288.401086) (xy 387.938121 -288.429042) (xy 387.973614 -288.463134) (xy 388.003179 -288.502478)
			(xy 388.02605 -288.546055) (xy 388.041634 -288.592736) (xy 388.049529 -288.641313) (xy 388.050024 -288.66592)
			(xy 388.049529 -288.690527) (xy 388.041634 -288.739104) (xy 388.02605 -288.785785) (xy 388.003179 -288.829362)
			(xy 387.973614 -288.868706) (xy 387.938121 -288.902798) (xy 387.897618 -288.930754) (xy 387.853156 -288.951852)
			(xy 387.805885 -288.965544) (xy 387.75703 -288.971476) (xy 387.707855 -288.969495) (xy 387.659636 -288.959651)
			(xy 387.61362 -288.942199) (xy 387.570999 -288.917592) (xy 387.532878 -288.886467) (xy 387.500243 -288.84963)
			(xy 387.47394 -288.808034) (xy 387.454649 -288.762758) (xy 387.442872 -288.714974) (xy 387.438912 -288.66592)
			(xy 387.110224 -288.66592) (xy 387.109729 -288.690527) (xy 387.101834 -288.739104) (xy 387.08625 -288.785785)
			(xy 387.063379 -288.829362) (xy 387.033814 -288.868706) (xy 386.998321 -288.902798) (xy 386.957818 -288.930754)
			(xy 386.913356 -288.951852) (xy 386.866085 -288.965544) (xy 386.81723 -288.971476) (xy 386.768055 -288.969495)
			(xy 386.719836 -288.959651) (xy 386.67382 -288.942199) (xy 386.631199 -288.917592) (xy 386.593078 -288.886467)
			(xy 386.560443 -288.84963) (xy 386.53414 -288.808034) (xy 386.514849 -288.762758) (xy 386.503072 -288.714974)
			(xy 386.499112 -288.66592) (xy 386.17017 -288.66592) (xy 386.169675 -288.690527) (xy 386.16178 -288.739104)
			(xy 386.146196 -288.785785) (xy 386.123325 -288.829362) (xy 386.09376 -288.868706) (xy 386.058267 -288.902798)
			(xy 386.017764 -288.930754) (xy 385.973302 -288.951852) (xy 385.926031 -288.965544) (xy 385.877176 -288.971476)
			(xy 385.828001 -288.969495) (xy 385.779782 -288.959651) (xy 385.733766 -288.942199) (xy 385.691145 -288.917592)
			(xy 385.653024 -288.886467) (xy 385.620389 -288.84963) (xy 385.594086 -288.808034) (xy 385.574795 -288.762758)
			(xy 385.563018 -288.714974) (xy 385.559058 -288.66592) (xy 385.230116 -288.66592) (xy 385.229621 -288.690527)
			(xy 385.221726 -288.739104) (xy 385.206142 -288.785785) (xy 385.183271 -288.829362) (xy 385.153706 -288.868706)
			(xy 385.118213 -288.902798) (xy 385.07771 -288.930754) (xy 385.033248 -288.951852) (xy 384.985977 -288.965544)
			(xy 384.937122 -288.971476) (xy 384.887947 -288.969495) (xy 384.839728 -288.959651) (xy 384.793712 -288.942199)
			(xy 384.751091 -288.917592) (xy 384.71297 -288.886467) (xy 384.680335 -288.84963) (xy 384.654032 -288.808034)
			(xy 384.634741 -288.762758) (xy 384.622964 -288.714974) (xy 384.619004 -288.66592) (xy 384.290062 -288.66592)
			(xy 384.289567 -288.690527) (xy 384.281672 -288.739104) (xy 384.266088 -288.785785) (xy 384.243217 -288.829362)
			(xy 384.213652 -288.868706) (xy 384.178159 -288.902798) (xy 384.137656 -288.930754) (xy 384.093194 -288.951852)
			(xy 384.045923 -288.965544) (xy 383.997068 -288.971476) (xy 383.947893 -288.969495) (xy 383.899674 -288.959651)
			(xy 383.853658 -288.942199) (xy 383.811037 -288.917592) (xy 383.772916 -288.886467) (xy 383.740281 -288.84963)
			(xy 383.713978 -288.808034) (xy 383.694687 -288.762758) (xy 383.68291 -288.714974) (xy 383.67895 -288.66592)
			(xy 383.350008 -288.66592) (xy 383.349513 -288.690527) (xy 383.341618 -288.739104) (xy 383.326034 -288.785785)
			(xy 383.303163 -288.829362) (xy 383.273598 -288.868706) (xy 383.238105 -288.902798) (xy 383.197602 -288.930754)
			(xy 383.15314 -288.951852) (xy 383.105869 -288.965544) (xy 383.057014 -288.971476) (xy 383.007839 -288.969495)
			(xy 382.95962 -288.959651) (xy 382.913604 -288.942199) (xy 382.870983 -288.917592) (xy 382.832862 -288.886467)
			(xy 382.800227 -288.84963) (xy 382.773924 -288.808034) (xy 382.754633 -288.762758) (xy 382.742856 -288.714974)
			(xy 382.738896 -288.66592) (xy 382.410208 -288.66592) (xy 382.409713 -288.690527) (xy 382.401818 -288.739104)
			(xy 382.386234 -288.785785) (xy 382.363363 -288.829362) (xy 382.333798 -288.868706) (xy 382.298305 -288.902798)
			(xy 382.257802 -288.930754) (xy 382.21334 -288.951852) (xy 382.166069 -288.965544) (xy 382.117214 -288.971476)
			(xy 382.068039 -288.969495) (xy 382.01982 -288.959651) (xy 381.973804 -288.942199) (xy 381.931183 -288.917592)
			(xy 381.893062 -288.886467) (xy 381.860427 -288.84963) (xy 381.834124 -288.808034) (xy 381.814833 -288.762758)
			(xy 381.803056 -288.714974) (xy 381.799096 -288.66592) (xy 381.480568 -288.66592) (xy 381.480056 -288.691366)
			(xy 381.471892 -288.7416) (xy 381.455776 -288.789874) (xy 381.432125 -288.834937) (xy 381.401552 -288.875623)
			(xy 381.364848 -288.910878) (xy 381.322964 -288.939788) (xy 381.276985 -288.961605) (xy 381.228101 -288.975765)
			(xy 381.17758 -288.981899) (xy 381.126728 -288.97985) (xy 381.076864 -288.96967) (xy 381.029278 -288.951623)
			(xy 380.985204 -288.926177) (xy 380.945782 -288.89399) (xy 380.912034 -288.855896) (xy 380.884833 -288.812882)
			(xy 380.864885 -288.766062) (xy 380.852706 -288.716648) (xy 380.848611 -288.66592) (xy 380.5301 -288.66592)
			(xy 380.529605 -288.690527) (xy 380.52171 -288.739104) (xy 380.506126 -288.785785) (xy 380.483255 -288.829362)
			(xy 380.45369 -288.868706) (xy 380.418197 -288.902798) (xy 380.377694 -288.930754) (xy 380.333232 -288.951852)
			(xy 380.285961 -288.965544) (xy 380.237106 -288.971476) (xy 380.187931 -288.969495) (xy 380.139712 -288.959651)
			(xy 380.093696 -288.942199) (xy 380.051075 -288.917592) (xy 380.012954 -288.886467) (xy 379.980319 -288.84963)
			(xy 379.954016 -288.808034) (xy 379.934725 -288.762758) (xy 379.922948 -288.714974) (xy 379.918988 -288.66592)
			(xy 379.60046 -288.66592) (xy 379.599948 -288.691366) (xy 379.591784 -288.7416) (xy 379.575668 -288.789874)
			(xy 379.552017 -288.834937) (xy 379.521444 -288.875623) (xy 379.48474 -288.910878) (xy 379.442856 -288.939788)
			(xy 379.396877 -288.961605) (xy 379.347993 -288.975765) (xy 379.297472 -288.981899) (xy 379.24662 -288.97985)
			(xy 379.196756 -288.96967) (xy 379.14917 -288.951623) (xy 379.105096 -288.926177) (xy 379.065674 -288.89399)
			(xy 379.031926 -288.855896) (xy 379.004725 -288.812882) (xy 378.984777 -288.766062) (xy 378.972598 -288.716648)
			(xy 378.968503 -288.66592) (xy 378.650246 -288.66592) (xy 378.649751 -288.690527) (xy 378.641856 -288.739104)
			(xy 378.626272 -288.785785) (xy 378.603401 -288.829362) (xy 378.573836 -288.868706) (xy 378.538343 -288.902798)
			(xy 378.49784 -288.930754) (xy 378.453378 -288.951852) (xy 378.406107 -288.965544) (xy 378.357252 -288.971476)
			(xy 378.308077 -288.969495) (xy 378.259858 -288.959651) (xy 378.213842 -288.942199) (xy 378.171221 -288.917592)
			(xy 378.1331 -288.886467) (xy 378.100465 -288.84963) (xy 378.074162 -288.808034) (xy 378.054871 -288.762758)
			(xy 378.043094 -288.714974) (xy 378.039134 -288.66592) (xy 377.720606 -288.66592) (xy 377.720094 -288.691366)
			(xy 377.71193 -288.7416) (xy 377.695814 -288.789874) (xy 377.672163 -288.834937) (xy 377.64159 -288.875623)
			(xy 377.604886 -288.910878) (xy 377.563002 -288.939788) (xy 377.517023 -288.961605) (xy 377.468139 -288.975765)
			(xy 377.417618 -288.981899) (xy 377.366766 -288.97985) (xy 377.316902 -288.96967) (xy 377.269316 -288.951623)
			(xy 377.225242 -288.926177) (xy 377.18582 -288.89399) (xy 377.152072 -288.855896) (xy 377.124871 -288.812882)
			(xy 377.104923 -288.766062) (xy 377.092744 -288.716648) (xy 377.088649 -288.66592) (xy 376.780552 -288.66592)
			(xy 376.78004 -288.691366) (xy 376.771876 -288.7416) (xy 376.75576 -288.789874) (xy 376.732109 -288.834937)
			(xy 376.701536 -288.875623) (xy 376.664832 -288.910878) (xy 376.622948 -288.939788) (xy 376.576969 -288.961605)
			(xy 376.528085 -288.975765) (xy 376.477564 -288.981899) (xy 376.426712 -288.97985) (xy 376.376848 -288.96967)
			(xy 376.329262 -288.951623) (xy 376.285188 -288.926177) (xy 376.245766 -288.89399) (xy 376.212018 -288.855896)
			(xy 376.184817 -288.812882) (xy 376.164869 -288.766062) (xy 376.15269 -288.716648) (xy 376.148595 -288.66592)
			(xy 375.855977 -288.66592) (xy 375.851804 -288.718318) (xy 375.839389 -288.769404) (xy 375.819045 -288.817883)
			(xy 375.791287 -288.862531) (xy 375.756813 -288.902224) (xy 375.716493 -288.935961) (xy 375.694194 -288.949892)
			(xy 375.693686 -288.950146) (xy 375.686444 -288.955039) (xy 375.675531 -288.968675) (xy 375.67235 -288.976816)
			(xy 375.666762 -288.99612) (xy 375.666254 -288.997644) (xy 375.659396 -289.018472) (xy 375.637806 -289.078416)
			(xy 375.618897 -289.125162) (xy 375.573891 -289.215408) (xy 375.521022 -289.301283) (xy 375.460709 -289.382105)
			(xy 375.427494 -289.420046) (xy 375.424539 -289.423519) (xy 375.419809 -289.431314) (xy 375.418096 -289.43554)
			(xy 375.411746 -289.45205) (xy 375.410103 -289.456443) (xy 375.408312 -289.465649) (xy 375.40819 -289.470338)
			(xy 375.40819 -289.475926) (xy 375.678695 -289.475926) (xy 375.68279 -289.425198) (xy 375.694969 -289.375784)
			(xy 375.714917 -289.328964) (xy 375.742118 -289.28595) (xy 375.775866 -289.247856) (xy 375.815288 -289.215669)
			(xy 375.859362 -289.190223) (xy 375.906948 -289.172176) (xy 375.956812 -289.161996) (xy 376.007664 -289.159947)
			(xy 376.058185 -289.166081) (xy 376.107069 -289.180241) (xy 376.153048 -289.202058) (xy 376.194932 -289.230968)
			(xy 376.231636 -289.266223) (xy 376.262209 -289.306909) (xy 376.28586 -289.351972) (xy 376.301976 -289.400246)
			(xy 376.31014 -289.45048) (xy 376.310652 -289.475926) (xy 376.628926 -289.475926) (xy 376.632886 -289.426872)
			(xy 376.644663 -289.379088) (xy 376.663954 -289.333812) (xy 376.690257 -289.292216) (xy 376.722892 -289.255379)
			(xy 376.761013 -289.224254) (xy 376.803634 -289.199647) (xy 376.84965 -289.182195) (xy 376.897869 -289.172351)
			(xy 376.947044 -289.17037) (xy 376.995899 -289.176302) (xy 377.04317 -289.189994) (xy 377.087632 -289.211092)
			(xy 377.128135 -289.239048) (xy 377.163628 -289.27314) (xy 377.193193 -289.312484) (xy 377.216064 -289.356061)
			(xy 377.231648 -289.402742) (xy 377.239543 -289.451319) (xy 377.240038 -289.475926) (xy 377.558549 -289.475926)
			(xy 377.562644 -289.425198) (xy 377.574823 -289.375784) (xy 377.594771 -289.328964) (xy 377.621972 -289.28595)
			(xy 377.65572 -289.247856) (xy 377.695142 -289.215669) (xy 377.739216 -289.190223) (xy 377.786802 -289.172176)
			(xy 377.836666 -289.161996) (xy 377.887518 -289.159947) (xy 377.938039 -289.166081) (xy 377.986923 -289.180241)
			(xy 378.032902 -289.202058) (xy 378.074786 -289.230968) (xy 378.11149 -289.266223) (xy 378.142063 -289.306909)
			(xy 378.165714 -289.351972) (xy 378.18183 -289.400246) (xy 378.189994 -289.45048) (xy 378.190506 -289.475926)
			(xy 378.509034 -289.475926) (xy 378.512994 -289.426872) (xy 378.524771 -289.379088) (xy 378.544062 -289.333812)
			(xy 378.570365 -289.292216) (xy 378.603 -289.255379) (xy 378.641121 -289.224254) (xy 378.683742 -289.199647)
			(xy 378.729758 -289.182195) (xy 378.777977 -289.172351) (xy 378.827152 -289.17037) (xy 378.876007 -289.176302)
			(xy 378.923278 -289.189994) (xy 378.96774 -289.211092) (xy 379.008243 -289.239048) (xy 379.043736 -289.27314)
			(xy 379.073301 -289.312484) (xy 379.096172 -289.356061) (xy 379.111756 -289.402742) (xy 379.119651 -289.451319)
			(xy 379.120146 -289.475926) (xy 379.438657 -289.475926) (xy 379.442752 -289.425198) (xy 379.454931 -289.375784)
			(xy 379.474879 -289.328964) (xy 379.50208 -289.28595) (xy 379.535828 -289.247856) (xy 379.57525 -289.215669)
			(xy 379.619324 -289.190223) (xy 379.66691 -289.172176) (xy 379.716774 -289.161996) (xy 379.767626 -289.159947)
			(xy 379.818147 -289.166081) (xy 379.867031 -289.180241) (xy 379.91301 -289.202058) (xy 379.954894 -289.230968)
			(xy 379.991598 -289.266223) (xy 380.022171 -289.306909) (xy 380.045822 -289.351972) (xy 380.061938 -289.400246)
			(xy 380.070102 -289.45048) (xy 380.070614 -289.475926) (xy 380.378711 -289.475926) (xy 380.382806 -289.425198)
			(xy 380.394985 -289.375784) (xy 380.414933 -289.328964) (xy 380.442134 -289.28595) (xy 380.475882 -289.247856)
			(xy 380.515304 -289.215669) (xy 380.559378 -289.190223) (xy 380.606964 -289.172176) (xy 380.656828 -289.161996)
			(xy 380.70768 -289.159947) (xy 380.758201 -289.166081) (xy 380.807085 -289.180241) (xy 380.853064 -289.202058)
			(xy 380.894948 -289.230968) (xy 380.931652 -289.266223) (xy 380.962225 -289.306909) (xy 380.985876 -289.351972)
			(xy 381.001992 -289.400246) (xy 381.010156 -289.45048) (xy 381.010668 -289.475926) (xy 381.328942 -289.475926)
			(xy 381.332902 -289.426872) (xy 381.344679 -289.379088) (xy 381.36397 -289.333812) (xy 381.390273 -289.292216)
			(xy 381.422908 -289.255379) (xy 381.461029 -289.224254) (xy 381.50365 -289.199647) (xy 381.549666 -289.182195)
			(xy 381.597885 -289.172351) (xy 381.64706 -289.17037) (xy 381.695915 -289.176302) (xy 381.743186 -289.189994)
			(xy 381.787648 -289.211092) (xy 381.828151 -289.239048) (xy 381.863644 -289.27314) (xy 381.893209 -289.312484)
			(xy 381.91608 -289.356061) (xy 381.931664 -289.402742) (xy 381.939559 -289.451319) (xy 381.940054 -289.475926)
			(xy 382.268996 -289.475926) (xy 382.272956 -289.426872) (xy 382.284733 -289.379088) (xy 382.304024 -289.333812)
			(xy 382.330327 -289.292216) (xy 382.362962 -289.255379) (xy 382.401083 -289.224254) (xy 382.443704 -289.199647)
			(xy 382.48972 -289.182195) (xy 382.537939 -289.172351) (xy 382.587114 -289.17037) (xy 382.635969 -289.176302)
			(xy 382.68324 -289.189994) (xy 382.727702 -289.211092) (xy 382.768205 -289.239048) (xy 382.803698 -289.27314)
			(xy 382.833263 -289.312484) (xy 382.856134 -289.356061) (xy 382.871718 -289.402742) (xy 382.879613 -289.451319)
			(xy 382.880108 -289.475926) (xy 383.20905 -289.475926) (xy 383.21301 -289.426872) (xy 383.224787 -289.379088)
			(xy 383.244078 -289.333812) (xy 383.270381 -289.292216) (xy 383.303016 -289.255379) (xy 383.341137 -289.224254)
			(xy 383.383758 -289.199647) (xy 383.429774 -289.182195) (xy 383.477993 -289.172351) (xy 383.527168 -289.17037)
			(xy 383.576023 -289.176302) (xy 383.623294 -289.189994) (xy 383.667756 -289.211092) (xy 383.708259 -289.239048)
			(xy 383.743752 -289.27314) (xy 383.773317 -289.312484) (xy 383.796188 -289.356061) (xy 383.811772 -289.402742)
			(xy 383.819667 -289.451319) (xy 383.820162 -289.475926) (xy 384.149104 -289.475926) (xy 384.153064 -289.426872)
			(xy 384.164841 -289.379088) (xy 384.184132 -289.333812) (xy 384.210435 -289.292216) (xy 384.24307 -289.255379)
			(xy 384.281191 -289.224254) (xy 384.323812 -289.199647) (xy 384.369828 -289.182195) (xy 384.418047 -289.172351)
			(xy 384.467222 -289.17037) (xy 384.516077 -289.176302) (xy 384.563348 -289.189994) (xy 384.60781 -289.211092)
			(xy 384.648313 -289.239048) (xy 384.683806 -289.27314) (xy 384.713371 -289.312484) (xy 384.736242 -289.356061)
			(xy 384.751826 -289.402742) (xy 384.759721 -289.451319) (xy 384.760216 -289.475926) (xy 385.088904 -289.475926)
			(xy 385.092864 -289.426872) (xy 385.104641 -289.379088) (xy 385.123932 -289.333812) (xy 385.150235 -289.292216)
			(xy 385.18287 -289.255379) (xy 385.220991 -289.224254) (xy 385.263612 -289.199647) (xy 385.309628 -289.182195)
			(xy 385.357847 -289.172351) (xy 385.407022 -289.17037) (xy 385.455877 -289.176302) (xy 385.503148 -289.189994)
			(xy 385.54761 -289.211092) (xy 385.588113 -289.239048) (xy 385.623606 -289.27314) (xy 385.653171 -289.312484)
			(xy 385.676042 -289.356061) (xy 385.691626 -289.402742) (xy 385.699521 -289.451319) (xy 385.700016 -289.475926)
			(xy 386.028958 -289.475926) (xy 386.032918 -289.426872) (xy 386.044695 -289.379088) (xy 386.063986 -289.333812)
			(xy 386.090289 -289.292216) (xy 386.122924 -289.255379) (xy 386.161045 -289.224254) (xy 386.203666 -289.199647)
			(xy 386.249682 -289.182195) (xy 386.297901 -289.172351) (xy 386.347076 -289.17037) (xy 386.395931 -289.176302)
			(xy 386.443202 -289.189994) (xy 386.487664 -289.211092) (xy 386.528167 -289.239048) (xy 386.56366 -289.27314)
			(xy 386.593225 -289.312484) (xy 386.616096 -289.356061) (xy 386.63168 -289.402742) (xy 386.639575 -289.451319)
			(xy 386.64007 -289.475926) (xy 386.969012 -289.475926) (xy 386.972972 -289.426872) (xy 386.984749 -289.379088)
			(xy 387.00404 -289.333812) (xy 387.030343 -289.292216) (xy 387.062978 -289.255379) (xy 387.101099 -289.224254)
			(xy 387.14372 -289.199647) (xy 387.189736 -289.182195) (xy 387.237955 -289.172351) (xy 387.28713 -289.17037)
			(xy 387.335985 -289.176302) (xy 387.383256 -289.189994) (xy 387.427718 -289.211092) (xy 387.468221 -289.239048)
			(xy 387.503714 -289.27314) (xy 387.533279 -289.312484) (xy 387.55615 -289.356061) (xy 387.571734 -289.402742)
			(xy 387.579629 -289.451319) (xy 387.580124 -289.475926) (xy 387.579629 -289.500533) (xy 387.571734 -289.54911)
			(xy 387.55615 -289.595791) (xy 387.533279 -289.639368) (xy 387.503714 -289.678712) (xy 387.468221 -289.712804)
			(xy 387.427718 -289.74076) (xy 387.383256 -289.761858) (xy 387.335985 -289.77555) (xy 387.28713 -289.781482)
			(xy 387.237955 -289.779501) (xy 387.189736 -289.769657) (xy 387.14372 -289.752205) (xy 387.101099 -289.727598)
			(xy 387.062978 -289.696473) (xy 387.030343 -289.659636) (xy 387.00404 -289.61804) (xy 386.984749 -289.572764)
			(xy 386.972972 -289.52498) (xy 386.969012 -289.475926) (xy 386.64007 -289.475926) (xy 386.639575 -289.500533)
			(xy 386.63168 -289.54911) (xy 386.616096 -289.595791) (xy 386.593225 -289.639368) (xy 386.56366 -289.678712)
			(xy 386.528167 -289.712804) (xy 386.487664 -289.74076) (xy 386.443202 -289.761858) (xy 386.395931 -289.77555)
			(xy 386.347076 -289.781482) (xy 386.297901 -289.779501) (xy 386.249682 -289.769657) (xy 386.203666 -289.752205)
			(xy 386.161045 -289.727598) (xy 386.122924 -289.696473) (xy 386.090289 -289.659636) (xy 386.063986 -289.61804)
			(xy 386.044695 -289.572764) (xy 386.032918 -289.52498) (xy 386.028958 -289.475926) (xy 385.700016 -289.475926)
			(xy 385.699521 -289.500533) (xy 385.691626 -289.54911) (xy 385.676042 -289.595791) (xy 385.653171 -289.639368)
			(xy 385.623606 -289.678712) (xy 385.588113 -289.712804) (xy 385.54761 -289.74076) (xy 385.503148 -289.761858)
			(xy 385.455877 -289.77555) (xy 385.407022 -289.781482) (xy 385.357847 -289.779501) (xy 385.309628 -289.769657)
			(xy 385.263612 -289.752205) (xy 385.220991 -289.727598) (xy 385.18287 -289.696473) (xy 385.150235 -289.659636)
			(xy 385.123932 -289.61804) (xy 385.104641 -289.572764) (xy 385.092864 -289.52498) (xy 385.088904 -289.475926)
			(xy 384.760216 -289.475926) (xy 384.759721 -289.500533) (xy 384.751826 -289.54911) (xy 384.736242 -289.595791)
			(xy 384.713371 -289.639368) (xy 384.683806 -289.678712) (xy 384.648313 -289.712804) (xy 384.60781 -289.74076)
			(xy 384.563348 -289.761858) (xy 384.516077 -289.77555) (xy 384.467222 -289.781482) (xy 384.418047 -289.779501)
			(xy 384.369828 -289.769657) (xy 384.323812 -289.752205) (xy 384.281191 -289.727598) (xy 384.24307 -289.696473)
			(xy 384.210435 -289.659636) (xy 384.184132 -289.61804) (xy 384.164841 -289.572764) (xy 384.153064 -289.52498)
			(xy 384.149104 -289.475926) (xy 383.820162 -289.475926) (xy 383.819667 -289.500533) (xy 383.811772 -289.54911)
			(xy 383.796188 -289.595791) (xy 383.773317 -289.639368) (xy 383.743752 -289.678712) (xy 383.708259 -289.712804)
			(xy 383.667756 -289.74076) (xy 383.623294 -289.761858) (xy 383.576023 -289.77555) (xy 383.527168 -289.781482)
			(xy 383.477993 -289.779501) (xy 383.429774 -289.769657) (xy 383.383758 -289.752205) (xy 383.341137 -289.727598)
			(xy 383.303016 -289.696473) (xy 383.270381 -289.659636) (xy 383.244078 -289.61804) (xy 383.224787 -289.572764)
			(xy 383.21301 -289.52498) (xy 383.20905 -289.475926) (xy 382.880108 -289.475926) (xy 382.879613 -289.500533)
			(xy 382.871718 -289.54911) (xy 382.856134 -289.595791) (xy 382.833263 -289.639368) (xy 382.803698 -289.678712)
			(xy 382.768205 -289.712804) (xy 382.727702 -289.74076) (xy 382.68324 -289.761858) (xy 382.635969 -289.77555)
			(xy 382.587114 -289.781482) (xy 382.537939 -289.779501) (xy 382.48972 -289.769657) (xy 382.443704 -289.752205)
			(xy 382.401083 -289.727598) (xy 382.362962 -289.696473) (xy 382.330327 -289.659636) (xy 382.304024 -289.61804)
			(xy 382.284733 -289.572764) (xy 382.272956 -289.52498) (xy 382.268996 -289.475926) (xy 381.940054 -289.475926)
			(xy 381.939559 -289.500533) (xy 381.931664 -289.54911) (xy 381.91608 -289.595791) (xy 381.893209 -289.639368)
			(xy 381.863644 -289.678712) (xy 381.828151 -289.712804) (xy 381.787648 -289.74076) (xy 381.743186 -289.761858)
			(xy 381.695915 -289.77555) (xy 381.64706 -289.781482) (xy 381.597885 -289.779501) (xy 381.549666 -289.769657)
			(xy 381.50365 -289.752205) (xy 381.461029 -289.727598) (xy 381.422908 -289.696473) (xy 381.390273 -289.659636)
			(xy 381.36397 -289.61804) (xy 381.344679 -289.572764) (xy 381.332902 -289.52498) (xy 381.328942 -289.475926)
			(xy 381.010668 -289.475926) (xy 381.010156 -289.501372) (xy 381.001992 -289.551606) (xy 380.985876 -289.59988)
			(xy 380.962225 -289.644943) (xy 380.931652 -289.685629) (xy 380.894948 -289.720884) (xy 380.853064 -289.749794)
			(xy 380.807085 -289.771611) (xy 380.758201 -289.785771) (xy 380.70768 -289.791905) (xy 380.656828 -289.789856)
			(xy 380.606964 -289.779676) (xy 380.559378 -289.761629) (xy 380.515304 -289.736183) (xy 380.475882 -289.703996)
			(xy 380.442134 -289.665902) (xy 380.414933 -289.622888) (xy 380.394985 -289.576068) (xy 380.382806 -289.526654)
			(xy 380.378711 -289.475926) (xy 380.070614 -289.475926) (xy 380.070102 -289.501372) (xy 380.061938 -289.551606)
			(xy 380.045822 -289.59988) (xy 380.022171 -289.644943) (xy 379.991598 -289.685629) (xy 379.954894 -289.720884)
			(xy 379.91301 -289.749794) (xy 379.867031 -289.771611) (xy 379.818147 -289.785771) (xy 379.767626 -289.791905)
			(xy 379.716774 -289.789856) (xy 379.66691 -289.779676) (xy 379.619324 -289.761629) (xy 379.57525 -289.736183)
			(xy 379.535828 -289.703996) (xy 379.50208 -289.665902) (xy 379.474879 -289.622888) (xy 379.454931 -289.576068)
			(xy 379.442752 -289.526654) (xy 379.438657 -289.475926) (xy 379.120146 -289.475926) (xy 379.119651 -289.500533)
			(xy 379.111756 -289.54911) (xy 379.096172 -289.595791) (xy 379.073301 -289.639368) (xy 379.043736 -289.678712)
			(xy 379.008243 -289.712804) (xy 378.96774 -289.74076) (xy 378.923278 -289.761858) (xy 378.876007 -289.77555)
			(xy 378.827152 -289.781482) (xy 378.777977 -289.779501) (xy 378.729758 -289.769657) (xy 378.683742 -289.752205)
			(xy 378.641121 -289.727598) (xy 378.603 -289.696473) (xy 378.570365 -289.659636) (xy 378.544062 -289.61804)
			(xy 378.524771 -289.572764) (xy 378.512994 -289.52498) (xy 378.509034 -289.475926) (xy 378.190506 -289.475926)
			(xy 378.189994 -289.501372) (xy 378.18183 -289.551606) (xy 378.165714 -289.59988) (xy 378.142063 -289.644943)
			(xy 378.11149 -289.685629) (xy 378.074786 -289.720884) (xy 378.032902 -289.749794) (xy 377.986923 -289.771611)
			(xy 377.938039 -289.785771) (xy 377.887518 -289.791905) (xy 377.836666 -289.789856) (xy 377.786802 -289.779676)
			(xy 377.739216 -289.761629) (xy 377.695142 -289.736183) (xy 377.65572 -289.703996) (xy 377.621972 -289.665902)
			(xy 377.594771 -289.622888) (xy 377.574823 -289.576068) (xy 377.562644 -289.526654) (xy 377.558549 -289.475926)
			(xy 377.240038 -289.475926) (xy 377.239543 -289.500533) (xy 377.231648 -289.54911) (xy 377.216064 -289.595791)
			(xy 377.193193 -289.639368) (xy 377.163628 -289.678712) (xy 377.128135 -289.712804) (xy 377.087632 -289.74076)
			(xy 377.04317 -289.761858) (xy 376.995899 -289.77555) (xy 376.947044 -289.781482) (xy 376.897869 -289.779501)
			(xy 376.84965 -289.769657) (xy 376.803634 -289.752205) (xy 376.761013 -289.727598) (xy 376.722892 -289.696473)
			(xy 376.690257 -289.659636) (xy 376.663954 -289.61804) (xy 376.644663 -289.572764) (xy 376.632886 -289.52498)
			(xy 376.628926 -289.475926) (xy 376.310652 -289.475926) (xy 376.31014 -289.501372) (xy 376.301976 -289.551606)
			(xy 376.28586 -289.59988) (xy 376.262209 -289.644943) (xy 376.231636 -289.685629) (xy 376.194932 -289.720884)
			(xy 376.153048 -289.749794) (xy 376.107069 -289.771611) (xy 376.058185 -289.785771) (xy 376.007664 -289.791905)
			(xy 375.956812 -289.789856) (xy 375.906948 -289.779676) (xy 375.859362 -289.761629) (xy 375.815288 -289.736183)
			(xy 375.775866 -289.703996) (xy 375.742118 -289.665902) (xy 375.714917 -289.622888) (xy 375.694969 -289.576068)
			(xy 375.68279 -289.526654) (xy 375.678695 -289.475926) (xy 375.40819 -289.475926) (xy 375.40819 -289.481514)
			(xy 375.408344 -289.486199) (xy 375.410129 -289.495402) (xy 375.411746 -289.499802) (xy 375.418096 -289.516312)
			(xy 375.419831 -289.520527) (xy 375.424561 -289.528317) (xy 375.427494 -289.531806) (xy 375.457422 -289.565902)
			(xy 375.512337 -289.638127) (xy 375.561286 -289.71452) (xy 375.603954 -289.794592) (xy 375.640066 -289.877826)
			(xy 375.66939 -289.963688) (xy 375.680986 -290.007548) (xy 375.683384 -290.015641) (xy 375.692579 -290.029781)
			(xy 375.69902 -290.035234) (xy 375.718878 -290.049631) (xy 375.754158 -290.083702) (xy 375.783537 -290.122975)
			(xy 375.806258 -290.166441) (xy 375.821738 -290.21298) (xy 375.829577 -290.261395) (xy 375.829575 -290.285932)
			(xy 376.148595 -290.285932) (xy 376.15269 -290.235204) (xy 376.164869 -290.18579) (xy 376.184817 -290.13897)
			(xy 376.212018 -290.095956) (xy 376.245766 -290.057862) (xy 376.285188 -290.025675) (xy 376.329262 -290.000229)
			(xy 376.376848 -289.982182) (xy 376.426712 -289.972002) (xy 376.477564 -289.969953) (xy 376.528085 -289.976087)
			(xy 376.576969 -289.990247) (xy 376.622948 -290.012064) (xy 376.664832 -290.040974) (xy 376.701536 -290.076229)
			(xy 376.732109 -290.116915) (xy 376.75576 -290.161978) (xy 376.771876 -290.210252) (xy 376.78004 -290.260486)
			(xy 376.780552 -290.285932) (xy 377.088649 -290.285932) (xy 377.092744 -290.235204) (xy 377.104923 -290.18579)
			(xy 377.124871 -290.13897) (xy 377.152072 -290.095956) (xy 377.18582 -290.057862) (xy 377.225242 -290.025675)
			(xy 377.269316 -290.000229) (xy 377.316902 -289.982182) (xy 377.366766 -289.972002) (xy 377.417618 -289.969953)
			(xy 377.468139 -289.976087) (xy 377.517023 -289.990247) (xy 377.563002 -290.012064) (xy 377.604886 -290.040974)
			(xy 377.64159 -290.076229) (xy 377.672163 -290.116915) (xy 377.695814 -290.161978) (xy 377.71193 -290.210252)
			(xy 377.720094 -290.260486) (xy 377.720606 -290.285932) (xy 378.968503 -290.285932) (xy 378.972598 -290.235204)
			(xy 378.984777 -290.18579) (xy 379.004725 -290.13897) (xy 379.031926 -290.095956) (xy 379.065674 -290.057862)
			(xy 379.105096 -290.025675) (xy 379.14917 -290.000229) (xy 379.196756 -289.982182) (xy 379.24662 -289.972002)
			(xy 379.297472 -289.969953) (xy 379.347993 -289.976087) (xy 379.396877 -289.990247) (xy 379.442856 -290.012064)
			(xy 379.48474 -290.040974) (xy 379.521444 -290.076229) (xy 379.552017 -290.116915) (xy 379.575668 -290.161978)
			(xy 379.591784 -290.210252) (xy 379.599948 -290.260486) (xy 379.60046 -290.285932) (xy 379.918988 -290.285932)
			(xy 379.922948 -290.236878) (xy 379.934725 -290.189094) (xy 379.954016 -290.143818) (xy 379.980319 -290.102222)
			(xy 380.012954 -290.065385) (xy 380.051075 -290.03426) (xy 380.093696 -290.009653) (xy 380.139712 -289.992201)
			(xy 380.187931 -289.982357) (xy 380.237106 -289.980376) (xy 380.285961 -289.986308) (xy 380.333232 -290)
			(xy 380.377694 -290.021098) (xy 380.418197 -290.049054) (xy 380.45369 -290.083146) (xy 380.483255 -290.12249)
			(xy 380.506126 -290.166067) (xy 380.52171 -290.212748) (xy 380.529605 -290.261325) (xy 380.5301 -290.285932)
			(xy 380.848611 -290.285932) (xy 380.852706 -290.235204) (xy 380.864885 -290.18579) (xy 380.884833 -290.13897)
			(xy 380.912034 -290.095956) (xy 380.945782 -290.057862) (xy 380.985204 -290.025675) (xy 381.029278 -290.000229)
			(xy 381.076864 -289.982182) (xy 381.126728 -289.972002) (xy 381.17758 -289.969953) (xy 381.228101 -289.976087)
			(xy 381.276985 -289.990247) (xy 381.322964 -290.012064) (xy 381.364848 -290.040974) (xy 381.401552 -290.076229)
			(xy 381.432125 -290.116915) (xy 381.455776 -290.161978) (xy 381.471892 -290.210252) (xy 381.480056 -290.260486)
			(xy 381.480568 -290.285932) (xy 381.799096 -290.285932) (xy 381.803056 -290.236878) (xy 381.814833 -290.189094)
			(xy 381.834124 -290.143818) (xy 381.860427 -290.102222) (xy 381.893062 -290.065385) (xy 381.931183 -290.03426)
			(xy 381.973804 -290.009653) (xy 382.01982 -289.992201) (xy 382.068039 -289.982357) (xy 382.117214 -289.980376)
			(xy 382.166069 -289.986308) (xy 382.21334 -290) (xy 382.257802 -290.021098) (xy 382.298305 -290.049054)
			(xy 382.333798 -290.083146) (xy 382.363363 -290.12249) (xy 382.386234 -290.166067) (xy 382.401818 -290.212748)
			(xy 382.409713 -290.261325) (xy 382.410208 -290.285932) (xy 382.738896 -290.285932) (xy 382.742856 -290.236878)
			(xy 382.754633 -290.189094) (xy 382.773924 -290.143818) (xy 382.800227 -290.102222) (xy 382.832862 -290.065385)
			(xy 382.870983 -290.03426) (xy 382.913604 -290.009653) (xy 382.95962 -289.992201) (xy 383.007839 -289.982357)
			(xy 383.057014 -289.980376) (xy 383.105869 -289.986308) (xy 383.15314 -290) (xy 383.197602 -290.021098)
			(xy 383.238105 -290.049054) (xy 383.273598 -290.083146) (xy 383.303163 -290.12249) (xy 383.326034 -290.166067)
			(xy 383.341618 -290.212748) (xy 383.349513 -290.261325) (xy 383.350008 -290.285932) (xy 383.67895 -290.285932)
			(xy 383.68291 -290.236878) (xy 383.694687 -290.189094) (xy 383.713978 -290.143818) (xy 383.740281 -290.102222)
			(xy 383.772916 -290.065385) (xy 383.811037 -290.03426) (xy 383.853658 -290.009653) (xy 383.899674 -289.992201)
			(xy 383.947893 -289.982357) (xy 383.997068 -289.980376) (xy 384.045923 -289.986308) (xy 384.093194 -290)
			(xy 384.137656 -290.021098) (xy 384.178159 -290.049054) (xy 384.213652 -290.083146) (xy 384.243217 -290.12249)
			(xy 384.266088 -290.166067) (xy 384.281672 -290.212748) (xy 384.289567 -290.261325) (xy 384.290062 -290.285932)
			(xy 385.559058 -290.285932) (xy 385.563018 -290.236878) (xy 385.574795 -290.189094) (xy 385.594086 -290.143818)
			(xy 385.620389 -290.102222) (xy 385.653024 -290.065385) (xy 385.691145 -290.03426) (xy 385.733766 -290.009653)
			(xy 385.779782 -289.992201) (xy 385.828001 -289.982357) (xy 385.877176 -289.980376) (xy 385.926031 -289.986308)
			(xy 385.973302 -290) (xy 386.017764 -290.021098) (xy 386.058267 -290.049054) (xy 386.09376 -290.083146)
			(xy 386.123325 -290.12249) (xy 386.146196 -290.166067) (xy 386.16178 -290.212748) (xy 386.169675 -290.261325)
			(xy 386.17017 -290.285932) (xy 386.499112 -290.285932) (xy 386.503072 -290.236878) (xy 386.514849 -290.189094)
			(xy 386.53414 -290.143818) (xy 386.560443 -290.102222) (xy 386.593078 -290.065385) (xy 386.631199 -290.03426)
			(xy 386.67382 -290.009653) (xy 386.719836 -289.992201) (xy 386.768055 -289.982357) (xy 386.81723 -289.980376)
			(xy 386.866085 -289.986308) (xy 386.913356 -290) (xy 386.957818 -290.021098) (xy 386.998321 -290.049054)
			(xy 387.033814 -290.083146) (xy 387.063379 -290.12249) (xy 387.08625 -290.166067) (xy 387.101834 -290.212748)
			(xy 387.109729 -290.261325) (xy 387.110224 -290.285932) (xy 387.438912 -290.285932) (xy 387.442872 -290.236878)
			(xy 387.454649 -290.189094) (xy 387.47394 -290.143818) (xy 387.500243 -290.102222) (xy 387.532878 -290.065385)
			(xy 387.570999 -290.03426) (xy 387.61362 -290.009653) (xy 387.659636 -289.992201) (xy 387.707855 -289.982357)
			(xy 387.75703 -289.980376) (xy 387.805885 -289.986308) (xy 387.853156 -290) (xy 387.897618 -290.021098)
			(xy 387.938121 -290.049054) (xy 387.973614 -290.083146) (xy 388.003179 -290.12249) (xy 388.02605 -290.166067)
			(xy 388.041634 -290.212748) (xy 388.049529 -290.261325) (xy 388.050024 -290.285932) (xy 388.049529 -290.310539)
			(xy 388.041634 -290.359116) (xy 388.02605 -290.405797) (xy 388.003179 -290.449374) (xy 387.973614 -290.488718)
			(xy 387.938121 -290.52281) (xy 387.897618 -290.550766) (xy 387.853156 -290.571864) (xy 387.805885 -290.585556)
			(xy 387.75703 -290.591488) (xy 387.707855 -290.589507) (xy 387.659636 -290.579663) (xy 387.61362 -290.562211)
			(xy 387.570999 -290.537604) (xy 387.532878 -290.506479) (xy 387.500243 -290.469642) (xy 387.47394 -290.428046)
			(xy 387.454649 -290.38277) (xy 387.442872 -290.334986) (xy 387.438912 -290.285932) (xy 387.110224 -290.285932)
			(xy 387.109729 -290.310539) (xy 387.101834 -290.359116) (xy 387.08625 -290.405797) (xy 387.063379 -290.449374)
			(xy 387.033814 -290.488718) (xy 386.998321 -290.52281) (xy 386.957818 -290.550766) (xy 386.913356 -290.571864)
			(xy 386.866085 -290.585556) (xy 386.81723 -290.591488) (xy 386.768055 -290.589507) (xy 386.719836 -290.579663)
			(xy 386.67382 -290.562211) (xy 386.631199 -290.537604) (xy 386.593078 -290.506479) (xy 386.560443 -290.469642)
			(xy 386.53414 -290.428046) (xy 386.514849 -290.38277) (xy 386.503072 -290.334986) (xy 386.499112 -290.285932)
			(xy 386.17017 -290.285932) (xy 386.169675 -290.310539) (xy 386.16178 -290.359116) (xy 386.146196 -290.405797)
			(xy 386.123325 -290.449374) (xy 386.09376 -290.488718) (xy 386.058267 -290.52281) (xy 386.017764 -290.550766)
			(xy 385.973302 -290.571864) (xy 385.926031 -290.585556) (xy 385.877176 -290.591488) (xy 385.828001 -290.589507)
			(xy 385.779782 -290.579663) (xy 385.733766 -290.562211) (xy 385.691145 -290.537604) (xy 385.653024 -290.506479)
			(xy 385.620389 -290.469642) (xy 385.594086 -290.428046) (xy 385.574795 -290.38277) (xy 385.563018 -290.334986)
			(xy 385.559058 -290.285932) (xy 384.290062 -290.285932) (xy 384.289567 -290.310539) (xy 384.281672 -290.359116)
			(xy 384.266088 -290.405797) (xy 384.243217 -290.449374) (xy 384.213652 -290.488718) (xy 384.178159 -290.52281)
			(xy 384.137656 -290.550766) (xy 384.093194 -290.571864) (xy 384.045923 -290.585556) (xy 383.997068 -290.591488)
			(xy 383.947893 -290.589507) (xy 383.899674 -290.579663) (xy 383.853658 -290.562211) (xy 383.811037 -290.537604)
			(xy 383.772916 -290.506479) (xy 383.740281 -290.469642) (xy 383.713978 -290.428046) (xy 383.694687 -290.38277)
			(xy 383.68291 -290.334986) (xy 383.67895 -290.285932) (xy 383.350008 -290.285932) (xy 383.349513 -290.310539)
			(xy 383.341618 -290.359116) (xy 383.326034 -290.405797) (xy 383.303163 -290.449374) (xy 383.273598 -290.488718)
			(xy 383.238105 -290.52281) (xy 383.197602 -290.550766) (xy 383.15314 -290.571864) (xy 383.105869 -290.585556)
			(xy 383.057014 -290.591488) (xy 383.007839 -290.589507) (xy 382.95962 -290.579663) (xy 382.913604 -290.562211)
			(xy 382.870983 -290.537604) (xy 382.832862 -290.506479) (xy 382.800227 -290.469642) (xy 382.773924 -290.428046)
			(xy 382.754633 -290.38277) (xy 382.742856 -290.334986) (xy 382.738896 -290.285932) (xy 382.410208 -290.285932)
			(xy 382.409713 -290.310539) (xy 382.401818 -290.359116) (xy 382.386234 -290.405797) (xy 382.363363 -290.449374)
			(xy 382.333798 -290.488718) (xy 382.298305 -290.52281) (xy 382.257802 -290.550766) (xy 382.21334 -290.571864)
			(xy 382.166069 -290.585556) (xy 382.117214 -290.591488) (xy 382.068039 -290.589507) (xy 382.01982 -290.579663)
			(xy 381.973804 -290.562211) (xy 381.931183 -290.537604) (xy 381.893062 -290.506479) (xy 381.860427 -290.469642)
			(xy 381.834124 -290.428046) (xy 381.814833 -290.38277) (xy 381.803056 -290.334986) (xy 381.799096 -290.285932)
			(xy 381.480568 -290.285932) (xy 381.480056 -290.311378) (xy 381.471892 -290.361612) (xy 381.455776 -290.409886)
			(xy 381.432125 -290.454949) (xy 381.401552 -290.495635) (xy 381.364848 -290.53089) (xy 381.322964 -290.5598)
			(xy 381.276985 -290.581617) (xy 381.228101 -290.595777) (xy 381.17758 -290.601911) (xy 381.126728 -290.599862)
			(xy 381.076864 -290.589682) (xy 381.029278 -290.571635) (xy 380.985204 -290.546189) (xy 380.945782 -290.514002)
			(xy 380.912034 -290.475908) (xy 380.884833 -290.432894) (xy 380.864885 -290.386074) (xy 380.852706 -290.33666)
			(xy 380.848611 -290.285932) (xy 380.5301 -290.285932) (xy 380.529605 -290.310539) (xy 380.52171 -290.359116)
			(xy 380.506126 -290.405797) (xy 380.483255 -290.449374) (xy 380.45369 -290.488718) (xy 380.418197 -290.52281)
			(xy 380.377694 -290.550766) (xy 380.333232 -290.571864) (xy 380.285961 -290.585556) (xy 380.237106 -290.591488)
			(xy 380.187931 -290.589507) (xy 380.139712 -290.579663) (xy 380.093696 -290.562211) (xy 380.051075 -290.537604)
			(xy 380.012954 -290.506479) (xy 379.980319 -290.469642) (xy 379.954016 -290.428046) (xy 379.934725 -290.38277)
			(xy 379.922948 -290.334986) (xy 379.918988 -290.285932) (xy 379.60046 -290.285932) (xy 379.599948 -290.311378)
			(xy 379.591784 -290.361612) (xy 379.575668 -290.409886) (xy 379.552017 -290.454949) (xy 379.521444 -290.495635)
			(xy 379.48474 -290.53089) (xy 379.442856 -290.5598) (xy 379.396877 -290.581617) (xy 379.347993 -290.595777)
			(xy 379.297472 -290.601911) (xy 379.24662 -290.599862) (xy 379.196756 -290.589682) (xy 379.14917 -290.571635)
			(xy 379.105096 -290.546189) (xy 379.065674 -290.514002) (xy 379.031926 -290.475908) (xy 379.004725 -290.432894)
			(xy 378.984777 -290.386074) (xy 378.972598 -290.33666) (xy 378.968503 -290.285932) (xy 377.720606 -290.285932)
			(xy 377.720094 -290.311378) (xy 377.71193 -290.361612) (xy 377.695814 -290.409886) (xy 377.672163 -290.454949)
			(xy 377.64159 -290.495635) (xy 377.604886 -290.53089) (xy 377.563002 -290.5598) (xy 377.517023 -290.581617)
			(xy 377.468139 -290.595777) (xy 377.417618 -290.601911) (xy 377.366766 -290.599862) (xy 377.316902 -290.589682)
			(xy 377.269316 -290.571635) (xy 377.225242 -290.546189) (xy 377.18582 -290.514002) (xy 377.152072 -290.475908)
			(xy 377.124871 -290.432894) (xy 377.104923 -290.386074) (xy 377.092744 -290.33666) (xy 377.088649 -290.285932)
			(xy 376.780552 -290.285932) (xy 376.78004 -290.311378) (xy 376.771876 -290.361612) (xy 376.75576 -290.409886)
			(xy 376.732109 -290.454949) (xy 376.701536 -290.495635) (xy 376.664832 -290.53089) (xy 376.622948 -290.5598)
			(xy 376.576969 -290.581617) (xy 376.528085 -290.595777) (xy 376.477564 -290.601911) (xy 376.426712 -290.599862)
			(xy 376.376848 -290.589682) (xy 376.329262 -290.571635) (xy 376.285188 -290.546189) (xy 376.245766 -290.514002)
			(xy 376.212018 -290.475908) (xy 376.184817 -290.432894) (xy 376.164869 -290.386074) (xy 376.15269 -290.33666)
			(xy 376.148595 -290.285932) (xy 375.829575 -290.285932) (xy 375.829574 -290.310441) (xy 375.821729 -290.358856)
			(xy 375.806244 -290.405393) (xy 375.783518 -290.448856) (xy 375.754134 -290.488126) (xy 375.71885 -290.522192)
			(xy 375.69902 -290.53663) (xy 375.692549 -290.542057) (xy 375.683342 -290.556205) (xy 375.680986 -290.564316)
			(xy 375.669369 -290.60817) (xy 375.640036 -290.694026) (xy 375.603921 -290.777256) (xy 375.561255 -290.857326)
			(xy 375.512312 -290.933721) (xy 375.457407 -291.00595) (xy 375.427494 -291.040058) (xy 375.42454 -291.043531)
			(xy 375.419812 -291.051327) (xy 375.418096 -291.055552) (xy 375.411746 -291.072062) (xy 375.410104 -291.076455)
			(xy 375.408315 -291.085661) (xy 375.40819 -291.09035) (xy 375.40819 -291.095938) (xy 375.678695 -291.095938)
			(xy 375.68279 -291.04521) (xy 375.694969 -290.995796) (xy 375.714917 -290.948976) (xy 375.742118 -290.905962)
			(xy 375.775866 -290.867868) (xy 375.815288 -290.835681) (xy 375.859362 -290.810235) (xy 375.906948 -290.792188)
			(xy 375.956812 -290.782008) (xy 376.007664 -290.779959) (xy 376.058185 -290.786093) (xy 376.107069 -290.800253)
			(xy 376.153048 -290.82207) (xy 376.194932 -290.85098) (xy 376.231636 -290.886235) (xy 376.262209 -290.926921)
			(xy 376.28586 -290.971984) (xy 376.301976 -291.020258) (xy 376.31014 -291.070492) (xy 376.310652 -291.095938)
			(xy 376.628926 -291.095938) (xy 376.632886 -291.046884) (xy 376.644663 -290.9991) (xy 376.663954 -290.953824)
			(xy 376.690257 -290.912228) (xy 376.722892 -290.875391) (xy 376.761013 -290.844266) (xy 376.803634 -290.819659)
			(xy 376.84965 -290.802207) (xy 376.897869 -290.792363) (xy 376.947044 -290.790382) (xy 376.995899 -290.796314)
			(xy 377.04317 -290.810006) (xy 377.087632 -290.831104) (xy 377.128135 -290.85906) (xy 377.163628 -290.893152)
			(xy 377.193193 -290.932496) (xy 377.216064 -290.976073) (xy 377.231648 -291.022754) (xy 377.239543 -291.071331)
			(xy 377.240038 -291.095938) (xy 377.558549 -291.095938) (xy 377.562644 -291.04521) (xy 377.574823 -290.995796)
			(xy 377.594771 -290.948976) (xy 377.621972 -290.905962) (xy 377.65572 -290.867868) (xy 377.695142 -290.835681)
			(xy 377.739216 -290.810235) (xy 377.786802 -290.792188) (xy 377.836666 -290.782008) (xy 377.887518 -290.779959)
			(xy 377.938039 -290.786093) (xy 377.986923 -290.800253) (xy 378.032902 -290.82207) (xy 378.074786 -290.85098)
			(xy 378.11149 -290.886235) (xy 378.142063 -290.926921) (xy 378.165714 -290.971984) (xy 378.18183 -291.020258)
			(xy 378.189994 -291.070492) (xy 378.190506 -291.095938) (xy 378.509034 -291.095938) (xy 378.512994 -291.046884)
			(xy 378.524771 -290.9991) (xy 378.544062 -290.953824) (xy 378.570365 -290.912228) (xy 378.603 -290.875391)
			(xy 378.641121 -290.844266) (xy 378.683742 -290.819659) (xy 378.729758 -290.802207) (xy 378.777977 -290.792363)
			(xy 378.827152 -290.790382) (xy 378.876007 -290.796314) (xy 378.923278 -290.810006) (xy 378.96774 -290.831104)
			(xy 379.008243 -290.85906) (xy 379.043736 -290.893152) (xy 379.073301 -290.932496) (xy 379.096172 -290.976073)
			(xy 379.111756 -291.022754) (xy 379.119651 -291.071331) (xy 379.120146 -291.095938) (xy 379.438657 -291.095938)
			(xy 379.442752 -291.04521) (xy 379.454931 -290.995796) (xy 379.474879 -290.948976) (xy 379.50208 -290.905962)
			(xy 379.535828 -290.867868) (xy 379.57525 -290.835681) (xy 379.619324 -290.810235) (xy 379.66691 -290.792188)
			(xy 379.716774 -290.782008) (xy 379.767626 -290.779959) (xy 379.818147 -290.786093) (xy 379.867031 -290.800253)
			(xy 379.91301 -290.82207) (xy 379.954894 -290.85098) (xy 379.991598 -290.886235) (xy 380.022171 -290.926921)
			(xy 380.045822 -290.971984) (xy 380.061938 -291.020258) (xy 380.070102 -291.070492) (xy 380.070614 -291.095938)
			(xy 380.378711 -291.095938) (xy 380.382806 -291.04521) (xy 380.394985 -290.995796) (xy 380.414933 -290.948976)
			(xy 380.442134 -290.905962) (xy 380.475882 -290.867868) (xy 380.515304 -290.835681) (xy 380.559378 -290.810235)
			(xy 380.606964 -290.792188) (xy 380.656828 -290.782008) (xy 380.70768 -290.779959) (xy 380.758201 -290.786093)
			(xy 380.807085 -290.800253) (xy 380.853064 -290.82207) (xy 380.894948 -290.85098) (xy 380.931652 -290.886235)
			(xy 380.962225 -290.926921) (xy 380.985876 -290.971984) (xy 381.001992 -291.020258) (xy 381.010156 -291.070492)
			(xy 381.010668 -291.095938) (xy 381.328942 -291.095938) (xy 381.332902 -291.046884) (xy 381.344679 -290.9991)
			(xy 381.36397 -290.953824) (xy 381.390273 -290.912228) (xy 381.422908 -290.875391) (xy 381.461029 -290.844266)
			(xy 381.50365 -290.819659) (xy 381.549666 -290.802207) (xy 381.597885 -290.792363) (xy 381.64706 -290.790382)
			(xy 381.695915 -290.796314) (xy 381.743186 -290.810006) (xy 381.787648 -290.831104) (xy 381.828151 -290.85906)
			(xy 381.863644 -290.893152) (xy 381.893209 -290.932496) (xy 381.91608 -290.976073) (xy 381.931664 -291.022754)
			(xy 381.939559 -291.071331) (xy 381.940054 -291.095938) (xy 382.268996 -291.095938) (xy 382.272956 -291.046884)
			(xy 382.284733 -290.9991) (xy 382.304024 -290.953824) (xy 382.330327 -290.912228) (xy 382.362962 -290.875391)
			(xy 382.401083 -290.844266) (xy 382.443704 -290.819659) (xy 382.48972 -290.802207) (xy 382.537939 -290.792363)
			(xy 382.587114 -290.790382) (xy 382.635969 -290.796314) (xy 382.68324 -290.810006) (xy 382.727702 -290.831104)
			(xy 382.768205 -290.85906) (xy 382.803698 -290.893152) (xy 382.833263 -290.932496) (xy 382.856134 -290.976073)
			(xy 382.871718 -291.022754) (xy 382.879613 -291.071331) (xy 382.880108 -291.095938) (xy 383.20905 -291.095938)
			(xy 383.21301 -291.046884) (xy 383.224787 -290.9991) (xy 383.244078 -290.953824) (xy 383.270381 -290.912228)
			(xy 383.303016 -290.875391) (xy 383.341137 -290.844266) (xy 383.383758 -290.819659) (xy 383.429774 -290.802207)
			(xy 383.477993 -290.792363) (xy 383.527168 -290.790382) (xy 383.576023 -290.796314) (xy 383.623294 -290.810006)
			(xy 383.667756 -290.831104) (xy 383.708259 -290.85906) (xy 383.743752 -290.893152) (xy 383.773317 -290.932496)
			(xy 383.796188 -290.976073) (xy 383.811772 -291.022754) (xy 383.819667 -291.071331) (xy 383.820162 -291.095938)
			(xy 384.149104 -291.095938) (xy 384.153064 -291.046884) (xy 384.164841 -290.9991) (xy 384.184132 -290.953824)
			(xy 384.210435 -290.912228) (xy 384.24307 -290.875391) (xy 384.281191 -290.844266) (xy 384.323812 -290.819659)
			(xy 384.369828 -290.802207) (xy 384.418047 -290.792363) (xy 384.467222 -290.790382) (xy 384.516077 -290.796314)
			(xy 384.563348 -290.810006) (xy 384.60781 -290.831104) (xy 384.648313 -290.85906) (xy 384.683806 -290.893152)
			(xy 384.713371 -290.932496) (xy 384.736242 -290.976073) (xy 384.751826 -291.022754) (xy 384.759721 -291.071331)
			(xy 384.760216 -291.095938) (xy 385.088904 -291.095938) (xy 385.092864 -291.046884) (xy 385.104641 -290.9991)
			(xy 385.123932 -290.953824) (xy 385.150235 -290.912228) (xy 385.18287 -290.875391) (xy 385.220991 -290.844266)
			(xy 385.263612 -290.819659) (xy 385.309628 -290.802207) (xy 385.357847 -290.792363) (xy 385.407022 -290.790382)
			(xy 385.455877 -290.796314) (xy 385.503148 -290.810006) (xy 385.54761 -290.831104) (xy 385.588113 -290.85906)
			(xy 385.623606 -290.893152) (xy 385.653171 -290.932496) (xy 385.676042 -290.976073) (xy 385.691626 -291.022754)
			(xy 385.699521 -291.071331) (xy 385.700016 -291.095938) (xy 386.028958 -291.095938) (xy 386.032918 -291.046884)
			(xy 386.044695 -290.9991) (xy 386.063986 -290.953824) (xy 386.090289 -290.912228) (xy 386.122924 -290.875391)
			(xy 386.161045 -290.844266) (xy 386.203666 -290.819659) (xy 386.249682 -290.802207) (xy 386.297901 -290.792363)
			(xy 386.347076 -290.790382) (xy 386.395931 -290.796314) (xy 386.443202 -290.810006) (xy 386.487664 -290.831104)
			(xy 386.528167 -290.85906) (xy 386.56366 -290.893152) (xy 386.593225 -290.932496) (xy 386.616096 -290.976073)
			(xy 386.63168 -291.022754) (xy 386.639575 -291.071331) (xy 386.64007 -291.095938) (xy 386.969012 -291.095938)
			(xy 386.972972 -291.046884) (xy 386.984749 -290.9991) (xy 387.00404 -290.953824) (xy 387.030343 -290.912228)
			(xy 387.062978 -290.875391) (xy 387.101099 -290.844266) (xy 387.14372 -290.819659) (xy 387.189736 -290.802207)
			(xy 387.237955 -290.792363) (xy 387.28713 -290.790382) (xy 387.335985 -290.796314) (xy 387.383256 -290.810006)
			(xy 387.427718 -290.831104) (xy 387.468221 -290.85906) (xy 387.503714 -290.893152) (xy 387.533279 -290.932496)
			(xy 387.55615 -290.976073) (xy 387.571734 -291.022754) (xy 387.579629 -291.071331) (xy 387.580124 -291.095938)
			(xy 387.579629 -291.120545) (xy 387.571734 -291.169122) (xy 387.55615 -291.215803) (xy 387.533279 -291.25938)
			(xy 387.503714 -291.298724) (xy 387.468221 -291.332816) (xy 387.427718 -291.360772) (xy 387.383256 -291.38187)
			(xy 387.335985 -291.395562) (xy 387.28713 -291.401494) (xy 387.237955 -291.399513) (xy 387.189736 -291.389669)
			(xy 387.14372 -291.372217) (xy 387.101099 -291.34761) (xy 387.062978 -291.316485) (xy 387.030343 -291.279648)
			(xy 387.00404 -291.238052) (xy 386.984749 -291.192776) (xy 386.972972 -291.144992) (xy 386.969012 -291.095938)
			(xy 386.64007 -291.095938) (xy 386.639575 -291.120545) (xy 386.63168 -291.169122) (xy 386.616096 -291.215803)
			(xy 386.593225 -291.25938) (xy 386.56366 -291.298724) (xy 386.528167 -291.332816) (xy 386.487664 -291.360772)
			(xy 386.443202 -291.38187) (xy 386.395931 -291.395562) (xy 386.347076 -291.401494) (xy 386.297901 -291.399513)
			(xy 386.249682 -291.389669) (xy 386.203666 -291.372217) (xy 386.161045 -291.34761) (xy 386.122924 -291.316485)
			(xy 386.090289 -291.279648) (xy 386.063986 -291.238052) (xy 386.044695 -291.192776) (xy 386.032918 -291.144992)
			(xy 386.028958 -291.095938) (xy 385.700016 -291.095938) (xy 385.699521 -291.120545) (xy 385.691626 -291.169122)
			(xy 385.676042 -291.215803) (xy 385.653171 -291.25938) (xy 385.623606 -291.298724) (xy 385.588113 -291.332816)
			(xy 385.54761 -291.360772) (xy 385.503148 -291.38187) (xy 385.455877 -291.395562) (xy 385.407022 -291.401494)
			(xy 385.357847 -291.399513) (xy 385.309628 -291.389669) (xy 385.263612 -291.372217) (xy 385.220991 -291.34761)
			(xy 385.18287 -291.316485) (xy 385.150235 -291.279648) (xy 385.123932 -291.238052) (xy 385.104641 -291.192776)
			(xy 385.092864 -291.144992) (xy 385.088904 -291.095938) (xy 384.760216 -291.095938) (xy 384.759721 -291.120545)
			(xy 384.751826 -291.169122) (xy 384.736242 -291.215803) (xy 384.713371 -291.25938) (xy 384.683806 -291.298724)
			(xy 384.648313 -291.332816) (xy 384.60781 -291.360772) (xy 384.563348 -291.38187) (xy 384.516077 -291.395562)
			(xy 384.467222 -291.401494) (xy 384.418047 -291.399513) (xy 384.369828 -291.389669) (xy 384.323812 -291.372217)
			(xy 384.281191 -291.34761) (xy 384.24307 -291.316485) (xy 384.210435 -291.279648) (xy 384.184132 -291.238052)
			(xy 384.164841 -291.192776) (xy 384.153064 -291.144992) (xy 384.149104 -291.095938) (xy 383.820162 -291.095938)
			(xy 383.819667 -291.120545) (xy 383.811772 -291.169122) (xy 383.796188 -291.215803) (xy 383.773317 -291.25938)
			(xy 383.743752 -291.298724) (xy 383.708259 -291.332816) (xy 383.667756 -291.360772) (xy 383.623294 -291.38187)
			(xy 383.576023 -291.395562) (xy 383.527168 -291.401494) (xy 383.477993 -291.399513) (xy 383.429774 -291.389669)
			(xy 383.383758 -291.372217) (xy 383.341137 -291.34761) (xy 383.303016 -291.316485) (xy 383.270381 -291.279648)
			(xy 383.244078 -291.238052) (xy 383.224787 -291.192776) (xy 383.21301 -291.144992) (xy 383.20905 -291.095938)
			(xy 382.880108 -291.095938) (xy 382.879613 -291.120545) (xy 382.871718 -291.169122) (xy 382.856134 -291.215803)
			(xy 382.833263 -291.25938) (xy 382.803698 -291.298724) (xy 382.768205 -291.332816) (xy 382.727702 -291.360772)
			(xy 382.68324 -291.38187) (xy 382.635969 -291.395562) (xy 382.587114 -291.401494) (xy 382.537939 -291.399513)
			(xy 382.48972 -291.389669) (xy 382.443704 -291.372217) (xy 382.401083 -291.34761) (xy 382.362962 -291.316485)
			(xy 382.330327 -291.279648) (xy 382.304024 -291.238052) (xy 382.284733 -291.192776) (xy 382.272956 -291.144992)
			(xy 382.268996 -291.095938) (xy 381.940054 -291.095938) (xy 381.939559 -291.120545) (xy 381.931664 -291.169122)
			(xy 381.91608 -291.215803) (xy 381.893209 -291.25938) (xy 381.863644 -291.298724) (xy 381.828151 -291.332816)
			(xy 381.787648 -291.360772) (xy 381.743186 -291.38187) (xy 381.695915 -291.395562) (xy 381.64706 -291.401494)
			(xy 381.597885 -291.399513) (xy 381.549666 -291.389669) (xy 381.50365 -291.372217) (xy 381.461029 -291.34761)
			(xy 381.422908 -291.316485) (xy 381.390273 -291.279648) (xy 381.36397 -291.238052) (xy 381.344679 -291.192776)
			(xy 381.332902 -291.144992) (xy 381.328942 -291.095938) (xy 381.010668 -291.095938) (xy 381.010156 -291.121384)
			(xy 381.001992 -291.171618) (xy 380.985876 -291.219892) (xy 380.962225 -291.264955) (xy 380.931652 -291.305641)
			(xy 380.894948 -291.340896) (xy 380.853064 -291.369806) (xy 380.807085 -291.391623) (xy 380.758201 -291.405783)
			(xy 380.70768 -291.411917) (xy 380.656828 -291.409868) (xy 380.606964 -291.399688) (xy 380.559378 -291.381641)
			(xy 380.515304 -291.356195) (xy 380.475882 -291.324008) (xy 380.442134 -291.285914) (xy 380.414933 -291.2429)
			(xy 380.394985 -291.19608) (xy 380.382806 -291.146666) (xy 380.378711 -291.095938) (xy 380.070614 -291.095938)
			(xy 380.070102 -291.121384) (xy 380.061938 -291.171618) (xy 380.045822 -291.219892) (xy 380.022171 -291.264955)
			(xy 379.991598 -291.305641) (xy 379.954894 -291.340896) (xy 379.91301 -291.369806) (xy 379.867031 -291.391623)
			(xy 379.818147 -291.405783) (xy 379.767626 -291.411917) (xy 379.716774 -291.409868) (xy 379.66691 -291.399688)
			(xy 379.619324 -291.381641) (xy 379.57525 -291.356195) (xy 379.535828 -291.324008) (xy 379.50208 -291.285914)
			(xy 379.474879 -291.2429) (xy 379.454931 -291.19608) (xy 379.442752 -291.146666) (xy 379.438657 -291.095938)
			(xy 379.120146 -291.095938) (xy 379.119651 -291.120545) (xy 379.111756 -291.169122) (xy 379.096172 -291.215803)
			(xy 379.073301 -291.25938) (xy 379.043736 -291.298724) (xy 379.008243 -291.332816) (xy 378.96774 -291.360772)
			(xy 378.923278 -291.38187) (xy 378.876007 -291.395562) (xy 378.827152 -291.401494) (xy 378.777977 -291.399513)
			(xy 378.729758 -291.389669) (xy 378.683742 -291.372217) (xy 378.641121 -291.34761) (xy 378.603 -291.316485)
			(xy 378.570365 -291.279648) (xy 378.544062 -291.238052) (xy 378.524771 -291.192776) (xy 378.512994 -291.144992)
			(xy 378.509034 -291.095938) (xy 378.190506 -291.095938) (xy 378.189994 -291.121384) (xy 378.18183 -291.171618)
			(xy 378.165714 -291.219892) (xy 378.142063 -291.264955) (xy 378.11149 -291.305641) (xy 378.074786 -291.340896)
			(xy 378.032902 -291.369806) (xy 377.986923 -291.391623) (xy 377.938039 -291.405783) (xy 377.887518 -291.411917)
			(xy 377.836666 -291.409868) (xy 377.786802 -291.399688) (xy 377.739216 -291.381641) (xy 377.695142 -291.356195)
			(xy 377.65572 -291.324008) (xy 377.621972 -291.285914) (xy 377.594771 -291.2429) (xy 377.574823 -291.19608)
			(xy 377.562644 -291.146666) (xy 377.558549 -291.095938) (xy 377.240038 -291.095938) (xy 377.239543 -291.120545)
			(xy 377.231648 -291.169122) (xy 377.216064 -291.215803) (xy 377.193193 -291.25938) (xy 377.163628 -291.298724)
			(xy 377.128135 -291.332816) (xy 377.087632 -291.360772) (xy 377.04317 -291.38187) (xy 376.995899 -291.395562)
			(xy 376.947044 -291.401494) (xy 376.897869 -291.399513) (xy 376.84965 -291.389669) (xy 376.803634 -291.372217)
			(xy 376.761013 -291.34761) (xy 376.722892 -291.316485) (xy 376.690257 -291.279648) (xy 376.663954 -291.238052)
			(xy 376.644663 -291.192776) (xy 376.632886 -291.144992) (xy 376.628926 -291.095938) (xy 376.310652 -291.095938)
			(xy 376.31014 -291.121384) (xy 376.301976 -291.171618) (xy 376.28586 -291.219892) (xy 376.262209 -291.264955)
			(xy 376.231636 -291.305641) (xy 376.194932 -291.340896) (xy 376.153048 -291.369806) (xy 376.107069 -291.391623)
			(xy 376.058185 -291.405783) (xy 376.007664 -291.411917) (xy 375.956812 -291.409868) (xy 375.906948 -291.399688)
			(xy 375.859362 -291.381641) (xy 375.815288 -291.356195) (xy 375.775866 -291.324008) (xy 375.742118 -291.285914)
			(xy 375.714917 -291.2429) (xy 375.694969 -291.19608) (xy 375.68279 -291.146666) (xy 375.678695 -291.095938)
			(xy 375.40819 -291.095938) (xy 375.40819 -291.101526) (xy 375.408346 -291.106211) (xy 375.410132 -291.115413)
			(xy 375.411746 -291.119814) (xy 375.418096 -291.136324) (xy 375.419832 -291.140538) (xy 375.424564 -291.148327)
			(xy 375.427494 -291.151818) (xy 375.457421 -291.185914) (xy 375.512336 -291.258139) (xy 375.561284 -291.334533)
			(xy 375.603951 -291.414605) (xy 375.640063 -291.49784) (xy 375.669386 -291.583701) (xy 375.680986 -291.62756)
			(xy 375.683386 -291.635651) (xy 375.692582 -291.64979) (xy 375.69902 -291.655246) (xy 375.718877 -291.669643)
			(xy 375.754155 -291.703713) (xy 375.783532 -291.742986) (xy 375.806252 -291.786451) (xy 375.82173 -291.832989)
			(xy 375.829568 -291.881403) (xy 375.829566 -291.905944) (xy 376.148595 -291.905944) (xy 376.15269 -291.855216)
			(xy 376.164869 -291.805802) (xy 376.184817 -291.758982) (xy 376.212018 -291.715968) (xy 376.245766 -291.677874)
			(xy 376.285188 -291.645687) (xy 376.329262 -291.620241) (xy 376.376848 -291.602194) (xy 376.426712 -291.592014)
			(xy 376.477564 -291.589965) (xy 376.528085 -291.596099) (xy 376.576969 -291.610259) (xy 376.622948 -291.632076)
			(xy 376.664832 -291.660986) (xy 376.701536 -291.696241) (xy 376.732109 -291.736927) (xy 376.75576 -291.78199)
			(xy 376.771876 -291.830264) (xy 376.78004 -291.880498) (xy 376.780552 -291.905944) (xy 377.088649 -291.905944)
			(xy 377.092744 -291.855216) (xy 377.104923 -291.805802) (xy 377.124871 -291.758982) (xy 377.152072 -291.715968)
			(xy 377.18582 -291.677874) (xy 377.225242 -291.645687) (xy 377.269316 -291.620241) (xy 377.316902 -291.602194)
			(xy 377.366766 -291.592014) (xy 377.417618 -291.589965) (xy 377.468139 -291.596099) (xy 377.517023 -291.610259)
			(xy 377.563002 -291.632076) (xy 377.604886 -291.660986) (xy 377.64159 -291.696241) (xy 377.672163 -291.736927)
			(xy 377.695814 -291.78199) (xy 377.71193 -291.830264) (xy 377.720094 -291.880498) (xy 377.720606 -291.905944)
			(xy 378.039134 -291.905944) (xy 378.043094 -291.85689) (xy 378.054871 -291.809106) (xy 378.074162 -291.76383)
			(xy 378.100465 -291.722234) (xy 378.1331 -291.685397) (xy 378.171221 -291.654272) (xy 378.213842 -291.629665)
			(xy 378.259858 -291.612213) (xy 378.308077 -291.602369) (xy 378.357252 -291.600388) (xy 378.406107 -291.60632)
			(xy 378.453378 -291.620012) (xy 378.49784 -291.64111) (xy 378.538343 -291.669066) (xy 378.573836 -291.703158)
			(xy 378.603401 -291.742502) (xy 378.626272 -291.786079) (xy 378.641856 -291.83276) (xy 378.649751 -291.881337)
			(xy 378.650246 -291.905944) (xy 378.968503 -291.905944) (xy 378.972598 -291.855216) (xy 378.984777 -291.805802)
			(xy 379.004725 -291.758982) (xy 379.031926 -291.715968) (xy 379.065674 -291.677874) (xy 379.105096 -291.645687)
			(xy 379.14917 -291.620241) (xy 379.196756 -291.602194) (xy 379.24662 -291.592014) (xy 379.297472 -291.589965)
			(xy 379.347993 -291.596099) (xy 379.396877 -291.610259) (xy 379.442856 -291.632076) (xy 379.48474 -291.660986)
			(xy 379.521444 -291.696241) (xy 379.552017 -291.736927) (xy 379.575668 -291.78199) (xy 379.591784 -291.830264)
			(xy 379.599948 -291.880498) (xy 379.60046 -291.905944) (xy 379.918988 -291.905944) (xy 379.922948 -291.85689)
			(xy 379.934725 -291.809106) (xy 379.954016 -291.76383) (xy 379.980319 -291.722234) (xy 380.012954 -291.685397)
			(xy 380.051075 -291.654272) (xy 380.093696 -291.629665) (xy 380.139712 -291.612213) (xy 380.187931 -291.602369)
			(xy 380.237106 -291.600388) (xy 380.285961 -291.60632) (xy 380.333232 -291.620012) (xy 380.377694 -291.64111)
			(xy 380.418197 -291.669066) (xy 380.45369 -291.703158) (xy 380.483255 -291.742502) (xy 380.506126 -291.786079)
			(xy 380.52171 -291.83276) (xy 380.529605 -291.881337) (xy 380.5301 -291.905944) (xy 380.848611 -291.905944)
			(xy 380.852706 -291.855216) (xy 380.864885 -291.805802) (xy 380.884833 -291.758982) (xy 380.912034 -291.715968)
			(xy 380.945782 -291.677874) (xy 380.985204 -291.645687) (xy 381.029278 -291.620241) (xy 381.076864 -291.602194)
			(xy 381.126728 -291.592014) (xy 381.17758 -291.589965) (xy 381.228101 -291.596099) (xy 381.276985 -291.610259)
			(xy 381.322964 -291.632076) (xy 381.364848 -291.660986) (xy 381.401552 -291.696241) (xy 381.432125 -291.736927)
			(xy 381.455776 -291.78199) (xy 381.471892 -291.830264) (xy 381.480056 -291.880498) (xy 381.480568 -291.905944)
			(xy 381.799096 -291.905944) (xy 381.803056 -291.85689) (xy 381.814833 -291.809106) (xy 381.834124 -291.76383)
			(xy 381.860427 -291.722234) (xy 381.893062 -291.685397) (xy 381.931183 -291.654272) (xy 381.973804 -291.629665)
			(xy 382.01982 -291.612213) (xy 382.068039 -291.602369) (xy 382.117214 -291.600388) (xy 382.166069 -291.60632)
			(xy 382.21334 -291.620012) (xy 382.257802 -291.64111) (xy 382.298305 -291.669066) (xy 382.333798 -291.703158)
			(xy 382.363363 -291.742502) (xy 382.386234 -291.786079) (xy 382.401818 -291.83276) (xy 382.409713 -291.881337)
			(xy 382.410208 -291.905944) (xy 382.738896 -291.905944) (xy 382.742856 -291.85689) (xy 382.754633 -291.809106)
			(xy 382.773924 -291.76383) (xy 382.800227 -291.722234) (xy 382.832862 -291.685397) (xy 382.870983 -291.654272)
			(xy 382.913604 -291.629665) (xy 382.95962 -291.612213) (xy 383.007839 -291.602369) (xy 383.057014 -291.600388)
			(xy 383.105869 -291.60632) (xy 383.15314 -291.620012) (xy 383.197602 -291.64111) (xy 383.238105 -291.669066)
			(xy 383.273598 -291.703158) (xy 383.303163 -291.742502) (xy 383.326034 -291.786079) (xy 383.341618 -291.83276)
			(xy 383.349513 -291.881337) (xy 383.350008 -291.905944) (xy 383.67895 -291.905944) (xy 383.68291 -291.85689)
			(xy 383.694687 -291.809106) (xy 383.713978 -291.76383) (xy 383.740281 -291.722234) (xy 383.772916 -291.685397)
			(xy 383.811037 -291.654272) (xy 383.853658 -291.629665) (xy 383.899674 -291.612213) (xy 383.947893 -291.602369)
			(xy 383.997068 -291.600388) (xy 384.045923 -291.60632) (xy 384.093194 -291.620012) (xy 384.137656 -291.64111)
			(xy 384.178159 -291.669066) (xy 384.213652 -291.703158) (xy 384.243217 -291.742502) (xy 384.266088 -291.786079)
			(xy 384.281672 -291.83276) (xy 384.289567 -291.881337) (xy 384.290062 -291.905944) (xy 384.619004 -291.905944)
			(xy 384.622964 -291.85689) (xy 384.634741 -291.809106) (xy 384.654032 -291.76383) (xy 384.680335 -291.722234)
			(xy 384.71297 -291.685397) (xy 384.751091 -291.654272) (xy 384.793712 -291.629665) (xy 384.839728 -291.612213)
			(xy 384.887947 -291.602369) (xy 384.937122 -291.600388) (xy 384.985977 -291.60632) (xy 385.033248 -291.620012)
			(xy 385.07771 -291.64111) (xy 385.118213 -291.669066) (xy 385.153706 -291.703158) (xy 385.183271 -291.742502)
			(xy 385.206142 -291.786079) (xy 385.221726 -291.83276) (xy 385.229621 -291.881337) (xy 385.230116 -291.905944)
			(xy 385.559058 -291.905944) (xy 385.563018 -291.85689) (xy 385.574795 -291.809106) (xy 385.594086 -291.76383)
			(xy 385.620389 -291.722234) (xy 385.653024 -291.685397) (xy 385.691145 -291.654272) (xy 385.733766 -291.629665)
			(xy 385.779782 -291.612213) (xy 385.828001 -291.602369) (xy 385.877176 -291.600388) (xy 385.926031 -291.60632)
			(xy 385.973302 -291.620012) (xy 386.017764 -291.64111) (xy 386.058267 -291.669066) (xy 386.09376 -291.703158)
			(xy 386.123325 -291.742502) (xy 386.146196 -291.786079) (xy 386.16178 -291.83276) (xy 386.169675 -291.881337)
			(xy 386.17017 -291.905944) (xy 386.499112 -291.905944) (xy 386.503072 -291.85689) (xy 386.514849 -291.809106)
			(xy 386.53414 -291.76383) (xy 386.560443 -291.722234) (xy 386.593078 -291.685397) (xy 386.631199 -291.654272)
			(xy 386.67382 -291.629665) (xy 386.719836 -291.612213) (xy 386.768055 -291.602369) (xy 386.81723 -291.600388)
			(xy 386.866085 -291.60632) (xy 386.913356 -291.620012) (xy 386.957818 -291.64111) (xy 386.998321 -291.669066)
			(xy 387.033814 -291.703158) (xy 387.063379 -291.742502) (xy 387.08625 -291.786079) (xy 387.101834 -291.83276)
			(xy 387.109729 -291.881337) (xy 387.110224 -291.905944) (xy 387.438912 -291.905944) (xy 387.442872 -291.85689)
			(xy 387.454649 -291.809106) (xy 387.47394 -291.76383) (xy 387.500243 -291.722234) (xy 387.532878 -291.685397)
			(xy 387.570999 -291.654272) (xy 387.61362 -291.629665) (xy 387.659636 -291.612213) (xy 387.707855 -291.602369)
			(xy 387.75703 -291.600388) (xy 387.805885 -291.60632) (xy 387.853156 -291.620012) (xy 387.897618 -291.64111)
			(xy 387.938121 -291.669066) (xy 387.973614 -291.703158) (xy 388.003179 -291.742502) (xy 388.02605 -291.786079)
			(xy 388.041634 -291.83276) (xy 388.049529 -291.881337) (xy 388.050024 -291.905944) (xy 388.049529 -291.930551)
			(xy 388.041634 -291.979128) (xy 388.02605 -292.025809) (xy 388.003179 -292.069386) (xy 387.973614 -292.10873)
			(xy 387.938121 -292.142822) (xy 387.897618 -292.170778) (xy 387.853156 -292.191876) (xy 387.805885 -292.205568)
			(xy 387.75703 -292.2115) (xy 387.707855 -292.209519) (xy 387.659636 -292.199675) (xy 387.61362 -292.182223)
			(xy 387.570999 -292.157616) (xy 387.532878 -292.126491) (xy 387.500243 -292.089654) (xy 387.47394 -292.048058)
			(xy 387.454649 -292.002782) (xy 387.442872 -291.954998) (xy 387.438912 -291.905944) (xy 387.110224 -291.905944)
			(xy 387.109729 -291.930551) (xy 387.101834 -291.979128) (xy 387.08625 -292.025809) (xy 387.063379 -292.069386)
			(xy 387.033814 -292.10873) (xy 386.998321 -292.142822) (xy 386.957818 -292.170778) (xy 386.913356 -292.191876)
			(xy 386.866085 -292.205568) (xy 386.81723 -292.2115) (xy 386.768055 -292.209519) (xy 386.719836 -292.199675)
			(xy 386.67382 -292.182223) (xy 386.631199 -292.157616) (xy 386.593078 -292.126491) (xy 386.560443 -292.089654)
			(xy 386.53414 -292.048058) (xy 386.514849 -292.002782) (xy 386.503072 -291.954998) (xy 386.499112 -291.905944)
			(xy 386.17017 -291.905944) (xy 386.169675 -291.930551) (xy 386.16178 -291.979128) (xy 386.146196 -292.025809)
			(xy 386.123325 -292.069386) (xy 386.09376 -292.10873) (xy 386.058267 -292.142822) (xy 386.017764 -292.170778)
			(xy 385.973302 -292.191876) (xy 385.926031 -292.205568) (xy 385.877176 -292.2115) (xy 385.828001 -292.209519)
			(xy 385.779782 -292.199675) (xy 385.733766 -292.182223) (xy 385.691145 -292.157616) (xy 385.653024 -292.126491)
			(xy 385.620389 -292.089654) (xy 385.594086 -292.048058) (xy 385.574795 -292.002782) (xy 385.563018 -291.954998)
			(xy 385.559058 -291.905944) (xy 385.230116 -291.905944) (xy 385.229621 -291.930551) (xy 385.221726 -291.979128)
			(xy 385.206142 -292.025809) (xy 385.183271 -292.069386) (xy 385.153706 -292.10873) (xy 385.118213 -292.142822)
			(xy 385.07771 -292.170778) (xy 385.033248 -292.191876) (xy 384.985977 -292.205568) (xy 384.937122 -292.2115)
			(xy 384.887947 -292.209519) (xy 384.839728 -292.199675) (xy 384.793712 -292.182223) (xy 384.751091 -292.157616)
			(xy 384.71297 -292.126491) (xy 384.680335 -292.089654) (xy 384.654032 -292.048058) (xy 384.634741 -292.002782)
			(xy 384.622964 -291.954998) (xy 384.619004 -291.905944) (xy 384.290062 -291.905944) (xy 384.289567 -291.930551)
			(xy 384.281672 -291.979128) (xy 384.266088 -292.025809) (xy 384.243217 -292.069386) (xy 384.213652 -292.10873)
			(xy 384.178159 -292.142822) (xy 384.137656 -292.170778) (xy 384.093194 -292.191876) (xy 384.045923 -292.205568)
			(xy 383.997068 -292.2115) (xy 383.947893 -292.209519) (xy 383.899674 -292.199675) (xy 383.853658 -292.182223)
			(xy 383.811037 -292.157616) (xy 383.772916 -292.126491) (xy 383.740281 -292.089654) (xy 383.713978 -292.048058)
			(xy 383.694687 -292.002782) (xy 383.68291 -291.954998) (xy 383.67895 -291.905944) (xy 383.350008 -291.905944)
			(xy 383.349513 -291.930551) (xy 383.341618 -291.979128) (xy 383.326034 -292.025809) (xy 383.303163 -292.069386)
			(xy 383.273598 -292.10873) (xy 383.238105 -292.142822) (xy 383.197602 -292.170778) (xy 383.15314 -292.191876)
			(xy 383.105869 -292.205568) (xy 383.057014 -292.2115) (xy 383.007839 -292.209519) (xy 382.95962 -292.199675)
			(xy 382.913604 -292.182223) (xy 382.870983 -292.157616) (xy 382.832862 -292.126491) (xy 382.800227 -292.089654)
			(xy 382.773924 -292.048058) (xy 382.754633 -292.002782) (xy 382.742856 -291.954998) (xy 382.738896 -291.905944)
			(xy 382.410208 -291.905944) (xy 382.409713 -291.930551) (xy 382.401818 -291.979128) (xy 382.386234 -292.025809)
			(xy 382.363363 -292.069386) (xy 382.333798 -292.10873) (xy 382.298305 -292.142822) (xy 382.257802 -292.170778)
			(xy 382.21334 -292.191876) (xy 382.166069 -292.205568) (xy 382.117214 -292.2115) (xy 382.068039 -292.209519)
			(xy 382.01982 -292.199675) (xy 381.973804 -292.182223) (xy 381.931183 -292.157616) (xy 381.893062 -292.126491)
			(xy 381.860427 -292.089654) (xy 381.834124 -292.048058) (xy 381.814833 -292.002782) (xy 381.803056 -291.954998)
			(xy 381.799096 -291.905944) (xy 381.480568 -291.905944) (xy 381.480056 -291.93139) (xy 381.471892 -291.981624)
			(xy 381.455776 -292.029898) (xy 381.432125 -292.074961) (xy 381.401552 -292.115647) (xy 381.364848 -292.150902)
			(xy 381.322964 -292.179812) (xy 381.276985 -292.201629) (xy 381.228101 -292.215789) (xy 381.17758 -292.221923)
			(xy 381.126728 -292.219874) (xy 381.076864 -292.209694) (xy 381.029278 -292.191647) (xy 380.985204 -292.166201)
			(xy 380.945782 -292.134014) (xy 380.912034 -292.09592) (xy 380.884833 -292.052906) (xy 380.864885 -292.006086)
			(xy 380.852706 -291.956672) (xy 380.848611 -291.905944) (xy 380.5301 -291.905944) (xy 380.529605 -291.930551)
			(xy 380.52171 -291.979128) (xy 380.506126 -292.025809) (xy 380.483255 -292.069386) (xy 380.45369 -292.10873)
			(xy 380.418197 -292.142822) (xy 380.377694 -292.170778) (xy 380.333232 -292.191876) (xy 380.285961 -292.205568)
			(xy 380.237106 -292.2115) (xy 380.187931 -292.209519) (xy 380.139712 -292.199675) (xy 380.093696 -292.182223)
			(xy 380.051075 -292.157616) (xy 380.012954 -292.126491) (xy 379.980319 -292.089654) (xy 379.954016 -292.048058)
			(xy 379.934725 -292.002782) (xy 379.922948 -291.954998) (xy 379.918988 -291.905944) (xy 379.60046 -291.905944)
			(xy 379.599948 -291.93139) (xy 379.591784 -291.981624) (xy 379.575668 -292.029898) (xy 379.552017 -292.074961)
			(xy 379.521444 -292.115647) (xy 379.48474 -292.150902) (xy 379.442856 -292.179812) (xy 379.396877 -292.201629)
			(xy 379.347993 -292.215789) (xy 379.297472 -292.221923) (xy 379.24662 -292.219874) (xy 379.196756 -292.209694)
			(xy 379.14917 -292.191647) (xy 379.105096 -292.166201) (xy 379.065674 -292.134014) (xy 379.031926 -292.09592)
			(xy 379.004725 -292.052906) (xy 378.984777 -292.006086) (xy 378.972598 -291.956672) (xy 378.968503 -291.905944)
			(xy 378.650246 -291.905944) (xy 378.649751 -291.930551) (xy 378.641856 -291.979128) (xy 378.626272 -292.025809)
			(xy 378.603401 -292.069386) (xy 378.573836 -292.10873) (xy 378.538343 -292.142822) (xy 378.49784 -292.170778)
			(xy 378.453378 -292.191876) (xy 378.406107 -292.205568) (xy 378.357252 -292.2115) (xy 378.308077 -292.209519)
			(xy 378.259858 -292.199675) (xy 378.213842 -292.182223) (xy 378.171221 -292.157616) (xy 378.1331 -292.126491)
			(xy 378.100465 -292.089654) (xy 378.074162 -292.048058) (xy 378.054871 -292.002782) (xy 378.043094 -291.954998)
			(xy 378.039134 -291.905944) (xy 377.720606 -291.905944) (xy 377.720094 -291.93139) (xy 377.71193 -291.981624)
			(xy 377.695814 -292.029898) (xy 377.672163 -292.074961) (xy 377.64159 -292.115647) (xy 377.604886 -292.150902)
			(xy 377.563002 -292.179812) (xy 377.517023 -292.201629) (xy 377.468139 -292.215789) (xy 377.417618 -292.221923)
			(xy 377.366766 -292.219874) (xy 377.316902 -292.209694) (xy 377.269316 -292.191647) (xy 377.225242 -292.166201)
			(xy 377.18582 -292.134014) (xy 377.152072 -292.09592) (xy 377.124871 -292.052906) (xy 377.104923 -292.006086)
			(xy 377.092744 -291.956672) (xy 377.088649 -291.905944) (xy 376.780552 -291.905944) (xy 376.78004 -291.93139)
			(xy 376.771876 -291.981624) (xy 376.75576 -292.029898) (xy 376.732109 -292.074961) (xy 376.701536 -292.115647)
			(xy 376.664832 -292.150902) (xy 376.622948 -292.179812) (xy 376.576969 -292.201629) (xy 376.528085 -292.215789)
			(xy 376.477564 -292.221923) (xy 376.426712 -292.219874) (xy 376.376848 -292.209694) (xy 376.329262 -292.191647)
			(xy 376.285188 -292.166201) (xy 376.245766 -292.134014) (xy 376.212018 -292.09592) (xy 376.184817 -292.052906)
			(xy 376.164869 -292.006086) (xy 376.15269 -291.956672) (xy 376.148595 -291.905944) (xy 375.829566 -291.905944)
			(xy 375.829564 -291.930447) (xy 375.821718 -291.97886) (xy 375.806232 -292.025396) (xy 375.783506 -292.068856)
			(xy 375.754122 -292.108124) (xy 375.718838 -292.142189) (xy 375.69902 -292.156642) (xy 375.69254 -292.162064)
			(xy 375.683309 -292.176205) (xy 375.680986 -292.184328) (xy 375.669372 -292.228183) (xy 375.640045 -292.314043)
			(xy 375.603935 -292.397277) (xy 375.561273 -292.477351) (xy 375.512334 -292.553751) (xy 375.457433 -292.625984)
			(xy 375.427494 -292.66007) (xy 375.42454 -292.663544) (xy 375.419814 -292.67134) (xy 375.418096 -292.675564)
			(xy 375.411746 -292.692074) (xy 375.410105 -292.696468) (xy 375.408319 -292.705674) (xy 375.40819 -292.710362)
			(xy 375.40819 -292.71595) (xy 375.678695 -292.71595) (xy 375.68279 -292.665222) (xy 375.694969 -292.615808)
			(xy 375.714917 -292.568988) (xy 375.742118 -292.525974) (xy 375.775866 -292.48788) (xy 375.815288 -292.455693)
			(xy 375.859362 -292.430247) (xy 375.906948 -292.4122) (xy 375.956812 -292.40202) (xy 376.007664 -292.399971)
			(xy 376.058185 -292.406105) (xy 376.107069 -292.420265) (xy 376.153048 -292.442082) (xy 376.194932 -292.470992)
			(xy 376.231636 -292.506247) (xy 376.262209 -292.546933) (xy 376.28586 -292.591996) (xy 376.301976 -292.64027)
			(xy 376.31014 -292.690504) (xy 376.310652 -292.71595) (xy 376.628926 -292.71595) (xy 376.632886 -292.666896)
			(xy 376.644663 -292.619112) (xy 376.663954 -292.573836) (xy 376.690257 -292.53224) (xy 376.722892 -292.495403)
			(xy 376.761013 -292.464278) (xy 376.803634 -292.439671) (xy 376.84965 -292.422219) (xy 376.897869 -292.412375)
			(xy 376.947044 -292.410394) (xy 376.995899 -292.416326) (xy 377.04317 -292.430018) (xy 377.087632 -292.451116)
			(xy 377.128135 -292.479072) (xy 377.163628 -292.513164) (xy 377.193193 -292.552508) (xy 377.216064 -292.596085)
			(xy 377.231648 -292.642766) (xy 377.239543 -292.691343) (xy 377.240038 -292.71595) (xy 377.558549 -292.71595)
			(xy 377.562644 -292.665222) (xy 377.574823 -292.615808) (xy 377.594771 -292.568988) (xy 377.621972 -292.525974)
			(xy 377.65572 -292.48788) (xy 377.695142 -292.455693) (xy 377.739216 -292.430247) (xy 377.786802 -292.4122)
			(xy 377.836666 -292.40202) (xy 377.887518 -292.399971) (xy 377.938039 -292.406105) (xy 377.986923 -292.420265)
			(xy 378.032902 -292.442082) (xy 378.074786 -292.470992) (xy 378.11149 -292.506247) (xy 378.142063 -292.546933)
			(xy 378.165714 -292.591996) (xy 378.18183 -292.64027) (xy 378.189994 -292.690504) (xy 378.190506 -292.71595)
			(xy 379.438657 -292.71595) (xy 379.442752 -292.665222) (xy 379.454931 -292.615808) (xy 379.474879 -292.568988)
			(xy 379.50208 -292.525974) (xy 379.535828 -292.48788) (xy 379.57525 -292.455693) (xy 379.619324 -292.430247)
			(xy 379.66691 -292.4122) (xy 379.716774 -292.40202) (xy 379.767626 -292.399971) (xy 379.818147 -292.406105)
			(xy 379.867031 -292.420265) (xy 379.91301 -292.442082) (xy 379.954894 -292.470992) (xy 379.991598 -292.506247)
			(xy 380.022171 -292.546933) (xy 380.045822 -292.591996) (xy 380.061938 -292.64027) (xy 380.070102 -292.690504)
			(xy 380.070614 -292.71595) (xy 380.378711 -292.71595) (xy 380.382806 -292.665222) (xy 380.394985 -292.615808)
			(xy 380.414933 -292.568988) (xy 380.442134 -292.525974) (xy 380.475882 -292.48788) (xy 380.515304 -292.455693)
			(xy 380.559378 -292.430247) (xy 380.606964 -292.4122) (xy 380.656828 -292.40202) (xy 380.70768 -292.399971)
			(xy 380.758201 -292.406105) (xy 380.807085 -292.420265) (xy 380.853064 -292.442082) (xy 380.894948 -292.470992)
			(xy 380.931652 -292.506247) (xy 380.962225 -292.546933) (xy 380.985876 -292.591996) (xy 381.001992 -292.64027)
			(xy 381.010156 -292.690504) (xy 381.010668 -292.71595) (xy 381.328942 -292.71595) (xy 381.332902 -292.666896)
			(xy 381.344679 -292.619112) (xy 381.36397 -292.573836) (xy 381.390273 -292.53224) (xy 381.422908 -292.495403)
			(xy 381.461029 -292.464278) (xy 381.50365 -292.439671) (xy 381.549666 -292.422219) (xy 381.597885 -292.412375)
			(xy 381.64706 -292.410394) (xy 381.695915 -292.416326) (xy 381.743186 -292.430018) (xy 381.787648 -292.451116)
			(xy 381.828151 -292.479072) (xy 381.863644 -292.513164) (xy 381.893209 -292.552508) (xy 381.91608 -292.596085)
			(xy 381.931664 -292.642766) (xy 381.939559 -292.691343) (xy 381.940054 -292.71595) (xy 382.268996 -292.71595)
			(xy 382.272956 -292.666896) (xy 382.284733 -292.619112) (xy 382.304024 -292.573836) (xy 382.330327 -292.53224)
			(xy 382.362962 -292.495403) (xy 382.401083 -292.464278) (xy 382.443704 -292.439671) (xy 382.48972 -292.422219)
			(xy 382.537939 -292.412375) (xy 382.587114 -292.410394) (xy 382.635969 -292.416326) (xy 382.68324 -292.430018)
			(xy 382.727702 -292.451116) (xy 382.768205 -292.479072) (xy 382.803698 -292.513164) (xy 382.833263 -292.552508)
			(xy 382.856134 -292.596085) (xy 382.871718 -292.642766) (xy 382.879613 -292.691343) (xy 382.880108 -292.71595)
			(xy 383.20905 -292.71595) (xy 383.21301 -292.666896) (xy 383.224787 -292.619112) (xy 383.244078 -292.573836)
			(xy 383.270381 -292.53224) (xy 383.303016 -292.495403) (xy 383.341137 -292.464278) (xy 383.383758 -292.439671)
			(xy 383.429774 -292.422219) (xy 383.477993 -292.412375) (xy 383.527168 -292.410394) (xy 383.576023 -292.416326)
			(xy 383.623294 -292.430018) (xy 383.667756 -292.451116) (xy 383.708259 -292.479072) (xy 383.743752 -292.513164)
			(xy 383.773317 -292.552508) (xy 383.796188 -292.596085) (xy 383.811772 -292.642766) (xy 383.819667 -292.691343)
			(xy 383.820162 -292.71595) (xy 384.149104 -292.71595) (xy 384.153064 -292.666896) (xy 384.164841 -292.619112)
			(xy 384.184132 -292.573836) (xy 384.210435 -292.53224) (xy 384.24307 -292.495403) (xy 384.281191 -292.464278)
			(xy 384.323812 -292.439671) (xy 384.369828 -292.422219) (xy 384.418047 -292.412375) (xy 384.467222 -292.410394)
			(xy 384.516077 -292.416326) (xy 384.563348 -292.430018) (xy 384.60781 -292.451116) (xy 384.648313 -292.479072)
			(xy 384.683806 -292.513164) (xy 384.713371 -292.552508) (xy 384.736242 -292.596085) (xy 384.751826 -292.642766)
			(xy 384.759721 -292.691343) (xy 384.760216 -292.71595) (xy 386.028958 -292.71595) (xy 386.032918 -292.666896)
			(xy 386.044695 -292.619112) (xy 386.063986 -292.573836) (xy 386.090289 -292.53224) (xy 386.122924 -292.495403)
			(xy 386.161045 -292.464278) (xy 386.203666 -292.439671) (xy 386.249682 -292.422219) (xy 386.297901 -292.412375)
			(xy 386.347076 -292.410394) (xy 386.395931 -292.416326) (xy 386.443202 -292.430018) (xy 386.487664 -292.451116)
			(xy 386.528167 -292.479072) (xy 386.56366 -292.513164) (xy 386.593225 -292.552508) (xy 386.616096 -292.596085)
			(xy 386.63168 -292.642766) (xy 386.639575 -292.691343) (xy 386.64007 -292.71595) (xy 386.969012 -292.71595)
			(xy 386.972972 -292.666896) (xy 386.984749 -292.619112) (xy 387.00404 -292.573836) (xy 387.030343 -292.53224)
			(xy 387.062978 -292.495403) (xy 387.101099 -292.464278) (xy 387.14372 -292.439671) (xy 387.189736 -292.422219)
			(xy 387.237955 -292.412375) (xy 387.28713 -292.410394) (xy 387.335985 -292.416326) (xy 387.383256 -292.430018)
			(xy 387.427718 -292.451116) (xy 387.468221 -292.479072) (xy 387.503714 -292.513164) (xy 387.533279 -292.552508)
			(xy 387.55615 -292.596085) (xy 387.571734 -292.642766) (xy 387.579629 -292.691343) (xy 387.580124 -292.71595)
			(xy 387.579629 -292.740557) (xy 387.571734 -292.789134) (xy 387.55615 -292.835815) (xy 387.533279 -292.879392)
			(xy 387.503714 -292.918736) (xy 387.468221 -292.952828) (xy 387.427718 -292.980784) (xy 387.383256 -293.001882)
			(xy 387.335985 -293.015574) (xy 387.28713 -293.021506) (xy 387.237955 -293.019525) (xy 387.189736 -293.009681)
			(xy 387.14372 -292.992229) (xy 387.101099 -292.967622) (xy 387.062978 -292.936497) (xy 387.030343 -292.89966)
			(xy 387.00404 -292.858064) (xy 386.984749 -292.812788) (xy 386.972972 -292.765004) (xy 386.969012 -292.71595)
			(xy 386.64007 -292.71595) (xy 386.639575 -292.740557) (xy 386.63168 -292.789134) (xy 386.616096 -292.835815)
			(xy 386.593225 -292.879392) (xy 386.56366 -292.918736) (xy 386.528167 -292.952828) (xy 386.487664 -292.980784)
			(xy 386.443202 -293.001882) (xy 386.395931 -293.015574) (xy 386.347076 -293.021506) (xy 386.297901 -293.019525)
			(xy 386.249682 -293.009681) (xy 386.203666 -292.992229) (xy 386.161045 -292.967622) (xy 386.122924 -292.936497)
			(xy 386.090289 -292.89966) (xy 386.063986 -292.858064) (xy 386.044695 -292.812788) (xy 386.032918 -292.765004)
			(xy 386.028958 -292.71595) (xy 384.760216 -292.71595) (xy 384.759721 -292.740557) (xy 384.751826 -292.789134)
			(xy 384.736242 -292.835815) (xy 384.713371 -292.879392) (xy 384.683806 -292.918736) (xy 384.648313 -292.952828)
			(xy 384.60781 -292.980784) (xy 384.563348 -293.001882) (xy 384.516077 -293.015574) (xy 384.467222 -293.021506)
			(xy 384.418047 -293.019525) (xy 384.369828 -293.009681) (xy 384.323812 -292.992229) (xy 384.281191 -292.967622)
			(xy 384.24307 -292.936497) (xy 384.210435 -292.89966) (xy 384.184132 -292.858064) (xy 384.164841 -292.812788)
			(xy 384.153064 -292.765004) (xy 384.149104 -292.71595) (xy 383.820162 -292.71595) (xy 383.819667 -292.740557)
			(xy 383.811772 -292.789134) (xy 383.796188 -292.835815) (xy 383.773317 -292.879392) (xy 383.743752 -292.918736)
			(xy 383.708259 -292.952828) (xy 383.667756 -292.980784) (xy 383.623294 -293.001882) (xy 383.576023 -293.015574)
			(xy 383.527168 -293.021506) (xy 383.477993 -293.019525) (xy 383.429774 -293.009681) (xy 383.383758 -292.992229)
			(xy 383.341137 -292.967622) (xy 383.303016 -292.936497) (xy 383.270381 -292.89966) (xy 383.244078 -292.858064)
			(xy 383.224787 -292.812788) (xy 383.21301 -292.765004) (xy 383.20905 -292.71595) (xy 382.880108 -292.71595)
			(xy 382.879613 -292.740557) (xy 382.871718 -292.789134) (xy 382.856134 -292.835815) (xy 382.833263 -292.879392)
			(xy 382.803698 -292.918736) (xy 382.768205 -292.952828) (xy 382.727702 -292.980784) (xy 382.68324 -293.001882)
			(xy 382.635969 -293.015574) (xy 382.587114 -293.021506) (xy 382.537939 -293.019525) (xy 382.48972 -293.009681)
			(xy 382.443704 -292.992229) (xy 382.401083 -292.967622) (xy 382.362962 -292.936497) (xy 382.330327 -292.89966)
			(xy 382.304024 -292.858064) (xy 382.284733 -292.812788) (xy 382.272956 -292.765004) (xy 382.268996 -292.71595)
			(xy 381.940054 -292.71595) (xy 381.939559 -292.740557) (xy 381.931664 -292.789134) (xy 381.91608 -292.835815)
			(xy 381.893209 -292.879392) (xy 381.863644 -292.918736) (xy 381.828151 -292.952828) (xy 381.787648 -292.980784)
			(xy 381.743186 -293.001882) (xy 381.695915 -293.015574) (xy 381.64706 -293.021506) (xy 381.597885 -293.019525)
			(xy 381.549666 -293.009681) (xy 381.50365 -292.992229) (xy 381.461029 -292.967622) (xy 381.422908 -292.936497)
			(xy 381.390273 -292.89966) (xy 381.36397 -292.858064) (xy 381.344679 -292.812788) (xy 381.332902 -292.765004)
			(xy 381.328942 -292.71595) (xy 381.010668 -292.71595) (xy 381.010156 -292.741396) (xy 381.001992 -292.79163)
			(xy 380.985876 -292.839904) (xy 380.962225 -292.884967) (xy 380.931652 -292.925653) (xy 380.894948 -292.960908)
			(xy 380.853064 -292.989818) (xy 380.807085 -293.011635) (xy 380.758201 -293.025795) (xy 380.70768 -293.031929)
			(xy 380.656828 -293.02988) (xy 380.606964 -293.0197) (xy 380.559378 -293.001653) (xy 380.515304 -292.976207)
			(xy 380.475882 -292.94402) (xy 380.442134 -292.905926) (xy 380.414933 -292.862912) (xy 380.394985 -292.816092)
			(xy 380.382806 -292.766678) (xy 380.378711 -292.71595) (xy 380.070614 -292.71595) (xy 380.070102 -292.741396)
			(xy 380.061938 -292.79163) (xy 380.045822 -292.839904) (xy 380.022171 -292.884967) (xy 379.991598 -292.925653)
			(xy 379.954894 -292.960908) (xy 379.91301 -292.989818) (xy 379.867031 -293.011635) (xy 379.818147 -293.025795)
			(xy 379.767626 -293.031929) (xy 379.716774 -293.02988) (xy 379.66691 -293.0197) (xy 379.619324 -293.001653)
			(xy 379.57525 -292.976207) (xy 379.535828 -292.94402) (xy 379.50208 -292.905926) (xy 379.474879 -292.862912)
			(xy 379.454931 -292.816092) (xy 379.442752 -292.766678) (xy 379.438657 -292.71595) (xy 378.190506 -292.71595)
			(xy 378.189994 -292.741396) (xy 378.18183 -292.79163) (xy 378.165714 -292.839904) (xy 378.142063 -292.884967)
			(xy 378.11149 -292.925653) (xy 378.074786 -292.960908) (xy 378.032902 -292.989818) (xy 377.986923 -293.011635)
			(xy 377.938039 -293.025795) (xy 377.887518 -293.031929) (xy 377.836666 -293.02988) (xy 377.786802 -293.0197)
			(xy 377.739216 -293.001653) (xy 377.695142 -292.976207) (xy 377.65572 -292.94402) (xy 377.621972 -292.905926)
			(xy 377.594771 -292.862912) (xy 377.574823 -292.816092) (xy 377.562644 -292.766678) (xy 377.558549 -292.71595)
			(xy 377.240038 -292.71595) (xy 377.239543 -292.740557) (xy 377.231648 -292.789134) (xy 377.216064 -292.835815)
			(xy 377.193193 -292.879392) (xy 377.163628 -292.918736) (xy 377.128135 -292.952828) (xy 377.087632 -292.980784)
			(xy 377.04317 -293.001882) (xy 376.995899 -293.015574) (xy 376.947044 -293.021506) (xy 376.897869 -293.019525)
			(xy 376.84965 -293.009681) (xy 376.803634 -292.992229) (xy 376.761013 -292.967622) (xy 376.722892 -292.936497)
			(xy 376.690257 -292.89966) (xy 376.663954 -292.858064) (xy 376.644663 -292.812788) (xy 376.632886 -292.765004)
			(xy 376.628926 -292.71595) (xy 376.310652 -292.71595) (xy 376.31014 -292.741396) (xy 376.301976 -292.79163)
			(xy 376.28586 -292.839904) (xy 376.262209 -292.884967) (xy 376.231636 -292.925653) (xy 376.194932 -292.960908)
			(xy 376.153048 -292.989818) (xy 376.107069 -293.011635) (xy 376.058185 -293.025795) (xy 376.007664 -293.031929)
			(xy 375.956812 -293.02988) (xy 375.906948 -293.0197) (xy 375.859362 -293.001653) (xy 375.815288 -292.976207)
			(xy 375.775866 -292.94402) (xy 375.742118 -292.905926) (xy 375.714917 -292.862912) (xy 375.694969 -292.816092)
			(xy 375.68279 -292.766678) (xy 375.678695 -292.71595) (xy 375.40819 -292.71595) (xy 375.40819 -292.721538)
			(xy 375.408347 -292.726223) (xy 375.410135 -292.735424) (xy 375.411746 -292.739826) (xy 375.418096 -292.756336)
			(xy 375.419832 -292.76055) (xy 375.424565 -292.768337) (xy 375.427494 -292.77183) (xy 375.457421 -292.805926)
			(xy 375.512335 -292.878151) (xy 375.561282 -292.954546) (xy 375.603949 -293.034618) (xy 375.640059 -293.117853)
			(xy 375.669382 -293.203714) (xy 375.680986 -293.247572) (xy 375.683387 -293.255662) (xy 375.692586 -293.269798)
			(xy 375.69902 -293.275258) (xy 375.718884 -293.289655) (xy 375.754176 -293.323728) (xy 375.783567 -293.363005)
			(xy 375.806299 -293.406476) (xy 375.821788 -293.453023) (xy 375.829636 -293.501447) (xy 375.829638 -293.525956)
			(xy 376.148595 -293.525956) (xy 376.15269 -293.475228) (xy 376.164869 -293.425814) (xy 376.184817 -293.378994)
			(xy 376.212018 -293.33598) (xy 376.245766 -293.297886) (xy 376.285188 -293.265699) (xy 376.329262 -293.240253)
			(xy 376.376848 -293.222206) (xy 376.426712 -293.212026) (xy 376.477564 -293.209977) (xy 376.528085 -293.216111)
			(xy 376.576969 -293.230271) (xy 376.622948 -293.252088) (xy 376.664832 -293.280998) (xy 376.701536 -293.316253)
			(xy 376.732109 -293.356939) (xy 376.75576 -293.402002) (xy 376.771876 -293.450276) (xy 376.78004 -293.50051)
			(xy 376.780552 -293.525956) (xy 377.09908 -293.525956) (xy 377.10304 -293.476902) (xy 377.114817 -293.429118)
			(xy 377.134108 -293.383842) (xy 377.160411 -293.342246) (xy 377.193046 -293.305409) (xy 377.231167 -293.274284)
			(xy 377.273788 -293.249677) (xy 377.319804 -293.232225) (xy 377.368023 -293.222381) (xy 377.417198 -293.2204)
			(xy 377.466053 -293.226332) (xy 377.513324 -293.240024) (xy 377.557786 -293.261122) (xy 377.598289 -293.289078)
			(xy 377.633782 -293.32317) (xy 377.663347 -293.362514) (xy 377.686218 -293.406091) (xy 377.701802 -293.452772)
			(xy 377.709697 -293.501349) (xy 377.710192 -293.525956) (xy 378.039134 -293.525956) (xy 378.043094 -293.476902)
			(xy 378.054871 -293.429118) (xy 378.074162 -293.383842) (xy 378.100465 -293.342246) (xy 378.1331 -293.305409)
			(xy 378.171221 -293.274284) (xy 378.213842 -293.249677) (xy 378.259858 -293.232225) (xy 378.308077 -293.222381)
			(xy 378.357252 -293.2204) (xy 378.406107 -293.226332) (xy 378.453378 -293.240024) (xy 378.49784 -293.261122)
			(xy 378.538343 -293.289078) (xy 378.573836 -293.32317) (xy 378.603401 -293.362514) (xy 378.626272 -293.406091)
			(xy 378.641856 -293.452772) (xy 378.649751 -293.501349) (xy 378.650246 -293.525956) (xy 378.978934 -293.525956)
			(xy 378.982894 -293.476902) (xy 378.994671 -293.429118) (xy 379.013962 -293.383842) (xy 379.040265 -293.342246)
			(xy 379.0729 -293.305409) (xy 379.111021 -293.274284) (xy 379.153642 -293.249677) (xy 379.199658 -293.232225)
			(xy 379.247877 -293.222381) (xy 379.297052 -293.2204) (xy 379.345907 -293.226332) (xy 379.393178 -293.240024)
			(xy 379.43764 -293.261122) (xy 379.478143 -293.289078) (xy 379.513636 -293.32317) (xy 379.543201 -293.362514)
			(xy 379.566072 -293.406091) (xy 379.581656 -293.452772) (xy 379.589551 -293.501349) (xy 379.590046 -293.525956)
			(xy 379.918988 -293.525956) (xy 379.922948 -293.476902) (xy 379.934725 -293.429118) (xy 379.954016 -293.383842)
			(xy 379.980319 -293.342246) (xy 380.012954 -293.305409) (xy 380.051075 -293.274284) (xy 380.093696 -293.249677)
			(xy 380.139712 -293.232225) (xy 380.187931 -293.222381) (xy 380.237106 -293.2204) (xy 380.285961 -293.226332)
			(xy 380.333232 -293.240024) (xy 380.377694 -293.261122) (xy 380.418197 -293.289078) (xy 380.45369 -293.32317)
			(xy 380.483255 -293.362514) (xy 380.506126 -293.406091) (xy 380.52171 -293.452772) (xy 380.529605 -293.501349)
			(xy 380.5301 -293.525956) (xy 380.848611 -293.525956) (xy 380.852706 -293.475228) (xy 380.864885 -293.425814)
			(xy 380.884833 -293.378994) (xy 380.912034 -293.33598) (xy 380.945782 -293.297886) (xy 380.985204 -293.265699)
			(xy 381.029278 -293.240253) (xy 381.076864 -293.222206) (xy 381.126728 -293.212026) (xy 381.17758 -293.209977)
			(xy 381.228101 -293.216111) (xy 381.276985 -293.230271) (xy 381.322964 -293.252088) (xy 381.364848 -293.280998)
			(xy 381.401552 -293.316253) (xy 381.432125 -293.356939) (xy 381.455776 -293.402002) (xy 381.471892 -293.450276)
			(xy 381.480056 -293.50051) (xy 381.480568 -293.525956) (xy 381.799096 -293.525956) (xy 381.803056 -293.476902)
			(xy 381.814833 -293.429118) (xy 381.834124 -293.383842) (xy 381.860427 -293.342246) (xy 381.893062 -293.305409)
			(xy 381.931183 -293.274284) (xy 381.973804 -293.249677) (xy 382.01982 -293.232225) (xy 382.068039 -293.222381)
			(xy 382.117214 -293.2204) (xy 382.166069 -293.226332) (xy 382.21334 -293.240024) (xy 382.257802 -293.261122)
			(xy 382.298305 -293.289078) (xy 382.333798 -293.32317) (xy 382.363363 -293.362514) (xy 382.386234 -293.406091)
			(xy 382.401818 -293.452772) (xy 382.409713 -293.501349) (xy 382.410208 -293.525956) (xy 382.738896 -293.525956)
			(xy 382.742856 -293.476902) (xy 382.754633 -293.429118) (xy 382.773924 -293.383842) (xy 382.800227 -293.342246)
			(xy 382.832862 -293.305409) (xy 382.870983 -293.274284) (xy 382.913604 -293.249677) (xy 382.95962 -293.232225)
			(xy 383.007839 -293.222381) (xy 383.057014 -293.2204) (xy 383.105869 -293.226332) (xy 383.15314 -293.240024)
			(xy 383.197602 -293.261122) (xy 383.238105 -293.289078) (xy 383.273598 -293.32317) (xy 383.303163 -293.362514)
			(xy 383.326034 -293.406091) (xy 383.341618 -293.452772) (xy 383.349513 -293.501349) (xy 383.350008 -293.525956)
			(xy 383.67895 -293.525956) (xy 383.68291 -293.476902) (xy 383.694687 -293.429118) (xy 383.713978 -293.383842)
			(xy 383.740281 -293.342246) (xy 383.772916 -293.305409) (xy 383.811037 -293.274284) (xy 383.853658 -293.249677)
			(xy 383.899674 -293.232225) (xy 383.947893 -293.222381) (xy 383.997068 -293.2204) (xy 384.045923 -293.226332)
			(xy 384.093194 -293.240024) (xy 384.137656 -293.261122) (xy 384.178159 -293.289078) (xy 384.213652 -293.32317)
			(xy 384.243217 -293.362514) (xy 384.266088 -293.406091) (xy 384.281672 -293.452772) (xy 384.289567 -293.501349)
			(xy 384.290062 -293.525956) (xy 384.619004 -293.525956) (xy 384.622964 -293.476902) (xy 384.634741 -293.429118)
			(xy 384.654032 -293.383842) (xy 384.680335 -293.342246) (xy 384.71297 -293.305409) (xy 384.751091 -293.274284)
			(xy 384.793712 -293.249677) (xy 384.839728 -293.232225) (xy 384.887947 -293.222381) (xy 384.937122 -293.2204)
			(xy 384.985977 -293.226332) (xy 385.033248 -293.240024) (xy 385.07771 -293.261122) (xy 385.118213 -293.289078)
			(xy 385.153706 -293.32317) (xy 385.183271 -293.362514) (xy 385.206142 -293.406091) (xy 385.221726 -293.452772)
			(xy 385.229621 -293.501349) (xy 385.230116 -293.525956) (xy 385.559058 -293.525956) (xy 385.563018 -293.476902)
			(xy 385.574795 -293.429118) (xy 385.594086 -293.383842) (xy 385.620389 -293.342246) (xy 385.653024 -293.305409)
			(xy 385.691145 -293.274284) (xy 385.733766 -293.249677) (xy 385.779782 -293.232225) (xy 385.828001 -293.222381)
			(xy 385.877176 -293.2204) (xy 385.926031 -293.226332) (xy 385.973302 -293.240024) (xy 386.017764 -293.261122)
			(xy 386.058267 -293.289078) (xy 386.09376 -293.32317) (xy 386.123325 -293.362514) (xy 386.146196 -293.406091)
			(xy 386.16178 -293.452772) (xy 386.169675 -293.501349) (xy 386.17017 -293.525956) (xy 386.499112 -293.525956)
			(xy 386.503072 -293.476902) (xy 386.514849 -293.429118) (xy 386.53414 -293.383842) (xy 386.560443 -293.342246)
			(xy 386.593078 -293.305409) (xy 386.631199 -293.274284) (xy 386.67382 -293.249677) (xy 386.719836 -293.232225)
			(xy 386.768055 -293.222381) (xy 386.81723 -293.2204) (xy 386.866085 -293.226332) (xy 386.913356 -293.240024)
			(xy 386.957818 -293.261122) (xy 386.998321 -293.289078) (xy 387.033814 -293.32317) (xy 387.063379 -293.362514)
			(xy 387.08625 -293.406091) (xy 387.101834 -293.452772) (xy 387.109729 -293.501349) (xy 387.110224 -293.525956)
			(xy 387.438912 -293.525956) (xy 387.442872 -293.476902) (xy 387.454649 -293.429118) (xy 387.47394 -293.383842)
			(xy 387.500243 -293.342246) (xy 387.532878 -293.305409) (xy 387.570999 -293.274284) (xy 387.61362 -293.249677)
			(xy 387.659636 -293.232225) (xy 387.707855 -293.222381) (xy 387.75703 -293.2204) (xy 387.805885 -293.226332)
			(xy 387.853156 -293.240024) (xy 387.897618 -293.261122) (xy 387.938121 -293.289078) (xy 387.973614 -293.32317)
			(xy 388.003179 -293.362514) (xy 388.02605 -293.406091) (xy 388.041634 -293.452772) (xy 388.049529 -293.501349)
			(xy 388.050024 -293.525956) (xy 388.049529 -293.550563) (xy 388.041634 -293.59914) (xy 388.02605 -293.645821)
			(xy 388.003179 -293.689398) (xy 387.973614 -293.728742) (xy 387.938121 -293.762834) (xy 387.897618 -293.79079)
			(xy 387.853156 -293.811888) (xy 387.805885 -293.82558) (xy 387.75703 -293.831512) (xy 387.707855 -293.829531)
			(xy 387.659636 -293.819687) (xy 387.61362 -293.802235) (xy 387.570999 -293.777628) (xy 387.532878 -293.746503)
			(xy 387.500243 -293.709666) (xy 387.47394 -293.66807) (xy 387.454649 -293.622794) (xy 387.442872 -293.57501)
			(xy 387.438912 -293.525956) (xy 387.110224 -293.525956) (xy 387.109729 -293.550563) (xy 387.101834 -293.59914)
			(xy 387.08625 -293.645821) (xy 387.063379 -293.689398) (xy 387.033814 -293.728742) (xy 386.998321 -293.762834)
			(xy 386.957818 -293.79079) (xy 386.913356 -293.811888) (xy 386.866085 -293.82558) (xy 386.81723 -293.831512)
			(xy 386.768055 -293.829531) (xy 386.719836 -293.819687) (xy 386.67382 -293.802235) (xy 386.631199 -293.777628)
			(xy 386.593078 -293.746503) (xy 386.560443 -293.709666) (xy 386.53414 -293.66807) (xy 386.514849 -293.622794)
			(xy 386.503072 -293.57501) (xy 386.499112 -293.525956) (xy 386.17017 -293.525956) (xy 386.169675 -293.550563)
			(xy 386.16178 -293.59914) (xy 386.146196 -293.645821) (xy 386.123325 -293.689398) (xy 386.09376 -293.728742)
			(xy 386.058267 -293.762834) (xy 386.017764 -293.79079) (xy 385.973302 -293.811888) (xy 385.926031 -293.82558)
			(xy 385.877176 -293.831512) (xy 385.828001 -293.829531) (xy 385.779782 -293.819687) (xy 385.733766 -293.802235)
			(xy 385.691145 -293.777628) (xy 385.653024 -293.746503) (xy 385.620389 -293.709666) (xy 385.594086 -293.66807)
			(xy 385.574795 -293.622794) (xy 385.563018 -293.57501) (xy 385.559058 -293.525956) (xy 385.230116 -293.525956)
			(xy 385.229621 -293.550563) (xy 385.221726 -293.59914) (xy 385.206142 -293.645821) (xy 385.183271 -293.689398)
			(xy 385.153706 -293.728742) (xy 385.118213 -293.762834) (xy 385.07771 -293.79079) (xy 385.033248 -293.811888)
			(xy 384.985977 -293.82558) (xy 384.937122 -293.831512) (xy 384.887947 -293.829531) (xy 384.839728 -293.819687)
			(xy 384.793712 -293.802235) (xy 384.751091 -293.777628) (xy 384.71297 -293.746503) (xy 384.680335 -293.709666)
			(xy 384.654032 -293.66807) (xy 384.634741 -293.622794) (xy 384.622964 -293.57501) (xy 384.619004 -293.525956)
			(xy 384.290062 -293.525956) (xy 384.289567 -293.550563) (xy 384.281672 -293.59914) (xy 384.266088 -293.645821)
			(xy 384.243217 -293.689398) (xy 384.213652 -293.728742) (xy 384.178159 -293.762834) (xy 384.137656 -293.79079)
			(xy 384.093194 -293.811888) (xy 384.045923 -293.82558) (xy 383.997068 -293.831512) (xy 383.947893 -293.829531)
			(xy 383.899674 -293.819687) (xy 383.853658 -293.802235) (xy 383.811037 -293.777628) (xy 383.772916 -293.746503)
			(xy 383.740281 -293.709666) (xy 383.713978 -293.66807) (xy 383.694687 -293.622794) (xy 383.68291 -293.57501)
			(xy 383.67895 -293.525956) (xy 383.350008 -293.525956) (xy 383.349513 -293.550563) (xy 383.341618 -293.59914)
			(xy 383.326034 -293.645821) (xy 383.303163 -293.689398) (xy 383.273598 -293.728742) (xy 383.238105 -293.762834)
			(xy 383.197602 -293.79079) (xy 383.15314 -293.811888) (xy 383.105869 -293.82558) (xy 383.057014 -293.831512)
			(xy 383.007839 -293.829531) (xy 382.95962 -293.819687) (xy 382.913604 -293.802235) (xy 382.870983 -293.777628)
			(xy 382.832862 -293.746503) (xy 382.800227 -293.709666) (xy 382.773924 -293.66807) (xy 382.754633 -293.622794)
			(xy 382.742856 -293.57501) (xy 382.738896 -293.525956) (xy 382.410208 -293.525956) (xy 382.409713 -293.550563)
			(xy 382.401818 -293.59914) (xy 382.386234 -293.645821) (xy 382.363363 -293.689398) (xy 382.333798 -293.728742)
			(xy 382.298305 -293.762834) (xy 382.257802 -293.79079) (xy 382.21334 -293.811888) (xy 382.166069 -293.82558)
			(xy 382.117214 -293.831512) (xy 382.068039 -293.829531) (xy 382.01982 -293.819687) (xy 381.973804 -293.802235)
			(xy 381.931183 -293.777628) (xy 381.893062 -293.746503) (xy 381.860427 -293.709666) (xy 381.834124 -293.66807)
			(xy 381.814833 -293.622794) (xy 381.803056 -293.57501) (xy 381.799096 -293.525956) (xy 381.480568 -293.525956)
			(xy 381.480056 -293.551402) (xy 381.471892 -293.601636) (xy 381.455776 -293.64991) (xy 381.432125 -293.694973)
			(xy 381.401552 -293.735659) (xy 381.364848 -293.770914) (xy 381.322964 -293.799824) (xy 381.276985 -293.821641)
			(xy 381.228101 -293.835801) (xy 381.17758 -293.841935) (xy 381.126728 -293.839886) (xy 381.076864 -293.829706)
			(xy 381.029278 -293.811659) (xy 380.985204 -293.786213) (xy 380.945782 -293.754026) (xy 380.912034 -293.715932)
			(xy 380.884833 -293.672918) (xy 380.864885 -293.626098) (xy 380.852706 -293.576684) (xy 380.848611 -293.525956)
			(xy 380.5301 -293.525956) (xy 380.529605 -293.550563) (xy 380.52171 -293.59914) (xy 380.506126 -293.645821)
			(xy 380.483255 -293.689398) (xy 380.45369 -293.728742) (xy 380.418197 -293.762834) (xy 380.377694 -293.79079)
			(xy 380.333232 -293.811888) (xy 380.285961 -293.82558) (xy 380.237106 -293.831512) (xy 380.187931 -293.829531)
			(xy 380.139712 -293.819687) (xy 380.093696 -293.802235) (xy 380.051075 -293.777628) (xy 380.012954 -293.746503)
			(xy 379.980319 -293.709666) (xy 379.954016 -293.66807) (xy 379.934725 -293.622794) (xy 379.922948 -293.57501)
			(xy 379.918988 -293.525956) (xy 379.590046 -293.525956) (xy 379.589551 -293.550563) (xy 379.581656 -293.59914)
			(xy 379.566072 -293.645821) (xy 379.543201 -293.689398) (xy 379.513636 -293.728742) (xy 379.478143 -293.762834)
			(xy 379.43764 -293.79079) (xy 379.393178 -293.811888) (xy 379.345907 -293.82558) (xy 379.297052 -293.831512)
			(xy 379.247877 -293.829531) (xy 379.199658 -293.819687) (xy 379.153642 -293.802235) (xy 379.111021 -293.777628)
			(xy 379.0729 -293.746503) (xy 379.040265 -293.709666) (xy 379.013962 -293.66807) (xy 378.994671 -293.622794)
			(xy 378.982894 -293.57501) (xy 378.978934 -293.525956) (xy 378.650246 -293.525956) (xy 378.649751 -293.550563)
			(xy 378.641856 -293.59914) (xy 378.626272 -293.645821) (xy 378.603401 -293.689398) (xy 378.573836 -293.728742)
			(xy 378.538343 -293.762834) (xy 378.49784 -293.79079) (xy 378.453378 -293.811888) (xy 378.406107 -293.82558)
			(xy 378.357252 -293.831512) (xy 378.308077 -293.829531) (xy 378.259858 -293.819687) (xy 378.213842 -293.802235)
			(xy 378.171221 -293.777628) (xy 378.1331 -293.746503) (xy 378.100465 -293.709666) (xy 378.074162 -293.66807)
			(xy 378.054871 -293.622794) (xy 378.043094 -293.57501) (xy 378.039134 -293.525956) (xy 377.710192 -293.525956)
			(xy 377.709697 -293.550563) (xy 377.701802 -293.59914) (xy 377.686218 -293.645821) (xy 377.663347 -293.689398)
			(xy 377.633782 -293.728742) (xy 377.598289 -293.762834) (xy 377.557786 -293.79079) (xy 377.513324 -293.811888)
			(xy 377.466053 -293.82558) (xy 377.417198 -293.831512) (xy 377.368023 -293.829531) (xy 377.319804 -293.819687)
			(xy 377.273788 -293.802235) (xy 377.231167 -293.777628) (xy 377.193046 -293.746503) (xy 377.160411 -293.709666)
			(xy 377.134108 -293.66807) (xy 377.114817 -293.622794) (xy 377.10304 -293.57501) (xy 377.09908 -293.525956)
			(xy 376.780552 -293.525956) (xy 376.78004 -293.551402) (xy 376.771876 -293.601636) (xy 376.75576 -293.64991)
			(xy 376.732109 -293.694973) (xy 376.701536 -293.735659) (xy 376.664832 -293.770914) (xy 376.622948 -293.799824)
			(xy 376.576969 -293.821641) (xy 376.528085 -293.835801) (xy 376.477564 -293.841935) (xy 376.426712 -293.839886)
			(xy 376.376848 -293.829706) (xy 376.329262 -293.811659) (xy 376.285188 -293.786213) (xy 376.245766 -293.754026)
			(xy 376.212018 -293.715932) (xy 376.184817 -293.672918) (xy 376.164869 -293.626098) (xy 376.15269 -293.576684)
			(xy 376.148595 -293.525956) (xy 375.829638 -293.525956) (xy 375.82964 -293.550503) (xy 375.8218 -293.598928)
			(xy 375.806319 -293.645478) (xy 375.783594 -293.688952) (xy 375.75421 -293.728234) (xy 375.718923 -293.762313)
			(xy 375.69902 -293.776654) (xy 375.692541 -293.782077) (xy 375.683313 -293.796219) (xy 375.680986 -293.80434)
			(xy 375.669372 -293.848195) (xy 375.640044 -293.934054) (xy 375.603933 -294.017288) (xy 375.561271 -294.097361)
			(xy 375.512331 -294.17376) (xy 375.457429 -294.245993) (xy 375.427494 -294.280082) (xy 375.424541 -294.283556)
			(xy 375.419817 -294.291353) (xy 375.418096 -294.295576) (xy 375.411746 -294.312086) (xy 375.410106 -294.31648)
			(xy 375.408322 -294.325686) (xy 375.40819 -294.330374) (xy 375.40819 -294.335962) (xy 375.689126 -294.335962)
			(xy 375.693086 -294.286908) (xy 375.704863 -294.239124) (xy 375.724154 -294.193848) (xy 375.750457 -294.152252)
			(xy 375.783092 -294.115415) (xy 375.821213 -294.08429) (xy 375.863834 -294.059683) (xy 375.90985 -294.042231)
			(xy 375.958069 -294.032387) (xy 376.007244 -294.030406) (xy 376.056099 -294.036338) (xy 376.10337 -294.05003)
			(xy 376.147832 -294.071128) (xy 376.188335 -294.099084) (xy 376.223828 -294.133176) (xy 376.253393 -294.17252)
			(xy 376.276264 -294.216097) (xy 376.291848 -294.262778) (xy 376.299743 -294.311355) (xy 376.300238 -294.335962)
			(xy 376.628926 -294.335962) (xy 376.632886 -294.286908) (xy 376.644663 -294.239124) (xy 376.663954 -294.193848)
			(xy 376.690257 -294.152252) (xy 376.722892 -294.115415) (xy 376.761013 -294.08429) (xy 376.803634 -294.059683)
			(xy 376.84965 -294.042231) (xy 376.897869 -294.032387) (xy 376.947044 -294.030406) (xy 376.995899 -294.036338)
			(xy 377.04317 -294.05003) (xy 377.087632 -294.071128) (xy 377.128135 -294.099084) (xy 377.163628 -294.133176)
			(xy 377.193193 -294.17252) (xy 377.216064 -294.216097) (xy 377.231648 -294.262778) (xy 377.239543 -294.311355)
			(xy 377.240038 -294.335962) (xy 377.56898 -294.335962) (xy 377.57294 -294.286908) (xy 377.584717 -294.239124)
			(xy 377.604008 -294.193848) (xy 377.630311 -294.152252) (xy 377.662946 -294.115415) (xy 377.701067 -294.08429)
			(xy 377.743688 -294.059683) (xy 377.789704 -294.042231) (xy 377.837923 -294.032387) (xy 377.887098 -294.030406)
			(xy 377.935953 -294.036338) (xy 377.983224 -294.05003) (xy 378.027686 -294.071128) (xy 378.068189 -294.099084)
			(xy 378.103682 -294.133176) (xy 378.133247 -294.17252) (xy 378.156118 -294.216097) (xy 378.171702 -294.262778)
			(xy 378.179597 -294.311355) (xy 378.180092 -294.335962) (xy 378.509034 -294.335962) (xy 378.512994 -294.286908)
			(xy 378.524771 -294.239124) (xy 378.544062 -294.193848) (xy 378.570365 -294.152252) (xy 378.603 -294.115415)
			(xy 378.641121 -294.08429) (xy 378.683742 -294.059683) (xy 378.729758 -294.042231) (xy 378.777977 -294.032387)
			(xy 378.827152 -294.030406) (xy 378.876007 -294.036338) (xy 378.923278 -294.05003) (xy 378.96774 -294.071128)
			(xy 379.008243 -294.099084) (xy 379.043736 -294.133176) (xy 379.073301 -294.17252) (xy 379.096172 -294.216097)
			(xy 379.111756 -294.262778) (xy 379.119651 -294.311355) (xy 379.120146 -294.335962) (xy 380.389142 -294.335962)
			(xy 380.393102 -294.286908) (xy 380.404879 -294.239124) (xy 380.42417 -294.193848) (xy 380.450473 -294.152252)
			(xy 380.483108 -294.115415) (xy 380.521229 -294.08429) (xy 380.56385 -294.059683) (xy 380.609866 -294.042231)
			(xy 380.658085 -294.032387) (xy 380.70726 -294.030406) (xy 380.756115 -294.036338) (xy 380.803386 -294.05003)
			(xy 380.847848 -294.071128) (xy 380.888351 -294.099084) (xy 380.923844 -294.133176) (xy 380.953409 -294.17252)
			(xy 380.97628 -294.216097) (xy 380.991864 -294.262778) (xy 380.999759 -294.311355) (xy 381.000254 -294.335962)
			(xy 381.328942 -294.335962) (xy 381.332902 -294.286908) (xy 381.344679 -294.239124) (xy 381.36397 -294.193848)
			(xy 381.390273 -294.152252) (xy 381.422908 -294.115415) (xy 381.461029 -294.08429) (xy 381.50365 -294.059683)
			(xy 381.549666 -294.042231) (xy 381.597885 -294.032387) (xy 381.64706 -294.030406) (xy 381.695915 -294.036338)
			(xy 381.743186 -294.05003) (xy 381.787648 -294.071128) (xy 381.828151 -294.099084) (xy 381.863644 -294.133176)
			(xy 381.893209 -294.17252) (xy 381.91608 -294.216097) (xy 381.931664 -294.262778) (xy 381.939559 -294.311355)
			(xy 381.940054 -294.335962) (xy 382.268996 -294.335962) (xy 382.272956 -294.286908) (xy 382.284733 -294.239124)
			(xy 382.304024 -294.193848) (xy 382.330327 -294.152252) (xy 382.362962 -294.115415) (xy 382.401083 -294.08429)
			(xy 382.443704 -294.059683) (xy 382.48972 -294.042231) (xy 382.537939 -294.032387) (xy 382.587114 -294.030406)
			(xy 382.635969 -294.036338) (xy 382.68324 -294.05003) (xy 382.727702 -294.071128) (xy 382.768205 -294.099084)
			(xy 382.803698 -294.133176) (xy 382.833263 -294.17252) (xy 382.856134 -294.216097) (xy 382.871718 -294.262778)
			(xy 382.879613 -294.311355) (xy 382.880108 -294.335962) (xy 383.20905 -294.335962) (xy 383.21301 -294.286908)
			(xy 383.224787 -294.239124) (xy 383.244078 -294.193848) (xy 383.270381 -294.152252) (xy 383.303016 -294.115415)
			(xy 383.341137 -294.08429) (xy 383.383758 -294.059683) (xy 383.429774 -294.042231) (xy 383.477993 -294.032387)
			(xy 383.527168 -294.030406) (xy 383.576023 -294.036338) (xy 383.623294 -294.05003) (xy 383.667756 -294.071128)
			(xy 383.708259 -294.099084) (xy 383.743752 -294.133176) (xy 383.773317 -294.17252) (xy 383.796188 -294.216097)
			(xy 383.811772 -294.262778) (xy 383.819667 -294.311355) (xy 383.820162 -294.335962) (xy 384.149104 -294.335962)
			(xy 384.153064 -294.286908) (xy 384.164841 -294.239124) (xy 384.184132 -294.193848) (xy 384.210435 -294.152252)
			(xy 384.24307 -294.115415) (xy 384.281191 -294.08429) (xy 384.323812 -294.059683) (xy 384.369828 -294.042231)
			(xy 384.418047 -294.032387) (xy 384.467222 -294.030406) (xy 384.516077 -294.036338) (xy 384.563348 -294.05003)
			(xy 384.60781 -294.071128) (xy 384.648313 -294.099084) (xy 384.683806 -294.133176) (xy 384.713371 -294.17252)
			(xy 384.736242 -294.216097) (xy 384.751826 -294.262778) (xy 384.759721 -294.311355) (xy 384.760216 -294.335962)
			(xy 386.028958 -294.335962) (xy 386.032918 -294.286908) (xy 386.044695 -294.239124) (xy 386.063986 -294.193848)
			(xy 386.090289 -294.152252) (xy 386.122924 -294.115415) (xy 386.161045 -294.08429) (xy 386.203666 -294.059683)
			(xy 386.249682 -294.042231) (xy 386.297901 -294.032387) (xy 386.347076 -294.030406) (xy 386.395931 -294.036338)
			(xy 386.443202 -294.05003) (xy 386.487664 -294.071128) (xy 386.528167 -294.099084) (xy 386.56366 -294.133176)
			(xy 386.593225 -294.17252) (xy 386.616096 -294.216097) (xy 386.63168 -294.262778) (xy 386.639575 -294.311355)
			(xy 386.64007 -294.335962) (xy 386.969012 -294.335962) (xy 386.972972 -294.286908) (xy 386.984749 -294.239124)
			(xy 387.00404 -294.193848) (xy 387.030343 -294.152252) (xy 387.062978 -294.115415) (xy 387.101099 -294.08429)
			(xy 387.14372 -294.059683) (xy 387.189736 -294.042231) (xy 387.237955 -294.032387) (xy 387.28713 -294.030406)
			(xy 387.335985 -294.036338) (xy 387.383256 -294.05003) (xy 387.427718 -294.071128) (xy 387.468221 -294.099084)
			(xy 387.503714 -294.133176) (xy 387.533279 -294.17252) (xy 387.55615 -294.216097) (xy 387.571734 -294.262778)
			(xy 387.579629 -294.311355) (xy 387.580124 -294.335962) (xy 387.909066 -294.335962) (xy 387.913026 -294.286908)
			(xy 387.924803 -294.239124) (xy 387.944094 -294.193848) (xy 387.970397 -294.152252) (xy 388.003032 -294.115415)
			(xy 388.041153 -294.08429) (xy 388.083774 -294.059683) (xy 388.12979 -294.042231) (xy 388.178009 -294.032387)
			(xy 388.227184 -294.030406) (xy 388.276039 -294.036338) (xy 388.32331 -294.05003) (xy 388.367772 -294.071128)
			(xy 388.408275 -294.099084) (xy 388.443768 -294.133176) (xy 388.473333 -294.17252) (xy 388.496204 -294.216097)
			(xy 388.511788 -294.262778) (xy 388.519683 -294.311355) (xy 388.520178 -294.335962) (xy 388.519683 -294.360569)
			(xy 388.511788 -294.409146) (xy 388.496204 -294.455827) (xy 388.473333 -294.499404) (xy 388.443768 -294.538748)
			(xy 388.408275 -294.57284) (xy 388.367772 -294.600796) (xy 388.32331 -294.621894) (xy 388.276039 -294.635586)
			(xy 388.227184 -294.641518) (xy 388.178009 -294.639537) (xy 388.12979 -294.629693) (xy 388.083774 -294.612241)
			(xy 388.041153 -294.587634) (xy 388.003032 -294.556509) (xy 387.970397 -294.519672) (xy 387.944094 -294.478076)
			(xy 387.924803 -294.4328) (xy 387.913026 -294.385016) (xy 387.909066 -294.335962) (xy 387.580124 -294.335962)
			(xy 387.579629 -294.360569) (xy 387.571734 -294.409146) (xy 387.55615 -294.455827) (xy 387.533279 -294.499404)
			(xy 387.503714 -294.538748) (xy 387.468221 -294.57284) (xy 387.427718 -294.600796) (xy 387.383256 -294.621894)
			(xy 387.335985 -294.635586) (xy 387.28713 -294.641518) (xy 387.237955 -294.639537) (xy 387.189736 -294.629693)
			(xy 387.14372 -294.612241) (xy 387.101099 -294.587634) (xy 387.062978 -294.556509) (xy 387.030343 -294.519672)
			(xy 387.00404 -294.478076) (xy 386.984749 -294.4328) (xy 386.972972 -294.385016) (xy 386.969012 -294.335962)
			(xy 386.64007 -294.335962) (xy 386.639575 -294.360569) (xy 386.63168 -294.409146) (xy 386.616096 -294.455827)
			(xy 386.593225 -294.499404) (xy 386.56366 -294.538748) (xy 386.528167 -294.57284) (xy 386.487664 -294.600796)
			(xy 386.443202 -294.621894) (xy 386.395931 -294.635586) (xy 386.347076 -294.641518) (xy 386.297901 -294.639537)
			(xy 386.249682 -294.629693) (xy 386.203666 -294.612241) (xy 386.161045 -294.587634) (xy 386.122924 -294.556509)
			(xy 386.090289 -294.519672) (xy 386.063986 -294.478076) (xy 386.044695 -294.4328) (xy 386.032918 -294.385016)
			(xy 386.028958 -294.335962) (xy 384.760216 -294.335962) (xy 384.759721 -294.360569) (xy 384.751826 -294.409146)
			(xy 384.736242 -294.455827) (xy 384.713371 -294.499404) (xy 384.683806 -294.538748) (xy 384.648313 -294.57284)
			(xy 384.60781 -294.600796) (xy 384.563348 -294.621894) (xy 384.516077 -294.635586) (xy 384.467222 -294.641518)
			(xy 384.418047 -294.639537) (xy 384.369828 -294.629693) (xy 384.323812 -294.612241) (xy 384.281191 -294.587634)
			(xy 384.24307 -294.556509) (xy 384.210435 -294.519672) (xy 384.184132 -294.478076) (xy 384.164841 -294.4328)
			(xy 384.153064 -294.385016) (xy 384.149104 -294.335962) (xy 383.820162 -294.335962) (xy 383.819667 -294.360569)
			(xy 383.811772 -294.409146) (xy 383.796188 -294.455827) (xy 383.773317 -294.499404) (xy 383.743752 -294.538748)
			(xy 383.708259 -294.57284) (xy 383.667756 -294.600796) (xy 383.623294 -294.621894) (xy 383.576023 -294.635586)
			(xy 383.527168 -294.641518) (xy 383.477993 -294.639537) (xy 383.429774 -294.629693) (xy 383.383758 -294.612241)
			(xy 383.341137 -294.587634) (xy 383.303016 -294.556509) (xy 383.270381 -294.519672) (xy 383.244078 -294.478076)
			(xy 383.224787 -294.4328) (xy 383.21301 -294.385016) (xy 383.20905 -294.335962) (xy 382.880108 -294.335962)
			(xy 382.879613 -294.360569) (xy 382.871718 -294.409146) (xy 382.856134 -294.455827) (xy 382.833263 -294.499404)
			(xy 382.803698 -294.538748) (xy 382.768205 -294.57284) (xy 382.727702 -294.600796) (xy 382.68324 -294.621894)
			(xy 382.635969 -294.635586) (xy 382.587114 -294.641518) (xy 382.537939 -294.639537) (xy 382.48972 -294.629693)
			(xy 382.443704 -294.612241) (xy 382.401083 -294.587634) (xy 382.362962 -294.556509) (xy 382.330327 -294.519672)
			(xy 382.304024 -294.478076) (xy 382.284733 -294.4328) (xy 382.272956 -294.385016) (xy 382.268996 -294.335962)
			(xy 381.940054 -294.335962) (xy 381.939559 -294.360569) (xy 381.931664 -294.409146) (xy 381.91608 -294.455827)
			(xy 381.893209 -294.499404) (xy 381.863644 -294.538748) (xy 381.828151 -294.57284) (xy 381.787648 -294.600796)
			(xy 381.743186 -294.621894) (xy 381.695915 -294.635586) (xy 381.64706 -294.641518) (xy 381.597885 -294.639537)
			(xy 381.549666 -294.629693) (xy 381.50365 -294.612241) (xy 381.461029 -294.587634) (xy 381.422908 -294.556509)
			(xy 381.390273 -294.519672) (xy 381.36397 -294.478076) (xy 381.344679 -294.4328) (xy 381.332902 -294.385016)
			(xy 381.328942 -294.335962) (xy 381.000254 -294.335962) (xy 380.999759 -294.360569) (xy 380.991864 -294.409146)
			(xy 380.97628 -294.455827) (xy 380.953409 -294.499404) (xy 380.923844 -294.538748) (xy 380.888351 -294.57284)
			(xy 380.847848 -294.600796) (xy 380.803386 -294.621894) (xy 380.756115 -294.635586) (xy 380.70726 -294.641518)
			(xy 380.658085 -294.639537) (xy 380.609866 -294.629693) (xy 380.56385 -294.612241) (xy 380.521229 -294.587634)
			(xy 380.483108 -294.556509) (xy 380.450473 -294.519672) (xy 380.42417 -294.478076) (xy 380.404879 -294.4328)
			(xy 380.393102 -294.385016) (xy 380.389142 -294.335962) (xy 379.120146 -294.335962) (xy 379.119651 -294.360569)
			(xy 379.111756 -294.409146) (xy 379.096172 -294.455827) (xy 379.073301 -294.499404) (xy 379.043736 -294.538748)
			(xy 379.008243 -294.57284) (xy 378.96774 -294.600796) (xy 378.923278 -294.621894) (xy 378.876007 -294.635586)
			(xy 378.827152 -294.641518) (xy 378.777977 -294.639537) (xy 378.729758 -294.629693) (xy 378.683742 -294.612241)
			(xy 378.641121 -294.587634) (xy 378.603 -294.556509) (xy 378.570365 -294.519672) (xy 378.544062 -294.478076)
			(xy 378.524771 -294.4328) (xy 378.512994 -294.385016) (xy 378.509034 -294.335962) (xy 378.180092 -294.335962)
			(xy 378.179597 -294.360569) (xy 378.171702 -294.409146) (xy 378.156118 -294.455827) (xy 378.133247 -294.499404)
			(xy 378.103682 -294.538748) (xy 378.068189 -294.57284) (xy 378.027686 -294.600796) (xy 377.983224 -294.621894)
			(xy 377.935953 -294.635586) (xy 377.887098 -294.641518) (xy 377.837923 -294.639537) (xy 377.789704 -294.629693)
			(xy 377.743688 -294.612241) (xy 377.701067 -294.587634) (xy 377.662946 -294.556509) (xy 377.630311 -294.519672)
			(xy 377.604008 -294.478076) (xy 377.584717 -294.4328) (xy 377.57294 -294.385016) (xy 377.56898 -294.335962)
			(xy 377.240038 -294.335962) (xy 377.239543 -294.360569) (xy 377.231648 -294.409146) (xy 377.216064 -294.455827)
			(xy 377.193193 -294.499404) (xy 377.163628 -294.538748) (xy 377.128135 -294.57284) (xy 377.087632 -294.600796)
			(xy 377.04317 -294.621894) (xy 376.995899 -294.635586) (xy 376.947044 -294.641518) (xy 376.897869 -294.639537)
			(xy 376.84965 -294.629693) (xy 376.803634 -294.612241) (xy 376.761013 -294.587634) (xy 376.722892 -294.556509)
			(xy 376.690257 -294.519672) (xy 376.663954 -294.478076) (xy 376.644663 -294.4328) (xy 376.632886 -294.385016)
			(xy 376.628926 -294.335962) (xy 376.300238 -294.335962) (xy 376.299743 -294.360569) (xy 376.291848 -294.409146)
			(xy 376.276264 -294.455827) (xy 376.253393 -294.499404) (xy 376.223828 -294.538748) (xy 376.188335 -294.57284)
			(xy 376.147832 -294.600796) (xy 376.10337 -294.621894) (xy 376.056099 -294.635586) (xy 376.007244 -294.641518)
			(xy 375.958069 -294.639537) (xy 375.90985 -294.629693) (xy 375.863834 -294.612241) (xy 375.821213 -294.587634)
			(xy 375.783092 -294.556509) (xy 375.750457 -294.519672) (xy 375.724154 -294.478076) (xy 375.704863 -294.4328)
			(xy 375.693086 -294.385016) (xy 375.689126 -294.335962) (xy 375.40819 -294.335962) (xy 375.40819 -294.34155)
			(xy 375.408348 -294.346235) (xy 375.410138 -294.355435) (xy 375.411746 -294.359838) (xy 375.418096 -294.376348)
			(xy 375.419827 -294.380565) (xy 375.42455 -294.388362) (xy 375.427494 -294.391842) (xy 375.457421 -294.425939)
			(xy 375.512334 -294.498164) (xy 375.56128 -294.574559) (xy 375.603946 -294.654631) (xy 375.640056 -294.737866)
			(xy 375.669377 -294.823727) (xy 375.680986 -294.867584) (xy 375.683443 -294.875898) (xy 375.693054 -294.890312)
			(xy 375.699782 -294.895778) (xy 375.721228 -294.911472) (xy 375.758848 -294.949001) (xy 375.789403 -294.992475)
			(xy 375.81197 -295.040583) (xy 375.825868 -295.091871) (xy 375.828814 -295.118282) (xy 375.82983 -295.12768)
			(xy 375.833132 -295.134792) (xy 375.835116 -295.138771) (xy 375.840178 -295.145968) (xy 377.09908 -295.145968)
			(xy 377.10304 -295.096914) (xy 377.114817 -295.04913) (xy 377.134108 -295.003854) (xy 377.160411 -294.962258)
			(xy 377.193046 -294.925421) (xy 377.231167 -294.894296) (xy 377.273788 -294.869689) (xy 377.319804 -294.852237)
			(xy 377.368023 -294.842393) (xy 377.417198 -294.840412) (xy 377.466053 -294.846344) (xy 377.513324 -294.860036)
			(xy 377.557786 -294.881134) (xy 377.598289 -294.90909) (xy 377.633782 -294.943182) (xy 377.663347 -294.982526)
			(xy 377.686218 -295.026103) (xy 377.701802 -295.072784) (xy 377.709697 -295.121361) (xy 377.710192 -295.145968)
			(xy 378.039134 -295.145968) (xy 378.043094 -295.096914) (xy 378.054871 -295.04913) (xy 378.074162 -295.003854)
			(xy 378.100465 -294.962258) (xy 378.1331 -294.925421) (xy 378.171221 -294.894296) (xy 378.213842 -294.869689)
			(xy 378.259858 -294.852237) (xy 378.308077 -294.842393) (xy 378.357252 -294.840412) (xy 378.406107 -294.846344)
			(xy 378.453378 -294.860036) (xy 378.49784 -294.881134) (xy 378.538343 -294.90909) (xy 378.573836 -294.943182)
			(xy 378.603401 -294.982526) (xy 378.626272 -295.026103) (xy 378.641856 -295.072784) (xy 378.649751 -295.121361)
			(xy 378.650246 -295.145968) (xy 378.978934 -295.145968) (xy 378.982894 -295.096914) (xy 378.994671 -295.04913)
			(xy 379.013962 -295.003854) (xy 379.040265 -294.962258) (xy 379.0729 -294.925421) (xy 379.111021 -294.894296)
			(xy 379.153642 -294.869689) (xy 379.199658 -294.852237) (xy 379.247877 -294.842393) (xy 379.297052 -294.840412)
			(xy 379.345907 -294.846344) (xy 379.393178 -294.860036) (xy 379.43764 -294.881134) (xy 379.478143 -294.90909)
			(xy 379.513636 -294.943182) (xy 379.543201 -294.982526) (xy 379.566072 -295.026103) (xy 379.581656 -295.072784)
			(xy 379.589551 -295.121361) (xy 379.590046 -295.145968) (xy 380.859042 -295.145968) (xy 380.863002 -295.096914)
			(xy 380.874779 -295.04913) (xy 380.89407 -295.003854) (xy 380.920373 -294.962258) (xy 380.953008 -294.925421)
			(xy 380.991129 -294.894296) (xy 381.03375 -294.869689) (xy 381.079766 -294.852237) (xy 381.127985 -294.842393)
			(xy 381.17716 -294.840412) (xy 381.226015 -294.846344) (xy 381.273286 -294.860036) (xy 381.317748 -294.881134)
			(xy 381.358251 -294.90909) (xy 381.393744 -294.943182) (xy 381.423309 -294.982526) (xy 381.44618 -295.026103)
			(xy 381.461764 -295.072784) (xy 381.469659 -295.121361) (xy 381.470154 -295.145968) (xy 381.799096 -295.145968)
			(xy 381.803056 -295.096914) (xy 381.814833 -295.04913) (xy 381.834124 -295.003854) (xy 381.860427 -294.962258)
			(xy 381.893062 -294.925421) (xy 381.931183 -294.894296) (xy 381.973804 -294.869689) (xy 382.01982 -294.852237)
			(xy 382.068039 -294.842393) (xy 382.117214 -294.840412) (xy 382.166069 -294.846344) (xy 382.21334 -294.860036)
			(xy 382.257802 -294.881134) (xy 382.298305 -294.90909) (xy 382.333798 -294.943182) (xy 382.363363 -294.982526)
			(xy 382.386234 -295.026103) (xy 382.401818 -295.072784) (xy 382.409713 -295.121361) (xy 382.410208 -295.145968)
			(xy 384.619004 -295.145968) (xy 384.622964 -295.096914) (xy 384.634741 -295.04913) (xy 384.654032 -295.003854)
			(xy 384.680335 -294.962258) (xy 384.71297 -294.925421) (xy 384.751091 -294.894296) (xy 384.793712 -294.869689)
			(xy 384.839728 -294.852237) (xy 384.887947 -294.842393) (xy 384.937122 -294.840412) (xy 384.985977 -294.846344)
			(xy 385.033248 -294.860036) (xy 385.07771 -294.881134) (xy 385.118213 -294.90909) (xy 385.153706 -294.943182)
			(xy 385.183271 -294.982526) (xy 385.206142 -295.026103) (xy 385.221726 -295.072784) (xy 385.229621 -295.121361)
			(xy 385.230116 -295.145968) (xy 385.559058 -295.145968) (xy 385.563018 -295.096914) (xy 385.574795 -295.04913)
			(xy 385.594086 -295.003854) (xy 385.620389 -294.962258) (xy 385.653024 -294.925421) (xy 385.691145 -294.894296)
			(xy 385.733766 -294.869689) (xy 385.779782 -294.852237) (xy 385.828001 -294.842393) (xy 385.877176 -294.840412)
			(xy 385.926031 -294.846344) (xy 385.973302 -294.860036) (xy 386.017764 -294.881134) (xy 386.058267 -294.90909)
			(xy 386.09376 -294.943182) (xy 386.123325 -294.982526) (xy 386.146196 -295.026103) (xy 386.16178 -295.072784)
			(xy 386.169675 -295.121361) (xy 386.17017 -295.145968) (xy 388.378966 -295.145968) (xy 388.382926 -295.096914)
			(xy 388.394703 -295.04913) (xy 388.413994 -295.003854) (xy 388.440297 -294.962258) (xy 388.472932 -294.925421)
			(xy 388.511053 -294.894296) (xy 388.553674 -294.869689) (xy 388.59969 -294.852237) (xy 388.647909 -294.842393)
			(xy 388.697084 -294.840412) (xy 388.745939 -294.846344) (xy 388.79321 -294.860036) (xy 388.837672 -294.881134)
			(xy 388.878175 -294.90909) (xy 388.913668 -294.943182) (xy 388.943233 -294.982526) (xy 388.966104 -295.026103)
			(xy 388.981688 -295.072784) (xy 388.989583 -295.121361) (xy 388.990078 -295.145968) (xy 389.31902 -295.145968)
			(xy 389.32298 -295.096914) (xy 389.334757 -295.04913) (xy 389.354048 -295.003854) (xy 389.380351 -294.962258)
			(xy 389.412986 -294.925421) (xy 389.451107 -294.894296) (xy 389.493728 -294.869689) (xy 389.539744 -294.852237)
			(xy 389.587963 -294.842393) (xy 389.637138 -294.840412) (xy 389.685993 -294.846344) (xy 389.733264 -294.860036)
			(xy 389.777726 -294.881134) (xy 389.818229 -294.90909) (xy 389.853722 -294.943182) (xy 389.883287 -294.982526)
			(xy 389.906158 -295.026103) (xy 389.921742 -295.072784) (xy 389.929637 -295.121361) (xy 389.930132 -295.145968)
			(xy 390.259074 -295.145968) (xy 390.263034 -295.096914) (xy 390.274811 -295.04913) (xy 390.294102 -295.003854)
			(xy 390.320405 -294.962258) (xy 390.35304 -294.925421) (xy 390.391161 -294.894296) (xy 390.433782 -294.869689)
			(xy 390.479798 -294.852237) (xy 390.528017 -294.842393) (xy 390.577192 -294.840412) (xy 390.626047 -294.846344)
			(xy 390.673318 -294.860036) (xy 390.71778 -294.881134) (xy 390.758283 -294.90909) (xy 390.793776 -294.943182)
			(xy 390.823341 -294.982526) (xy 390.846212 -295.026103) (xy 390.861796 -295.072784) (xy 390.869691 -295.121361)
			(xy 390.870186 -295.145968) (xy 391.198874 -295.145968) (xy 391.202834 -295.096914) (xy 391.214611 -295.04913)
			(xy 391.233902 -295.003854) (xy 391.260205 -294.962258) (xy 391.29284 -294.925421) (xy 391.330961 -294.894296)
			(xy 391.373582 -294.869689) (xy 391.419598 -294.852237) (xy 391.467817 -294.842393) (xy 391.516992 -294.840412)
			(xy 391.565847 -294.846344) (xy 391.613118 -294.860036) (xy 391.65758 -294.881134) (xy 391.698083 -294.90909)
			(xy 391.733576 -294.943182) (xy 391.763141 -294.982526) (xy 391.786012 -295.026103) (xy 391.801596 -295.072784)
			(xy 391.809491 -295.121361) (xy 391.809986 -295.145968) (xy 391.809491 -295.170575) (xy 391.801596 -295.219152)
			(xy 391.786012 -295.265833) (xy 391.763141 -295.30941) (xy 391.733576 -295.348754) (xy 391.698083 -295.382846)
			(xy 391.65758 -295.410802) (xy 391.613118 -295.4319) (xy 391.565847 -295.445592) (xy 391.516992 -295.451524)
			(xy 391.467817 -295.449543) (xy 391.419598 -295.439699) (xy 391.373582 -295.422247) (xy 391.330961 -295.39764)
			(xy 391.29284 -295.366515) (xy 391.260205 -295.329678) (xy 391.233902 -295.288082) (xy 391.214611 -295.242806)
			(xy 391.202834 -295.195022) (xy 391.198874 -295.145968) (xy 390.870186 -295.145968) (xy 390.869691 -295.170575)
			(xy 390.861796 -295.219152) (xy 390.846212 -295.265833) (xy 390.823341 -295.30941) (xy 390.793776 -295.348754)
			(xy 390.758283 -295.382846) (xy 390.71778 -295.410802) (xy 390.673318 -295.4319) (xy 390.626047 -295.445592)
			(xy 390.577192 -295.451524) (xy 390.528017 -295.449543) (xy 390.479798 -295.439699) (xy 390.433782 -295.422247)
			(xy 390.391161 -295.39764) (xy 390.35304 -295.366515) (xy 390.320405 -295.329678) (xy 390.294102 -295.288082)
			(xy 390.274811 -295.242806) (xy 390.263034 -295.195022) (xy 390.259074 -295.145968) (xy 389.930132 -295.145968)
			(xy 389.929637 -295.170575) (xy 389.921742 -295.219152) (xy 389.906158 -295.265833) (xy 389.883287 -295.30941)
			(xy 389.853722 -295.348754) (xy 389.818229 -295.382846) (xy 389.777726 -295.410802) (xy 389.733264 -295.4319)
			(xy 389.685993 -295.445592) (xy 389.637138 -295.451524) (xy 389.587963 -295.449543) (xy 389.539744 -295.439699)
			(xy 389.493728 -295.422247) (xy 389.451107 -295.39764) (xy 389.412986 -295.366515) (xy 389.380351 -295.329678)
			(xy 389.354048 -295.288082) (xy 389.334757 -295.242806) (xy 389.32298 -295.195022) (xy 389.31902 -295.145968)
			(xy 388.990078 -295.145968) (xy 388.989583 -295.170575) (xy 388.981688 -295.219152) (xy 388.966104 -295.265833)
			(xy 388.943233 -295.30941) (xy 388.913668 -295.348754) (xy 388.878175 -295.382846) (xy 388.837672 -295.410802)
			(xy 388.79321 -295.4319) (xy 388.745939 -295.445592) (xy 388.697084 -295.451524) (xy 388.647909 -295.449543)
			(xy 388.59969 -295.439699) (xy 388.553674 -295.422247) (xy 388.511053 -295.39764) (xy 388.472932 -295.366515)
			(xy 388.440297 -295.329678) (xy 388.413994 -295.288082) (xy 388.394703 -295.242806) (xy 388.382926 -295.195022)
			(xy 388.378966 -295.145968) (xy 386.17017 -295.145968) (xy 386.169675 -295.170575) (xy 386.16178 -295.219152)
			(xy 386.146196 -295.265833) (xy 386.123325 -295.30941) (xy 386.09376 -295.348754) (xy 386.058267 -295.382846)
			(xy 386.017764 -295.410802) (xy 385.973302 -295.4319) (xy 385.926031 -295.445592) (xy 385.877176 -295.451524)
			(xy 385.828001 -295.449543) (xy 385.779782 -295.439699) (xy 385.733766 -295.422247) (xy 385.691145 -295.39764)
			(xy 385.653024 -295.366515) (xy 385.620389 -295.329678) (xy 385.594086 -295.288082) (xy 385.574795 -295.242806)
			(xy 385.563018 -295.195022) (xy 385.559058 -295.145968) (xy 385.230116 -295.145968) (xy 385.229621 -295.170575)
			(xy 385.221726 -295.219152) (xy 385.206142 -295.265833) (xy 385.183271 -295.30941) (xy 385.153706 -295.348754)
			(xy 385.118213 -295.382846) (xy 385.07771 -295.410802) (xy 385.033248 -295.4319) (xy 384.985977 -295.445592)
			(xy 384.937122 -295.451524) (xy 384.887947 -295.449543) (xy 384.839728 -295.439699) (xy 384.793712 -295.422247)
			(xy 384.751091 -295.39764) (xy 384.71297 -295.366515) (xy 384.680335 -295.329678) (xy 384.654032 -295.288082)
			(xy 384.634741 -295.242806) (xy 384.622964 -295.195022) (xy 384.619004 -295.145968) (xy 382.410208 -295.145968)
			(xy 382.409713 -295.170575) (xy 382.401818 -295.219152) (xy 382.386234 -295.265833) (xy 382.363363 -295.30941)
			(xy 382.333798 -295.348754) (xy 382.298305 -295.382846) (xy 382.257802 -295.410802) (xy 382.21334 -295.4319)
			(xy 382.166069 -295.445592) (xy 382.117214 -295.451524) (xy 382.068039 -295.449543) (xy 382.01982 -295.439699)
			(xy 381.973804 -295.422247) (xy 381.931183 -295.39764) (xy 381.893062 -295.366515) (xy 381.860427 -295.329678)
			(xy 381.834124 -295.288082) (xy 381.814833 -295.242806) (xy 381.803056 -295.195022) (xy 381.799096 -295.145968)
			(xy 381.470154 -295.145968) (xy 381.469659 -295.170575) (xy 381.461764 -295.219152) (xy 381.44618 -295.265833)
			(xy 381.423309 -295.30941) (xy 381.393744 -295.348754) (xy 381.358251 -295.382846) (xy 381.317748 -295.410802)
			(xy 381.273286 -295.4319) (xy 381.226015 -295.445592) (xy 381.17716 -295.451524) (xy 381.127985 -295.449543)
			(xy 381.079766 -295.439699) (xy 381.03375 -295.422247) (xy 380.991129 -295.39764) (xy 380.953008 -295.366515)
			(xy 380.920373 -295.329678) (xy 380.89407 -295.288082) (xy 380.874779 -295.242806) (xy 380.863002 -295.195022)
			(xy 380.859042 -295.145968) (xy 379.590046 -295.145968) (xy 379.589551 -295.170575) (xy 379.581656 -295.219152)
			(xy 379.566072 -295.265833) (xy 379.543201 -295.30941) (xy 379.513636 -295.348754) (xy 379.478143 -295.382846)
			(xy 379.43764 -295.410802) (xy 379.393178 -295.4319) (xy 379.345907 -295.445592) (xy 379.297052 -295.451524)
			(xy 379.247877 -295.449543) (xy 379.199658 -295.439699) (xy 379.153642 -295.422247) (xy 379.111021 -295.39764)
			(xy 379.0729 -295.366515) (xy 379.040265 -295.329678) (xy 379.013962 -295.288082) (xy 378.994671 -295.242806)
			(xy 378.982894 -295.195022) (xy 378.978934 -295.145968) (xy 378.650246 -295.145968) (xy 378.649751 -295.170575)
			(xy 378.641856 -295.219152) (xy 378.626272 -295.265833) (xy 378.603401 -295.30941) (xy 378.573836 -295.348754)
			(xy 378.538343 -295.382846) (xy 378.49784 -295.410802) (xy 378.453378 -295.4319) (xy 378.406107 -295.445592)
			(xy 378.357252 -295.451524) (xy 378.308077 -295.449543) (xy 378.259858 -295.439699) (xy 378.213842 -295.422247)
			(xy 378.171221 -295.39764) (xy 378.1331 -295.366515) (xy 378.100465 -295.329678) (xy 378.074162 -295.288082)
			(xy 378.054871 -295.242806) (xy 378.043094 -295.195022) (xy 378.039134 -295.145968) (xy 377.710192 -295.145968)
			(xy 377.709697 -295.170575) (xy 377.701802 -295.219152) (xy 377.686218 -295.265833) (xy 377.663347 -295.30941)
			(xy 377.633782 -295.348754) (xy 377.598289 -295.382846) (xy 377.557786 -295.410802) (xy 377.513324 -295.4319)
			(xy 377.466053 -295.445592) (xy 377.417198 -295.451524) (xy 377.368023 -295.449543) (xy 377.319804 -295.439699)
			(xy 377.273788 -295.422247) (xy 377.231167 -295.39764) (xy 377.193046 -295.366515) (xy 377.160411 -295.329678)
			(xy 377.134108 -295.288082) (xy 377.114817 -295.242806) (xy 377.10304 -295.195022) (xy 377.09908 -295.145968)
			(xy 375.840178 -295.145968) (xy 375.840231 -295.146044) (xy 375.843292 -295.14927) (xy 375.981976 -295.287954)
			(xy 375.98985 -295.291764) (xy 376.019086 -295.306314) (xy 376.074394 -295.341043) (xy 376.125449 -295.381766)
			(xy 376.148854 -295.40454) (xy 376.52706 -295.782746) (xy 376.552482 -295.808918) (xy 376.597223 -295.866556)
			(xy 376.634372 -295.929356) (xy 376.645886 -295.955974) (xy 377.56898 -295.955974) (xy 377.57294 -295.90692)
			(xy 377.584717 -295.859136) (xy 377.604008 -295.81386) (xy 377.630311 -295.772264) (xy 377.662946 -295.735427)
			(xy 377.701067 -295.704302) (xy 377.743688 -295.679695) (xy 377.789704 -295.662243) (xy 377.837923 -295.652399)
			(xy 377.887098 -295.650418) (xy 377.935953 -295.65635) (xy 377.983224 -295.670042) (xy 378.027686 -295.69114)
			(xy 378.068189 -295.719096) (xy 378.103682 -295.753188) (xy 378.133247 -295.792532) (xy 378.156118 -295.836109)
			(xy 378.171702 -295.88279) (xy 378.179597 -295.931367) (xy 378.180092 -295.955974) (xy 378.179597 -295.980581)
			(xy 378.177789 -295.991708) (xy 378.512342 -295.991708) (xy 378.515026 -295.942131) (xy 378.525696 -295.893641)
			(xy 378.54407 -295.847516) (xy 378.569664 -295.804972) (xy 378.601804 -295.767129) (xy 378.639644 -295.734984)
			(xy 378.682186 -295.709385) (xy 378.728308 -295.691006) (xy 378.776797 -295.680331) (xy 378.826374 -295.677641)
			(xy 378.875733 -295.683008) (xy 378.923573 -295.696289) (xy 378.968634 -295.717136) (xy 379.009729 -295.744998)
			(xy 379.045775 -295.779142) (xy 379.075822 -295.818668) (xy 379.099078 -295.862534) (xy 379.114931 -295.909585)
			(xy 379.122962 -295.958581) (xy 379.123448 -295.983406) (xy 379.123284 -295.998815) (xy 379.120228 -296.029481)
			(xy 379.117352 -296.04462) (xy 379.114812 -296.056812) (xy 379.12167 -296.080688) (xy 379.187964 -296.15003)
			(xy 379.19695 -296.158425) (xy 379.22017 -296.166395) (xy 379.232414 -296.16527) (xy 379.232668 -296.16527)
			(xy 379.246421 -296.163246) (xy 379.274139 -296.161086) (xy 379.28804 -296.160952) (xy 379.302005 -296.161073)
			(xy 379.32985 -296.163231) (xy 379.343666 -296.16527) (xy 379.355858 -296.167302) (xy 379.379734 -296.159428)
			(xy 379.446028 -296.090086) (xy 379.454112 -296.080682) (xy 379.460916 -296.056867) (xy 379.458982 -296.04462)
			(xy 379.45611 -296.02948) (xy 379.453054 -295.998815) (xy 379.452886 -295.983406) (xy 379.453408 -295.958151)
			(xy 379.461721 -295.908329) (xy 379.478122 -295.860555) (xy 379.502163 -295.816132) (xy 379.533187 -295.776272)
			(xy 379.570349 -295.742062) (xy 379.612635 -295.714436) (xy 379.658891 -295.694146) (xy 379.707856 -295.681746)
			(xy 379.758194 -295.677575) (xy 379.808532 -295.681746) (xy 379.857497 -295.694146) (xy 379.903753 -295.714436)
			(xy 379.946039 -295.742062) (xy 379.983201 -295.776272) (xy 380.014225 -295.816132) (xy 380.038266 -295.860555)
			(xy 380.054667 -295.908329) (xy 380.06298 -295.958151) (xy 380.063502 -295.983406) (xy 380.063339 -295.998815)
			(xy 380.060282 -296.029481) (xy 380.057406 -296.04462) (xy 380.054866 -296.056812) (xy 380.061724 -296.080688)
			(xy 380.128018 -296.15003) (xy 380.136981 -296.158454) (xy 380.160219 -296.166408) (xy 380.172468 -296.16527)
			(xy 380.172722 -296.16527) (xy 380.186413 -296.163261) (xy 380.214003 -296.161098) (xy 380.22784 -296.160952)
			(xy 380.241868 -296.161064) (xy 380.269841 -296.163223) (xy 380.28372 -296.16527) (xy 380.295912 -296.167302)
			(xy 380.319788 -296.159428) (xy 380.386082 -296.090086) (xy 380.394172 -296.080687) (xy 380.40097 -296.056868)
			(xy 380.399036 -296.04462) (xy 380.396163 -296.02948) (xy 380.393108 -295.998815) (xy 380.39294 -295.983406)
			(xy 380.393371 -295.958585) (xy 380.401401 -295.909598) (xy 380.41725 -295.862555) (xy 380.440501 -295.818695)
			(xy 380.470541 -295.779175) (xy 380.506579 -295.745035) (xy 380.547665 -295.717175) (xy 380.592717 -295.696329)
			(xy 380.640548 -295.683046) (xy 380.689898 -295.677676) (xy 380.739467 -295.68036) (xy 380.787948 -295.691028)
			(xy 380.834065 -295.709398) (xy 380.876603 -295.734988) (xy 380.91444 -295.767121) (xy 380.946581 -295.804953)
			(xy 380.972178 -295.847486) (xy 380.990556 -295.8936) (xy 381.001233 -295.942079) (xy 381.003926 -295.991648)
			(xy 381.003919 -295.991713) (xy 381.332233 -295.991713) (xy 381.334917 -295.942135) (xy 381.345586 -295.893643)
			(xy 381.36396 -295.847516) (xy 381.389555 -295.80497) (xy 381.421696 -295.767125) (xy 381.459536 -295.734979)
			(xy 381.502079 -295.709379) (xy 381.548203 -295.690998) (xy 381.596693 -295.680322) (xy 381.646271 -295.677632)
			(xy 381.695632 -295.682999) (xy 381.743474 -295.696281) (xy 381.788537 -295.717128) (xy 381.829633 -295.744991)
			(xy 381.86568 -295.779136) (xy 381.895728 -295.818663) (xy 381.918985 -295.86253) (xy 381.934839 -295.909583)
			(xy 381.942871 -295.95858) (xy 381.943356 -295.983406) (xy 381.943192 -295.998815) (xy 381.940136 -296.029481)
			(xy 381.93726 -296.04462) (xy 381.93472 -296.056812) (xy 381.941578 -296.080688) (xy 382.007872 -296.15003)
			(xy 382.016855 -296.158429) (xy 382.040077 -296.166397) (xy 382.052322 -296.16527) (xy 382.052576 -296.16527)
			(xy 382.066329 -296.163246) (xy 382.094047 -296.161086) (xy 382.107948 -296.160952) (xy 382.121913 -296.161072)
			(xy 382.149758 -296.16323) (xy 382.163574 -296.16527) (xy 382.175766 -296.167302) (xy 382.199642 -296.159428)
			(xy 382.265936 -296.090086) (xy 382.274021 -296.080683) (xy 382.280824 -296.056867) (xy 382.27889 -296.04462)
			(xy 382.276018 -296.02948) (xy 382.272962 -295.998815) (xy 382.272794 -295.983406) (xy 382.273316 -295.958151)
			(xy 382.281629 -295.908329) (xy 382.29803 -295.860555) (xy 382.322071 -295.816132) (xy 382.353095 -295.776272)
			(xy 382.390257 -295.742062) (xy 382.432543 -295.714436) (xy 382.478799 -295.694146) (xy 382.527764 -295.681746)
			(xy 382.578102 -295.677575) (xy 382.62844 -295.681746) (xy 382.677405 -295.694146) (xy 382.723661 -295.714436)
			(xy 382.765947 -295.742062) (xy 382.803109 -295.776272) (xy 382.834133 -295.816132) (xy 382.858174 -295.860555)
			(xy 382.874575 -295.908329) (xy 382.882888 -295.958151) (xy 382.88341 -295.983406) (xy 382.883246 -295.998815)
			(xy 382.88019 -296.029481) (xy 382.877314 -296.04462) (xy 382.874774 -296.056812) (xy 382.881632 -296.080688)
			(xy 382.947926 -296.15003) (xy 382.956885 -296.158459) (xy 382.980126 -296.16641) (xy 382.992376 -296.16527)
			(xy 382.99263 -296.16527) (xy 383.006384 -296.163251) (xy 383.034101 -296.161088) (xy 383.048002 -296.160952)
			(xy 383.061967 -296.161066) (xy 383.089813 -296.163228) (xy 383.103628 -296.16527) (xy 383.11582 -296.167302)
			(xy 383.139696 -296.159428) (xy 383.20599 -296.090086) (xy 383.214081 -296.080688) (xy 383.220878 -296.056868)
			(xy 383.218944 -296.04462) (xy 383.216072 -296.02948) (xy 383.213016 -295.998815) (xy 383.212848 -295.983406)
			(xy 383.213371 -295.958584) (xy 383.221402 -295.909593) (xy 383.237254 -295.862547) (xy 383.260507 -295.818686)
			(xy 383.290551 -295.779164) (xy 383.326593 -295.745024) (xy 383.367683 -295.717165) (xy 383.41274 -295.696321)
			(xy 383.460575 -295.683041) (xy 383.509929 -295.677675) (xy 383.5595 -295.680364) (xy 383.607983 -295.691039)
			(xy 383.654101 -295.709416) (xy 383.696638 -295.735013) (xy 383.734473 -295.767154) (xy 383.76661 -295.804993)
			(xy 383.792201 -295.847533) (xy 383.810573 -295.893653) (xy 383.821241 -295.942138) (xy 383.82199 -295.955974)
			(xy 388.84912 -295.955974) (xy 388.85308 -295.90692) (xy 388.864857 -295.859136) (xy 388.884148 -295.81386)
			(xy 388.910451 -295.772264) (xy 388.943086 -295.735427) (xy 388.981207 -295.704302) (xy 389.023828 -295.679695)
			(xy 389.069844 -295.662243) (xy 389.118063 -295.652399) (xy 389.167238 -295.650418) (xy 389.216093 -295.65635)
			(xy 389.263364 -295.670042) (xy 389.307826 -295.69114) (xy 389.348329 -295.719096) (xy 389.383822 -295.753188)
			(xy 389.413387 -295.792532) (xy 389.436258 -295.836109) (xy 389.451842 -295.88279) (xy 389.459737 -295.931367)
			(xy 389.460232 -295.955974) (xy 389.459737 -295.980581) (xy 389.451842 -296.029158) (xy 389.436258 -296.075839)
			(xy 389.413387 -296.119416) (xy 389.383822 -296.15876) (xy 389.348329 -296.192852) (xy 389.307826 -296.220808)
			(xy 389.263364 -296.241906) (xy 389.216093 -296.255598) (xy 389.167238 -296.26153) (xy 389.118063 -296.259549)
			(xy 389.069844 -296.249705) (xy 389.023828 -296.232253) (xy 388.981207 -296.207646) (xy 388.943086 -296.176521)
			(xy 388.910451 -296.139684) (xy 388.884148 -296.098088) (xy 388.864857 -296.052812) (xy 388.85308 -296.005028)
			(xy 388.84912 -295.955974) (xy 383.82199 -295.955974) (xy 383.823924 -295.99171) (xy 383.818552 -296.041062)
			(xy 383.805266 -296.088896) (xy 383.784416 -296.13395) (xy 383.756552 -296.175037) (xy 383.722407 -296.211075)
			(xy 383.682882 -296.241113) (xy 383.639018 -296.264362) (xy 383.59197 -296.280207) (xy 383.542978 -296.288232)
			(xy 383.518156 -296.288714) (xy 383.495042 -296.287952) (xy 383.482596 -296.286936) (xy 383.459736 -296.296842)
			(xy 383.39141 -296.38117) (xy 383.38633 -296.405554) (xy 383.389886 -296.417492) (xy 383.39653 -296.441846)
			(xy 383.403671 -296.49182) (xy 383.40411 -296.51706) (xy 383.403612 -296.543709) (xy 383.395669 -296.596413)
			(xy 383.379959 -296.647343) (xy 383.356833 -296.695364) (xy 383.326809 -296.739401) (xy 383.290557 -296.778472)
			(xy 383.248886 -296.811703) (xy 383.202728 -296.838352) (xy 383.153114 -296.857824) (xy 383.101152 -296.869684)
			(xy 383.048002 -296.873668) (xy 382.994852 -296.869684) (xy 382.94289 -296.857824) (xy 382.893276 -296.838352)
			(xy 382.847118 -296.811703) (xy 382.805447 -296.778472) (xy 382.769195 -296.739401) (xy 382.739171 -296.695364)
			(xy 382.716045 -296.647343) (xy 382.700335 -296.596413) (xy 382.692392 -296.543709) (xy 382.691894 -296.51706)
			(xy 382.69234 -296.49182) (xy 382.699482 -296.441848) (xy 382.706118 -296.417492) (xy 382.709674 -296.405554)
			(xy 382.704594 -296.38117) (xy 382.636268 -296.296842) (xy 382.613408 -296.286936) (xy 382.600962 -296.287952)
			(xy 382.578356 -296.288714) (xy 382.577848 -296.288714) (xy 382.554988 -296.287952) (xy 382.542542 -296.286936)
			(xy 382.519682 -296.296842) (xy 382.451356 -296.38117) (xy 382.446276 -296.405554) (xy 382.449832 -296.417492)
			(xy 382.456475 -296.441847) (xy 382.463617 -296.49182) (xy 382.464056 -296.51706) (xy 382.463558 -296.543709)
			(xy 382.455615 -296.596413) (xy 382.439905 -296.647343) (xy 382.416779 -296.695364) (xy 382.386755 -296.739401)
			(xy 382.350503 -296.778472) (xy 382.308832 -296.811703) (xy 382.262674 -296.838352) (xy 382.21306 -296.857824)
			(xy 382.161098 -296.869684) (xy 382.107948 -296.873668) (xy 382.054798 -296.869684) (xy 382.002836 -296.857824)
			(xy 381.953222 -296.838352) (xy 381.907064 -296.811703) (xy 381.865393 -296.778472) (xy 381.829141 -296.739401)
			(xy 381.799117 -296.695364) (xy 381.775991 -296.647343) (xy 381.760281 -296.596413) (xy 381.752338 -296.543709)
			(xy 381.75184 -296.51706) (xy 381.752284 -296.49182) (xy 381.759428 -296.441848) (xy 381.766064 -296.417492)
			(xy 381.76962 -296.405554) (xy 381.76454 -296.38117) (xy 381.696214 -296.296842) (xy 381.673354 -296.286936)
			(xy 381.660908 -296.287952) (xy 381.638048 -296.288714) (xy 381.613222 -296.288274) (xy 381.564224 -296.280249)
			(xy 381.517169 -296.264402) (xy 381.473298 -296.241151) (xy 381.433767 -296.211108) (xy 381.399617 -296.175066)
			(xy 381.371748 -296.133973) (xy 381.350895 -296.088913) (xy 381.337607 -296.041073) (xy 381.332233 -295.991713)
			(xy 381.003919 -295.991713) (xy 380.998564 -296.040998) (xy 380.98529 -296.088832) (xy 380.964451 -296.133888)
			(xy 380.936599 -296.174979) (xy 380.902465 -296.211023) (xy 380.86295 -296.24107) (xy 380.819095 -296.264328)
			(xy 380.772055 -296.280186) (xy 380.723069 -296.288224) (xy 380.698248 -296.288714) (xy 380.675134 -296.287952)
			(xy 380.662747 -296.287551) (xy 380.63998 -296.297273) (xy 380.6317 -296.306494) (xy 380.571248 -296.38117)
			(xy 380.566168 -296.405554) (xy 380.569724 -296.417492) (xy 380.576367 -296.441847) (xy 380.583509 -296.49182)
			(xy 380.583948 -296.51706) (xy 380.58345 -296.543709) (xy 380.575507 -296.596413) (xy 380.559797 -296.647343)
			(xy 380.536671 -296.695364) (xy 380.506647 -296.739401) (xy 380.470395 -296.778472) (xy 380.428724 -296.811703)
			(xy 380.382566 -296.838352) (xy 380.332952 -296.857824) (xy 380.28099 -296.869684) (xy 380.22784 -296.873668)
			(xy 380.17469 -296.869684) (xy 380.122728 -296.857824) (xy 380.073114 -296.838352) (xy 380.026956 -296.811703)
			(xy 379.985285 -296.778472) (xy 379.949033 -296.739401) (xy 379.919009 -296.695364) (xy 379.895883 -296.647343)
			(xy 379.880173 -296.596413) (xy 379.87223 -296.543709) (xy 379.871732 -296.51706) (xy 379.872177 -296.49182)
			(xy 379.87932 -296.441848) (xy 379.885956 -296.417492) (xy 379.889512 -296.405554) (xy 379.884432 -296.38117)
			(xy 379.816106 -296.296842) (xy 379.793246 -296.286936) (xy 379.7808 -296.287952) (xy 379.758448 -296.288714)
			(xy 379.75794 -296.288714) (xy 379.73508 -296.287952) (xy 379.722634 -296.286936) (xy 379.699774 -296.296842)
			(xy 379.631448 -296.38117) (xy 379.626368 -296.405554) (xy 379.629924 -296.417492) (xy 379.636567 -296.441847)
			(xy 379.643709 -296.49182) (xy 379.644148 -296.51706) (xy 379.64365 -296.543709) (xy 379.635707 -296.596413)
			(xy 379.619997 -296.647343) (xy 379.596871 -296.695364) (xy 379.566847 -296.739401) (xy 379.530595 -296.778472)
			(xy 379.488924 -296.811703) (xy 379.442766 -296.838352) (xy 379.393152 -296.857824) (xy 379.34119 -296.869684)
			(xy 379.28804 -296.873668) (xy 379.23489 -296.869684) (xy 379.182928 -296.857824) (xy 379.133314 -296.838352)
			(xy 379.087156 -296.811703) (xy 379.045485 -296.778472) (xy 379.009233 -296.739401) (xy 378.979209 -296.695364)
			(xy 378.956083 -296.647343) (xy 378.940373 -296.596413) (xy 378.93243 -296.543709) (xy 378.931932 -296.51706)
			(xy 378.932377 -296.49182) (xy 378.93952 -296.441848) (xy 378.946156 -296.417492) (xy 378.949712 -296.405554)
			(xy 378.944632 -296.38117) (xy 378.876306 -296.296842) (xy 378.853446 -296.286936) (xy 378.841 -296.287952)
			(xy 378.81814 -296.288714) (xy 378.793315 -296.288265) (xy 378.744318 -296.280239) (xy 378.697266 -296.264391)
			(xy 378.653397 -296.24114) (xy 378.613868 -296.211098) (xy 378.57972 -296.175056) (xy 378.551853 -296.133964)
			(xy 378.531001 -296.088905) (xy 378.517714 -296.041066) (xy 378.512342 -295.991708) (xy 378.177789 -295.991708)
			(xy 378.171702 -296.029158) (xy 378.156118 -296.075839) (xy 378.133247 -296.119416) (xy 378.103682 -296.15876)
			(xy 378.068189 -296.192852) (xy 378.027686 -296.220808) (xy 377.983224 -296.241906) (xy 377.935953 -296.255598)
			(xy 377.887098 -296.26153) (xy 377.837923 -296.259549) (xy 377.789704 -296.249705) (xy 377.743688 -296.232253)
			(xy 377.701067 -296.207646) (xy 377.662946 -296.176521) (xy 377.630311 -296.139684) (xy 377.604008 -296.098088)
			(xy 377.584717 -296.052812) (xy 377.57294 -296.005028) (xy 377.56898 -295.955974) (xy 376.645886 -295.955974)
			(xy 376.66334 -295.996324) (xy 376.683669 -296.0664) (xy 376.695037 -296.138474) (xy 376.696732 -296.174922)
			(xy 376.696732 -296.175176) (xy 376.69739 -296.184815) (xy 376.704962 -296.202574) (xy 376.711464 -296.20972)
			(xy 377.583657 -297.081913) (xy 385.826756 -297.081913) (xy 385.826756 -297.017991) (xy 385.834767 -296.954573)
			(xy 385.850664 -296.892659) (xy 385.874196 -296.833226) (xy 385.90499 -296.777211) (xy 385.942563 -296.725496)
			(xy 385.98632 -296.678899) (xy 386.035573 -296.638154) (xy 386.089544 -296.603903) (xy 386.147383 -296.576686)
			(xy 386.208176 -296.556933) (xy 386.270966 -296.544955) (xy 386.334762 -296.540942) (xy 386.398558 -296.544955)
			(xy 386.461348 -296.556933) (xy 386.522141 -296.576686) (xy 386.57998 -296.603903) (xy 386.633951 -296.638154)
			(xy 386.683204 -296.678899) (xy 386.726961 -296.725496) (xy 386.764534 -296.777211) (xy 386.795328 -296.833226)
			(xy 386.81886 -296.892659) (xy 386.834757 -296.954573) (xy 386.842768 -297.017991) (xy 386.84327 -297.049952)
			(xy 386.842768 -297.081913) (xy 386.834757 -297.145331) (xy 386.81886 -297.207245) (xy 386.795328 -297.266678)
			(xy 386.764534 -297.322693) (xy 386.726961 -297.374408) (xy 386.683204 -297.421005) (xy 386.633951 -297.46175)
			(xy 386.57998 -297.496001) (xy 386.522141 -297.523218) (xy 386.461348 -297.542971) (xy 386.398558 -297.554949)
			(xy 386.334762 -297.558963) (xy 386.270966 -297.554949) (xy 386.208176 -297.542971) (xy 386.147383 -297.523218)
			(xy 386.089544 -297.496001) (xy 386.035573 -297.46175) (xy 385.98632 -297.421005) (xy 385.942563 -297.374408)
			(xy 385.90499 -297.322693) (xy 385.874196 -297.266678) (xy 385.850664 -297.207245) (xy 385.834767 -297.145331)
			(xy 385.826756 -297.081913) (xy 377.583657 -297.081913) (xy 379.507242 -299.005498) (xy 379.511226 -299.009252)
			(xy 379.520447 -299.01515) (xy 379.52553 -299.017182) (xy 379.535436 -299.020992) (xy 379.538992 -299.020738)
			(xy 379.546358 -299.02023) (xy 379.574044 -299.019214) (xy 379.601293 -299.019703) (xy 379.655234 -299.027465)
			(xy 379.707522 -299.042824) (xy 379.757093 -299.065468) (xy 379.802936 -299.094936) (xy 379.844119 -299.130628)
			(xy 379.879804 -299.171817) (xy 379.909264 -299.217665) (xy 379.931899 -299.267239) (xy 379.935442 -299.27931)
			(xy 381.753362 -299.27931) (xy 381.757433 -299.223688) (xy 381.769559 -299.169251) (xy 381.789482 -299.11716)
			(xy 381.816778 -299.068525) (xy 381.850864 -299.024382) (xy 381.891013 -298.985673) (xy 381.936371 -298.953222)
			(xy 381.985971 -298.927721) (xy 382.038755 -298.909714) (xy 382.093598 -298.899584) (xy 382.149332 -298.897547)
			(xy 382.204769 -298.903647) (xy 382.258726 -298.917753) (xy 382.310055 -298.939565) (xy 382.357661 -298.968619)
			(xy 382.400529 -299.004294) (xy 382.437746 -299.045831) (xy 382.468519 -299.092344) (xy 382.492191 -299.142841)
			(xy 382.508259 -299.196248) (xy 382.516379 -299.251424) (xy 382.516888 -299.27931) (xy 384.039362 -299.27931)
			(xy 384.043433 -299.223688) (xy 384.055559 -299.169251) (xy 384.075482 -299.11716) (xy 384.102778 -299.068525)
			(xy 384.136864 -299.024382) (xy 384.177013 -298.985673) (xy 384.222371 -298.953222) (xy 384.271971 -298.927721)
			(xy 384.324755 -298.909714) (xy 384.379598 -298.899584) (xy 384.435332 -298.897547) (xy 384.490769 -298.903647)
			(xy 384.544726 -298.917753) (xy 384.596055 -298.939565) (xy 384.643661 -298.968619) (xy 384.686529 -299.004294)
			(xy 384.723746 -299.045831) (xy 384.754519 -299.092344) (xy 384.762249 -299.108833) (xy 387.935718 -299.108833)
			(xy 387.935718 -299.044911) (xy 387.943729 -298.981493) (xy 387.959626 -298.919579) (xy 387.983158 -298.860146)
			(xy 388.013952 -298.804131) (xy 388.051525 -298.752416) (xy 388.095282 -298.705819) (xy 388.144535 -298.665074)
			(xy 388.198506 -298.630823) (xy 388.256345 -298.603606) (xy 388.317138 -298.583853) (xy 388.379928 -298.571875)
			(xy 388.443724 -298.567862) (xy 388.50752 -298.571875) (xy 388.57031 -298.583853) (xy 388.631103 -298.603606)
			(xy 388.688942 -298.630823) (xy 388.742913 -298.665074) (xy 388.792166 -298.705819) (xy 388.835923 -298.752416)
			(xy 388.873496 -298.804131) (xy 388.90429 -298.860146) (xy 388.927822 -298.919579) (xy 388.943719 -298.981493)
			(xy 388.95173 -299.044911) (xy 388.952232 -299.076872) (xy 388.95173 -299.108833) (xy 388.943719 -299.172251)
			(xy 388.927822 -299.234165) (xy 388.90429 -299.293598) (xy 388.873496 -299.349613) (xy 388.835923 -299.401328)
			(xy 388.792166 -299.447925) (xy 388.742913 -299.48867) (xy 388.688942 -299.522921) (xy 388.631103 -299.550138)
			(xy 388.57031 -299.569891) (xy 388.50752 -299.581869) (xy 388.443724 -299.585883) (xy 388.379928 -299.581869)
			(xy 388.317138 -299.569891) (xy 388.256345 -299.550138) (xy 388.198506 -299.522921) (xy 388.144535 -299.48867)
			(xy 388.095282 -299.447925) (xy 388.051525 -299.401328) (xy 388.013952 -299.349613) (xy 387.983158 -299.293598)
			(xy 387.959626 -299.234165) (xy 387.943729 -299.172251) (xy 387.935718 -299.108833) (xy 384.762249 -299.108833)
			(xy 384.778191 -299.142841) (xy 384.794259 -299.196248) (xy 384.802379 -299.251424) (xy 384.802888 -299.27931)
			(xy 384.802379 -299.307196) (xy 384.794259 -299.362372) (xy 384.778191 -299.415779) (xy 384.754519 -299.466276)
			(xy 384.723746 -299.512789) (xy 384.686529 -299.554326) (xy 384.643661 -299.590001) (xy 384.596055 -299.619055)
			(xy 384.544726 -299.640867) (xy 384.490769 -299.654973) (xy 384.435332 -299.661073) (xy 384.379598 -299.659036)
			(xy 384.324755 -299.648906) (xy 384.271971 -299.630899) (xy 384.222371 -299.605398) (xy 384.177013 -299.572947)
			(xy 384.136864 -299.534238) (xy 384.102778 -299.490095) (xy 384.075482 -299.44146) (xy 384.055559 -299.389369)
			(xy 384.043433 -299.334932) (xy 384.039362 -299.27931) (xy 382.516888 -299.27931) (xy 382.516379 -299.307196)
			(xy 382.508259 -299.362372) (xy 382.492191 -299.415779) (xy 382.468519 -299.466276) (xy 382.437746 -299.512789)
			(xy 382.400529 -299.554326) (xy 382.357661 -299.590001) (xy 382.310055 -299.619055) (xy 382.258726 -299.640867)
			(xy 382.204769 -299.654973) (xy 382.149332 -299.661073) (xy 382.093598 -299.659036) (xy 382.038755 -299.648906)
			(xy 381.985971 -299.630899) (xy 381.936371 -299.605398) (xy 381.891013 -299.572947) (xy 381.850864 -299.534238)
			(xy 381.816778 -299.490095) (xy 381.789482 -299.44146) (xy 381.769559 -299.389369) (xy 381.757433 -299.334932)
			(xy 381.753362 -299.27931) (xy 379.935442 -299.27931) (xy 379.947249 -299.31953) (xy 379.955001 -299.373473)
			(xy 379.955552 -299.400722) (xy 379.954536 -299.428408) (xy 379.954028 -299.435774) (xy 379.953774 -299.43933)
			(xy 379.957584 -299.449236) (xy 379.959592 -299.454332) (xy 379.965484 -299.463564) (xy 379.969268 -299.467524)
			(xy 381.584919 -301.083175) (xy 386.695944 -301.083175) (xy 386.695944 -301.019253) (xy 386.703955 -300.955835)
			(xy 386.719852 -300.893921) (xy 386.743384 -300.834488) (xy 386.774178 -300.778473) (xy 386.811751 -300.726758)
			(xy 386.855508 -300.680161) (xy 386.904761 -300.639416) (xy 386.958732 -300.605165) (xy 387.016571 -300.577948)
			(xy 387.077364 -300.558195) (xy 387.140154 -300.546217) (xy 387.20395 -300.542204) (xy 387.267746 -300.546217)
			(xy 387.330536 -300.558195) (xy 387.391329 -300.577948) (xy 387.449168 -300.605165) (xy 387.503139 -300.639416)
			(xy 387.552392 -300.680161) (xy 387.596149 -300.726758) (xy 387.633722 -300.778473) (xy 387.664516 -300.834488)
			(xy 387.688048 -300.893921) (xy 387.703945 -300.955835) (xy 387.711956 -301.019253) (xy 387.712458 -301.051214)
			(xy 387.711956 -301.083175) (xy 387.703945 -301.146593) (xy 387.688048 -301.208507) (xy 387.664516 -301.26794)
			(xy 387.633722 -301.323955) (xy 387.596149 -301.37567) (xy 387.552392 -301.422267) (xy 387.503139 -301.463012)
			(xy 387.449168 -301.497263) (xy 387.391329 -301.52448) (xy 387.330536 -301.544233) (xy 387.267746 -301.556211)
			(xy 387.20395 -301.560225) (xy 387.140154 -301.556211) (xy 387.077364 -301.544233) (xy 387.016571 -301.52448)
			(xy 386.958732 -301.497263) (xy 386.904761 -301.463012) (xy 386.855508 -301.422267) (xy 386.811751 -301.37567)
			(xy 386.774178 -301.323955) (xy 386.743384 -301.26794) (xy 386.719852 -301.208507) (xy 386.703955 -301.146593)
			(xy 386.695944 -301.083175) (xy 381.584919 -301.083175) (xy 382.687576 -302.185832) (xy 382.694823 -302.192388)
			(xy 382.712867 -302.199839) (xy 382.722628 -302.20031)
		)
		(stroke
			(width 0)
			(type solid)
		)
		(fill yes)
		(layer "In6.Cu")
		(net "PVDD11_S3_P0")
	)
)
